LOGICAL PART CROSS REFERENCE - 24-Aug-2023 AT 15:36:33

DRAWING: @S9S_MB_2U_LIB.S9S_MB_2U(SCH_1):PAGE310 

TP_TDR_4P_FTS_TH-TP_TDR_4P_DIPA  I5  X38
   2 T1_GND     P1 @S9S_MB_2U_LIB.S9S_MB_2U(SCH_1):T1_GND
   3 T1_GND     P2 @S9S_MB_2U_LIB.S9S_MB_2U(SCH_1):T1_GND
   1 UNNAMED_310_TPTDR4PFTS_I5_S1     S1 @S9S_MB_2U_LIB.S9S_MB_2U(SCH_1):UNNAMED_310_TPTDR4PFTS_I5_S1
   4 UNNAMED_310_TPTDR4PFTS_I5_S2     S2 @S9S_MB_2U_LIB.S9S_MB_2U(SCH_1):UNNAMED_310_TPTDR4PFTS_I5_S2

TP_TDR_4P_FTS_TH-TP_TDR_4P_DIPA  I6  X44
   2 T1_GND     P1 @S9S_MB_2U_LIB.S9S_MB_2U(SCH_1):T1_GND
   3 T1_GND     P2 @S9S_MB_2U_LIB.S9S_MB_2U(SCH_1):T1_GND
   1 UNNAMED_310_TPTDR4PFTS_I5_S2     S1 @S9S_MB_2U_LIB.S9S_MB_2U(SCH_1):UNNAMED_310_TPTDR4PFTS_I5_S2
   4 UNNAMED_310_TPTDR4PFTS_I5_S1     S2 @S9S_MB_2U_LIB.S9S_MB_2U(SCH_1):UNNAMED_310_TPTDR4PFTS_I5_S1

TP_TDR_4P_FTS_TH-TP_TDR_4P_DIPA  I7  X37
   2 T1_GND     P1 @S9S_MB_2U_LIB.S9S_MB_2U(SCH_1):T1_GND
   3 T1_GND     P2 @S9S_MB_2U_LIB.S9S_MB_2U(SCH_1):T1_GND
   1 UNNAMED_310_TPTDR4PFTS_I7_S1     S1 @S9S_MB_2U_LIB.S9S_MB_2U(SCH_1):UNNAMED_310_TPTDR4PFTS_I7_S1
   4 UNNAMED_310_TPTDR4PFTS_I7_S2     S2 @S9S_MB_2U_LIB.S9S_MB_2U(SCH_1):UNNAMED_310_TPTDR4PFTS_I7_S2

TP_TDR_4P_FTS_TH-TP_TDR_4P_DIPA  I8  X36
   2 T1_GND     P1 @S9S_MB_2U_LIB.S9S_MB_2U(SCH_1):T1_GND
   3 T1_GND     P2 @S9S_MB_2U_LIB.S9S_MB_2U(SCH_1):T1_GND
   1 UNNAMED_310_TPTDR4PFTS_I10_S2     S1 @S9S_MB_2U_LIB.S9S_MB_2U(SCH_1):UNNAMED_310_TPTDR4PFTS_I10_S2
   4 UNNAMED_310_TPTDR4PFTS_I10_S1     S2 @S9S_MB_2U_LIB.S9S_MB_2U(SCH_1):UNNAMED_310_TPTDR4PFTS_I10_S1

TP_TDR_4P_FTS_TH-TP_TDR_4P_DIPA  I9  X43
   2 T1_GND     P1 @S9S_MB_2U_LIB.S9S_MB_2U(SCH_1):T1_GND
   3 T1_GND     P2 @S9S_MB_2U_LIB.S9S_MB_2U(SCH_1):T1_GND
   1 UNNAMED_310_TPTDR4PFTS_I7_S2     S1 @S9S_MB_2U_LIB.S9S_MB_2U(SCH_1):UNNAMED_310_TPTDR4PFTS_I7_S2
   4 UNNAMED_310_TPTDR4PFTS_I7_S1     S2 @S9S_MB_2U_LIB.S9S_MB_2U(SCH_1):UNNAMED_310_TPTDR4PFTS_I7_S1

TP_TDR_4P_FTS_TH-TP_TDR_4P_DIPA  I10  X42
   2 T1_GND     P1 @S9S_MB_2U_LIB.S9S_MB_2U(SCH_1):T1_GND
   3 T1_GND     P2 @S9S_MB_2U_LIB.S9S_MB_2U(SCH_1):T1_GND
   1 UNNAMED_310_TPTDR4PFTS_I10_S1     S1 @S9S_MB_2U_LIB.S9S_MB_2U(SCH_1):UNNAMED_310_TPTDR4PFTS_I10_S1
   4 UNNAMED_310_TPTDR4PFTS_I10_S2     S2 @S9S_MB_2U_LIB.S9S_MB_2U(SCH_1):UNNAMED_310_TPTDR4PFTS_I10_S2

TP_TDR_4P_FTS_TH-TP_TDR_4P_DIPA  I15  X41
   2 T1_GND     P1 @S9S_MB_2U_LIB.S9S_MB_2U(SCH_1):T1_GND
   3 T1_GND     P2 @S9S_MB_2U_LIB.S9S_MB_2U(SCH_1):T1_GND
   1 UNNAMED_310_TPTDR4PFTS_I15_S1     S1 @S9S_MB_2U_LIB.S9S_MB_2U(SCH_1):UNNAMED_310_TPTDR4PFTS_I15_S1
   4 UNNAMED_310_TPTDR4PFTS_I15_S2     S2 @S9S_MB_2U_LIB.S9S_MB_2U(SCH_1):UNNAMED_310_TPTDR4PFTS_I15_S2

TP_TDR_4P_FTS_TH-TP_TDR_4P_DIPA  I16  X35
   2 T1_GND     P1 @S9S_MB_2U_LIB.S9S_MB_2U(SCH_1):T1_GND
   3 T1_GND     P2 @S9S_MB_2U_LIB.S9S_MB_2U(SCH_1):T1_GND
   1 UNNAMED_310_TPTDR4PFTS_I15_S2     S1 @S9S_MB_2U_LIB.S9S_MB_2U(SCH_1):UNNAMED_310_TPTDR4PFTS_I15_S2
   4 UNNAMED_310_TPTDR4PFTS_I15_S1     S2 @S9S_MB_2U_LIB.S9S_MB_2U(SCH_1):UNNAMED_310_TPTDR4PFTS_I15_S1

TP_TDR_4P_FTS_TH-TP_TDR_4P_DIPA  I19  X34
   2 T1_GND     P1 @S9S_MB_2U_LIB.S9S_MB_2U(SCH_1):T1_GND
   3 T1_GND     P2 @S9S_MB_2U_LIB.S9S_MB_2U(SCH_1):T1_GND
   1 UNNAMED_310_TPTDR4PFTS_I19_S1     S1 @S9S_MB_2U_LIB.S9S_MB_2U(SCH_1):UNNAMED_310_TPTDR4PFTS_I19_S1
   4 UNNAMED_310_TPTDR4PFTS_I19_S2     S2 @S9S_MB_2U_LIB.S9S_MB_2U(SCH_1):UNNAMED_310_TPTDR4PFTS_I19_S2

TP_TDR_4P_FTS_TH-TP_TDR_4P_DIPA  I20  X33
   2 T1_GND     P1 @S9S_MB_2U_LIB.S9S_MB_2U(SCH_1):T1_GND
   3 T1_GND     P2 @S9S_MB_2U_LIB.S9S_MB_2U(SCH_1):T1_GND
   1 UNNAMED_310_TPTDR4PFTS_I20_S1     S1 @S9S_MB_2U_LIB.S9S_MB_2U(SCH_1):UNNAMED_310_TPTDR4PFTS_I20_S1
   4 UNNAMED_310_TPTDR4PFTS_I20_S2     S2 @S9S_MB_2U_LIB.S9S_MB_2U(SCH_1):UNNAMED_310_TPTDR4PFTS_I20_S2

TP_TDR_4P_FTS_TH-TP_TDR_4P_DIPA  I21  X40
   2 T1_GND     P1 @S9S_MB_2U_LIB.S9S_MB_2U(SCH_1):T1_GND
   3 T1_GND     P2 @S9S_MB_2U_LIB.S9S_MB_2U(SCH_1):T1_GND
   1 UNNAMED_310_TPTDR4PFTS_I19_S2     S1 @S9S_MB_2U_LIB.S9S_MB_2U(SCH_1):UNNAMED_310_TPTDR4PFTS_I19_S2
   4 UNNAMED_310_TPTDR4PFTS_I19_S1     S2 @S9S_MB_2U_LIB.S9S_MB_2U(SCH_1):UNNAMED_310_TPTDR4PFTS_I19_S1

TP_TDR_4P_FTS_TH-TP_TDR_4P_DIPA  I22  X39
   2 T1_GND     P1 @S9S_MB_2U_LIB.S9S_MB_2U(SCH_1):T1_GND
   3 T1_GND     P2 @S9S_MB_2U_LIB.S9S_MB_2U(SCH_1):T1_GND
   1 UNNAMED_310_TPTDR4PFTS_I20_S2     S1 @S9S_MB_2U_LIB.S9S_MB_2U(SCH_1):UNNAMED_310_TPTDR4PFTS_I20_S2
   4 UNNAMED_310_TPTDR4PFTS_I20_S1     S2 @S9S_MB_2U_LIB.S9S_MB_2U(SCH_1):UNNAMED_310_TPTDR4PFTS_I20_S1


DRAWING: @S9S_MB_2U_LIB.S9S_MB_2U(SCH_1):PAGE13 

Q_RES_0402LF-100,1%,1/16W,CHIPA  I16  R2
   1 H_CPU_PREQ_QS_GTL_N      A @S9S_MB_2U_LIB.S9S_MB_2U(SCH_1):H_CPU_PREQ_QS_GTL_N
   2 H_CPU0_PREQ_QS_GTL_R_N      B @S9S_MB_2U_LIB.S9S_MB_2U(SCH_1):H_CPU0_PREQ_QS_GTL_R_N

Q_RES_0402LF-10,1%,1/16W,CHIP,A  I18  R1
   1 H_CPU_PRDY_QS_GTL_N      A @S9S_MB_2U_LIB.S9S_MB_2U(SCH_1):H_CPU_PRDY_QS_GTL_N
   2 H_CPU0_PRDY_QS_GTL_R_N      B @S9S_MB_2U_LIB.S9S_MB_2U(SCH_1):H_CPU0_PRDY_QS_GTL_R_N

Q_RES_0402LF-33.2,1%,1/16W,CHIA  I21  R3
   1 PECI_CPU_GTL      A @S9S_MB_2U_LIB.S9S_MB_2U(SCH_1):PECI_CPU_GTL
   2 PECI_CPU0_GTL_R      B @S9S_MB_2U_LIB.S9S_MB_2U(SCH_1):PECI_CPU0_GTL_R

Q_RES_0402LF-100,1%,1/16W,CHIPA  I24  R5
   1 JTAG_DBP_CPU_GTL_TCK      A @S9S_MB_2U_LIB.S9S_MB_2U(SCH_1):JTAG_DBP_CPU_GTL_TCK
   2 JTAG_DBP_CPU0_GTL_R_TCK      B @S9S_MB_2U_LIB.S9S_MB_2U(SCH_1):JTAG_DBP_CPU0_GTL_R_TCK

Q_RES_0402LF-100,1%,1/16W,CHIPA  I25  R6
   1 JTAG_DBP_CPU_QS_GTL_TMS      A @S9S_MB_2U_LIB.S9S_MB_2U(SCH_1):JTAG_DBP_CPU_QS_GTL_TMS
   2 JTAG_DBP_CPU0_QS_GTL_R_TMS      B @S9S_MB_2U_LIB.S9S_MB_2U(SCH_1):JTAG_DBP_CPU0_QS_GTL_R_TMS

Q_RES_0402LF-200,1%,1/16W,CHIPA  I29  R4
   1 JTAG_MUX_CPU0_GTL_TDI      A @S9S_MB_2U_LIB.S9S_MB_2U(SCH_1):JTAG_MUX_CPU0_GTL_TDI
   2 JTAG_DBP_CPU0_GTL_R_TDI      B @S9S_MB_2U_LIB.S9S_MB_2U(SCH_1):JTAG_DBP_CPU0_GTL_R_TDI

SOCKET4677_AZIF0045P001C01CS-SA  I57  U2
CY32 CLK_25M_NSSC_CPU0_DP XTAL_CLK_DP @S9S_MB_2U_LIB.S9S_MB_2U(SCH_1):CLK_25M_NSSC_CPU0_DP
CT20 PD_CPU0_TXT_PLTEN TXT_PLTEN @S9S_MB_2U_LIB.S9S_MB_2U(SCH_1):PD_CPU0_TXT_PLTEN
BT26 PU_CPU0_TXT_AGENT TXT_AGENT @S9S_MB_2U_LIB.S9S_MB_2U(SCH_1):PU_CPU0_TXT_AGENT
BR25 JTAG_DBP_CPU0_QS_GTL_R_TMS    TMS @S9S_MB_2U_LIB.S9S_MB_2U(SCH_1):JTAG_DBP_CPU0_QS_GTL_R_TMS
BW25 JTAG_CPU0_MUX_GTL_TDO    TDO @S9S_MB_2U_LIB.S9S_MB_2U(SCH_1):JTAG_CPU0_MUX_GTL_TDO
BV24 JTAG_DBP_CPU0_GTL_R_TDI    TDI @S9S_MB_2U_LIB.S9S_MB_2U(SCH_1):JTAG_DBP_CPU0_GTL_R_TDI
BT24 JTAG_DBP_CPU0_GTL_R_TCK    TCK @S9S_MB_2U_LIB.S9S_MB_2U(SCH_1):JTAG_DBP_CPU0_GTL_R_TCK
CW60 PU_CPU0_SOCKET_ID0 SOCKET_ID0 @S9S_MB_2U_LIB.S9S_MB_2U(SCH_1):PU_CPU0_SOCKET_ID0
CY61 PU_CPU0_SOCKET_ID1 SOCKET_ID1 @S9S_MB_2U_LIB.S9S_MB_2U(SCH_1):PU_CPU0_SOCKET_ID1
CT61 PU_CPU0_SOCKET_ID2 SOCKET_ID2 @S9S_MB_2U_LIB.S9S_MB_2U(SCH_1):PU_CPU0_SOCKET_ID2
AU23 PU_CPU0_SAFE_MODE_BOOT SAFE_MODE_BOOT @S9S_MB_2U_LIB.S9S_MB_2U(SCH_1):PU_CPU0_SAFE_MODE_BOOT
CE70 NC_CLK_PFT_OUT_CPU0_DN RSVD91 @S9S_MB_2U_LIB.S9S_MB_2U(SCH_1):NC_CLK_PFT_OUT_CPU0_DN
CD71 NC_CLK_PFT_OUT_CPU0_DP RSVD88 @S9S_MB_2U_LIB.S9S_MB_2U(SCH_1):NC_CLK_PFT_OUT_CPU0_DP
BY24 PD_EXT_CLK_SEL_CPU0 RSVD76 @S9S_MB_2U_LIB.S9S_MB_2U(SCH_1):PD_EXT_CLK_SEL_CPU0
  G5 NC_XTAL_CPU0_25M_IN RSVD161 @S9S_MB_2U_LIB.S9S_MB_2U(SCH_1):NC_XTAL_CPU0_25M_IN
CJ72 PUD_XTAL_CPU0_MODE1 RSVD108 @S9S_MB_2U_LIB.S9S_MB_2U(SCH_1):PUD_XTAL_CPU0_MODE1
BG72 FM_CPU0_PROC_ID0 PROC_ID0 @S9S_MB_2U_LIB.S9S_MB_2U(SCH_1):FM_CPU0_PROC_ID0
BH71 FM_CPU0_PROC_ID1 PROC_ID1 @S9S_MB_2U_LIB.S9S_MB_2U(SCH_1):FM_CPU0_PROC_ID1
DA52 TP_CPU0_PROCDIS_COD_GTL_N PROCDIS_N @S9S_MB_2U_LIB.S9S_MB_2U(SCH_1):TP_CPU0_PROCDIS_COD_GTL_N
AV22 H_CPU0_PREQ_QS_GTL_R_N PREQ_N @S9S_MB_2U_LIB.S9S_MB_2U(SCH_1):H_CPU0_PREQ_QS_GTL_R_N
BP26 H_CPU0_PRDY_QS_GTL_R_N PRDY_N @S9S_MB_2U_LIB.S9S_MB_2U(SCH_1):H_CPU0_PRDY_QS_GTL_R_N
BL64 FM_CPU0_PKGID0 PKG_ID0 @S9S_MB_2U_LIB.S9S_MB_2U(SCH_1):FM_CPU0_PKGID0
AY63 FM_CPU0_PKGID1 PKG_ID1 @S9S_MB_2U_LIB.S9S_MB_2U(SCH_1):FM_CPU0_PKGID1
BN64 FM_CPU0_PKGID2 PKG_ID2 @S9S_MB_2U_LIB.S9S_MB_2U(SCH_1):FM_CPU0_PKGID2
BH24 PECI_CPU0_GTL_R   PECI @S9S_MB_2U_LIB.S9S_MB_2U(SCH_1):PECI_CPU0_GTL_R
BR23 TP_CPU0_BR23 RSVD72 @S9S_MB_2U_LIB.S9S_MB_2U(SCH_1):TP_CPU0_BR23
CY59 PU_CPU0_LEGACY_SKT LEGACY_SKT @S9S_MB_2U_LIB.S9S_MB_2U(SCH_1):PU_CPU0_LEGACY_SKT
AU17 PU_CPU0_FRMAGENT FRMAGENT @S9S_MB_2U_LIB.S9S_MB_2U(SCH_1):PU_CPU0_FRMAGENT
AW17 PD_CPU0_DMIMODE_OVERRIDE DMIMODE_OVERRIDE @S9S_MB_2U_LIB.S9S_MB_2U(SCH_1):PD_CPU0_DMIMODE_OVERRIDE
CY55 RST_CPU0_DRAM_GH_N DDR67_RESET_N @S9S_MB_2U_LIB.S9S_MB_2U(SCH_1):RST_CPU0_DRAM_GH_N
CY42 RST_CPU0_DRAM_EF_N DDR45_RESET_N @S9S_MB_2U_LIB.S9S_MB_2U(SCH_1):RST_CPU0_DRAM_EF_N
CT18 I3C_SPD_DDREFGH_CPU0_SDA DDR4567_SPDSDA @S9S_MB_2U_LIB.S9S_MB_2U(SCH_1):I3C_SPD_DDREFGH_CPU0_SDA
CU17 I3C_SPD_DDREFGH_CPU0_SCL DDR4567_SPDSCL @S9S_MB_2U_LIB.S9S_MB_2U(SCH_1):I3C_SPD_DDREFGH_CPU0_SCL
AV51 RST_CPU0_DRAM_CD_N DDR23_RESET_N @S9S_MB_2U_LIB.S9S_MB_2U(SCH_1):RST_CPU0_DRAM_CD_N
AU50 RST_CPU0_DRAM_AB_N DDR01_RESET_N @S9S_MB_2U_LIB.S9S_MB_2U(SCH_1):RST_CPU0_DRAM_AB_N
BY22 I3C_SPD_DDRABCD_CPU0_SDA DDR0123_SPDSDA @S9S_MB_2U_LIB.S9S_MB_2U(SCH_1):I3C_SPD_DDRABCD_CPU0_SDA
BT22 I3C_SPD_DDRABCD_CPU0_SCL DDR0123_SPDSCL @S9S_MB_2U_LIB.S9S_MB_2U(SCH_1):I3C_SPD_DDRABCD_CPU0_SCL
BN23 H_CPU0_BMCINIT_LVC1 BMCINIT @S9S_MB_2U_LIB.S9S_MB_2U(SCH_1):H_CPU0_BMCINIT_LVC1
AT18 PD_CPU0_BIST_ENABLE BIST_ENABLE @S9S_MB_2U_LIB.S9S_MB_2U(SCH_1):PD_CPU0_BIST_ENABLE
DA27 CLK_100M_DB2000_CPU0_BCLK3_DP BCLK3_DP @S9S_MB_2U_LIB.S9S_MB_2U(SCH_1):CLK_100M_DB2000_CPU0_BCLK3_DP
CW27 CLK_100M_DB2000_CPU0_BCLK3_DN BCLK3_DN @S9S_MB_2U_LIB.S9S_MB_2U(SCH_1):CLK_100M_DB2000_CPU0_BCLK3_DN
AV28 CLK_100M_DB2000_CPU0_BCLK2_DP BCLK2_DP @S9S_MB_2U_LIB.S9S_MB_2U(SCH_1):CLK_100M_DB2000_CPU0_BCLK2_DP
AU29 CLK_100M_DB2000_CPU0_BCLK2_DN BCLK2_DN @S9S_MB_2U_LIB.S9S_MB_2U(SCH_1):CLK_100M_DB2000_CPU0_BCLK2_DN
AV30 CLK_100M_DB2000_CPU0_BCLK0_DP BCLK0_DP @S9S_MB_2U_LIB.S9S_MB_2U(SCH_1):CLK_100M_DB2000_CPU0_BCLK0_DP
CY28 CLK_100M_DB2000_CPU0_BCLK1_DN BCLK1_DN @S9S_MB_2U_LIB.S9S_MB_2U(SCH_1):CLK_100M_DB2000_CPU0_BCLK1_DN
CW29 CLK_100M_DB2000_CPU0_BCLK1_DP BCLK1_DP @S9S_MB_2U_LIB.S9S_MB_2U(SCH_1):CLK_100M_DB2000_CPU0_BCLK1_DP
AT30 CLK_100M_DB2000_CPU0_BCLK0_DN BCLK0_DN @S9S_MB_2U_LIB.S9S_MB_2U(SCH_1):CLK_100M_DB2000_CPU0_BCLK0_DN
CL72 PUD_XTAL_CPU0_MODE0 RSVD120 @S9S_MB_2U_LIB.S9S_MB_2U(SCH_1):PUD_XTAL_CPU0_MODE0
  D4 NC_XTAL_CPU0_25M_OUT RSVD157 @S9S_MB_2U_LIB.S9S_MB_2U(SCH_1):NC_XTAL_CPU0_25M_OUT
CW31 CLK_25M_NSSC_CPU0_DN XTAL_CLK_DN @S9S_MB_2U_LIB.S9S_MB_2U(SCH_1):CLK_25M_NSSC_CPU0_DN


DRAWING: @S9S_MB_2U_LIB.S9S_MB_2U(SCH_1):PAGE14 

SOCKET4677_AZIF0045P001C01CS-SA  I1  U2
BP24 H_CPU0_CATERR_LVC1_R_N CATERR_N @S9S_MB_2U_LIB.S9S_MB_2U(SCH_1):H_CPU0_CATERR_LVC1_R_N
CA25 SMB_PEHPCPU0_GTL_SCL CXPSMBUSSCL @S9S_MB_2U_LIB.S9S_MB_2U(SCH_1):SMB_PEHPCPU0_GTL_SCL
BY26 SMB_PEHPCPU0_GTL_SDA CXPSMBUSSDA @S9S_MB_2U_LIB.S9S_MB_2U(SCH_1):SMB_PEHPCPU0_GTL_SDA
BV26 FM_PEHPCPU0_ALERT_N CXPSMBUS_ALERT_N @S9S_MB_2U_LIB.S9S_MB_2U(SCH_1):FM_PEHPCPU0_ALERT_N
 A43 PWRGD_DRAMPWRGD_CPU0_AB_LVC1_R DDR01_DRAM_PWR_OK @S9S_MB_2U_LIB.S9S_MB_2U(SCH_1):PWRGD_DRAMPWRGD_CPU0_AB_LVC1_R
 F47 PWRGD_DRAMPWRGD_CPU0_CD_LVC1_R DDR23_DRAM_PWR_OK @S9S_MB_2U_LIB.S9S_MB_2U(SCH_1):PWRGD_DRAMPWRGD_CPU0_CD_LVC1_R
CY44 PWRGD_DRAMPWRGD_CPU0_EF_LVC1_R DDR45_DRAM_PWR_OK @S9S_MB_2U_LIB.S9S_MB_2U(SCH_1):PWRGD_DRAMPWRGD_CPU0_EF_LVC1_R
CW45 PWRGD_DRAMPWRGD_CPU0_GH_LVC1_R DDR67_DRAM_PWR_OK @S9S_MB_2U_LIB.S9S_MB_2U(SCH_1):PWRGD_DRAMPWRGD_CPU0_GH_LVC1_R
CH22 PD_CPU0_ENH_MCECC_DIS RSVD96 @S9S_MB_2U_LIB.S9S_MB_2U(SCH_1):PD_CPU0_ENH_MCECC_DIS
BD22 H_CPU0_ERR2_LVC1_R_N ERROR_N2 @S9S_MB_2U_LIB.S9S_MB_2U(SCH_1):H_CPU0_ERR2_LVC1_R_N
AY22 H_CPU0_ERR1_LVC1_R_N ERROR_N1 @S9S_MB_2U_LIB.S9S_MB_2U(SCH_1):H_CPU0_ERR1_LVC1_R_N
BF22 H_CPU0_ERR0_LVC1_R_N ERROR_N0 @S9S_MB_2U_LIB.S9S_MB_2U(SCH_1):H_CPU0_ERR0_LVC1_R_N
AV57 FM_CPU_FBRK_DEBUG_R_N FBRK_N @S9S_MB_2U_LIB.S9S_MB_2U(SCH_1):FM_CPU_FBRK_DEBUG_R_N
AU21 H_CPU0_MEMHOT_IN_LVC1_N MEMHOT_IN_N @S9S_MB_2U_LIB.S9S_MB_2U(SCH_1):H_CPU0_MEMHOT_IN_LVC1_N
CF26 H_CPU0_MEMHOT_OUT_LVC1_R_N MEMHOT_OUT_N @S9S_MB_2U_LIB.S9S_MB_2U(SCH_1):H_CPU0_MEMHOT_OUT_LVC1_R_N
AV24 H_CPU0_MEMTRIP_LVC1_R_N MEMTRIP_N @S9S_MB_2U_LIB.S9S_MB_2U(SCH_1):H_CPU0_MEMTRIP_LVC1_R_N
AV18 H_CPU0_NMI_LVC1_N    NMI @S9S_MB_2U_LIB.S9S_MB_2U(SCH_1):H_CPU0_NMI_LVC1_N
CP71 PD_PIROM_CPU0_ADDR2 PIROM_AD2 @S9S_MB_2U_LIB.S9S_MB_2U(SCH_1):PD_PIROM_CPU0_ADDR2
CT71 PD_PIROM_CPU0_ADDR1 PIROM_AD1 @S9S_MB_2U_LIB.S9S_MB_2U(SCH_1):PD_PIROM_CPU0_ADDR1
CR70 PD_PIROM_CPU0_ADDR0 PIROM_AD0 @S9S_MB_2U_LIB.S9S_MB_2U(SCH_1):PD_PIROM_CPU0_ADDR0
CU70 SMB_S3M_CPU0_PIROM_3V3AUX_SCL_1 PIROM_SCL @S9S_MB_2U_LIB.S9S_MB_2U(SCH_1):SMB_S3M_CPU0_PIROM_3V3AUX_SCL_R1
CM71 SMB_S3M_CPU0_PIROM_3V3AUX_SDA_1 PIROM_SDA @S9S_MB_2U_LIB.S9S_MB_2U(SCH_1):SMB_S3M_CPU0_PIROM_3V3AUX_SDA_R1
CR72 PU_PIROM_CPU0_SM_WP PIROM_SM_WP @S9S_MB_2U_LIB.S9S_MB_2U(SCH_1):PU_PIROM_CPU0_SM_WP
CC25 TP_H_SBLINK7_CPU0_PMDOWN PMDOWN6 @S9S_MB_2U_LIB.S9S_MB_2U(SCH_1):TP_H_SBLINK7_CPU0_PMDOWN
CE23 TP_H_SBLINK6_CPU0_PMDOWN PMDOWN5 @S9S_MB_2U_LIB.S9S_MB_2U(SCH_1):TP_H_SBLINK6_CPU0_PMDOWN
CV18 TP_H_SBLINK5_CPU0_PMDOWN PMDOWN4 @S9S_MB_2U_LIB.S9S_MB_2U(SCH_1):TP_H_SBLINK5_CPU0_PMDOWN
CD24 TP_H_SBLINK4_CPU0_PMDOWN PMDOWN3 @S9S_MB_2U_LIB.S9S_MB_2U(SCH_1):TP_H_SBLINK4_CPU0_PMDOWN
CM26 TP_H_SBLINK3_CPU0_PMDOWN PMDOWN2 @S9S_MB_2U_LIB.S9S_MB_2U(SCH_1):TP_H_SBLINK3_CPU0_PMDOWN
CP26 TP_H_SBLINK2_CPU0_PMDOWN PMDOWN1 @S9S_MB_2U_LIB.S9S_MB_2U(SCH_1):TP_H_SBLINK2_CPU0_PMDOWN
CW39 H_CPU0_PMDOWN_CPU1_R PMDOWN0 @S9S_MB_2U_LIB.S9S_MB_2U(SCH_1):H_CPU0_PMDOWN_CPU1_R
CY40 H_CPU0_PMDOWN_PCH_R2 PMDOWN_PCH @S9S_MB_2U_LIB.S9S_MB_2U(SCH_1):H_CPU0_PMDOWN_PCH_R2
CP20 H_CPU0_PM_FAST_WAKE_N PMFAST_WAKE_N @S9S_MB_2U_LIB.S9S_MB_2U(SCH_1):H_CPU0_PM_FAST_WAKE_N
CF24 TP_H_SBLINK7_CPU0_PMSYNC PMSYNC6 @S9S_MB_2U_LIB.S9S_MB_2U(SCH_1):TP_H_SBLINK7_CPU0_PMSYNC
CH24 TP_H_SBLINK6_CPU0_PMSYNC PMSYNC5 @S9S_MB_2U_LIB.S9S_MB_2U(SCH_1):TP_H_SBLINK6_CPU0_PMSYNC
CR19 TP_H_SBLINK5_CPU0_PMSYNC PMSYNC4 @S9S_MB_2U_LIB.S9S_MB_2U(SCH_1):TP_H_SBLINK5_CPU0_PMSYNC
CE25 TP_H_SBLINK4_CPU0_PMSYNC PMSYNC3 @S9S_MB_2U_LIB.S9S_MB_2U(SCH_1):TP_H_SBLINK4_CPU0_PMSYNC
CH26 TP_H_SBLINK3_CPU0_PMSYNC PMSYNC2 @S9S_MB_2U_LIB.S9S_MB_2U(SCH_1):TP_H_SBLINK3_CPU0_PMSYNC
CL25 TP_H_SBLINK2_CPU0_PMSYNC PMSYNC1 @S9S_MB_2U_LIB.S9S_MB_2U(SCH_1):TP_H_SBLINK2_CPU0_PMSYNC
CN25 H_CPU0_PMSYNC_CPU1_R PMSYNC0 @S9S_MB_2U_LIB.S9S_MB_2U(SCH_1):H_CPU0_PMSYNC_CPU1_R
DA39 H_CPU0_PMSYNC_PCH PMSYNC_PCH @S9S_MB_2U_LIB.S9S_MB_2U(SCH_1):H_CPU0_PMSYNC_PCH
AU19 H_CPU0_PROCHOT_LVC1_N PROCHOT_N @S9S_MB_2U_LIB.S9S_MB_2U(SCH_1):H_CPU0_PROCHOT_LVC1_N
AV20 PWRGD_CPU0_LVC1 PWRGOOD @S9S_MB_2U_LIB.S9S_MB_2U(SCH_1):PWRGD_CPU0_LVC1
BH61 RST_CPU0_LVC1_N RESET_N @S9S_MB_2U_LIB.S9S_MB_2U(SCH_1):RST_CPU0_LVC1_N
CL21 TP_IBL_PLT_RST_SYNC_N RSVD113 @S9S_MB_2U_LIB.S9S_MB_2U(SCH_1):TP_IBL_PLT_RST_SYNC_N
CL64 NC_CPU0_VIEWPIN_DIE11<3> RSVD116 @S9S_MB_2U_LIB.S9S_MB_2U(SCH_1):NC_CPU0_VIEWPIN_DIE11(3)
CM63 NC_CPU0_VIEWPIN_DIE11<2> RSVD121 @S9S_MB_2U_LIB.S9S_MB_2U(SCH_1):NC_CPU0_VIEWPIN_DIE11(2)
CN62 NC_CPU0_VIEWPIN_DIE11<1> RSVD126 @S9S_MB_2U_LIB.S9S_MB_2U(SCH_1):NC_CPU0_VIEWPIN_DIE11(1)
CR23 NC_CPU0_VIEWPIN_DIE10<0> RSVD132 @S9S_MB_2U_LIB.S9S_MB_2U(SCH_1):NC_CPU0_VIEWPIN_DIE10(0)
CV24 NC_CPU0_VIEWPIN_DIE10<2> RSVD141 @S9S_MB_2U_LIB.S9S_MB_2U(SCH_1):NC_CPU0_VIEWPIN_DIE10(2)
CW23 NC_CPU0_VIEWPIN_DIE10<3> RSVD145 @S9S_MB_2U_LIB.S9S_MB_2U(SCH_1):NC_CPU0_VIEWPIN_DIE10(3)
CW25 NC_CPU0_VIEWPIN_DIE10<1> RSVD146 @S9S_MB_2U_LIB.S9S_MB_2U(SCH_1):NC_CPU0_VIEWPIN_DIE10(1)
CW68 NC_CPU0_RSVD<144> RSVD150 @S9S_MB_2U_LIB.S9S_MB_2U(SCH_1):NC_CPU0_RSVD(144)
AV26 NC_CPU0_VIEWPIN_DIE00<3> RSVD15 @S9S_MB_2U_LIB.S9S_MB_2U(SCH_1):NC_CPU0_VIEWPIN_DIE00(3)
AY26 NC_CPU0_VIEWPIN_DIE00<0> RSVD27 @S9S_MB_2U_LIB.S9S_MB_2U(SCH_1):NC_CPU0_VIEWPIN_DIE00(0)
AY65 NC_CPU0_VIEWPIN_DIE01<2> RSVD29 @S9S_MB_2U_LIB.S9S_MB_2U(SCH_1):NC_CPU0_VIEWPIN_DIE01(2)
AT24 NC_CPU0_VIEWPIN_DIE00<1>  RSVD4 @S9S_MB_2U_LIB.S9S_MB_2U(SCH_1):NC_CPU0_VIEWPIN_DIE00(1)
BJ70 NC_CPU0_VIEWPIN_DIE01<3> RSVD59 @S9S_MB_2U_LIB.S9S_MB_2U(SCH_1):NC_CPU0_VIEWPIN_DIE01(3)
AU25 NC_CPU0_VIEWPIN_DIE00<2>  RSVD6 @S9S_MB_2U_LIB.S9S_MB_2U(SCH_1):NC_CPU0_VIEWPIN_DIE00(2)
BP67 NC_CPU0_VIEWPIN_DIE01<1> RSVD69 @S9S_MB_2U_LIB.S9S_MB_2U(SCH_1):NC_CPU0_VIEWPIN_DIE01(1)
BP69 NC_CPU0_VIEWPIN_DIE01<0> RSVD70 @S9S_MB_2U_LIB.S9S_MB_2U(SCH_1):NC_CPU0_VIEWPIN_DIE01(0)
CJ62 NC_CPU0_VIEWPIN_DIE11<0> RSVD104 @S9S_MB_2U_LIB.S9S_MB_2U(SCH_1):NC_CPU0_VIEWPIN_DIE11(0)
CG66 FM_CPU0_SKTOCC_LVT3_N SKTOCC_N @S9S_MB_2U_LIB.S9S_MB_2U(SCH_1):FM_CPU0_SKTOCC_LVT3_N
BK26 SVID_ALERT0_CPU0_N SVIDALERT0_N @S9S_MB_2U_LIB.S9S_MB_2U(SCH_1):SVID_ALERT0_CPU0_N
BJ25 SVID_ALERT1_CPU0_N SVIDALERT1_N @S9S_MB_2U_LIB.S9S_MB_2U(SCH_1):SVID_ALERT1_CPU0_N
BH26 SVID_CLK0_CPU0 SVIDCLK0 @S9S_MB_2U_LIB.S9S_MB_2U(SCH_1):SVID_CLK0_CPU0
BF26 SVID_CLK1_CPU0 SVIDCLK1 @S9S_MB_2U_LIB.S9S_MB_2U(SCH_1):SVID_CLK1_CPU0
BD26 SVID_DIO0_CPU0 SVIDDATA0 @S9S_MB_2U_LIB.S9S_MB_2U(SCH_1):SVID_DIO0_CPU0
BL25 SVID_DIO1_CPU0 SVIDDATA1 @S9S_MB_2U_LIB.S9S_MB_2U(SCH_1):SVID_DIO1_CPU0
AY20 PU_TAP_ODT_CPU0_EN TAP_ODT_EN @S9S_MB_2U_LIB.S9S_MB_2U(SCH_1):PU_TAP_ODT_CPU0_EN
AV59 TP_EV_CPU0_EXT_BGREF RSVD19 @S9S_MB_2U_LIB.S9S_MB_2U(SCH_1):TP_EV_CPU0_EXT_BGREF
BL62 H_CPU0_THERMTRIP_LVC1_R_N THERMTRIP_N @S9S_MB_2U_LIB.S9S_MB_2U(SCH_1):H_CPU0_THERMTRIP_LVC1_R_N

Q_RES_0402LF-0,5%,1/16W,CHIP,CA  I59  R12
   1 SVID_DIO0_CPU0      A @S9S_MB_2U_LIB.S9S_MB_2U(SCH_1):SVID_DIO0_CPU0
   2 SVID_DIO0_CPU0_R      B @S9S_MB_2U_LIB.S9S_MB_2U(SCH_1):SVID_DIO0_CPU0_R

Q_RES_0402LF-0,5%,1/16W,CHIP,CA  I60  R13
   1 SVID_CLK0_CPU0      A @S9S_MB_2U_LIB.S9S_MB_2U(SCH_1):SVID_CLK0_CPU0
   2 SVID_CLK0_CPU0_R      B @S9S_MB_2U_LIB.S9S_MB_2U(SCH_1):SVID_CLK0_CPU0_R

Q_RES_0402LF-200,1%,1/16W,CHIPA  I61  R14
   1 SVID_ALERT0_CPU0_N      A @S9S_MB_2U_LIB.S9S_MB_2U(SCH_1):SVID_ALERT0_CPU0_N
   2 SVID_ALERT0_CPU0_R_N      B @S9S_MB_2U_LIB.S9S_MB_2U(SCH_1):SVID_ALERT0_CPU0_R_N

Q_RES_0402LF-0,5%,1/16W,CHIP,CA  I62  R15
   1 SVID_DIO1_CPU0      A @S9S_MB_2U_LIB.S9S_MB_2U(SCH_1):SVID_DIO1_CPU0
   2 SVID_DIO1_CPU0_R      B @S9S_MB_2U_LIB.S9S_MB_2U(SCH_1):SVID_DIO1_CPU0_R

Q_RES_0402LF-0,5%,1/16W,CHIP,CA  I63  R16
   1 SVID_CLK1_CPU0      A @S9S_MB_2U_LIB.S9S_MB_2U(SCH_1):SVID_CLK1_CPU0
   2 SVID_CLK1_CPU0_R      B @S9S_MB_2U_LIB.S9S_MB_2U(SCH_1):SVID_CLK1_CPU0_R

Q_RES_0402LF-200,1%,1/16W,CHIPA  I64  R17
   1 SVID_ALERT1_CPU0_N      A @S9S_MB_2U_LIB.S9S_MB_2U(SCH_1):SVID_ALERT1_CPU0_N
   2 SVID_ALERT1_CPU0_R_N      B @S9S_MB_2U_LIB.S9S_MB_2U(SCH_1):SVID_ALERT1_CPU0_R_N

Q_RES_0402LF-33.2,1%,1/16W,CHIA  I66  R7
   1 H_CPU0_PMDOWN_PCH_R      A @S9S_MB_2U_LIB.S9S_MB_2U(SCH_1):H_CPU0_PMDOWN_PCH_R
   2 H_CPU0_PMDOWN_PCH      B @S9S_MB_2U_LIB.S9S_MB_2U(SCH_1):H_CPU0_PMDOWN_PCH

Q_RES_0402LF-33.2,1%,1/16W,CHIA  I78  R10
   1 H_CPU0_PMSYNC_PCH_R      A @S9S_MB_2U_LIB.S9S_MB_2U(SCH_1):H_CPU0_PMSYNC_PCH_R
   2 H_CPU0_PMSYNC_PCH      B @S9S_MB_2U_LIB.S9S_MB_2U(SCH_1):H_CPU0_PMSYNC_PCH

Q_RES_0402LF-33.2,1%,1/16W,CHIA  I79  R11
   1 H_CPU0_PMDOWN_CPU1_R1      A @S9S_MB_2U_LIB.S9S_MB_2U(SCH_1):H_CPU0_PMDOWN_CPU1_R1
   2 H_CPU0_PMDOWN_CPU1      B @S9S_MB_2U_LIB.S9S_MB_2U(SCH_1):H_CPU0_PMDOWN_CPU1

Q_RES_0402LF-33.2,1%,1/16W,CHIA  I90  R322
   1 H_CPU0_PMSYNC_CPU1_R      A @S9S_MB_2U_LIB.S9S_MB_2U(SCH_1):H_CPU0_PMSYNC_CPU1_R
   2 H_CPU0_PMSYNC_CPU1_R1      B @S9S_MB_2U_LIB.S9S_MB_2U(SCH_1):H_CPU0_PMSYNC_CPU1_R1

Q_RES_0402LF-100,1%,1/16W,CHIPA  I93  R328
   1 SVID_DIO0_CPU0_R      A @S9S_MB_2U_LIB.S9S_MB_2U(SCH_1):SVID_DIO0_CPU0_R
   2 PVNN_TERM_CPU0      B @S9S_MB_2U_LIB.S9S_MB_2U(SCH_1):PVNN_TERM_CPU0

Q_RES_0402LF-49.9,1%,1/16W,CHIA  I94  R548
   1 SVID_ALERT0_CPU0_R_N      A @S9S_MB_2U_LIB.S9S_MB_2U(SCH_1):SVID_ALERT0_CPU0_R_N
   2 PVNN_TERM_CPU0      B @S9S_MB_2U_LIB.S9S_MB_2U(SCH_1):PVNN_TERM_CPU0

Q_RES_0402LF-100,1%,1/16W,CHIPA  I98  R555
   1 SVID_DIO1_CPU0_R      A @S9S_MB_2U_LIB.S9S_MB_2U(SCH_1):SVID_DIO1_CPU0_R
   2 PVNN_TERM_CPU0      B @S9S_MB_2U_LIB.S9S_MB_2U(SCH_1):PVNN_TERM_CPU0

Q_RES_0402LF-49.9,1%,1/16W,CHIA  I100  R556
   1 SVID_ALERT1_CPU0_R_N      A @S9S_MB_2U_LIB.S9S_MB_2U(SCH_1):SVID_ALERT1_CPU0_R_N
   2 PVNN_TERM_CPU0      B @S9S_MB_2U_LIB.S9S_MB_2U(SCH_1):PVNN_TERM_CPU0

Q_RES_0402LF-33.2,1%,1/16W,CHIA  I109  R1932
   1 SMB_S3M_CPU0_PIROM_3V3AUX_SCL      A @S9S_MB_2U_LIB.S9S_MB_2U(SCH_1):SMB_S3M_CPU0_PIROM_3V3AUX_SCL
   2 SMB_S3M_CPU0_PIROM_3V3AUX_SCL_1      B @S9S_MB_2U_LIB.S9S_MB_2U(SCH_1):SMB_S3M_CPU0_PIROM_3V3AUX_SCL_R1

Q_RES_0402LF-33.2,1%,1/16W,CHIA  I110  R1933
   1 SMB_S3M_CPU0_PIROM_3V3AUX_SDA      A @S9S_MB_2U_LIB.S9S_MB_2U(SCH_1):SMB_S3M_CPU0_PIROM_3V3AUX_SDA
   2 SMB_S3M_CPU0_PIROM_3V3AUX_SDA_1      B @S9S_MB_2U_LIB.S9S_MB_2U(SCH_1):SMB_S3M_CPU0_PIROM_3V3AUX_SDA_R1

Q_RES_0402LF-0,5%,1/16W,CHIP,CA  I115  R1959
   1 H_CPU0_PMDOWN_PCH_R2      A @S9S_MB_2U_LIB.S9S_MB_2U(SCH_1):H_CPU0_PMDOWN_PCH_R2
   2 H_CPU0_PMDOWN_PCH_R      B @S9S_MB_2U_LIB.S9S_MB_2U(SCH_1):H_CPU0_PMDOWN_PCH_R

Q_RES_0402LF-0,5%,1/16W,CHIP,CA  I117  R1960
   1 H_CPU0_PMSYNC_PCH_R2      A @S9S_MB_2U_LIB.S9S_MB_2U(SCH_1):H_CPU0_PMSYNC_PCH_R2
   2 H_CPU0_PMSYNC_PCH_R      B @S9S_MB_2U_LIB.S9S_MB_2U(SCH_1):H_CPU0_PMSYNC_PCH_R

Q_RES_0402LF-33.2,1%,1/16W,CHIA  I122  R2362
   1 H_CPU0_PMDOWN_CPU1_R      A @S9S_MB_2U_LIB.S9S_MB_2U(SCH_1):H_CPU0_PMDOWN_CPU1_R
   2 H_CPU0_PMDOWN_CPU1_R1      B @S9S_MB_2U_LIB.S9S_MB_2U(SCH_1):H_CPU0_PMDOWN_CPU1_R1

Q_RES_0402LF-33.2,1%,1/16W,CHIA  I128  R4089
   1 H_CPU0_PMSYNC_CPU1_R1      A @S9S_MB_2U_LIB.S9S_MB_2U(SCH_1):H_CPU0_PMSYNC_CPU1_R1
   2 H_CPU0_PMSYNC_CPU1      B @S9S_MB_2U_LIB.S9S_MB_2U(SCH_1):H_CPU0_PMSYNC_CPU1


DRAWING: @S9S_MB_2U_LIB.S9S_MB_2U(SCH_1):PAGE15 

SOCKET4677_AZIF0045P001C01CS-SA  I1  U2
CV20 PWRGD_PLT_AUX_CPU0_LVT3 PLT_AUX_PWRGOOD @S9S_MB_2U_LIB.S9S_MB_2U(SCH_1):PWRGD_PLT_AUX_CPU0_LVT3
CK22 TP_FM_IBL_SYS_RST_CPU0_N RSVD109 @S9S_MB_2U_LIB.S9S_MB_2U(SCH_1):TP_FM_IBL_SYS_RST_CPU0_N
CK24 TP_CPU0_PWRBTN_N RSVD110 @S9S_MB_2U_LIB.S9S_MB_2U(SCH_1):TP_CPU0_PWRBTN_N
CL23 TP_I2C_S3M_RTC_CPU0_SCL RSVD114 @S9S_MB_2U_LIB.S9S_MB_2U(SCH_1):TP_I2C_S3M_RTC_CPU0_SCL
AU62 TP_SPI_IBL_CPU0_TPM_CLK RSVD11 @S9S_MB_2U_LIB.S9S_MB_2U(SCH_1):TP_SPI_IBL_CPU0_TPM_CLK
CL66 TP_CPU0_SSC_SYNC RSVD117 @S9S_MB_2U_LIB.S9S_MB_2U(SCH_1):TP_CPU0_SSC_SYNC
CN21 TP_IBL_SLPS4_CPU0_R_N RSVD123 @S9S_MB_2U_LIB.S9S_MB_2U(SCH_1):TP_IBL_SLPS4_CPU0_R_N
CN23 TP_FM_IBL_ADR_ACK_CPU0 RSVD124 @S9S_MB_2U_LIB.S9S_MB_2U(SCH_1):TP_FM_IBL_ADR_ACK_CPU0
AU64 TP_ESPI_IBL_CPU0_IO2_LVC1 RSVD12 @S9S_MB_2U_LIB.S9S_MB_2U(SCH_1):TP_ESPI_IBL_CPU0_IO2_LVC1
CP22 TP_JTAG_CPU0_PLD_TDO RSVD127 @S9S_MB_2U_LIB.S9S_MB_2U(SCH_1):TP_JTAG_CPU0_PLD_TDO
CP24 TP_FM_IBL_ADR_COMPLETE_CPU0_R RSVD128 @S9S_MB_2U_LIB.S9S_MB_2U(SCH_1):TP_FM_IBL_ADR_COMPLETE_CPU0_R
CR21 TP_IBL_SLPS3_CPU0_R_N RSVD131 @S9S_MB_2U_LIB.S9S_MB_2U(SCH_1):TP_IBL_SLPS3_CPU0_R_N
CT22 TP_JTAG_CPU0_PLD_TDI RSVD136 @S9S_MB_2U_LIB.S9S_MB_2U(SCH_1):TP_JTAG_CPU0_PLD_TDI
CT24 TP_FM_IBL_ADR_TRIGGER_CPU0_R RSVD137 @S9S_MB_2U_LIB.S9S_MB_2U(SCH_1):TP_FM_IBL_ADR_TRIGGER_CPU0_R
CV22 TP_JTAG_CPU0_PLD_TMS RSVD140 @S9S_MB_2U_LIB.S9S_MB_2U(SCH_1):TP_JTAG_CPU0_PLD_TMS
CV69 NC_UART_IBL_CPU0_TXD RSVD142 @S9S_MB_2U_LIB.S9S_MB_2U(SCH_1):NC_UART_IBL_CPU0_TXD
CV71 NC_UART_IBL_CPU0_CTS RSVD143 @S9S_MB_2U_LIB.S9S_MB_2U(SCH_1):NC_UART_IBL_CPU0_CTS
CW21 TP_IBL_SLPS5_CPU0_R_N RSVD144 @S9S_MB_2U_LIB.S9S_MB_2U(SCH_1):TP_IBL_SLPS5_CPU0_R_N
CY20 FM_S3M_CPU0_CPLD_CRC_ERROR CD_INIT_ERROR @S9S_MB_2U_LIB.S9S_MB_2U(SCH_1):FM_S3M_CPU0_CPLD_CRC_ERROR
CY22 PD_JTAG_CPU0_PLD_TCK TEST_5 @S9S_MB_2U_LIB.S9S_MB_2U(SCH_1):PD_JTAG_CPU0_PLD_TCK
CY69 NC_UART_IBL_CPU0_RXD RSVD155 @S9S_MB_2U_LIB.S9S_MB_2U(SCH_1):NC_UART_IBL_CPU0_RXD
CY71 NC_UART_IBL_CPU0_RTS RSVD156 @S9S_MB_2U_LIB.S9S_MB_2U(SCH_1):NC_UART_IBL_CPU0_RTS
AV63 TP_SPI_S3M_CPU0_CS1_LVC1_R_N RSVD20 @S9S_MB_2U_LIB.S9S_MB_2U(SCH_1):TP_SPI_S3M_CPU0_CS1_LVC1_R_N
AW19 TP_FM_IBL_WAKE_CPU0_N RSVD23 @S9S_MB_2U_LIB.S9S_MB_2U(SCH_1):TP_FM_IBL_WAKE_CPU0_N
AW64 TP_SPI_S3M_CPU0_IO1_LVC1_R RSVD24 @S9S_MB_2U_LIB.S9S_MB_2U(SCH_1):TP_SPI_S3M_CPU0_IO1_LVC1_R
AY61 TP_SPI_IBL_CPU0_TPM_IO1 RSVD28 @S9S_MB_2U_LIB.S9S_MB_2U(SCH_1):TP_SPI_IBL_CPU0_TPM_IO1
AY67 TP_SPI_IBL_CPU0_TPM_CS0_N RSVD30 @S9S_MB_2U_LIB.S9S_MB_2U(SCH_1):TP_SPI_IBL_CPU0_TPM_CS0_N
BA62 TP_SPI_S3M_CPU0_IO0_LVC1_R RSVD32 @S9S_MB_2U_LIB.S9S_MB_2U(SCH_1):TP_SPI_S3M_CPU0_IO0_LVC1_R
BA66 TP_SPI_IBL_CPU0_TPM_IO0 RSVD33 @S9S_MB_2U_LIB.S9S_MB_2U(SCH_1):TP_SPI_IBL_CPU0_TPM_IO0
BA68 TP_SPI_S3M_CPU0_OE_LVC1_R_N RSVD34 @S9S_MB_2U_LIB.S9S_MB_2U(SCH_1):TP_SPI_S3M_CPU0_OE_LVC1_R_N
BB61 TP_SPI_S3M_CPU0_CS0_LVC1_R_N RSVD35 @S9S_MB_2U_LIB.S9S_MB_2U(SCH_1):TP_SPI_S3M_CPU0_CS0_LVC1_R_N
BB67 TP_SPI_IBL_CPU0_TPM_OE_N RSVD36 @S9S_MB_2U_LIB.S9S_MB_2U(SCH_1):TP_SPI_IBL_CPU0_TPM_OE_N
BC25 TP_I3C_MNG2_BMC_SW_SDA RSVD38 @S9S_MB_2U_LIB.S9S_MB_2U(SCH_1):TP_I3C_MNG2_BMC_SW_SDA
BC64 TP_SPI_S3M_CPU0_CLK_LVC1_R RSVD39 @S9S_MB_2U_LIB.S9S_MB_2U(SCH_1):TP_SPI_S3M_CPU0_CLK_LVC1_R
BD61 TP_SPI_S3M_CPU0_IO3_LVC1_R RSVD40 @S9S_MB_2U_LIB.S9S_MB_2U(SCH_1):TP_SPI_S3M_CPU0_IO3_LVC1_R
BD63 TP_ESPI_IBL_CPU0_ALERT1_N RSVD41 @S9S_MB_2U_LIB.S9S_MB_2U(SCH_1):TP_ESPI_IBL_CPU0_ALERT1_N
BD65 TP_SPI_S3M_CPU0_IO2_LVC1_R RSVD42 @S9S_MB_2U_LIB.S9S_MB_2U(SCH_1):TP_SPI_S3M_CPU0_IO2_LVC1_R
BE25 TP_I3C_MNG2_BMC_SW_SCL RSVD47 @S9S_MB_2U_LIB.S9S_MB_2U(SCH_1):TP_I3C_MNG2_BMC_SW_SCL
BE62 TP_ESPI_IBL_CPU0_ALERT0_LVC1_N RSVD48 @S9S_MB_2U_LIB.S9S_MB_2U(SCH_1):TP_ESPI_IBL_CPU0_ALERT0_LVC1_N
BF65 TP_ESPI_IBL_CPU0_CS0_LVC1_N RSVD50 @S9S_MB_2U_LIB.S9S_MB_2U(SCH_1):TP_ESPI_IBL_CPU0_CS0_LVC1_N
BG62 TP_CLK_66M_ESPI_IBL_CPU0_LVC1 RSVD52 @S9S_MB_2U_LIB.S9S_MB_2U(SCH_1):TP_CLK_66M_ESPI_IBL_CPU0_LVC1
BG64 TP_RST_ESPI_IBL_CPU0_LVC1_N RSVD53 @S9S_MB_2U_LIB.S9S_MB_2U(SCH_1):TP_RST_ESPI_IBL_CPU0_LVC1_N
BH63 TP_ESPI_IBL_CPU0_OE_LVC1_N RSVD55 @S9S_MB_2U_LIB.S9S_MB_2U(SCH_1):TP_ESPI_IBL_CPU0_OE_LVC1_N
BH65 TP_ESPI_IBL_CPU0_CS1_N RSVD56 @S9S_MB_2U_LIB.S9S_MB_2U(SCH_1):TP_ESPI_IBL_CPU0_CS1_N
BJ64 TP_ESPI_IBL_CPU0_IO1_LVC1 RSVD58 @S9S_MB_2U_LIB.S9S_MB_2U(SCH_1):TP_ESPI_IBL_CPU0_IO1_LVC1
BK63 TP_ESPI_IBL_CPU0_IO0_LVC1 RSVD61 @S9S_MB_2U_LIB.S9S_MB_2U(SCH_1):TP_ESPI_IBL_CPU0_IO0_LVC1
BM63 TP_ESPI_IBL_CPU0_IO3_LVC1 RSVD64 @S9S_MB_2U_LIB.S9S_MB_2U(SCH_1):TP_ESPI_IBL_CPU0_IO3_LVC1
CD65 TP_SGPIO_S3M_CPU0_RST_R_N RSVD86 @S9S_MB_2U_LIB.S9S_MB_2U(SCH_1):TP_SGPIO_S3M_CPU0_RST_R_N
CF61 PUD_PCH_BOOT_MODE_CPU0 TEST_6 @S9S_MB_2U_LIB.S9S_MB_2U(SCH_1):PUD_PCH_BOOT_MODE_CPU0
CF63 TP_SGPIO_S3M_CPU0_GSXCLK_R RSVD93 @S9S_MB_2U_LIB.S9S_MB_2U(SCH_1):TP_SGPIO_S3M_CPU0_GSXCLK_R
CF65 TP_SGPIO_S3M_CPU0_GSXDOUT_R RSVD94 @S9S_MB_2U_LIB.S9S_MB_2U(SCH_1):TP_SGPIO_S3M_CPU0_GSXDOUT_R
CH63 TP_SGPIO_S3M_CPU0_GSXDIN RSVD98 @S9S_MB_2U_LIB.S9S_MB_2U(SCH_1):TP_SGPIO_S3M_CPU0_GSXDIN
CH71 TP_PWRGD_S0_PWROK_CPU0_LVC1 RSVD100 @S9S_MB_2U_LIB.S9S_MB_2U(SCH_1):TP_PWRGD_S0_PWROK_CPU0_LVC1
CJ21 TP_IBL_GRST_WARN_PLD_R_N RSVD101 @S9S_MB_2U_LIB.S9S_MB_2U(SCH_1):TP_IBL_GRST_WARN_PLD_R_N
CJ23 TP_I2C_S3M_RTC_CPU0_SDA RSVD102 @S9S_MB_2U_LIB.S9S_MB_2U(SCH_1):TP_I2C_S3M_RTC_CPU0_SDA
CJ25 TP_I2C_S3M_RTC_CPU0_ALERT_N RSVD103 @S9S_MB_2U_LIB.S9S_MB_2U(SCH_1):TP_I2C_S3M_RTC_CPU0_ALERT_N
CJ66 TP_SGPIO_S3M_CPU0_GSXDLOAD_R RSVD105 @S9S_MB_2U_LIB.S9S_MB_2U(SCH_1):TP_SGPIO_S3M_CPU0_GSXDLOAD_R
AW70 FM_S3M_CPU0_LVC1_GPIO_4 RSVD25 @S9S_MB_2U_LIB.S9S_MB_2U(SCH_1):FM_S3M_CPU0_LVC1_GPIO_4
AY69 FM_S3M_CPU0_LVC1_GPIO_3 TEST_8 @S9S_MB_2U_LIB.S9S_MB_2U(SCH_1):FM_S3M_CPU0_LVC1_GPIO_3
AV69 FM_S3M_CPU0_LVC1_GPIO_2 TEST_7 @S9S_MB_2U_LIB.S9S_MB_2U(SCH_1):FM_S3M_CPU0_LVC1_GPIO_2
AV71 FM_S3M_CPU0_LVC1_GPIO_1 PARTITION_ID1 @S9S_MB_2U_LIB.S9S_MB_2U(SCH_1):FM_S3M_CPU0_LVC1_GPIO_1
BA70 FM_S3M_CPU0_LVC1_GPIO_0 PARTITION_ID0 @S9S_MB_2U_LIB.S9S_MB_2U(SCH_1):FM_S3M_CPU0_LVC1_GPIO_0
CE64 SMB_S3M_CPU0_SCL SMB_CLK @S9S_MB_2U_LIB.S9S_MB_2U(SCH_1):SMB_S3M_CPU0_SCL
CD63 SMB_S3M_CPU0_SDA SMB_DATA @S9S_MB_2U_LIB.S9S_MB_2U(SCH_1):SMB_S3M_CPU0_SDA
CJ64 PU_S3M_CPU0_CPLD_CONFD TEST_1 @S9S_MB_2U_LIB.S9S_MB_2U(SCH_1):PU_S3M_CPU0_CPLD_CONFD
CK65 FM_S3M_CPU0_CPLD_CONFIG_N TEST_2 @S9S_MB_2U_LIB.S9S_MB_2U(SCH_1):FM_S3M_CPU0_CPLD_CONFIG_N
CH65 PU_S3M_CPU0_CPLD_STATUS TEST_3 @S9S_MB_2U_LIB.S9S_MB_2U(SCH_1):PU_S3M_CPU0_CPLD_STATUS


DRAWING: @S9S_MB_2U_LIB.S9S_MB_2U(SCH_1):PAGE16 

SOCKET4677_AZIF0045P001C01CS-SA  I1  U2
BC23 TP_CPU0_IFST_DONE_LVC1_R RSVD37 @S9S_MB_2U_LIB.S9S_MB_2U(SCH_1):TP_CPU0_IFST_DONE_LVC1_R
BE23 TP_CPU0_IFST_KOT_LVC1_R RSVD46 @S9S_MB_2U_LIB.S9S_MB_2U(SCH_1):TP_CPU0_IFST_KOT_LVC1_R
BF24 TP_CPU0_IFST_TRIG_LVC1_R RSVD49 @S9S_MB_2U_LIB.S9S_MB_2U(SCH_1):TP_CPU0_IFST_TRIG_LVC1_R
BL23 DBP_CPU0_MBP0_GTL_R_N MBP0_N @S9S_MB_2U_LIB.S9S_MB_2U(SCH_1):DBP_CPU0_MBP0_GTL_R_N
BN25 DBP_CPU0_MBP1_GTL_R_N MBP1_N @S9S_MB_2U_LIB.S9S_MB_2U(SCH_1):DBP_CPU0_MBP1_GTL_R_N
BJ23 DBP_CPU0_HOOK8_MBP2_GTL_QS_R_N MBP2_N @S9S_MB_2U_LIB.S9S_MB_2U(SCH_1):DBP_CPU0_HOOK8_MBP2_GTL_QS_R_N
BK24 DBP_CPU0_HOOK9_MBP3_GTL_QS_R_N MBP3_N @S9S_MB_2U_LIB.S9S_MB_2U(SCH_1):DBP_CPU0_HOOK9_MBP3_GTL_QS_R_N
BD24 H_PMAX_TRIGGER_IO_CPU0 PMAX_TRIGGER_IO @S9S_MB_2U_LIB.S9S_MB_2U(SCH_1):H_PMAX_TRIGGER_IO_CPU0
BH22 H_CPU0_RMCA_LVC1_R_N RMCA_N @S9S_MB_2U_LIB.S9S_MB_2U(SCH_1):H_CPU0_RMCA_LVC1_R_N
AU58 NC_CPU0_DDR01_VIEWDIG0 RSVD10 @S9S_MB_2U_LIB.S9S_MB_2U(SCH_1):NC_CPU0_DDR01_VIEWDIG0
CE62 NC_CPU0_LGSSPARE3 RSVD90 @S9S_MB_2U_LIB.S9S_MB_2U(SCH_1):NC_CPU0_LGSSPARE3
CU62 NC_CPU0_LGSSPARE2 RSVD139 @S9S_MB_2U_LIB.S9S_MB_2U(SCH_1):NC_CPU0_LGSSPARE2
CN60 NC_CPU0_LGSSPARE1 RSVD125 @S9S_MB_2U_LIB.S9S_MB_2U(SCH_1):NC_CPU0_LGSSPARE1
CP61 NC_CPU0_LGSSPARE5 RSVD129 @S9S_MB_2U_LIB.S9S_MB_2U(SCH_1):NC_CPU0_LGSSPARE5
CR60 NC_CPU0_LGSSPARE0 RSVD134 @S9S_MB_2U_LIB.S9S_MB_2U(SCH_1):NC_CPU0_LGSSPARE0
CY24 NC_CPU0_DDR45_VIEWDIG0 RSVD151 @S9S_MB_2U_LIB.S9S_MB_2U(SCH_1):NC_CPU0_DDR45_VIEWDIG0
CY38 NC_CPU0_DDR45_VIEWDIG1 RSVD152 @S9S_MB_2U_LIB.S9S_MB_2U(SCH_1):NC_CPU0_DDR45_VIEWDIG1
CY49 NC_CPU0_DDR67_VIEWDIG1 RSVD153 @S9S_MB_2U_LIB.S9S_MB_2U(SCH_1):NC_CPU0_DDR67_VIEWDIG1
DA45 NC_CPU0_DDR67_VIEWDIG0 RSVD158 @S9S_MB_2U_LIB.S9S_MB_2U(SCH_1):NC_CPU0_DDR67_VIEWDIG0
 H12 TP_CPU0_A0_DEBUG_EN RSVD162 @S9S_MB_2U_LIB.S9S_MB_2U(SCH_1):TP_CPU0_A0_DEBUG_EN
AV32 NC_CPU0_DDR23_VIEWDIG0 RSVD16 @S9S_MB_2U_LIB.S9S_MB_2U(SCH_1):NC_CPU0_DDR23_VIEWDIG0
AV38 NC_CPU0_THERMADC RSVD17 @S9S_MB_2U_LIB.S9S_MB_2U(SCH_1):NC_CPU0_THERMADC
AV40 NC_CPU0_THERMADA RSVD18 @S9S_MB_2U_LIB.S9S_MB_2U(SCH_1):NC_CPU0_THERMADA
AU33 NC_CPU0_DDR23_VIEWDIG1  RSVD7 @S9S_MB_2U_LIB.S9S_MB_2U(SCH_1):NC_CPU0_DDR23_VIEWDIG1
AU56 NC_CPU0_DDR01_VIEWDIG1  RSVD9 @S9S_MB_2U_LIB.S9S_MB_2U(SCH_1):NC_CPU0_DDR01_VIEWDIG1
CC64 NC_CPU0_LGSSPARE4 RSVD81 @S9S_MB_2U_LIB.S9S_MB_2U(SCH_1):NC_CPU0_LGSSPARE4
BU11 VSENSE_PVCCD_HV_CPU0_DP VCCD_HV_SENSE @S9S_MB_2U_LIB.S9S_MB_2U(SCH_1):VSENSE_PVCCD_HV_CPU0_DP
AY85 VSENSE_PVCCFA_EHV_FIVRA_CPU0_DP VCCFA_EHV_FIVRA_SENSE @S9S_MB_2U_LIB.S9S_MB_2U(SCH_1):VSENSE_PVCCFA_EHV_FIVRA_CPU0_DP
AU11 VSENSE_PVCCFA_EHV_CPU0_DP VCCFA_EHV_SENSE @S9S_MB_2U_LIB.S9S_MB_2U(SCH_1):VSENSE_PVCCFA_EHV_CPU0_DP
CA11 VSENSE_PVCCINFAON_CPU0_DP VCCINFAON_SENSE @S9S_MB_2U_LIB.S9S_MB_2U(SCH_1):VSENSE_PVCCINFAON_CPU0_DP
BD87 VSENSE_PVCCIN_CPU0_DP VCCIN_SENSE @S9S_MB_2U_LIB.S9S_MB_2U(SCH_1):VSENSE_PVCCIN_CPU0_DP
BN11 VSENSE_PVCCD_HV_CPU0_DN VSS_VCCD_HV_SENSE @S9S_MB_2U_LIB.S9S_MB_2U(SCH_1):VSENSE_PVCCD_HV_CPU0_DN
AT85 VSENSE_PVCCFA_EHV_FIVRA_CPU0_DN VSS_VCCFA_EHV_FIVRA_SENSE @S9S_MB_2U_LIB.S9S_MB_2U(SCH_1):VSENSE_PVCCFA_EHV_FIVRA_CPU0_DN
BA11 VSENSE_PVCCFA_EHV_CPU0_DN VSS_VCCFA_EHV_SENSE @S9S_MB_2U_LIB.S9S_MB_2U(SCH_1):VSENSE_PVCCFA_EHV_CPU0_DN
CE11 VSENSE_PVCCINFAON_CPU0_DN VSS_VCCINFAON_SENSE @S9S_MB_2U_LIB.S9S_MB_2U(SCH_1):VSENSE_PVCCINFAON_CPU0_DN
BC90 VSENSE_PVCCIN_CPU0_DN VSS_VCCIN_SENSE @S9S_MB_2U_LIB.S9S_MB_2U(SCH_1):VSENSE_PVCCIN_CPU0_DN

Q_RES_0402LF-100,1%,1/16W,CHIPA  I19  R22
   1 DBP_CPU0_MBP0_GTL_R_N      A @S9S_MB_2U_LIB.S9S_MB_2U(SCH_1):DBP_CPU0_MBP0_GTL_R_N
   2 DBP_CPU_MBP0_GTL_N      B @S9S_MB_2U_LIB.S9S_MB_2U(SCH_1):DBP_CPU_MBP0_GTL_N

Q_RES_0402LF-100,1%,1/16W,CHIPA  I20  R23
   1 DBP_CPU0_MBP1_GTL_R_N      A @S9S_MB_2U_LIB.S9S_MB_2U(SCH_1):DBP_CPU0_MBP1_GTL_R_N
   2 DBP_CPU_MBP1_GTL_N      B @S9S_MB_2U_LIB.S9S_MB_2U(SCH_1):DBP_CPU_MBP1_GTL_N

Q_RES_0402LF-10,1%,1/16W,CHIP,A  I25  R24
   1 DBP_CPU0_HOOK8_MBP2_GTL_QS_R_N      A @S9S_MB_2U_LIB.S9S_MB_2U(SCH_1):DBP_CPU0_HOOK8_MBP2_GTL_QS_R_N
   2 DBP_CPU_HOOK8_MBP2_GTL_QS_N      B @S9S_MB_2U_LIB.S9S_MB_2U(SCH_1):DBP_CPU_HOOK8_MBP2_GTL_QS_N

Q_RES_0402LF-10,1%,1/16W,CHIP,A  I26  R25
   1 DBP_CPU0_HOOK9_MBP3_GTL_QS_R_N      A @S9S_MB_2U_LIB.S9S_MB_2U(SCH_1):DBP_CPU0_HOOK9_MBP3_GTL_QS_R_N
   2 DBP_CPU_HOOK9_MBP3_GTL_QS_N      B @S9S_MB_2U_LIB.S9S_MB_2U(SCH_1):DBP_CPU_HOOK9_MBP3_GTL_QS_N

Q_RES_0402LF-0,5%,1/16W,CHIP,CA  I31  R20
   1 DBP_CPU_MBP0_GTL_N      A @S9S_MB_2U_LIB.S9S_MB_2U(SCH_1):DBP_CPU_MBP0_GTL_N
   2 FM_PCH_TRIGGER0_N      B @S9S_MB_2U_LIB.S9S_MB_2U(SCH_1):FM_PCH_TRIGGER0_N

Q_RES_0402LF-0,5%,1/16W,CHIP,CA  I32  R21
   1 DBP_CPU_MBP1_GTL_N      A @S9S_MB_2U_LIB.S9S_MB_2U(SCH_1):DBP_CPU_MBP1_GTL_N
   2 FM_PCH_TRIGGER1_N      B @S9S_MB_2U_LIB.S9S_MB_2U(SCH_1):FM_PCH_TRIGGER1_N

Q_RES_0402LF-499,1%,1/16W,CHIPA  I35  R18
   1 PVNN_TERM_CPU0      A @S9S_MB_2U_LIB.S9S_MB_2U(SCH_1):PVNN_TERM_CPU0
   2 DBP_CPU_MBP0_GTL_N      B @S9S_MB_2U_LIB.S9S_MB_2U(SCH_1):DBP_CPU_MBP0_GTL_N

Q_RES_0402LF-499,1%,1/16W,CHIPA  I36  R19
   1 PVNN_TERM_CPU0      A @S9S_MB_2U_LIB.S9S_MB_2U(SCH_1):PVNN_TERM_CPU0
   2 DBP_CPU_MBP1_GTL_N      B @S9S_MB_2U_LIB.S9S_MB_2U(SCH_1):DBP_CPU_MBP1_GTL_N


DRAWING: @S9S_MB_2U_LIB.S9S_MB_2U(SCH_1):PAGE17 

SOCKET4677_AZIF0045P001C01CS-SA  I1  U2
AC78 NC_CPU0_HBM2_VIEWDIG0  RSVD0 @S9S_MB_2U_LIB.S9S_MB_2U(SCH_1):NC_CPU0_HBM2_VIEWDIG0
AD77 NC_CPU0_HBM2_VIEWDIG1  RSVD1 @S9S_MB_2U_LIB.S9S_MB_2U(SCH_1):NC_CPU0_HBM2_VIEWDIG1
CJ68 NC_CPU0_MDFI_DIE11_NS0 RSVD106 @S9S_MB_2U_LIB.S9S_MB_2U(SCH_1):NC_CPU0_MDFI_DIE11_NS0
CJ70 NC_CPU0_MDFI_DIE11_EW0 RSVD107 @S9S_MB_2U_LIB.S9S_MB_2U(SCH_1):NC_CPU0_MDFI_DIE11_EW0
CK67 NC_CPU0_MDFI_DIE11_NS1 RSVD112 @S9S_MB_2U_LIB.S9S_MB_2U(SCH_1):NC_CPU0_MDFI_DIE11_NS1
CR25 NC_CPU0_VIEWPIN_GNR2 RSVD133 @S9S_MB_2U_LIB.S9S_MB_2U(SCH_1):NC_CPU0_VIEWPIN_GNR2
CT26 NC_CPU0_VIEWPIN_GNR0 RSVD138 @S9S_MB_2U_LIB.S9S_MB_2U(SCH_1):NC_CPU0_VIEWPIN_GNR0
CW41 NC_CPU0_HBM1_VIEWDIG1 RSVD147 @S9S_MB_2U_LIB.S9S_MB_2U(SCH_1):NC_CPU0_HBM1_VIEWDIG1
CW58 NC_CPU0_VIEWPIN_GNR1 RSVD149 @S9S_MB_2U_LIB.S9S_MB_2U(SCH_1):NC_CPU0_VIEWPIN_GNR1
CY57 NC_CPU0_VIEWPIN_GNR3 RSVD154 @S9S_MB_2U_LIB.S9S_MB_2U(SCH_1):NC_CPU0_VIEWPIN_GNR3
EG17 NC_CPU0_HBM0_VIEWDIG1 RSVD160 @S9S_MB_2U_LIB.S9S_MB_2U(SCH_1):NC_CPU0_HBM0_VIEWDIG1
 U17 NC_CPU0_HBM0_VIEWDIG0 RSVD164 @S9S_MB_2U_LIB.S9S_MB_2U(SCH_1):NC_CPU0_HBM0_VIEWDIG0
 W17 NC_CPU0_HBM1_VIEWDIG0 RSVD165 @S9S_MB_2U_LIB.S9S_MB_2U(SCH_1):NC_CPU0_HBM1_VIEWDIG0
AV65 NC_CPU0_MDFI_DIE01_EW0 RSVD21 @S9S_MB_2U_LIB.S9S_MB_2U(SCH_1):NC_CPU0_MDFI_DIE01_EW0
AY24 NC_CPU0_SOC_SPARE0 RSVD26 @S9S_MB_2U_LIB.S9S_MB_2U(SCH_1):NC_CPU0_SOC_SPARE0
BA25 NC_CPU0_SOC_SPARE4 RSVD31 @S9S_MB_2U_LIB.S9S_MB_2U(SCH_1):NC_CPU0_SOC_SPARE4
BD71 NC_CPU0_MDFI_DIE01_NS1 RSVD43 @S9S_MB_2U_LIB.S9S_MB_2U(SCH_1):NC_CPU0_MDFI_DIE01_NS1
BE21 TP_CPU0_DIE_HVM_EN_LVC1 RSVD45 @S9S_MB_2U_LIB.S9S_MB_2U(SCH_1):TP_CPU0_DIE_HVM_EN_LVC1
BF71 NC_CPU0_MDFI_DIE01_NS0 RSVD51 @S9S_MB_2U_LIB.S9S_MB_2U(SCH_1):NC_CPU0_MDFI_DIE01_NS0
BG78 NC_CPU0_HBM3_VIEWDIG0 RSVD54 @S9S_MB_2U_LIB.S9S_MB_2U(SCH_1):NC_CPU0_HBM3_VIEWDIG0
BJ21 NC_CPU0_MDFI_DIE00_NS1 RSVD57 @S9S_MB_2U_LIB.S9S_MB_2U(SCH_1):NC_CPU0_MDFI_DIE00_NS1
BK22 NC_CPU0_MDFI_DIE00_NS0 RSVD60 @S9S_MB_2U_LIB.S9S_MB_2U(SCH_1):NC_CPU0_MDFI_DIE00_NS0
BL60 NC_CPU0_HBM3_VIEWDIG1 RSVD63 @S9S_MB_2U_LIB.S9S_MB_2U(SCH_1):NC_CPU0_HBM3_VIEWDIG1
BM65 NC_CPU0_SOC_SPARE1 RSVD65 @S9S_MB_2U_LIB.S9S_MB_2U(SCH_1):NC_CPU0_SOC_SPARE1
BP22 NC_CPU0_MDFI_DIE00_EW0 RSVD67 @S9S_MB_2U_LIB.S9S_MB_2U(SCH_1):NC_CPU0_MDFI_DIE00_EW0
BP65 NC_CPU0_SOC_SPARE5 RSVD68 @S9S_MB_2U_LIB.S9S_MB_2U(SCH_1):NC_CPU0_SOC_SPARE5
BR21 NC_CPU0_MDFI_DIE00_EW1 RSVD71 @S9S_MB_2U_LIB.S9S_MB_2U(SCH_1):NC_CPU0_MDFI_DIE00_EW1
CC66 NC_CPU0_MDFI_DIE01_EW1 RSVD82 @S9S_MB_2U_LIB.S9S_MB_2U(SCH_1):NC_CPU0_MDFI_DIE01_EW1
CD22 NC_CPU0_MDFI_DIE10_NS1 RSVD83 @S9S_MB_2U_LIB.S9S_MB_2U(SCH_1):NC_CPU0_MDFI_DIE10_NS1
CD26 NC_CPU0_MDFI_DIE10_EW0 RSVD84 @S9S_MB_2U_LIB.S9S_MB_2U(SCH_1):NC_CPU0_MDFI_DIE10_EW0
CD30 NC_CPU0_MDFI_DIE10_EW1 RSVD85 @S9S_MB_2U_LIB.S9S_MB_2U(SCH_1):NC_CPU0_MDFI_DIE10_EW1
CF22 NC_CPU0_MDFI_DIE10_NS0 RSVD92 @S9S_MB_2U_LIB.S9S_MB_2U(SCH_1):NC_CPU0_MDFI_DIE10_NS0
CH69 NC_CPU0_MDFI_DIE11_EW1 RSVD99 @S9S_MB_2U_LIB.S9S_MB_2U(SCH_1):NC_CPU0_MDFI_DIE11_EW1


DRAWING: @S9S_MB_2U_LIB.S9S_MB_2U(SCH_1):PAGE18 

SOCKET4677_AZIF0045P001C01CS-SA  I1  U2
CL70 TP_CPU0_SPARE12 RSVD119 @S9S_MB_2U_LIB.S9S_MB_2U(SCH_1):TP_CPU0_SPARE12
CL60 TP_CPU0_SPARE7 RSVD115 @S9S_MB_2U_LIB.S9S_MB_2U(SCH_1):TP_CPU0_SPARE7
CW43 TP_CPU0_SPARE6 RSVD148 @S9S_MB_2U_LIB.S9S_MB_2U(SCH_1):TP_CPU0_SPARE6
DA70 TP_CPU0_SPARE4 RSVD159 @S9S_MB_2U_LIB.S9S_MB_2U(SCH_1):TP_CPU0_SPARE4
BD77 TP_CPU0_SPARE13 RSVD44 @S9S_MB_2U_LIB.S9S_MB_2U(SCH_1):TP_CPU0_SPARE13
CH61 TP_CPU0_SPARE9 RSVD97 @S9S_MB_2U_LIB.S9S_MB_2U(SCH_1):TP_CPU0_SPARE9
AU52 TP_CPU0_SPARE5  RSVD8 @S9S_MB_2U_LIB.S9S_MB_2U(SCH_1):TP_CPU0_SPARE5
CD69 TP_CPU0_SPARE11 RSVD87 @S9S_MB_2U_LIB.S9S_MB_2U(SCH_1):TP_CPU0_SPARE11
CK61 TP_CPU0_SPARE8 RSVD111 @S9S_MB_2U_LIB.S9S_MB_2U(SCH_1):TP_CPU0_SPARE8
CG60 TP_CPU0_SPARE10 RSVD95 @S9S_MB_2U_LIB.S9S_MB_2U(SCH_1):TP_CPU0_SPARE10
 J13 TP_CPU0_PPD RSVD163 @S9S_MB_2U_LIB.S9S_MB_2U(SCH_1):TP_CPU0_PPD


DRAWING: @S9S_MB_2U_LIB.S9S_MB_2U(SCH_1):PAGE19 

SOCKET4677_AZIF0045P001C01CS-SA  I1  U2
BP30 TP_TRC_CPU0_PTI<15> PTI_DIE0015 @S9S_MB_2U_LIB.S9S_MB_2U(SCH_1):TP_TRC_CPU0_PTI(15)
BN29 TP_TRC_CPU0_PTI<14> PTI_DIE0014 @S9S_MB_2U_LIB.S9S_MB_2U(SCH_1):TP_TRC_CPU0_PTI(14)
BP28 TP_TRC_CPU0_PTI<13> PTI_DIE0013 @S9S_MB_2U_LIB.S9S_MB_2U(SCH_1):TP_TRC_CPU0_PTI(13)
BN27 TP_TRC_CPU0_PTI<12> PTI_DIE0012 @S9S_MB_2U_LIB.S9S_MB_2U(SCH_1):TP_TRC_CPU0_PTI(12)
BT30 TP_TRC_CPU0_PTI<11> PTI_DIE0011 @S9S_MB_2U_LIB.S9S_MB_2U(SCH_1):TP_TRC_CPU0_PTI(11)
BU29 TP_TRC_CPU0_PTI<10> PTI_DIE0010 @S9S_MB_2U_LIB.S9S_MB_2U(SCH_1):TP_TRC_CPU0_PTI(10)
BT28 TP_TRC_CPU0_PTI<9> PTI_DIE009 @S9S_MB_2U_LIB.S9S_MB_2U(SCH_1):TP_TRC_CPU0_PTI(9)
BU27 TP_TRC_CPU0_PTI<8> PTI_DIE008 @S9S_MB_2U_LIB.S9S_MB_2U(SCH_1):TP_TRC_CPU0_PTI(8)
BV28 TP_TRC_CPU0_PTI<7> PTI_DIE007 @S9S_MB_2U_LIB.S9S_MB_2U(SCH_1):TP_TRC_CPU0_PTI(7)
CA27 TP_TRC_CPU0_PTI<6> PTI_DIE006 @S9S_MB_2U_LIB.S9S_MB_2U(SCH_1):TP_TRC_CPU0_PTI(6)
BV30 TP_TRC_CPU0_PTI<5> PTI_DIE005 @S9S_MB_2U_LIB.S9S_MB_2U(SCH_1):TP_TRC_CPU0_PTI(5)
CA29 TP_TRC_CPU0_PTI<4> PTI_DIE004 @S9S_MB_2U_LIB.S9S_MB_2U(SCH_1):TP_TRC_CPU0_PTI(4)
BY30 TP_TRC_CPU0_PTI<3> PTI_DIE003 @S9S_MB_2U_LIB.S9S_MB_2U(SCH_1):TP_TRC_CPU0_PTI(3)
CC27 TP_TRC_CPU0_PTI<2> PTI_DIE002 @S9S_MB_2U_LIB.S9S_MB_2U(SCH_1):TP_TRC_CPU0_PTI(2)
CD28 TP_TRC_CPU0_PTI_MON<1> PTI_DIE001 @S9S_MB_2U_LIB.S9S_MB_2U(SCH_1):TP_TRC_CPU0_PTI_MON(1)
CC29 TP_TP_TRC_CPU0_PTI_MON<0> PTI_DIE000 @S9S_MB_2U_LIB.S9S_MB_2U(SCH_1):TP_TP_TRC_CPU0_PTI_MON(0)
CB30 TP_TRC_CPU0_PTI0_CLK PTI_DIE00_STB_0 @S9S_MB_2U_LIB.S9S_MB_2U(SCH_1):TP_TRC_CPU0_PTI0_CLK
BY28 TP_TRC_CPU0_PTI1_CLK PTI_DIE00_STB_1 @S9S_MB_2U_LIB.S9S_MB_2U(SCH_1):TP_TRC_CPU0_PTI1_CLK
BN66 TP_TRC_CPU0_PTI<31> PTI_DIE0115 @S9S_MB_2U_LIB.S9S_MB_2U(SCH_1):TP_TRC_CPU0_PTI(31)
BM67 TP_TRC_CPU0_PTI<30> PTI_DIE0114 @S9S_MB_2U_LIB.S9S_MB_2U(SCH_1):TP_TRC_CPU0_PTI(30)
BL66 TP_TRC_CPU0_PTI<29> PTI_DIE0113 @S9S_MB_2U_LIB.S9S_MB_2U(SCH_1):TP_TRC_CPU0_PTI(29)
BJ66 TP_TRC_CPU0_PTI<28> PTI_DIE0112 @S9S_MB_2U_LIB.S9S_MB_2U(SCH_1):TP_TRC_CPU0_PTI(28)
BG66 TP_TRC_CPU0_PTI<27> PTI_DIE0111 @S9S_MB_2U_LIB.S9S_MB_2U(SCH_1):TP_TRC_CPU0_PTI(27)
BN68 TP_TRC_CPU0_PTI<26> PTI_DIE0110 @S9S_MB_2U_LIB.S9S_MB_2U(SCH_1):TP_TRC_CPU0_PTI(26)
BM69 TP_TRC_CPU0_PTI<25> PTI_DIE019 @S9S_MB_2U_LIB.S9S_MB_2U(SCH_1):TP_TRC_CPU0_PTI(25)
BK69 TP_TRC_CPU0_PTI<24> PTI_DIE018 @S9S_MB_2U_LIB.S9S_MB_2U(SCH_1):TP_TRC_CPU0_PTI(24)
BD67 TP_TRC_CPU0_PTI<23> PTI_DIE017 @S9S_MB_2U_LIB.S9S_MB_2U(SCH_1):TP_TRC_CPU0_PTI(23)
BG68 TP_TRC_CPU0_PTI<22> PTI_DIE016 @S9S_MB_2U_LIB.S9S_MB_2U(SCH_1):TP_TRC_CPU0_PTI(22)
BC68 TP_TRC_CPU0_PTI<21> PTI_DIE015 @S9S_MB_2U_LIB.S9S_MB_2U(SCH_1):TP_TRC_CPU0_PTI(21)
BH69 TP_TRC_CPU0_PTI<20> PTI_DIE014 @S9S_MB_2U_LIB.S9S_MB_2U(SCH_1):TP_TRC_CPU0_PTI(20)
BF69 TP_TRC_CPU0_PTI<19> PTI_DIE013 @S9S_MB_2U_LIB.S9S_MB_2U(SCH_1):TP_TRC_CPU0_PTI(19)
BD69 TP_TRC_CPU0_PTI<18> PTI_DIE012 @S9S_MB_2U_LIB.S9S_MB_2U(SCH_1):TP_TRC_CPU0_PTI(18)
BE70 TP_TRC_CPU0_PTI<17> PTI_DIE011 @S9S_MB_2U_LIB.S9S_MB_2U(SCH_1):TP_TRC_CPU0_PTI(17)
BC70 TP_TRC_CPU0_PTI<16> PTI_DIE010 @S9S_MB_2U_LIB.S9S_MB_2U(SCH_1):TP_TRC_CPU0_PTI(16)
BF67 TP_TRC_CPU0_PTI2_CLK PTI_DIE01_STB_0 @S9S_MB_2U_LIB.S9S_MB_2U(SCH_1):TP_TRC_CPU0_PTI2_CLK
BK67 TP_TRC_CPU0_PTI3_CLK PTI_DIE01_STB_1 @S9S_MB_2U_LIB.S9S_MB_2U(SCH_1):TP_TRC_CPU0_PTI3_CLK
CL68 NC_CPU0_PE3_APROBE<0> RSVD118 @S9S_MB_2U_LIB.S9S_MB_2U(SCH_1):NC_CPU0_PE3_APROBE(0)
CM69 NC_CPU0_PE3_APROBE<1> RSVD122 @S9S_MB_2U_LIB.S9S_MB_2U(SCH_1):NC_CPU0_PE3_APROBE(1)
CP69 NC_CPU0_UPI3_APROBE<0> RSVD130 @S9S_MB_2U_LIB.S9S_MB_2U(SCH_1):NC_CPU0_UPI3_APROBE(0)
CR68 NC_CPU0_UPI3_APROBE<1> RSVD135 @S9S_MB_2U_LIB.S9S_MB_2U(SCH_1):NC_CPU0_UPI3_APROBE(1)
AU66 NC_CPU0_PE4_APROBE<1> RSVD13 @S9S_MB_2U_LIB.S9S_MB_2U(SCH_1):NC_CPU0_PE4_APROBE(1)
AU68 NC_CPU0_UPI2_APROBE<0> RSVD14 @S9S_MB_2U_LIB.S9S_MB_2U(SCH_1):NC_CPU0_UPI2_APROBE(0)
AN17 NC_CPU0_UPI0_APROBE<0>  RSVD2 @S9S_MB_2U_LIB.S9S_MB_2U(SCH_1):NC_CPU0_UPI0_APROBE(0)
AV67 NC_CPU0_PE4_APROBE<0> RSVD22 @S9S_MB_2U_LIB.S9S_MB_2U(SCH_1):NC_CPU0_PE4_APROBE(0)
AR17 NC_CPU0_UPI0_APROBE<1>  RSVD3 @S9S_MB_2U_LIB.S9S_MB_2U(SCH_1):NC_CPU0_UPI0_APROBE(1)
AT67 NC_CPU0_UPI2_APROBE<1>  RSVD5 @S9S_MB_2U_LIB.S9S_MB_2U(SCH_1):NC_CPU0_UPI2_APROBE(1)
BL21 NC_CPU0_PE0_APROBE<1> RSVD62 @S9S_MB_2U_LIB.S9S_MB_2U(SCH_1):NC_CPU0_PE0_APROBE(1)
BN21 NC_CPU0_PE0_APROBE<0> RSVD66 @S9S_MB_2U_LIB.S9S_MB_2U(SCH_1):NC_CPU0_PE0_APROBE(0)
BV22 NC_CPU0_UPI1_APROBE<0> RSVD73 @S9S_MB_2U_LIB.S9S_MB_2U(SCH_1):NC_CPU0_UPI1_APROBE(0)
BW21 NC_CPU0_DMI_APROBE<1> RSVD74 @S9S_MB_2U_LIB.S9S_MB_2U(SCH_1):NC_CPU0_DMI_APROBE(1)
BW23 NC_CPU0_PE2_APROBE<1> RSVD75 @S9S_MB_2U_LIB.S9S_MB_2U(SCH_1):NC_CPU0_PE2_APROBE(1)
CA21 NC_CPU0_DMI_APROBE<0> RSVD77 @S9S_MB_2U_LIB.S9S_MB_2U(SCH_1):NC_CPU0_DMI_APROBE(0)
CA23 NC_CPU0_UPI1_APROBE<1> RSVD78 @S9S_MB_2U_LIB.S9S_MB_2U(SCH_1):NC_CPU0_UPI1_APROBE(1)
CC21 NC_CPU0_PE1_APROBE<1> RSVD79 @S9S_MB_2U_LIB.S9S_MB_2U(SCH_1):NC_CPU0_PE1_APROBE(1)
CC23 NC_CPU0_PE2_APROBE<0> RSVD80 @S9S_MB_2U_LIB.S9S_MB_2U(SCH_1):NC_CPU0_PE2_APROBE(0)
CE21 NC_CPU0_PE1_APROBE<0> RSVD89 @S9S_MB_2U_LIB.S9S_MB_2U(SCH_1):NC_CPU0_PE1_APROBE(0)
BA23 PU_CPU0_UPI0_AC_COUPLING UPI0_AC_COUPLING @S9S_MB_2U_LIB.S9S_MB_2U(SCH_1):PU_CPU0_UPI0_AC_COUPLING
CW19 PU_CPU0_UPI1_AC_COUPLING UPI1_AC_COUPLING @S9S_MB_2U_LIB.S9S_MB_2U(SCH_1):PU_CPU0_UPI1_AC_COUPLING
BB65 PU_CPU0_UPI2_AC_COUPLING UPI2_AC_COUPLING @S9S_MB_2U_LIB.S9S_MB_2U(SCH_1):PU_CPU0_UPI2_AC_COUPLING
CK71 PU_CPU0_UPI3_AC_COUPLING UPI3_AC_COUPLING @S9S_MB_2U_LIB.S9S_MB_2U(SCH_1):PU_CPU0_UPI3_AC_COUPLING


DRAWING: @S9S_MB_2U_LIB.S9S_MB_2U(SCH_1):PAGE20 

SOCKET4677_AZIF0045P001C01CS-SA  I1  U2
AT49 M_A_CPU0_ALERT_N DDR0_ALERT_N @S9S_MB_2U_LIB.S9S_MB_2U(SCH_1):M_A_CPU0_ALERT_N
AU43 M_A_CPU0_SA_RSP<1> DDR0_A_RSP1 @S9S_MB_2U_LIB.S9S_MB_2U(SCH_1):M_A_CPU0_SA_RSP(1)
AT42 M_A_CPU0_SA_RSP<0> DDR0_A_RSP0 @S9S_MB_2U_LIB.S9S_MB_2U(SCH_1):M_A_CPU0_SA_RSP(0)
AV42 M_A_CPU0_SB_RSP<1> DDR0_B_RSP1 @S9S_MB_2U_LIB.S9S_MB_2U(SCH_1):M_A_CPU0_SB_RSP(1)
AV44 M_A_CPU0_SB_RSP<0> DDR0_B_RSP0 @S9S_MB_2U_LIB.S9S_MB_2U(SCH_1):M_A_CPU0_SB_RSP(0)
 G45 M_A_CPU0_CLK_DN<1> DDR0_CLK_DN1 @S9S_MB_2U_LIB.S9S_MB_2U(SCH_1):M_A_CPU0_CLK_DN(1)
 B44 M_A_CPU0_CLK_DN<0> DDR0_CLK_DN0 @S9S_MB_2U_LIB.S9S_MB_2U(SCH_1):M_A_CPU0_CLK_DN(0)
 E45 M_A_CPU0_CLK_DP<1> DDR0_CLK_DP1 @S9S_MB_2U_LIB.S9S_MB_2U(SCH_1):M_A_CPU0_CLK_DP(1)
 C43 M_A_CPU0_CLK_DP<0> DDR0_CLK_DP0 @S9S_MB_2U_LIB.S9S_MB_2U(SCH_1):M_A_CPU0_CLK_DP(0)
 C48 M_A_CPU0_SA_CA<6> DDR0_SA_CA6 @S9S_MB_2U_LIB.S9S_MB_2U(SCH_1):M_A_CPU0_SA_CA(6)
 E50 M_A_CPU0_SA_CA<5> DDR0_SA_CA5 @S9S_MB_2U_LIB.S9S_MB_2U(SCH_1):M_A_CPU0_SA_CA(5)
 C50 M_A_CPU0_SA_CA<4> DDR0_SA_CA4 @S9S_MB_2U_LIB.S9S_MB_2U(SCH_1):M_A_CPU0_SA_CA(4)
 F51 M_A_CPU0_SA_CA<3> DDR0_SA_CA3 @S9S_MB_2U_LIB.S9S_MB_2U(SCH_1):M_A_CPU0_SA_CA(3)
 B51 M_A_CPU0_SA_CA<2> DDR0_SA_CA2 @S9S_MB_2U_LIB.S9S_MB_2U(SCH_1):M_A_CPU0_SA_CA(2)
 G52 M_A_CPU0_SA_CA<1> DDR0_SA_CA1 @S9S_MB_2U_LIB.S9S_MB_2U(SCH_1):M_A_CPU0_SA_CA(1)
 A52 M_A_CPU0_SA_CA<0> DDR0_SA_CA0 @S9S_MB_2U_LIB.S9S_MB_2U(SCH_1):M_A_CPU0_SA_CA(0)
 F53 M_A_CPU0_SA_CS_N<3> DDR0_SA_CS_N3 @S9S_MB_2U_LIB.S9S_MB_2U(SCH_1):M_A_CPU0_SA_CS_N(3)
 E54 M_A_CPU0_SA_CS_N<2> DDR0_SA_CS_N2 @S9S_MB_2U_LIB.S9S_MB_2U(SCH_1):M_A_CPU0_SA_CS_N(2)
 B53 M_A_CPU0_SA_CS_N<1> DDR0_SA_CS_N1 @S9S_MB_2U_LIB.S9S_MB_2U(SCH_1):M_A_CPU0_SA_CS_N(1)
 C54 M_A_CPU0_SA_CS_N<0> DDR0_SA_CS_N0 @S9S_MB_2U_LIB.S9S_MB_2U(SCH_1):M_A_CPU0_SA_CS_N(0)
 E62 M_A_CPU0_SA_DQ<31> DDR0_SA_DQ31 @S9S_MB_2U_LIB.S9S_MB_2U(SCH_1):M_A_CPU0_SA_DQ(31)
 F63 M_A_CPU0_SA_DQ<30> DDR0_SA_DQ30 @S9S_MB_2U_LIB.S9S_MB_2U(SCH_1):M_A_CPU0_SA_DQ(30)
 C62 M_A_CPU0_SA_DQ<29> DDR0_SA_DQ29 @S9S_MB_2U_LIB.S9S_MB_2U(SCH_1):M_A_CPU0_SA_DQ(29)
 B63 M_A_CPU0_SA_DQ<28> DDR0_SA_DQ28 @S9S_MB_2U_LIB.S9S_MB_2U(SCH_1):M_A_CPU0_SA_DQ(28)
 F65 M_A_CPU0_SA_DQ<27> DDR0_SA_DQ27 @S9S_MB_2U_LIB.S9S_MB_2U(SCH_1):M_A_CPU0_SA_DQ(27)
 E66 M_A_CPU0_SA_DQ<26> DDR0_SA_DQ26 @S9S_MB_2U_LIB.S9S_MB_2U(SCH_1):M_A_CPU0_SA_DQ(26)
 B65 M_A_CPU0_SA_DQ<25> DDR0_SA_DQ25 @S9S_MB_2U_LIB.S9S_MB_2U(SCH_1):M_A_CPU0_SA_DQ(25)
 C66 M_A_CPU0_SA_DQ<24> DDR0_SA_DQ24 @S9S_MB_2U_LIB.S9S_MB_2U(SCH_1):M_A_CPU0_SA_DQ(24)
 E68 M_A_CPU0_SA_DQ<23> DDR0_SA_DQ23 @S9S_MB_2U_LIB.S9S_MB_2U(SCH_1):M_A_CPU0_SA_DQ(23)
 F69 M_A_CPU0_SA_DQ<22> DDR0_SA_DQ22 @S9S_MB_2U_LIB.S9S_MB_2U(SCH_1):M_A_CPU0_SA_DQ(22)
 C68 M_A_CPU0_SA_DQ<21> DDR0_SA_DQ21 @S9S_MB_2U_LIB.S9S_MB_2U(SCH_1):M_A_CPU0_SA_DQ(21)
 B69 M_A_CPU0_SA_DQ<20> DDR0_SA_DQ20 @S9S_MB_2U_LIB.S9S_MB_2U(SCH_1):M_A_CPU0_SA_DQ(20)
 F71 M_A_CPU0_SA_DQ<19> DDR0_SA_DQ19 @S9S_MB_2U_LIB.S9S_MB_2U(SCH_1):M_A_CPU0_SA_DQ(19)
 D73 M_A_CPU0_SA_DQ<18> DDR0_SA_DQ18 @S9S_MB_2U_LIB.S9S_MB_2U(SCH_1):M_A_CPU0_SA_DQ(18)
 E72 M_A_CPU0_SA_DQ<17> DDR0_SA_DQ17 @S9S_MB_2U_LIB.S9S_MB_2U(SCH_1):M_A_CPU0_SA_DQ(17)
 B73 M_A_CPU0_SA_DQ<16> DDR0_SA_DQ16 @S9S_MB_2U_LIB.S9S_MB_2U(SCH_1):M_A_CPU0_SA_DQ(16)
 M65 M_A_CPU0_SA_DQ<15> DDR0_SA_DQ15 @S9S_MB_2U_LIB.S9S_MB_2U(SCH_1):M_A_CPU0_SA_DQ(15)
 N66 M_A_CPU0_SA_DQ<14> DDR0_SA_DQ14 @S9S_MB_2U_LIB.S9S_MB_2U(SCH_1):M_A_CPU0_SA_DQ(14)
 K65 M_A_CPU0_SA_DQ<13> DDR0_SA_DQ13 @S9S_MB_2U_LIB.S9S_MB_2U(SCH_1):M_A_CPU0_SA_DQ(13)
 J66 M_A_CPU0_SA_DQ<12> DDR0_SA_DQ12 @S9S_MB_2U_LIB.S9S_MB_2U(SCH_1):M_A_CPU0_SA_DQ(12)
 N68 M_A_CPU0_SA_DQ<11> DDR0_SA_DQ11 @S9S_MB_2U_LIB.S9S_MB_2U(SCH_1):M_A_CPU0_SA_DQ(11)
 M69 M_A_CPU0_SA_DQ<10> DDR0_SA_DQ10 @S9S_MB_2U_LIB.S9S_MB_2U(SCH_1):M_A_CPU0_SA_DQ(10)
 J68 M_A_CPU0_SA_DQ<9> DDR0_SA_DQ9 @S9S_MB_2U_LIB.S9S_MB_2U(SCH_1):M_A_CPU0_SA_DQ(9)
 K69 M_A_CPU0_SA_DQ<8> DDR0_SA_DQ8 @S9S_MB_2U_LIB.S9S_MB_2U(SCH_1):M_A_CPU0_SA_DQ(8)
 F75 M_A_CPU0_SA_DQ<7> DDR0_SA_DQ7 @S9S_MB_2U_LIB.S9S_MB_2U(SCH_1):M_A_CPU0_SA_DQ(7)
 G76 M_A_CPU0_SA_DQ<6> DDR0_SA_DQ6 @S9S_MB_2U_LIB.S9S_MB_2U(SCH_1):M_A_CPU0_SA_DQ(6)
 D75 M_A_CPU0_SA_DQ<5> DDR0_SA_DQ5 @S9S_MB_2U_LIB.S9S_MB_2U(SCH_1):M_A_CPU0_SA_DQ(5)
 C76 M_A_CPU0_SA_DQ<4> DDR0_SA_DQ4 @S9S_MB_2U_LIB.S9S_MB_2U(SCH_1):M_A_CPU0_SA_DQ(4)
 G78 M_A_CPU0_SA_DQ<3> DDR0_SA_DQ3 @S9S_MB_2U_LIB.S9S_MB_2U(SCH_1):M_A_CPU0_SA_DQ(3)
 M77 M_A_CPU0_SA_DQ<2> DDR0_SA_DQ2 @S9S_MB_2U_LIB.S9S_MB_2U(SCH_1):M_A_CPU0_SA_DQ(2)
 B79 M_A_CPU0_SA_DQ<1> DDR0_SA_DQ1 @S9S_MB_2U_LIB.S9S_MB_2U(SCH_1):M_A_CPU0_SA_DQ(1)
 B81 M_A_CPU0_SA_DQ<0> DDR0_SA_DQ0 @S9S_MB_2U_LIB.S9S_MB_2U(SCH_1):M_A_CPU0_SA_DQ(0)
 G58 M_A_CPU0_SA_DQS_DN<9> DDR0_SA_DQS_DN9 @S9S_MB_2U_LIB.S9S_MB_2U(SCH_1):M_A_CPU0_SA_DQS_DN(9)
 G64 M_A_CPU0_SA_DQS_DN<8> DDR0_SA_DQS_DN8 @S9S_MB_2U_LIB.S9S_MB_2U(SCH_1):M_A_CPU0_SA_DQS_DN(8)
 G70 M_A_CPU0_SA_DQS_DN<7> DDR0_SA_DQS_DN7 @S9S_MB_2U_LIB.S9S_MB_2U(SCH_1):M_A_CPU0_SA_DQS_DN(7)
 P67 M_A_CPU0_SA_DQS_DN<6> DDR0_SA_DQS_DN6 @S9S_MB_2U_LIB.S9S_MB_2U(SCH_1):M_A_CPU0_SA_DQS_DN(6)
 H77 M_A_CPU0_SA_DQS_DN<5> DDR0_SA_DQS_DN5 @S9S_MB_2U_LIB.S9S_MB_2U(SCH_1):M_A_CPU0_SA_DQS_DN(5)
 A58 M_A_CPU0_SA_DQS_DN<4> DDR0_SA_DQS_DN4 @S9S_MB_2U_LIB.S9S_MB_2U(SCH_1):M_A_CPU0_SA_DQS_DN(4)
 A64 M_A_CPU0_SA_DQS_DN<3> DDR0_SA_DQS_DN3 @S9S_MB_2U_LIB.S9S_MB_2U(SCH_1):M_A_CPU0_SA_DQS_DN(3)
 B71 M_A_CPU0_SA_DQS_DN<2> DDR0_SA_DQS_DN2 @S9S_MB_2U_LIB.S9S_MB_2U(SCH_1):M_A_CPU0_SA_DQS_DN(2)
 H67 M_A_CPU0_SA_DQS_DN<1> DDR0_SA_DQS_DN1 @S9S_MB_2U_LIB.S9S_MB_2U(SCH_1):M_A_CPU0_SA_DQS_DN(1)
 B77 M_A_CPU0_SA_DQS_DN<0> DDR0_SA_DQS_DN0 @S9S_MB_2U_LIB.S9S_MB_2U(SCH_1):M_A_CPU0_SA_DQS_DN(0)
 E58 M_A_CPU0_SA_DQS_DP<9> DDR0_SA_DQS_DP9 @S9S_MB_2U_LIB.S9S_MB_2U(SCH_1):M_A_CPU0_SA_DQS_DP(9)
 E64 M_A_CPU0_SA_DQS_DP<8> DDR0_SA_DQS_DP8 @S9S_MB_2U_LIB.S9S_MB_2U(SCH_1):M_A_CPU0_SA_DQS_DP(8)
 E70 M_A_CPU0_SA_DQS_DP<7> DDR0_SA_DQS_DP7 @S9S_MB_2U_LIB.S9S_MB_2U(SCH_1):M_A_CPU0_SA_DQS_DP(7)
 M67 M_A_CPU0_SA_DQS_DP<6> DDR0_SA_DQS_DP6 @S9S_MB_2U_LIB.S9S_MB_2U(SCH_1):M_A_CPU0_SA_DQS_DP(6)
 F77 M_A_CPU0_SA_DQS_DP<5> DDR0_SA_DQS_DP5 @S9S_MB_2U_LIB.S9S_MB_2U(SCH_1):M_A_CPU0_SA_DQS_DP(5)
 C58 M_A_CPU0_SA_DQS_DP<4> DDR0_SA_DQS_DP4 @S9S_MB_2U_LIB.S9S_MB_2U(SCH_1):M_A_CPU0_SA_DQS_DP(4)
 C64 M_A_CPU0_SA_DQS_DP<3> DDR0_SA_DQS_DP3 @S9S_MB_2U_LIB.S9S_MB_2U(SCH_1):M_A_CPU0_SA_DQS_DP(3)
 C70 M_A_CPU0_SA_DQS_DP<2> DDR0_SA_DQS_DP2 @S9S_MB_2U_LIB.S9S_MB_2U(SCH_1):M_A_CPU0_SA_DQS_DP(2)
 K67 M_A_CPU0_SA_DQS_DP<1> DDR0_SA_DQS_DP1 @S9S_MB_2U_LIB.S9S_MB_2U(SCH_1):M_A_CPU0_SA_DQS_DP(1)
 D77 M_A_CPU0_SA_DQS_DP<0> DDR0_SA_DQS_DP0 @S9S_MB_2U_LIB.S9S_MB_2U(SCH_1):M_A_CPU0_SA_DQS_DP(0)
 E56 M_A_CPU0_SA_CB<7> DDR0_SA_ECC7 @S9S_MB_2U_LIB.S9S_MB_2U(SCH_1):M_A_CPU0_SA_CB(7)
 F57 M_A_CPU0_SA_CB<6> DDR0_SA_ECC6 @S9S_MB_2U_LIB.S9S_MB_2U(SCH_1):M_A_CPU0_SA_CB(6)
 C56 M_A_CPU0_SA_CB<5> DDR0_SA_ECC5 @S9S_MB_2U_LIB.S9S_MB_2U(SCH_1):M_A_CPU0_SA_CB(5)
 B57 M_A_CPU0_SA_CB<4> DDR0_SA_ECC4 @S9S_MB_2U_LIB.S9S_MB_2U(SCH_1):M_A_CPU0_SA_CB(4)
 F59 M_A_CPU0_SA_CB<3> DDR0_SA_ECC3 @S9S_MB_2U_LIB.S9S_MB_2U(SCH_1):M_A_CPU0_SA_CB(3)
 E60 M_A_CPU0_SA_CB<2> DDR0_SA_ECC2 @S9S_MB_2U_LIB.S9S_MB_2U(SCH_1):M_A_CPU0_SA_CB(2)
 B59 M_A_CPU0_SA_CB<1> DDR0_SA_ECC1 @S9S_MB_2U_LIB.S9S_MB_2U(SCH_1):M_A_CPU0_SA_CB(1)
 C60 M_A_CPU0_SA_CB<0> DDR0_SA_ECC0 @S9S_MB_2U_LIB.S9S_MB_2U(SCH_1):M_A_CPU0_SA_CB(0)
 E48 M_A_CPU0_SA_PAR DDR0_SA_PAR @S9S_MB_2U_LIB.S9S_MB_2U(SCH_1):M_A_CPU0_SA_PAR
 A39 M_A_CPU0_SB_CA<6> DDR0_SB_CA6 @S9S_MB_2U_LIB.S9S_MB_2U(SCH_1):M_A_CPU0_SB_CA(6)
 F40 M_A_CPU0_SB_CA<5> DDR0_SB_CA5 @S9S_MB_2U_LIB.S9S_MB_2U(SCH_1):M_A_CPU0_SB_CA(5)
 B40 M_A_CPU0_SB_CA<4> DDR0_SB_CA4 @S9S_MB_2U_LIB.S9S_MB_2U(SCH_1):M_A_CPU0_SB_CA(4)
 E41 M_A_CPU0_SB_CA<3> DDR0_SB_CA3 @S9S_MB_2U_LIB.S9S_MB_2U(SCH_1):M_A_CPU0_SB_CA(3)
 C41 M_A_CPU0_SB_CA<2> DDR0_SB_CA2 @S9S_MB_2U_LIB.S9S_MB_2U(SCH_1):M_A_CPU0_SB_CA(2)
 F44 M_A_CPU0_SB_CA<1> DDR0_SB_CA1 @S9S_MB_2U_LIB.S9S_MB_2U(SCH_1):M_A_CPU0_SB_CA(1)
 E43 M_A_CPU0_SB_CA<0> DDR0_SB_CA0 @S9S_MB_2U_LIB.S9S_MB_2U(SCH_1):M_A_CPU0_SB_CA(0)
 E37 M_A_CPU0_SB_CS_N<3> DDR0_SB_CS_N3 @S9S_MB_2U_LIB.S9S_MB_2U(SCH_1):M_A_CPU0_SB_CS_N(3)
 F38 M_A_CPU0_SB_CS_N<2> DDR0_SB_CS_N2 @S9S_MB_2U_LIB.S9S_MB_2U(SCH_1):M_A_CPU0_SB_CS_N(2)
 C37 M_A_CPU0_SB_CS_N<1> DDR0_SB_CS_N1 @S9S_MB_2U_LIB.S9S_MB_2U(SCH_1):M_A_CPU0_SB_CS_N(1)
 B38 M_A_CPU0_SB_CS_N<0> DDR0_SB_CS_N0 @S9S_MB_2U_LIB.S9S_MB_2U(SCH_1):M_A_CPU0_SB_CS_N(0)
  E7 M_A_CPU0_SB_DQ<31> DDR0_SB_DQ31 @S9S_MB_2U_LIB.S9S_MB_2U(SCH_1):M_A_CPU0_SB_DQ(31)
  F8 M_A_CPU0_SB_DQ<30> DDR0_SB_DQ30 @S9S_MB_2U_LIB.S9S_MB_2U(SCH_1):M_A_CPU0_SB_DQ(30)
  C7 M_A_CPU0_SB_DQ<29> DDR0_SB_DQ29 @S9S_MB_2U_LIB.S9S_MB_2U(SCH_1):M_A_CPU0_SB_DQ(29)
  B8 M_A_CPU0_SB_DQ<28> DDR0_SB_DQ28 @S9S_MB_2U_LIB.S9S_MB_2U(SCH_1):M_A_CPU0_SB_DQ(28)
 F10 M_A_CPU0_SB_DQ<27> DDR0_SB_DQ27 @S9S_MB_2U_LIB.S9S_MB_2U(SCH_1):M_A_CPU0_SB_DQ(27)
 E11 M_A_CPU0_SB_DQ<26> DDR0_SB_DQ26 @S9S_MB_2U_LIB.S9S_MB_2U(SCH_1):M_A_CPU0_SB_DQ(26)
 B10 M_A_CPU0_SB_DQ<25> DDR0_SB_DQ25 @S9S_MB_2U_LIB.S9S_MB_2U(SCH_1):M_A_CPU0_SB_DQ(25)
 C11 M_A_CPU0_SB_DQ<24> DDR0_SB_DQ24 @S9S_MB_2U_LIB.S9S_MB_2U(SCH_1):M_A_CPU0_SB_DQ(24)
 E19 M_A_CPU0_SB_DQ<23> DDR0_SB_DQ23 @S9S_MB_2U_LIB.S9S_MB_2U(SCH_1):M_A_CPU0_SB_DQ(23)
 F20 M_A_CPU0_SB_DQ<22> DDR0_SB_DQ22 @S9S_MB_2U_LIB.S9S_MB_2U(SCH_1):M_A_CPU0_SB_DQ(22)
 C19 M_A_CPU0_SB_DQ<21> DDR0_SB_DQ21 @S9S_MB_2U_LIB.S9S_MB_2U(SCH_1):M_A_CPU0_SB_DQ(21)
 B20 M_A_CPU0_SB_DQ<20> DDR0_SB_DQ20 @S9S_MB_2U_LIB.S9S_MB_2U(SCH_1):M_A_CPU0_SB_DQ(20)
 F22 M_A_CPU0_SB_DQ<19> DDR0_SB_DQ19 @S9S_MB_2U_LIB.S9S_MB_2U(SCH_1):M_A_CPU0_SB_DQ(19)
 E23 M_A_CPU0_SB_DQ<18> DDR0_SB_DQ18 @S9S_MB_2U_LIB.S9S_MB_2U(SCH_1):M_A_CPU0_SB_DQ(18)
 B22 M_A_CPU0_SB_DQ<17> DDR0_SB_DQ17 @S9S_MB_2U_LIB.S9S_MB_2U(SCH_1):M_A_CPU0_SB_DQ(17)
 C23 M_A_CPU0_SB_DQ<16> DDR0_SB_DQ16 @S9S_MB_2U_LIB.S9S_MB_2U(SCH_1):M_A_CPU0_SB_DQ(16)
 E25 M_A_CPU0_SB_DQ<15> DDR0_SB_DQ15 @S9S_MB_2U_LIB.S9S_MB_2U(SCH_1):M_A_CPU0_SB_DQ(15)
 F26 M_A_CPU0_SB_DQ<14> DDR0_SB_DQ14 @S9S_MB_2U_LIB.S9S_MB_2U(SCH_1):M_A_CPU0_SB_DQ(14)
 C25 M_A_CPU0_SB_DQ<13> DDR0_SB_DQ13 @S9S_MB_2U_LIB.S9S_MB_2U(SCH_1):M_A_CPU0_SB_DQ(13)
 B26 M_A_CPU0_SB_DQ<12> DDR0_SB_DQ12 @S9S_MB_2U_LIB.S9S_MB_2U(SCH_1):M_A_CPU0_SB_DQ(12)
 F28 M_A_CPU0_SB_DQ<11> DDR0_SB_DQ11 @S9S_MB_2U_LIB.S9S_MB_2U(SCH_1):M_A_CPU0_SB_DQ(11)
 E29 M_A_CPU0_SB_DQ<10> DDR0_SB_DQ10 @S9S_MB_2U_LIB.S9S_MB_2U(SCH_1):M_A_CPU0_SB_DQ(10)
 B28 M_A_CPU0_SB_DQ<9> DDR0_SB_DQ9 @S9S_MB_2U_LIB.S9S_MB_2U(SCH_1):M_A_CPU0_SB_DQ(9)
 C29 M_A_CPU0_SB_DQ<8> DDR0_SB_DQ8 @S9S_MB_2U_LIB.S9S_MB_2U(SCH_1):M_A_CPU0_SB_DQ(8)
 M28 M_A_CPU0_SB_DQ<7> DDR0_SB_DQ7 @S9S_MB_2U_LIB.S9S_MB_2U(SCH_1):M_A_CPU0_SB_DQ(7)
 N29 M_A_CPU0_SB_DQ<6> DDR0_SB_DQ6 @S9S_MB_2U_LIB.S9S_MB_2U(SCH_1):M_A_CPU0_SB_DQ(6)
 K28 M_A_CPU0_SB_DQ<5> DDR0_SB_DQ5 @S9S_MB_2U_LIB.S9S_MB_2U(SCH_1):M_A_CPU0_SB_DQ(5)
 J29 M_A_CPU0_SB_DQ<4> DDR0_SB_DQ4 @S9S_MB_2U_LIB.S9S_MB_2U(SCH_1):M_A_CPU0_SB_DQ(4)
 N31 M_A_CPU0_SB_DQ<3> DDR0_SB_DQ3 @S9S_MB_2U_LIB.S9S_MB_2U(SCH_1):M_A_CPU0_SB_DQ(3)
 M32 M_A_CPU0_SB_DQ<2> DDR0_SB_DQ2 @S9S_MB_2U_LIB.S9S_MB_2U(SCH_1):M_A_CPU0_SB_DQ(2)
 J31 M_A_CPU0_SB_DQ<1> DDR0_SB_DQ1 @S9S_MB_2U_LIB.S9S_MB_2U(SCH_1):M_A_CPU0_SB_DQ(1)
 K32 M_A_CPU0_SB_DQ<0> DDR0_SB_DQ0 @S9S_MB_2U_LIB.S9S_MB_2U(SCH_1):M_A_CPU0_SB_DQ(0)
 A33 M_A_CPU0_SB_DQS_DN<9> DDR0_SB_DQS_DN9 @S9S_MB_2U_LIB.S9S_MB_2U(SCH_1):M_A_CPU0_SB_DQS_DN(9)
  G9 M_A_CPU0_SB_DQS_DN<8> DDR0_SB_DQS_DN8 @S9S_MB_2U_LIB.S9S_MB_2U(SCH_1):M_A_CPU0_SB_DQS_DN(8)
 G21 M_A_CPU0_SB_DQS_DN<7> DDR0_SB_DQS_DN7 @S9S_MB_2U_LIB.S9S_MB_2U(SCH_1):M_A_CPU0_SB_DQS_DN(7)
 G27 M_A_CPU0_SB_DQS_DN<6> DDR0_SB_DQS_DN6 @S9S_MB_2U_LIB.S9S_MB_2U(SCH_1):M_A_CPU0_SB_DQS_DN(6)
 M30 M_A_CPU0_SB_DQS_DN<5> DDR0_SB_DQS_DN5 @S9S_MB_2U_LIB.S9S_MB_2U(SCH_1):M_A_CPU0_SB_DQS_DN(5)
 G33 M_A_CPU0_SB_DQS_DN<4> DDR0_SB_DQS_DN4 @S9S_MB_2U_LIB.S9S_MB_2U(SCH_1):M_A_CPU0_SB_DQS_DN(4)
  A9 M_A_CPU0_SB_DQS_DN<3> DDR0_SB_DQS_DN3 @S9S_MB_2U_LIB.S9S_MB_2U(SCH_1):M_A_CPU0_SB_DQS_DN(3)
 A21 M_A_CPU0_SB_DQS_DN<2> DDR0_SB_DQS_DN2 @S9S_MB_2U_LIB.S9S_MB_2U(SCH_1):M_A_CPU0_SB_DQS_DN(2)
 A27 M_A_CPU0_SB_DQS_DN<1> DDR0_SB_DQS_DN1 @S9S_MB_2U_LIB.S9S_MB_2U(SCH_1):M_A_CPU0_SB_DQS_DN(1)
 H30 M_A_CPU0_SB_DQS_DN<0> DDR0_SB_DQS_DN0 @S9S_MB_2U_LIB.S9S_MB_2U(SCH_1):M_A_CPU0_SB_DQS_DN(0)
 C33 M_A_CPU0_SB_DQS_DP<9> DDR0_SB_DQS_DP9 @S9S_MB_2U_LIB.S9S_MB_2U(SCH_1):M_A_CPU0_SB_DQS_DP(9)
  E9 M_A_CPU0_SB_DQS_DP<8> DDR0_SB_DQS_DP8 @S9S_MB_2U_LIB.S9S_MB_2U(SCH_1):M_A_CPU0_SB_DQS_DP(8)
 E21 M_A_CPU0_SB_DQS_DP<7> DDR0_SB_DQS_DP7 @S9S_MB_2U_LIB.S9S_MB_2U(SCH_1):M_A_CPU0_SB_DQS_DP(7)
 E27 M_A_CPU0_SB_DQS_DP<6> DDR0_SB_DQS_DP6 @S9S_MB_2U_LIB.S9S_MB_2U(SCH_1):M_A_CPU0_SB_DQS_DP(6)
 P30 M_A_CPU0_SB_DQS_DP<5> DDR0_SB_DQS_DP5 @S9S_MB_2U_LIB.S9S_MB_2U(SCH_1):M_A_CPU0_SB_DQS_DP(5)
 E33 M_A_CPU0_SB_DQS_DP<4> DDR0_SB_DQS_DP4 @S9S_MB_2U_LIB.S9S_MB_2U(SCH_1):M_A_CPU0_SB_DQS_DP(4)
  C9 M_A_CPU0_SB_DQS_DP<3> DDR0_SB_DQS_DP3 @S9S_MB_2U_LIB.S9S_MB_2U(SCH_1):M_A_CPU0_SB_DQS_DP(3)
 C21 M_A_CPU0_SB_DQS_DP<2> DDR0_SB_DQS_DP2 @S9S_MB_2U_LIB.S9S_MB_2U(SCH_1):M_A_CPU0_SB_DQS_DP(2)
 C27 M_A_CPU0_SB_DQS_DP<1> DDR0_SB_DQS_DP1 @S9S_MB_2U_LIB.S9S_MB_2U(SCH_1):M_A_CPU0_SB_DQS_DP(1)
 K30 M_A_CPU0_SB_DQS_DP<0> DDR0_SB_DQS_DP0 @S9S_MB_2U_LIB.S9S_MB_2U(SCH_1):M_A_CPU0_SB_DQS_DP(0)
 F34 M_A_CPU0_SB_CB<7> DDR0_SB_ECC7 @S9S_MB_2U_LIB.S9S_MB_2U(SCH_1):M_A_CPU0_SB_CB(7)
 E35 M_A_CPU0_SB_CB<6> DDR0_SB_ECC6 @S9S_MB_2U_LIB.S9S_MB_2U(SCH_1):M_A_CPU0_SB_CB(6)
 B34 M_A_CPU0_SB_CB<5> DDR0_SB_ECC5 @S9S_MB_2U_LIB.S9S_MB_2U(SCH_1):M_A_CPU0_SB_CB(5)
 C35 M_A_CPU0_SB_CB<4> DDR0_SB_ECC4 @S9S_MB_2U_LIB.S9S_MB_2U(SCH_1):M_A_CPU0_SB_CB(4)
 E31 M_A_CPU0_SB_CB<3> DDR0_SB_ECC3 @S9S_MB_2U_LIB.S9S_MB_2U(SCH_1):M_A_CPU0_SB_CB(3)
 F32 M_A_CPU0_SB_CB<2> DDR0_SB_ECC2 @S9S_MB_2U_LIB.S9S_MB_2U(SCH_1):M_A_CPU0_SB_CB(2)
 C31 M_A_CPU0_SB_CB<1> DDR0_SB_ECC1 @S9S_MB_2U_LIB.S9S_MB_2U(SCH_1):M_A_CPU0_SB_CB(1)
 B32 M_A_CPU0_SB_CB<0> DDR0_SB_ECC0 @S9S_MB_2U_LIB.S9S_MB_2U(SCH_1):M_A_CPU0_SB_CB(0)
 G39 M_A_CPU0_SB_PAR DDR0_SB_PAR @S9S_MB_2U_LIB.S9S_MB_2U(SCH_1):M_A_CPU0_SB_PAR


DRAWING: @S9S_MB_2U_LIB.S9S_MB_2U(SCH_1):PAGE21 

SOCKET4677_AZIF0045P001C01CS-SA  I169  U2
AV49 M_B_CPU0_ALERT_N DDR1_ALERT_N @S9S_MB_2U_LIB.S9S_MB_2U(SCH_1):M_B_CPU0_ALERT_N
AK47 M_B_CPU0_SA_RSP<1> DDR1_A_RSP1 @S9S_MB_2U_LIB.S9S_MB_2U(SCH_1):M_B_CPU0_SA_RSP(1)
AL48 M_B_CPU0_SA_RSP<0> DDR1_A_RSP0 @S9S_MB_2U_LIB.S9S_MB_2U(SCH_1):M_B_CPU0_SA_RSP(0)
AP47 M_B_CPU0_SB_RSP<1> DDR1_B_RSP1 @S9S_MB_2U_LIB.S9S_MB_2U(SCH_1):M_B_CPU0_SB_RSP(1)
AN48 M_B_CPU0_SB_RSP<0> DDR1_B_RSP0 @S9S_MB_2U_LIB.S9S_MB_2U(SCH_1):M_B_CPU0_SB_RSP(0)
 W45 M_B_CPU0_CLK_DN<1> DDR1_CLK_DN1 @S9S_MB_2U_LIB.S9S_MB_2U(SCH_1):M_B_CPU0_CLK_DN(1)
 R45 M_B_CPU0_CLK_DN<0> DDR1_CLK_DN0 @S9S_MB_2U_LIB.S9S_MB_2U(SCH_1):M_B_CPU0_CLK_DN(0)
AA45 M_B_CPU0_CLK_DP<1> DDR1_CLK_DP1 @S9S_MB_2U_LIB.S9S_MB_2U(SCH_1):M_B_CPU0_CLK_DP(1)
 U45 M_B_CPU0_CLK_DP<0> DDR1_CLK_DP0 @S9S_MB_2U_LIB.S9S_MB_2U(SCH_1):M_B_CPU0_CLK_DP(0)
 Y44 M_B_CPU0_SA_CA<6> DDR1_SA_CA6 @S9S_MB_2U_LIB.S9S_MB_2U(SCH_1):M_B_CPU0_SA_CA(6)
 M47 M_B_CPU0_SA_CA<5> DDR1_SA_CA5 @S9S_MB_2U_LIB.S9S_MB_2U(SCH_1):M_B_CPU0_SA_CA(5)
 K47 M_B_CPU0_SA_CA<4> DDR1_SA_CA4 @S9S_MB_2U_LIB.S9S_MB_2U(SCH_1):M_B_CPU0_SA_CA(4)
 N48 M_B_CPU0_SA_CA<3> DDR1_SA_CA3 @S9S_MB_2U_LIB.S9S_MB_2U(SCH_1):M_B_CPU0_SA_CA(3)
 J48 M_B_CPU0_SA_CA<2> DDR1_SA_CA2 @S9S_MB_2U_LIB.S9S_MB_2U(SCH_1):M_B_CPU0_SA_CA(2)
 P49 M_B_CPU0_SA_CA<1> DDR1_SA_CA1 @S9S_MB_2U_LIB.S9S_MB_2U(SCH_1):M_B_CPU0_SA_CA(1)
 H49 M_B_CPU0_SA_CA<0> DDR1_SA_CA0 @S9S_MB_2U_LIB.S9S_MB_2U(SCH_1):M_B_CPU0_SA_CA(0)
 N50 M_B_CPU0_SA_CS_N<3> DDR1_SA_CS_N3 @S9S_MB_2U_LIB.S9S_MB_2U(SCH_1):M_B_CPU0_SA_CS_N(3)
 M51 M_B_CPU0_SA_CS_N<2> DDR1_SA_CS_N2 @S9S_MB_2U_LIB.S9S_MB_2U(SCH_1):M_B_CPU0_SA_CS_N(2)
 J50 M_B_CPU0_SA_CS_N<1> DDR1_SA_CS_N1 @S9S_MB_2U_LIB.S9S_MB_2U(SCH_1):M_B_CPU0_SA_CS_N(1)
 K51 M_B_CPU0_SA_CS_N<0> DDR1_SA_CS_N0 @S9S_MB_2U_LIB.S9S_MB_2U(SCH_1):M_B_CPU0_SA_CS_N(0)
 W56 M_B_CPU0_SA_DQ<31> DDR1_SA_DQ31 @S9S_MB_2U_LIB.S9S_MB_2U(SCH_1):M_B_CPU0_SA_DQ(31)
 Y57 M_B_CPU0_SA_DQ<30> DDR1_SA_DQ30 @S9S_MB_2U_LIB.S9S_MB_2U(SCH_1):M_B_CPU0_SA_DQ(30)
 U56 M_B_CPU0_SA_DQ<29> DDR1_SA_DQ29 @S9S_MB_2U_LIB.S9S_MB_2U(SCH_1):M_B_CPU0_SA_DQ(29)
 T57 M_B_CPU0_SA_DQ<28> DDR1_SA_DQ28 @S9S_MB_2U_LIB.S9S_MB_2U(SCH_1):M_B_CPU0_SA_DQ(28)
 Y59 M_B_CPU0_SA_DQ<27> DDR1_SA_DQ27 @S9S_MB_2U_LIB.S9S_MB_2U(SCH_1):M_B_CPU0_SA_DQ(27)
 W60 M_B_CPU0_SA_DQ<26> DDR1_SA_DQ26 @S9S_MB_2U_LIB.S9S_MB_2U(SCH_1):M_B_CPU0_SA_DQ(26)
 T59 M_B_CPU0_SA_DQ<25> DDR1_SA_DQ25 @S9S_MB_2U_LIB.S9S_MB_2U(SCH_1):M_B_CPU0_SA_DQ(25)
 U60 M_B_CPU0_SA_DQ<24> DDR1_SA_DQ24 @S9S_MB_2U_LIB.S9S_MB_2U(SCH_1):M_B_CPU0_SA_DQ(24)
 M59 M_B_CPU0_SA_DQ<23> DDR1_SA_DQ23 @S9S_MB_2U_LIB.S9S_MB_2U(SCH_1):M_B_CPU0_SA_DQ(23)
 N60 M_B_CPU0_SA_DQ<22> DDR1_SA_DQ22 @S9S_MB_2U_LIB.S9S_MB_2U(SCH_1):M_B_CPU0_SA_DQ(22)
 K59 M_B_CPU0_SA_DQ<21> DDR1_SA_DQ21 @S9S_MB_2U_LIB.S9S_MB_2U(SCH_1):M_B_CPU0_SA_DQ(21)
 J60 M_B_CPU0_SA_DQ<20> DDR1_SA_DQ20 @S9S_MB_2U_LIB.S9S_MB_2U(SCH_1):M_B_CPU0_SA_DQ(20)
 N62 M_B_CPU0_SA_DQ<19> DDR1_SA_DQ19 @S9S_MB_2U_LIB.S9S_MB_2U(SCH_1):M_B_CPU0_SA_DQ(19)
 M63 M_B_CPU0_SA_DQ<18> DDR1_SA_DQ18 @S9S_MB_2U_LIB.S9S_MB_2U(SCH_1):M_B_CPU0_SA_DQ(18)
 J62 M_B_CPU0_SA_DQ<17> DDR1_SA_DQ17 @S9S_MB_2U_LIB.S9S_MB_2U(SCH_1):M_B_CPU0_SA_DQ(17)
 K63 M_B_CPU0_SA_DQ<16> DDR1_SA_DQ16 @S9S_MB_2U_LIB.S9S_MB_2U(SCH_1):M_B_CPU0_SA_DQ(16)
 W68 M_B_CPU0_SA_DQ<15> DDR1_SA_DQ15 @S9S_MB_2U_LIB.S9S_MB_2U(SCH_1):M_B_CPU0_SA_DQ(15)
 Y69 M_B_CPU0_SA_DQ<14> DDR1_SA_DQ14 @S9S_MB_2U_LIB.S9S_MB_2U(SCH_1):M_B_CPU0_SA_DQ(14)
 U68 M_B_CPU0_SA_DQ<13> DDR1_SA_DQ13 @S9S_MB_2U_LIB.S9S_MB_2U(SCH_1):M_B_CPU0_SA_DQ(13)
 T69 M_B_CPU0_SA_DQ<12> DDR1_SA_DQ12 @S9S_MB_2U_LIB.S9S_MB_2U(SCH_1):M_B_CPU0_SA_DQ(12)
 Y71 M_B_CPU0_SA_DQ<11> DDR1_SA_DQ11 @S9S_MB_2U_LIB.S9S_MB_2U(SCH_1):M_B_CPU0_SA_DQ(11)
 W72 M_B_CPU0_SA_DQ<10> DDR1_SA_DQ10 @S9S_MB_2U_LIB.S9S_MB_2U(SCH_1):M_B_CPU0_SA_DQ(10)
 T71 M_B_CPU0_SA_DQ<9> DDR1_SA_DQ9 @S9S_MB_2U_LIB.S9S_MB_2U(SCH_1):M_B_CPU0_SA_DQ(9)
 U72 M_B_CPU0_SA_DQ<8> DDR1_SA_DQ8 @S9S_MB_2U_LIB.S9S_MB_2U(SCH_1):M_B_CPU0_SA_DQ(8)
 M71 M_B_CPU0_SA_DQ<7> DDR1_SA_DQ7 @S9S_MB_2U_LIB.S9S_MB_2U(SCH_1):M_B_CPU0_SA_DQ(7)
 N72 M_B_CPU0_SA_DQ<6> DDR1_SA_DQ6 @S9S_MB_2U_LIB.S9S_MB_2U(SCH_1):M_B_CPU0_SA_DQ(6)
 K71 M_B_CPU0_SA_DQ<5> DDR1_SA_DQ5 @S9S_MB_2U_LIB.S9S_MB_2U(SCH_1):M_B_CPU0_SA_DQ(5)
 J72 M_B_CPU0_SA_DQ<4> DDR1_SA_DQ4 @S9S_MB_2U_LIB.S9S_MB_2U(SCH_1):M_B_CPU0_SA_DQ(4)
 N74 M_B_CPU0_SA_DQ<3> DDR1_SA_DQ3 @S9S_MB_2U_LIB.S9S_MB_2U(SCH_1):M_B_CPU0_SA_DQ(3)
 M75 M_B_CPU0_SA_DQ<2> DDR1_SA_DQ2 @S9S_MB_2U_LIB.S9S_MB_2U(SCH_1):M_B_CPU0_SA_DQ(2)
 J74 M_B_CPU0_SA_DQ<1> DDR1_SA_DQ1 @S9S_MB_2U_LIB.S9S_MB_2U(SCH_1):M_B_CPU0_SA_DQ(1)
 K75 M_B_CPU0_SA_DQ<0> DDR1_SA_DQ0 @S9S_MB_2U_LIB.S9S_MB_2U(SCH_1):M_B_CPU0_SA_DQ(0)
 M55 M_B_CPU0_SA_DQS_DN<9> DDR1_SA_DQS_DN9 @S9S_MB_2U_LIB.S9S_MB_2U(SCH_1):M_B_CPU0_SA_DQS_DN(9)
AA58 M_B_CPU0_SA_DQS_DN<8> DDR1_SA_DQS_DN8 @S9S_MB_2U_LIB.S9S_MB_2U(SCH_1):M_B_CPU0_SA_DQS_DN(8)
 M61 M_B_CPU0_SA_DQS_DN<7> DDR1_SA_DQS_DN7 @S9S_MB_2U_LIB.S9S_MB_2U(SCH_1):M_B_CPU0_SA_DQS_DN(7)
AA70 M_B_CPU0_SA_DQS_DN<6> DDR1_SA_DQS_DN6 @S9S_MB_2U_LIB.S9S_MB_2U(SCH_1):M_B_CPU0_SA_DQS_DN(6)
 M73 M_B_CPU0_SA_DQS_DN<5> DDR1_SA_DQS_DN5 @S9S_MB_2U_LIB.S9S_MB_2U(SCH_1):M_B_CPU0_SA_DQS_DN(5)
 H55 M_B_CPU0_SA_DQS_DN<4> DDR1_SA_DQS_DN4 @S9S_MB_2U_LIB.S9S_MB_2U(SCH_1):M_B_CPU0_SA_DQS_DN(4)
 R58 M_B_CPU0_SA_DQS_DN<3> DDR1_SA_DQS_DN3 @S9S_MB_2U_LIB.S9S_MB_2U(SCH_1):M_B_CPU0_SA_DQS_DN(3)
 H61 M_B_CPU0_SA_DQS_DN<2> DDR1_SA_DQS_DN2 @S9S_MB_2U_LIB.S9S_MB_2U(SCH_1):M_B_CPU0_SA_DQS_DN(2)
 R70 M_B_CPU0_SA_DQS_DN<1> DDR1_SA_DQS_DN1 @S9S_MB_2U_LIB.S9S_MB_2U(SCH_1):M_B_CPU0_SA_DQS_DN(1)
 H73 M_B_CPU0_SA_DQS_DN<0> DDR1_SA_DQS_DN0 @S9S_MB_2U_LIB.S9S_MB_2U(SCH_1):M_B_CPU0_SA_DQS_DN(0)
 P55 M_B_CPU0_SA_DQS_DP<9> DDR1_SA_DQS_DP9 @S9S_MB_2U_LIB.S9S_MB_2U(SCH_1):M_B_CPU0_SA_DQS_DP(9)
 W58 M_B_CPU0_SA_DQS_DP<8> DDR1_SA_DQS_DP8 @S9S_MB_2U_LIB.S9S_MB_2U(SCH_1):M_B_CPU0_SA_DQS_DP(8)
 P61 M_B_CPU0_SA_DQS_DP<7> DDR1_SA_DQS_DP7 @S9S_MB_2U_LIB.S9S_MB_2U(SCH_1):M_B_CPU0_SA_DQS_DP(7)
 W70 M_B_CPU0_SA_DQS_DP<6> DDR1_SA_DQS_DP6 @S9S_MB_2U_LIB.S9S_MB_2U(SCH_1):M_B_CPU0_SA_DQS_DP(6)
 P73 M_B_CPU0_SA_DQS_DP<5> DDR1_SA_DQS_DP5 @S9S_MB_2U_LIB.S9S_MB_2U(SCH_1):M_B_CPU0_SA_DQS_DP(5)
 K55 M_B_CPU0_SA_DQS_DP<4> DDR1_SA_DQS_DP4 @S9S_MB_2U_LIB.S9S_MB_2U(SCH_1):M_B_CPU0_SA_DQS_DP(4)
 U58 M_B_CPU0_SA_DQS_DP<3> DDR1_SA_DQS_DP3 @S9S_MB_2U_LIB.S9S_MB_2U(SCH_1):M_B_CPU0_SA_DQS_DP(3)
 K61 M_B_CPU0_SA_DQS_DP<2> DDR1_SA_DQS_DP2 @S9S_MB_2U_LIB.S9S_MB_2U(SCH_1):M_B_CPU0_SA_DQS_DP(2)
 U70 M_B_CPU0_SA_DQS_DP<1> DDR1_SA_DQS_DP1 @S9S_MB_2U_LIB.S9S_MB_2U(SCH_1):M_B_CPU0_SA_DQS_DP(1)
 K73 M_B_CPU0_SA_DQS_DP<0> DDR1_SA_DQS_DP0 @S9S_MB_2U_LIB.S9S_MB_2U(SCH_1):M_B_CPU0_SA_DQS_DP(0)
 M53 M_B_CPU0_SA_CB<7> DDR1_SA_ECC7 @S9S_MB_2U_LIB.S9S_MB_2U(SCH_1):M_B_CPU0_SA_CB(7)
 N54 M_B_CPU0_SA_CB<6> DDR1_SA_ECC6 @S9S_MB_2U_LIB.S9S_MB_2U(SCH_1):M_B_CPU0_SA_CB(6)
 K53 M_B_CPU0_SA_CB<5> DDR1_SA_ECC5 @S9S_MB_2U_LIB.S9S_MB_2U(SCH_1):M_B_CPU0_SA_CB(5)
 J54 M_B_CPU0_SA_CB<4> DDR1_SA_ECC4 @S9S_MB_2U_LIB.S9S_MB_2U(SCH_1):M_B_CPU0_SA_CB(4)
 N56 M_B_CPU0_SA_CB<3> DDR1_SA_ECC3 @S9S_MB_2U_LIB.S9S_MB_2U(SCH_1):M_B_CPU0_SA_CB(3)
 M57 M_B_CPU0_SA_CB<2> DDR1_SA_ECC2 @S9S_MB_2U_LIB.S9S_MB_2U(SCH_1):M_B_CPU0_SA_CB(2)
 J56 M_B_CPU0_SA_CB<1> DDR1_SA_ECC1 @S9S_MB_2U_LIB.S9S_MB_2U(SCH_1):M_B_CPU0_SA_CB(1)
 K57 M_B_CPU0_SA_CB<0> DDR1_SA_ECC0 @S9S_MB_2U_LIB.S9S_MB_2U(SCH_1):M_B_CPU0_SA_CB(0)
 W43 M_B_CPU0_SA_PAR DDR1_SA_PAR @S9S_MB_2U_LIB.S9S_MB_2U(SCH_1):M_B_CPU0_SA_PAR
 H42 M_B_CPU0_SB_CA<6> DDR1_SB_CA6 @S9S_MB_2U_LIB.S9S_MB_2U(SCH_1):M_B_CPU0_SB_CA(6)
 N43 M_B_CPU0_SB_CA<5> DDR1_SB_CA5 @S9S_MB_2U_LIB.S9S_MB_2U(SCH_1):M_B_CPU0_SB_CA(5)
 J43 M_B_CPU0_SB_CA<4> DDR1_SB_CA4 @S9S_MB_2U_LIB.S9S_MB_2U(SCH_1):M_B_CPU0_SB_CA(4)
 M44 M_B_CPU0_SB_CA<3> DDR1_SB_CA3 @S9S_MB_2U_LIB.S9S_MB_2U(SCH_1):M_B_CPU0_SB_CA(3)
 K44 M_B_CPU0_SB_CA<2> DDR1_SB_CA2 @S9S_MB_2U_LIB.S9S_MB_2U(SCH_1):M_B_CPU0_SB_CA(2)
 U43 M_B_CPU0_SB_CA<1> DDR1_SB_CA1 @S9S_MB_2U_LIB.S9S_MB_2U(SCH_1):M_B_CPU0_SB_CA(1)
 T44 M_B_CPU0_SB_CA<0> DDR1_SB_CA0 @S9S_MB_2U_LIB.S9S_MB_2U(SCH_1):M_B_CPU0_SB_CA(0)
 M40 M_B_CPU0_SB_CS_N<3> DDR1_SB_CS_N3 @S9S_MB_2U_LIB.S9S_MB_2U(SCH_1):M_B_CPU0_SB_CS_N(3)
 N41 M_B_CPU0_SB_CS_N<2> DDR1_SB_CS_N2 @S9S_MB_2U_LIB.S9S_MB_2U(SCH_1):M_B_CPU0_SB_CS_N(2)
 K40 M_B_CPU0_SB_CS_N<1> DDR1_SB_CS_N1 @S9S_MB_2U_LIB.S9S_MB_2U(SCH_1):M_B_CPU0_SB_CS_N(1)
 J41 M_B_CPU0_SB_CS_N<0> DDR1_SB_CS_N0 @S9S_MB_2U_LIB.S9S_MB_2U(SCH_1):M_B_CPU0_SB_CS_N(0)
 F14 M_B_CPU0_SB_DQ<31> DDR1_SB_DQ31 @S9S_MB_2U_LIB.S9S_MB_2U(SCH_1):M_B_CPU0_SB_DQ(31)
 B14 M_B_CPU0_SB_DQ<30> DDR1_SB_DQ30 @S9S_MB_2U_LIB.S9S_MB_2U(SCH_1):M_B_CPU0_SB_DQ(30)
 E13 M_B_CPU0_SB_DQ<29> DDR1_SB_DQ29 @S9S_MB_2U_LIB.S9S_MB_2U(SCH_1):M_B_CPU0_SB_DQ(29)
 C13 M_B_CPU0_SB_DQ<28> DDR1_SB_DQ28 @S9S_MB_2U_LIB.S9S_MB_2U(SCH_1):M_B_CPU0_SB_DQ(28)
 F16 M_B_CPU0_SB_DQ<27> DDR1_SB_DQ27 @S9S_MB_2U_LIB.S9S_MB_2U(SCH_1):M_B_CPU0_SB_DQ(27)
 E17 M_B_CPU0_SB_DQ<26> DDR1_SB_DQ26 @S9S_MB_2U_LIB.S9S_MB_2U(SCH_1):M_B_CPU0_SB_DQ(26)
 B16 M_B_CPU0_SB_DQ<25> DDR1_SB_DQ25 @S9S_MB_2U_LIB.S9S_MB_2U(SCH_1):M_B_CPU0_SB_DQ(25)
 C17 M_B_CPU0_SB_DQ<24> DDR1_SB_DQ24 @S9S_MB_2U_LIB.S9S_MB_2U(SCH_1):M_B_CPU0_SB_DQ(24)
 M16 M_B_CPU0_SB_DQ<23> DDR1_SB_DQ23 @S9S_MB_2U_LIB.S9S_MB_2U(SCH_1):M_B_CPU0_SB_DQ(23)
 N17 M_B_CPU0_SB_DQ<22> DDR1_SB_DQ22 @S9S_MB_2U_LIB.S9S_MB_2U(SCH_1):M_B_CPU0_SB_DQ(22)
 K16 M_B_CPU0_SB_DQ<21> DDR1_SB_DQ21 @S9S_MB_2U_LIB.S9S_MB_2U(SCH_1):M_B_CPU0_SB_DQ(21)
 J17 M_B_CPU0_SB_DQ<20> DDR1_SB_DQ20 @S9S_MB_2U_LIB.S9S_MB_2U(SCH_1):M_B_CPU0_SB_DQ(20)
 N19 M_B_CPU0_SB_DQ<19> DDR1_SB_DQ19 @S9S_MB_2U_LIB.S9S_MB_2U(SCH_1):M_B_CPU0_SB_DQ(19)
 M20 M_B_CPU0_SB_DQ<18> DDR1_SB_DQ18 @S9S_MB_2U_LIB.S9S_MB_2U(SCH_1):M_B_CPU0_SB_DQ(18)
 J19 M_B_CPU0_SB_DQ<17> DDR1_SB_DQ17 @S9S_MB_2U_LIB.S9S_MB_2U(SCH_1):M_B_CPU0_SB_DQ(17)
 K20 M_B_CPU0_SB_DQ<16> DDR1_SB_DQ16 @S9S_MB_2U_LIB.S9S_MB_2U(SCH_1):M_B_CPU0_SB_DQ(16)
 M22 M_B_CPU0_SB_DQ<15> DDR1_SB_DQ15 @S9S_MB_2U_LIB.S9S_MB_2U(SCH_1):M_B_CPU0_SB_DQ(15)
 N23 M_B_CPU0_SB_DQ<14> DDR1_SB_DQ14 @S9S_MB_2U_LIB.S9S_MB_2U(SCH_1):M_B_CPU0_SB_DQ(14)
 K22 M_B_CPU0_SB_DQ<13> DDR1_SB_DQ13 @S9S_MB_2U_LIB.S9S_MB_2U(SCH_1):M_B_CPU0_SB_DQ(13)
 J23 M_B_CPU0_SB_DQ<12> DDR1_SB_DQ12 @S9S_MB_2U_LIB.S9S_MB_2U(SCH_1):M_B_CPU0_SB_DQ(12)
 N25 M_B_CPU0_SB_DQ<11> DDR1_SB_DQ11 @S9S_MB_2U_LIB.S9S_MB_2U(SCH_1):M_B_CPU0_SB_DQ(11)
 M26 M_B_CPU0_SB_DQ<10> DDR1_SB_DQ10 @S9S_MB_2U_LIB.S9S_MB_2U(SCH_1):M_B_CPU0_SB_DQ(10)
 J25 M_B_CPU0_SB_DQ<9> DDR1_SB_DQ9 @S9S_MB_2U_LIB.S9S_MB_2U(SCH_1):M_B_CPU0_SB_DQ(9)
 K26 M_B_CPU0_SB_DQ<8> DDR1_SB_DQ8 @S9S_MB_2U_LIB.S9S_MB_2U(SCH_1):M_B_CPU0_SB_DQ(8)
 W25 M_B_CPU0_SB_DQ<7> DDR1_SB_DQ7 @S9S_MB_2U_LIB.S9S_MB_2U(SCH_1):M_B_CPU0_SB_DQ(7)
 Y26 M_B_CPU0_SB_DQ<6> DDR1_SB_DQ6 @S9S_MB_2U_LIB.S9S_MB_2U(SCH_1):M_B_CPU0_SB_DQ(6)
 U25 M_B_CPU0_SB_DQ<5> DDR1_SB_DQ5 @S9S_MB_2U_LIB.S9S_MB_2U(SCH_1):M_B_CPU0_SB_DQ(5)
 T26 M_B_CPU0_SB_DQ<4> DDR1_SB_DQ4 @S9S_MB_2U_LIB.S9S_MB_2U(SCH_1):M_B_CPU0_SB_DQ(4)
 Y28 M_B_CPU0_SB_DQ<3> DDR1_SB_DQ3 @S9S_MB_2U_LIB.S9S_MB_2U(SCH_1):M_B_CPU0_SB_DQ(3)
 W29 M_B_CPU0_SB_DQ<2> DDR1_SB_DQ2 @S9S_MB_2U_LIB.S9S_MB_2U(SCH_1):M_B_CPU0_SB_DQ(2)
 T28 M_B_CPU0_SB_DQ<1> DDR1_SB_DQ1 @S9S_MB_2U_LIB.S9S_MB_2U(SCH_1):M_B_CPU0_SB_DQ(1)
 U29 M_B_CPU0_SB_DQ<0> DDR1_SB_DQ0 @S9S_MB_2U_LIB.S9S_MB_2U(SCH_1):M_B_CPU0_SB_DQ(0)
 K36 M_B_CPU0_SB_DQS_DN<9> DDR1_SB_DQS_DN9 @S9S_MB_2U_LIB.S9S_MB_2U(SCH_1):M_B_CPU0_SB_DQS_DN(9)
 E15 M_B_CPU0_SB_DQS_DN<8> DDR1_SB_DQS_DN8 @S9S_MB_2U_LIB.S9S_MB_2U(SCH_1):M_B_CPU0_SB_DQS_DN(8)
 M18 M_B_CPU0_SB_DQS_DN<7> DDR1_SB_DQS_DN7 @S9S_MB_2U_LIB.S9S_MB_2U(SCH_1):M_B_CPU0_SB_DQS_DN(7)
 M24 M_B_CPU0_SB_DQS_DN<6> DDR1_SB_DQS_DN6 @S9S_MB_2U_LIB.S9S_MB_2U(SCH_1):M_B_CPU0_SB_DQS_DN(6)
 W27 M_B_CPU0_SB_DQS_DN<5> DDR1_SB_DQS_DN5 @S9S_MB_2U_LIB.S9S_MB_2U(SCH_1):M_B_CPU0_SB_DQS_DN(5)
 P36 M_B_CPU0_SB_DQS_DN<4> DDR1_SB_DQS_DN4 @S9S_MB_2U_LIB.S9S_MB_2U(SCH_1):M_B_CPU0_SB_DQS_DN(4)
 A15 M_B_CPU0_SB_DQS_DN<3> DDR1_SB_DQS_DN3 @S9S_MB_2U_LIB.S9S_MB_2U(SCH_1):M_B_CPU0_SB_DQS_DN(3)
 H18 M_B_CPU0_SB_DQS_DN<2> DDR1_SB_DQS_DN2 @S9S_MB_2U_LIB.S9S_MB_2U(SCH_1):M_B_CPU0_SB_DQS_DN(2)
 H24 M_B_CPU0_SB_DQS_DN<1> DDR1_SB_DQS_DN1 @S9S_MB_2U_LIB.S9S_MB_2U(SCH_1):M_B_CPU0_SB_DQS_DN(1)
 R27 M_B_CPU0_SB_DQS_DN<0> DDR1_SB_DQS_DN0 @S9S_MB_2U_LIB.S9S_MB_2U(SCH_1):M_B_CPU0_SB_DQS_DN(0)
 H36 M_B_CPU0_SB_DQS_DP<9> DDR1_SB_DQS_DP9 @S9S_MB_2U_LIB.S9S_MB_2U(SCH_1):M_B_CPU0_SB_DQS_DP(9)
 G15 M_B_CPU0_SB_DQS_DP<8> DDR1_SB_DQS_DP8 @S9S_MB_2U_LIB.S9S_MB_2U(SCH_1):M_B_CPU0_SB_DQS_DP(8)
 P18 M_B_CPU0_SB_DQS_DP<7> DDR1_SB_DQS_DP7 @S9S_MB_2U_LIB.S9S_MB_2U(SCH_1):M_B_CPU0_SB_DQS_DP(7)
 P24 M_B_CPU0_SB_DQS_DP<6> DDR1_SB_DQS_DP6 @S9S_MB_2U_LIB.S9S_MB_2U(SCH_1):M_B_CPU0_SB_DQS_DP(6)
AA27 M_B_CPU0_SB_DQS_DP<5> DDR1_SB_DQS_DP5 @S9S_MB_2U_LIB.S9S_MB_2U(SCH_1):M_B_CPU0_SB_DQS_DP(5)
 M36 M_B_CPU0_SB_DQS_DP<4> DDR1_SB_DQS_DP4 @S9S_MB_2U_LIB.S9S_MB_2U(SCH_1):M_B_CPU0_SB_DQS_DP(4)
 C15 M_B_CPU0_SB_DQS_DP<3> DDR1_SB_DQS_DP3 @S9S_MB_2U_LIB.S9S_MB_2U(SCH_1):M_B_CPU0_SB_DQS_DP(3)
 K18 M_B_CPU0_SB_DQS_DP<2> DDR1_SB_DQS_DP2 @S9S_MB_2U_LIB.S9S_MB_2U(SCH_1):M_B_CPU0_SB_DQS_DP(2)
 K24 M_B_CPU0_SB_DQS_DP<1> DDR1_SB_DQS_DP1 @S9S_MB_2U_LIB.S9S_MB_2U(SCH_1):M_B_CPU0_SB_DQS_DP(1)
 U27 M_B_CPU0_SB_DQS_DP<0> DDR1_SB_DQS_DP0 @S9S_MB_2U_LIB.S9S_MB_2U(SCH_1):M_B_CPU0_SB_DQS_DP(0)
 N37 M_B_CPU0_SB_CB<7> DDR1_SB_ECC7 @S9S_MB_2U_LIB.S9S_MB_2U(SCH_1):M_B_CPU0_SB_CB(7)
 M38 M_B_CPU0_SB_CB<6> DDR1_SB_ECC6 @S9S_MB_2U_LIB.S9S_MB_2U(SCH_1):M_B_CPU0_SB_CB(6)
 J37 M_B_CPU0_SB_CB<5> DDR1_SB_ECC5 @S9S_MB_2U_LIB.S9S_MB_2U(SCH_1):M_B_CPU0_SB_CB(5)
 K38 M_B_CPU0_SB_CB<4> DDR1_SB_ECC4 @S9S_MB_2U_LIB.S9S_MB_2U(SCH_1):M_B_CPU0_SB_CB(4)
 M34 M_B_CPU0_SB_CB<3> DDR1_SB_ECC3 @S9S_MB_2U_LIB.S9S_MB_2U(SCH_1):M_B_CPU0_SB_CB(3)
 N35 M_B_CPU0_SB_CB<2> DDR1_SB_ECC2 @S9S_MB_2U_LIB.S9S_MB_2U(SCH_1):M_B_CPU0_SB_CB(2)
 K34 M_B_CPU0_SB_CB<1> DDR1_SB_ECC1 @S9S_MB_2U_LIB.S9S_MB_2U(SCH_1):M_B_CPU0_SB_CB(1)
 J35 M_B_CPU0_SB_CB<0> DDR1_SB_ECC0 @S9S_MB_2U_LIB.S9S_MB_2U(SCH_1):M_B_CPU0_SB_CB(0)
 P42 M_B_CPU0_SB_PAR DDR1_SB_PAR @S9S_MB_2U_LIB.S9S_MB_2U(SCH_1):M_B_CPU0_SB_PAR


DRAWING: @S9S_MB_2U_LIB.S9S_MB_2U(SCH_1):PAGE22 

SOCKET4677_AZIF0045P001C01CS-SA  I169  U2
AT47 M_C_CPU0_ALERT_N DDR2_ALERT_N @S9S_MB_2U_LIB.S9S_MB_2U(SCH_1):M_C_CPU0_ALERT_N
AD47 M_C_CPU0_SA_RSP<1> DDR2_A_RSP1 @S9S_MB_2U_LIB.S9S_MB_2U(SCH_1):M_C_CPU0_SA_RSP(1)
AC48 M_C_CPU0_SA_RSP<0> DDR2_A_RSP0 @S9S_MB_2U_LIB.S9S_MB_2U(SCH_1):M_C_CPU0_SA_RSP(0)
AF47 M_C_CPU0_SB_RSP<1> DDR2_B_RSP1 @S9S_MB_2U_LIB.S9S_MB_2U(SCH_1):M_C_CPU0_SB_RSP(1)
AG48 M_C_CPU0_SB_RSP<0> DDR2_B_RSP0 @S9S_MB_2U_LIB.S9S_MB_2U(SCH_1):M_C_CPU0_SB_RSP(0)
AF49 M_C_CPU0_CLK_DN<1> DDR2_CLK_DN1 @S9S_MB_2U_LIB.S9S_MB_2U(SCH_1):M_C_CPU0_CLK_DN(1)
AB49 M_C_CPU0_CLK_DN<0> DDR2_CLK_DN0 @S9S_MB_2U_LIB.S9S_MB_2U(SCH_1):M_C_CPU0_CLK_DN(0)
AH49 M_C_CPU0_CLK_DP<1> DDR2_CLK_DP1 @S9S_MB_2U_LIB.S9S_MB_2U(SCH_1):M_C_CPU0_CLK_DP(1)
AD49 M_C_CPU0_CLK_DP<0> DDR2_CLK_DP0 @S9S_MB_2U_LIB.S9S_MB_2U(SCH_1):M_C_CPU0_CLK_DP(0)
 U48 M_C_CPU0_SA_CA<6> DDR2_SA_CA6 @S9S_MB_2U_LIB.S9S_MB_2U(SCH_1):M_C_CPU0_SA_CA(6)
 W50 M_C_CPU0_SA_CA<5> DDR2_SA_CA5 @S9S_MB_2U_LIB.S9S_MB_2U(SCH_1):M_C_CPU0_SA_CA(5)
 U50 M_C_CPU0_SA_CA<4> DDR2_SA_CA4 @S9S_MB_2U_LIB.S9S_MB_2U(SCH_1):M_C_CPU0_SA_CA(4)
 Y51 M_C_CPU0_SA_CA<3> DDR2_SA_CA3 @S9S_MB_2U_LIB.S9S_MB_2U(SCH_1):M_C_CPU0_SA_CA(3)
 T51 M_C_CPU0_SA_CA<2> DDR2_SA_CA2 @S9S_MB_2U_LIB.S9S_MB_2U(SCH_1):M_C_CPU0_SA_CA(2)
AA52 M_C_CPU0_SA_CA<1> DDR2_SA_CA1 @S9S_MB_2U_LIB.S9S_MB_2U(SCH_1):M_C_CPU0_SA_CA(1)
 R52 M_C_CPU0_SA_CA<0> DDR2_SA_CA0 @S9S_MB_2U_LIB.S9S_MB_2U(SCH_1):M_C_CPU0_SA_CA(0)
 Y53 M_C_CPU0_SA_CS_N<3> DDR2_SA_CS_N3 @S9S_MB_2U_LIB.S9S_MB_2U(SCH_1):M_C_CPU0_SA_CS_N(3)
 W54 M_C_CPU0_SA_CS_N<2> DDR2_SA_CS_N2 @S9S_MB_2U_LIB.S9S_MB_2U(SCH_1):M_C_CPU0_SA_CS_N(2)
 T53 M_C_CPU0_SA_CS_N<1> DDR2_SA_CS_N1 @S9S_MB_2U_LIB.S9S_MB_2U(SCH_1):M_C_CPU0_SA_CS_N(1)
 U54 M_C_CPU0_SA_CS_N<0> DDR2_SA_CS_N0 @S9S_MB_2U_LIB.S9S_MB_2U(SCH_1):M_C_CPU0_SA_CS_N(0)
AF59 M_C_CPU0_SA_DQ<31> DDR2_SA_DQ31 @S9S_MB_2U_LIB.S9S_MB_2U(SCH_1):M_C_CPU0_SA_DQ(31)
AG60 M_C_CPU0_SA_DQ<30> DDR2_SA_DQ30 @S9S_MB_2U_LIB.S9S_MB_2U(SCH_1):M_C_CPU0_SA_DQ(30)
AD59 M_C_CPU0_SA_DQ<29> DDR2_SA_DQ29 @S9S_MB_2U_LIB.S9S_MB_2U(SCH_1):M_C_CPU0_SA_DQ(29)
AC60 M_C_CPU0_SA_DQ<28> DDR2_SA_DQ28 @S9S_MB_2U_LIB.S9S_MB_2U(SCH_1):M_C_CPU0_SA_DQ(28)
AG62 M_C_CPU0_SA_DQ<27> DDR2_SA_DQ27 @S9S_MB_2U_LIB.S9S_MB_2U(SCH_1):M_C_CPU0_SA_DQ(27)
AF63 M_C_CPU0_SA_DQ<26> DDR2_SA_DQ26 @S9S_MB_2U_LIB.S9S_MB_2U(SCH_1):M_C_CPU0_SA_DQ(26)
AC62 M_C_CPU0_SA_DQ<25> DDR2_SA_DQ25 @S9S_MB_2U_LIB.S9S_MB_2U(SCH_1):M_C_CPU0_SA_DQ(25)
AD63 M_C_CPU0_SA_DQ<24> DDR2_SA_DQ24 @S9S_MB_2U_LIB.S9S_MB_2U(SCH_1):M_C_CPU0_SA_DQ(24)
 W62 M_C_CPU0_SA_DQ<23> DDR2_SA_DQ23 @S9S_MB_2U_LIB.S9S_MB_2U(SCH_1):M_C_CPU0_SA_DQ(23)
 Y63 M_C_CPU0_SA_DQ<22> DDR2_SA_DQ22 @S9S_MB_2U_LIB.S9S_MB_2U(SCH_1):M_C_CPU0_SA_DQ(22)
 U62 M_C_CPU0_SA_DQ<21> DDR2_SA_DQ21 @S9S_MB_2U_LIB.S9S_MB_2U(SCH_1):M_C_CPU0_SA_DQ(21)
 T63 M_C_CPU0_SA_DQ<20> DDR2_SA_DQ20 @S9S_MB_2U_LIB.S9S_MB_2U(SCH_1):M_C_CPU0_SA_DQ(20)
 Y65 M_C_CPU0_SA_DQ<19> DDR2_SA_DQ19 @S9S_MB_2U_LIB.S9S_MB_2U(SCH_1):M_C_CPU0_SA_DQ(19)
 W66 M_C_CPU0_SA_DQ<18> DDR2_SA_DQ18 @S9S_MB_2U_LIB.S9S_MB_2U(SCH_1):M_C_CPU0_SA_DQ(18)
 T65 M_C_CPU0_SA_DQ<17> DDR2_SA_DQ17 @S9S_MB_2U_LIB.S9S_MB_2U(SCH_1):M_C_CPU0_SA_DQ(17)
 U66 M_C_CPU0_SA_DQ<16> DDR2_SA_DQ16 @S9S_MB_2U_LIB.S9S_MB_2U(SCH_1):M_C_CPU0_SA_DQ(16)
AF65 M_C_CPU0_SA_DQ<15> DDR2_SA_DQ15 @S9S_MB_2U_LIB.S9S_MB_2U(SCH_1):M_C_CPU0_SA_DQ(15)
AG66 M_C_CPU0_SA_DQ<14> DDR2_SA_DQ14 @S9S_MB_2U_LIB.S9S_MB_2U(SCH_1):M_C_CPU0_SA_DQ(14)
AD65 M_C_CPU0_SA_DQ<13> DDR2_SA_DQ13 @S9S_MB_2U_LIB.S9S_MB_2U(SCH_1):M_C_CPU0_SA_DQ(13)
AC66 M_C_CPU0_SA_DQ<12> DDR2_SA_DQ12 @S9S_MB_2U_LIB.S9S_MB_2U(SCH_1):M_C_CPU0_SA_DQ(12)
AG68 M_C_CPU0_SA_DQ<11> DDR2_SA_DQ11 @S9S_MB_2U_LIB.S9S_MB_2U(SCH_1):M_C_CPU0_SA_DQ(11)
AF69 M_C_CPU0_SA_DQ<10> DDR2_SA_DQ10 @S9S_MB_2U_LIB.S9S_MB_2U(SCH_1):M_C_CPU0_SA_DQ(10)
AC68 M_C_CPU0_SA_DQ<9> DDR2_SA_DQ9 @S9S_MB_2U_LIB.S9S_MB_2U(SCH_1):M_C_CPU0_SA_DQ(9)
AD69 M_C_CPU0_SA_DQ<8> DDR2_SA_DQ8 @S9S_MB_2U_LIB.S9S_MB_2U(SCH_1):M_C_CPU0_SA_DQ(8)
 W74 M_C_CPU0_SA_DQ<7> DDR2_SA_DQ7 @S9S_MB_2U_LIB.S9S_MB_2U(SCH_1):M_C_CPU0_SA_DQ(7)
 Y75 M_C_CPU0_SA_DQ<6> DDR2_SA_DQ6 @S9S_MB_2U_LIB.S9S_MB_2U(SCH_1):M_C_CPU0_SA_DQ(6)
 U74 M_C_CPU0_SA_DQ<5> DDR2_SA_DQ5 @S9S_MB_2U_LIB.S9S_MB_2U(SCH_1):M_C_CPU0_SA_DQ(5)
 T75 M_C_CPU0_SA_DQ<4> DDR2_SA_DQ4 @S9S_MB_2U_LIB.S9S_MB_2U(SCH_1):M_C_CPU0_SA_DQ(4)
 Y77 M_C_CPU0_SA_DQ<3> DDR2_SA_DQ3 @S9S_MB_2U_LIB.S9S_MB_2U(SCH_1):M_C_CPU0_SA_DQ(3)
 W78 M_C_CPU0_SA_DQ<2> DDR2_SA_DQ2 @S9S_MB_2U_LIB.S9S_MB_2U(SCH_1):M_C_CPU0_SA_DQ(2)
 T77 M_C_CPU0_SA_DQ<1> DDR2_SA_DQ1 @S9S_MB_2U_LIB.S9S_MB_2U(SCH_1):M_C_CPU0_SA_DQ(1)
 U78 M_C_CPU0_SA_DQ<0> DDR2_SA_DQ0 @S9S_MB_2U_LIB.S9S_MB_2U(SCH_1):M_C_CPU0_SA_DQ(0)
AH55 M_C_CPU0_SA_DQS_DN<9> DDR2_SA_DQS_DN9 @S9S_MB_2U_LIB.S9S_MB_2U(SCH_1):M_C_CPU0_SA_DQS_DN(9)
AF61 M_C_CPU0_SA_DQS_DN<8> DDR2_SA_DQS_DN8 @S9S_MB_2U_LIB.S9S_MB_2U(SCH_1):M_C_CPU0_SA_DQS_DN(8)
AA64 M_C_CPU0_SA_DQS_DN<7> DDR2_SA_DQS_DN7 @S9S_MB_2U_LIB.S9S_MB_2U(SCH_1):M_C_CPU0_SA_DQS_DN(7)
AH67 M_C_CPU0_SA_DQS_DN<6> DDR2_SA_DQS_DN6 @S9S_MB_2U_LIB.S9S_MB_2U(SCH_1):M_C_CPU0_SA_DQS_DN(6)
 W76 M_C_CPU0_SA_DQS_DN<5> DDR2_SA_DQS_DN5 @S9S_MB_2U_LIB.S9S_MB_2U(SCH_1):M_C_CPU0_SA_DQS_DN(5)
AD55 M_C_CPU0_SA_DQS_DN<4> DDR2_SA_DQS_DN4 @S9S_MB_2U_LIB.S9S_MB_2U(SCH_1):M_C_CPU0_SA_DQS_DN(4)
AB61 M_C_CPU0_SA_DQS_DN<3> DDR2_SA_DQS_DN3 @S9S_MB_2U_LIB.S9S_MB_2U(SCH_1):M_C_CPU0_SA_DQS_DN(3)
 R64 M_C_CPU0_SA_DQS_DN<2> DDR2_SA_DQS_DN2 @S9S_MB_2U_LIB.S9S_MB_2U(SCH_1):M_C_CPU0_SA_DQS_DN(2)
AB67 M_C_CPU0_SA_DQS_DN<1> DDR2_SA_DQS_DN1 @S9S_MB_2U_LIB.S9S_MB_2U(SCH_1):M_C_CPU0_SA_DQS_DN(1)
 R76 M_C_CPU0_SA_DQS_DN<0> DDR2_SA_DQS_DN0 @S9S_MB_2U_LIB.S9S_MB_2U(SCH_1):M_C_CPU0_SA_DQS_DN(0)
AF55 M_C_CPU0_SA_DQS_DP<9> DDR2_SA_DQS_DP9 @S9S_MB_2U_LIB.S9S_MB_2U(SCH_1):M_C_CPU0_SA_DQS_DP(9)
AH61 M_C_CPU0_SA_DQS_DP<8> DDR2_SA_DQS_DP8 @S9S_MB_2U_LIB.S9S_MB_2U(SCH_1):M_C_CPU0_SA_DQS_DP(8)
 W64 M_C_CPU0_SA_DQS_DP<7> DDR2_SA_DQS_DP7 @S9S_MB_2U_LIB.S9S_MB_2U(SCH_1):M_C_CPU0_SA_DQS_DP(7)
AF67 M_C_CPU0_SA_DQS_DP<6> DDR2_SA_DQS_DP6 @S9S_MB_2U_LIB.S9S_MB_2U(SCH_1):M_C_CPU0_SA_DQS_DP(6)
AA76 M_C_CPU0_SA_DQS_DP<5> DDR2_SA_DQS_DP5 @S9S_MB_2U_LIB.S9S_MB_2U(SCH_1):M_C_CPU0_SA_DQS_DP(5)
AB55 M_C_CPU0_SA_DQS_DP<4> DDR2_SA_DQS_DP4 @S9S_MB_2U_LIB.S9S_MB_2U(SCH_1):M_C_CPU0_SA_DQS_DP(4)
AD61 M_C_CPU0_SA_DQS_DP<3> DDR2_SA_DQS_DP3 @S9S_MB_2U_LIB.S9S_MB_2U(SCH_1):M_C_CPU0_SA_DQS_DP(3)
 U64 M_C_CPU0_SA_DQS_DP<2> DDR2_SA_DQS_DP2 @S9S_MB_2U_LIB.S9S_MB_2U(SCH_1):M_C_CPU0_SA_DQS_DP(2)
AD67 M_C_CPU0_SA_DQS_DP<1> DDR2_SA_DQS_DP1 @S9S_MB_2U_LIB.S9S_MB_2U(SCH_1):M_C_CPU0_SA_DQS_DP(1)
 U76 M_C_CPU0_SA_DQS_DP<0> DDR2_SA_DQS_DP0 @S9S_MB_2U_LIB.S9S_MB_2U(SCH_1):M_C_CPU0_SA_DQS_DP(0)
AF53 M_C_CPU0_SA_CB<7> DDR2_SA_ECC7 @S9S_MB_2U_LIB.S9S_MB_2U(SCH_1):M_C_CPU0_SA_CB(7)
AG54 M_C_CPU0_SA_CB<6> DDR2_SA_ECC6 @S9S_MB_2U_LIB.S9S_MB_2U(SCH_1):M_C_CPU0_SA_CB(6)
AD53 M_C_CPU0_SA_CB<5> DDR2_SA_ECC5 @S9S_MB_2U_LIB.S9S_MB_2U(SCH_1):M_C_CPU0_SA_CB(5)
AC54 M_C_CPU0_SA_CB<4> DDR2_SA_ECC4 @S9S_MB_2U_LIB.S9S_MB_2U(SCH_1):M_C_CPU0_SA_CB(4)
AG56 M_C_CPU0_SA_CB<3> DDR2_SA_ECC3 @S9S_MB_2U_LIB.S9S_MB_2U(SCH_1):M_C_CPU0_SA_CB(3)
AF57 M_C_CPU0_SA_CB<2> DDR2_SA_ECC2 @S9S_MB_2U_LIB.S9S_MB_2U(SCH_1):M_C_CPU0_SA_CB(2)
AC56 M_C_CPU0_SA_CB<1> DDR2_SA_ECC1 @S9S_MB_2U_LIB.S9S_MB_2U(SCH_1):M_C_CPU0_SA_CB(1)
AD57 M_C_CPU0_SA_CB<0> DDR2_SA_ECC0 @S9S_MB_2U_LIB.S9S_MB_2U(SCH_1):M_C_CPU0_SA_CB(0)
 T47 M_C_CPU0_SA_PAR DDR2_SA_PAR @S9S_MB_2U_LIB.S9S_MB_2U(SCH_1):M_C_CPU0_SA_PAR
 R39 M_C_CPU0_SB_CA<6> DDR2_SB_CA6 @S9S_MB_2U_LIB.S9S_MB_2U(SCH_1):M_C_CPU0_SB_CA(6)
 Y40 M_C_CPU0_SB_CA<5> DDR2_SB_CA5 @S9S_MB_2U_LIB.S9S_MB_2U(SCH_1):M_C_CPU0_SB_CA(5)
 T40 M_C_CPU0_SB_CA<4> DDR2_SB_CA4 @S9S_MB_2U_LIB.S9S_MB_2U(SCH_1):M_C_CPU0_SB_CA(4)
 W41 M_C_CPU0_SB_CA<3> DDR2_SB_CA3 @S9S_MB_2U_LIB.S9S_MB_2U(SCH_1):M_C_CPU0_SB_CA(3)
 U41 M_C_CPU0_SB_CA<2> DDR2_SB_CA2 @S9S_MB_2U_LIB.S9S_MB_2U(SCH_1):M_C_CPU0_SB_CA(2)
 Y47 M_C_CPU0_SB_CA<1> DDR2_SB_CA1 @S9S_MB_2U_LIB.S9S_MB_2U(SCH_1):M_C_CPU0_SB_CA(1)
 W48 M_C_CPU0_SB_CA<0> DDR2_SB_CA0 @S9S_MB_2U_LIB.S9S_MB_2U(SCH_1):M_C_CPU0_SB_CA(0)
 W37 M_C_CPU0_SB_CS_N<3> DDR2_SB_CS_N3 @S9S_MB_2U_LIB.S9S_MB_2U(SCH_1):M_C_CPU0_SB_CS_N(3)
 Y38 M_C_CPU0_SB_CS_N<2> DDR2_SB_CS_N2 @S9S_MB_2U_LIB.S9S_MB_2U(SCH_1):M_C_CPU0_SB_CS_N(2)
 U37 M_C_CPU0_SB_CS_N<1> DDR2_SB_CS_N1 @S9S_MB_2U_LIB.S9S_MB_2U(SCH_1):M_C_CPU0_SB_CS_N(1)
 T38 M_C_CPU0_SB_CS_N<0> DDR2_SB_CS_N0 @S9S_MB_2U_LIB.S9S_MB_2U(SCH_1):M_C_CPU0_SB_CS_N(0)
AJ17 M_C_CPU0_SB_DQ<31> DDR2_SB_DQ31 @S9S_MB_2U_LIB.S9S_MB_2U(SCH_1):M_C_CPU0_SB_DQ(31)
AC17 M_C_CPU0_SB_DQ<30> DDR2_SB_DQ30 @S9S_MB_2U_LIB.S9S_MB_2U(SCH_1):M_C_CPU0_SB_DQ(30)
AG17 M_C_CPU0_SB_DQ<29> DDR2_SB_DQ29 @S9S_MB_2U_LIB.S9S_MB_2U(SCH_1):M_C_CPU0_SB_DQ(29)
AA17 M_C_CPU0_SB_DQ<28> DDR2_SB_DQ28 @S9S_MB_2U_LIB.S9S_MB_2U(SCH_1):M_C_CPU0_SB_DQ(28)
AG19 M_C_CPU0_SB_DQ<27> DDR2_SB_DQ27 @S9S_MB_2U_LIB.S9S_MB_2U(SCH_1):M_C_CPU0_SB_DQ(27)
AF20 M_C_CPU0_SB_DQ<26> DDR2_SB_DQ26 @S9S_MB_2U_LIB.S9S_MB_2U(SCH_1):M_C_CPU0_SB_DQ(26)
AC19 M_C_CPU0_SB_DQ<25> DDR2_SB_DQ25 @S9S_MB_2U_LIB.S9S_MB_2U(SCH_1):M_C_CPU0_SB_DQ(25)
AD20 M_C_CPU0_SB_DQ<24> DDR2_SB_DQ24 @S9S_MB_2U_LIB.S9S_MB_2U(SCH_1):M_C_CPU0_SB_DQ(24)
 W19 M_C_CPU0_SB_DQ<23> DDR2_SB_DQ23 @S9S_MB_2U_LIB.S9S_MB_2U(SCH_1):M_C_CPU0_SB_DQ(23)
 Y20 M_C_CPU0_SB_DQ<22> DDR2_SB_DQ22 @S9S_MB_2U_LIB.S9S_MB_2U(SCH_1):M_C_CPU0_SB_DQ(22)
 U19 M_C_CPU0_SB_DQ<21> DDR2_SB_DQ21 @S9S_MB_2U_LIB.S9S_MB_2U(SCH_1):M_C_CPU0_SB_DQ(21)
 T20 M_C_CPU0_SB_DQ<20> DDR2_SB_DQ20 @S9S_MB_2U_LIB.S9S_MB_2U(SCH_1):M_C_CPU0_SB_DQ(20)
 Y22 M_C_CPU0_SB_DQ<19> DDR2_SB_DQ19 @S9S_MB_2U_LIB.S9S_MB_2U(SCH_1):M_C_CPU0_SB_DQ(19)
 W23 M_C_CPU0_SB_DQ<18> DDR2_SB_DQ18 @S9S_MB_2U_LIB.S9S_MB_2U(SCH_1):M_C_CPU0_SB_DQ(18)
 T22 M_C_CPU0_SB_DQ<17> DDR2_SB_DQ17 @S9S_MB_2U_LIB.S9S_MB_2U(SCH_1):M_C_CPU0_SB_DQ(17)
 U23 M_C_CPU0_SB_DQ<16> DDR2_SB_DQ16 @S9S_MB_2U_LIB.S9S_MB_2U(SCH_1):M_C_CPU0_SB_DQ(16)
AF28 M_C_CPU0_SB_DQ<15> DDR2_SB_DQ15 @S9S_MB_2U_LIB.S9S_MB_2U(SCH_1):M_C_CPU0_SB_DQ(15)
AG29 M_C_CPU0_SB_DQ<14> DDR2_SB_DQ14 @S9S_MB_2U_LIB.S9S_MB_2U(SCH_1):M_C_CPU0_SB_DQ(14)
AD28 M_C_CPU0_SB_DQ<13> DDR2_SB_DQ13 @S9S_MB_2U_LIB.S9S_MB_2U(SCH_1):M_C_CPU0_SB_DQ(13)
AC29 M_C_CPU0_SB_DQ<12> DDR2_SB_DQ12 @S9S_MB_2U_LIB.S9S_MB_2U(SCH_1):M_C_CPU0_SB_DQ(12)
AG31 M_C_CPU0_SB_DQ<11> DDR2_SB_DQ11 @S9S_MB_2U_LIB.S9S_MB_2U(SCH_1):M_C_CPU0_SB_DQ(11)
AF32 M_C_CPU0_SB_DQ<10> DDR2_SB_DQ10 @S9S_MB_2U_LIB.S9S_MB_2U(SCH_1):M_C_CPU0_SB_DQ(10)
AC31 M_C_CPU0_SB_DQ<9> DDR2_SB_DQ9 @S9S_MB_2U_LIB.S9S_MB_2U(SCH_1):M_C_CPU0_SB_DQ(9)
AD32 M_C_CPU0_SB_DQ<8> DDR2_SB_DQ8 @S9S_MB_2U_LIB.S9S_MB_2U(SCH_1):M_C_CPU0_SB_DQ(8)
AF34 M_C_CPU0_SB_DQ<7> DDR2_SB_DQ7 @S9S_MB_2U_LIB.S9S_MB_2U(SCH_1):M_C_CPU0_SB_DQ(7)
AG35 M_C_CPU0_SB_DQ<6> DDR2_SB_DQ6 @S9S_MB_2U_LIB.S9S_MB_2U(SCH_1):M_C_CPU0_SB_DQ(6)
AD34 M_C_CPU0_SB_DQ<5> DDR2_SB_DQ5 @S9S_MB_2U_LIB.S9S_MB_2U(SCH_1):M_C_CPU0_SB_DQ(5)
AC35 M_C_CPU0_SB_DQ<4> DDR2_SB_DQ4 @S9S_MB_2U_LIB.S9S_MB_2U(SCH_1):M_C_CPU0_SB_DQ(4)
AG37 M_C_CPU0_SB_DQ<3> DDR2_SB_DQ3 @S9S_MB_2U_LIB.S9S_MB_2U(SCH_1):M_C_CPU0_SB_DQ(3)
AF38 M_C_CPU0_SB_DQ<2> DDR2_SB_DQ2 @S9S_MB_2U_LIB.S9S_MB_2U(SCH_1):M_C_CPU0_SB_DQ(2)
AC37 M_C_CPU0_SB_DQ<1> DDR2_SB_DQ1 @S9S_MB_2U_LIB.S9S_MB_2U(SCH_1):M_C_CPU0_SB_DQ(1)
AD38 M_C_CPU0_SB_DQ<0> DDR2_SB_DQ0 @S9S_MB_2U_LIB.S9S_MB_2U(SCH_1):M_C_CPU0_SB_DQ(0)
 R33 M_C_CPU0_SB_DQS_DN<9> DDR2_SB_DQS_DN9 @S9S_MB_2U_LIB.S9S_MB_2U(SCH_1):M_C_CPU0_SB_DQS_DN(9)
AF18 M_C_CPU0_SB_DQS_DN<8> DDR2_SB_DQS_DN8 @S9S_MB_2U_LIB.S9S_MB_2U(SCH_1):M_C_CPU0_SB_DQS_DN(8)
 W21 M_C_CPU0_SB_DQS_DN<7> DDR2_SB_DQS_DN7 @S9S_MB_2U_LIB.S9S_MB_2U(SCH_1):M_C_CPU0_SB_DQS_DN(7)
AF30 M_C_CPU0_SB_DQS_DN<6> DDR2_SB_DQS_DN6 @S9S_MB_2U_LIB.S9S_MB_2U(SCH_1):M_C_CPU0_SB_DQS_DN(6)
AF36 M_C_CPU0_SB_DQS_DN<5> DDR2_SB_DQS_DN5 @S9S_MB_2U_LIB.S9S_MB_2U(SCH_1):M_C_CPU0_SB_DQS_DN(5)
 W33 M_C_CPU0_SB_DQS_DN<4> DDR2_SB_DQS_DN4 @S9S_MB_2U_LIB.S9S_MB_2U(SCH_1):M_C_CPU0_SB_DQS_DN(4)
AB18 M_C_CPU0_SB_DQS_DN<3> DDR2_SB_DQS_DN3 @S9S_MB_2U_LIB.S9S_MB_2U(SCH_1):M_C_CPU0_SB_DQS_DN(3)
 R21 M_C_CPU0_SB_DQS_DN<2> DDR2_SB_DQS_DN2 @S9S_MB_2U_LIB.S9S_MB_2U(SCH_1):M_C_CPU0_SB_DQS_DN(2)
AB30 M_C_CPU0_SB_DQS_DN<1> DDR2_SB_DQS_DN1 @S9S_MB_2U_LIB.S9S_MB_2U(SCH_1):M_C_CPU0_SB_DQS_DN(1)
AB36 M_C_CPU0_SB_DQS_DN<0> DDR2_SB_DQS_DN0 @S9S_MB_2U_LIB.S9S_MB_2U(SCH_1):M_C_CPU0_SB_DQS_DN(0)
 U33 M_C_CPU0_SB_DQS_DP<9> DDR2_SB_DQS_DP9 @S9S_MB_2U_LIB.S9S_MB_2U(SCH_1):M_C_CPU0_SB_DQS_DP(9)
AH18 M_C_CPU0_SB_DQS_DP<8> DDR2_SB_DQS_DP8 @S9S_MB_2U_LIB.S9S_MB_2U(SCH_1):M_C_CPU0_SB_DQS_DP(8)
AA21 M_C_CPU0_SB_DQS_DP<7> DDR2_SB_DQS_DP7 @S9S_MB_2U_LIB.S9S_MB_2U(SCH_1):M_C_CPU0_SB_DQS_DP(7)
AH30 M_C_CPU0_SB_DQS_DP<6> DDR2_SB_DQS_DP6 @S9S_MB_2U_LIB.S9S_MB_2U(SCH_1):M_C_CPU0_SB_DQS_DP(6)
AH36 M_C_CPU0_SB_DQS_DP<5> DDR2_SB_DQS_DP5 @S9S_MB_2U_LIB.S9S_MB_2U(SCH_1):M_C_CPU0_SB_DQS_DP(5)
AA33 M_C_CPU0_SB_DQS_DP<4> DDR2_SB_DQS_DP4 @S9S_MB_2U_LIB.S9S_MB_2U(SCH_1):M_C_CPU0_SB_DQS_DP(4)
AD18 M_C_CPU0_SB_DQS_DP<3> DDR2_SB_DQS_DP3 @S9S_MB_2U_LIB.S9S_MB_2U(SCH_1):M_C_CPU0_SB_DQS_DP(3)
 U21 M_C_CPU0_SB_DQS_DP<2> DDR2_SB_DQS_DP2 @S9S_MB_2U_LIB.S9S_MB_2U(SCH_1):M_C_CPU0_SB_DQS_DP(2)
AD30 M_C_CPU0_SB_DQS_DP<1> DDR2_SB_DQS_DP1 @S9S_MB_2U_LIB.S9S_MB_2U(SCH_1):M_C_CPU0_SB_DQS_DP(1)
AD36 M_C_CPU0_SB_DQS_DP<0> DDR2_SB_DQS_DP0 @S9S_MB_2U_LIB.S9S_MB_2U(SCH_1):M_C_CPU0_SB_DQS_DP(0)
 Y34 M_C_CPU0_SB_CB<7> DDR2_SB_ECC7 @S9S_MB_2U_LIB.S9S_MB_2U(SCH_1):M_C_CPU0_SB_CB(7)
 W35 M_C_CPU0_SB_CB<6> DDR2_SB_ECC6 @S9S_MB_2U_LIB.S9S_MB_2U(SCH_1):M_C_CPU0_SB_CB(6)
 T34 M_C_CPU0_SB_CB<5> DDR2_SB_ECC5 @S9S_MB_2U_LIB.S9S_MB_2U(SCH_1):M_C_CPU0_SB_CB(5)
 U35 M_C_CPU0_SB_CB<4> DDR2_SB_ECC4 @S9S_MB_2U_LIB.S9S_MB_2U(SCH_1):M_C_CPU0_SB_CB(4)
 W31 M_C_CPU0_SB_CB<3> DDR2_SB_ECC3 @S9S_MB_2U_LIB.S9S_MB_2U(SCH_1):M_C_CPU0_SB_CB(3)
 Y32 M_C_CPU0_SB_CB<2> DDR2_SB_ECC2 @S9S_MB_2U_LIB.S9S_MB_2U(SCH_1):M_C_CPU0_SB_CB(2)
 U31 M_C_CPU0_SB_CB<1> DDR2_SB_ECC1 @S9S_MB_2U_LIB.S9S_MB_2U(SCH_1):M_C_CPU0_SB_CB(1)
 T32 M_C_CPU0_SB_CB<0> DDR2_SB_ECC0 @S9S_MB_2U_LIB.S9S_MB_2U(SCH_1):M_C_CPU0_SB_CB(0)
AA39 M_C_CPU0_SB_PAR DDR2_SB_PAR @S9S_MB_2U_LIB.S9S_MB_2U(SCH_1):M_C_CPU0_SB_PAR


DRAWING: @S9S_MB_2U_LIB.S9S_MB_2U(SCH_1):PAGE23 

SOCKET4677_AZIF0045P001C01CS-SA  I169  U2
AV47 M_D_CPU0_ALERT_N DDR3_ALERT_N @S9S_MB_2U_LIB.S9S_MB_2U(SCH_1):M_D_CPU0_ALERT_N
AC50 M_D_CPU0_SA_RSP<1> DDR3_A_RSP1 @S9S_MB_2U_LIB.S9S_MB_2U(SCH_1):M_D_CPU0_SA_RSP(1)
AD51 M_D_CPU0_SA_RSP<0> DDR3_A_RSP0 @S9S_MB_2U_LIB.S9S_MB_2U(SCH_1):M_D_CPU0_SA_RSP(0)
AG50 M_D_CPU0_SB_RSP<1> DDR3_B_RSP1 @S9S_MB_2U_LIB.S9S_MB_2U(SCH_1):M_D_CPU0_SB_RSP(1)
AF51 M_D_CPU0_SB_RSP<0> DDR3_B_RSP0 @S9S_MB_2U_LIB.S9S_MB_2U(SCH_1):M_D_CPU0_SB_RSP(0)
AN45 M_D_CPU0_CLK_DN<1> DDR3_CLK_DN1 @S9S_MB_2U_LIB.S9S_MB_2U(SCH_1):M_D_CPU0_CLK_DN(1)
AJ45 M_D_CPU0_CLK_DN<0> DDR3_CLK_DN0 @S9S_MB_2U_LIB.S9S_MB_2U(SCH_1):M_D_CPU0_CLK_DN(0)
AR45 M_D_CPU0_CLK_DP<1> DDR3_CLK_DP1 @S9S_MB_2U_LIB.S9S_MB_2U(SCH_1):M_D_CPU0_CLK_DP(1)
AL45 M_D_CPU0_CLK_DP<0> DDR3_CLK_DP0 @S9S_MB_2U_LIB.S9S_MB_2U(SCH_1):M_D_CPU0_CLK_DP(0)
AN43 M_D_CPU0_SA_CA<6> DDR3_SA_CA6 @S9S_MB_2U_LIB.S9S_MB_2U(SCH_1):M_D_CPU0_SA_CA(6)
AN50 M_D_CPU0_SA_CA<5> DDR3_SA_CA5 @S9S_MB_2U_LIB.S9S_MB_2U(SCH_1):M_D_CPU0_SA_CA(5)
AL50 M_D_CPU0_SA_CA<4> DDR3_SA_CA4 @S9S_MB_2U_LIB.S9S_MB_2U(SCH_1):M_D_CPU0_SA_CA(4)
AP51 M_D_CPU0_SA_CA<3> DDR3_SA_CA3 @S9S_MB_2U_LIB.S9S_MB_2U(SCH_1):M_D_CPU0_SA_CA(3)
AK51 M_D_CPU0_SA_CA<2> DDR3_SA_CA2 @S9S_MB_2U_LIB.S9S_MB_2U(SCH_1):M_D_CPU0_SA_CA(2)
AR52 M_D_CPU0_SA_CA<1> DDR3_SA_CA1 @S9S_MB_2U_LIB.S9S_MB_2U(SCH_1):M_D_CPU0_SA_CA(1)
AJ52 M_D_CPU0_SA_CA<0> DDR3_SA_CA0 @S9S_MB_2U_LIB.S9S_MB_2U(SCH_1):M_D_CPU0_SA_CA(0)
AP53 M_D_CPU0_SA_CS_N<3> DDR3_SA_CS_N3 @S9S_MB_2U_LIB.S9S_MB_2U(SCH_1):M_D_CPU0_SA_CS_N(3)
AN54 M_D_CPU0_SA_CS_N<2> DDR3_SA_CS_N2 @S9S_MB_2U_LIB.S9S_MB_2U(SCH_1):M_D_CPU0_SA_CS_N(2)
AK53 M_D_CPU0_SA_CS_N<1> DDR3_SA_CS_N1 @S9S_MB_2U_LIB.S9S_MB_2U(SCH_1):M_D_CPU0_SA_CS_N(1)
AL54 M_D_CPU0_SA_CS_N<0> DDR3_SA_CS_N0 @S9S_MB_2U_LIB.S9S_MB_2U(SCH_1):M_D_CPU0_SA_CS_N(0)
AN62 M_D_CPU0_SA_DQ<31> DDR3_SA_DQ31 @S9S_MB_2U_LIB.S9S_MB_2U(SCH_1):M_D_CPU0_SA_DQ(31)
AP63 M_D_CPU0_SA_DQ<30> DDR3_SA_DQ30 @S9S_MB_2U_LIB.S9S_MB_2U(SCH_1):M_D_CPU0_SA_DQ(30)
AL62 M_D_CPU0_SA_DQ<29> DDR3_SA_DQ29 @S9S_MB_2U_LIB.S9S_MB_2U(SCH_1):M_D_CPU0_SA_DQ(29)
AK63 M_D_CPU0_SA_DQ<28> DDR3_SA_DQ28 @S9S_MB_2U_LIB.S9S_MB_2U(SCH_1):M_D_CPU0_SA_DQ(28)
AP65 M_D_CPU0_SA_DQ<27> DDR3_SA_DQ27 @S9S_MB_2U_LIB.S9S_MB_2U(SCH_1):M_D_CPU0_SA_DQ(27)
AN66 M_D_CPU0_SA_DQ<26> DDR3_SA_DQ26 @S9S_MB_2U_LIB.S9S_MB_2U(SCH_1):M_D_CPU0_SA_DQ(26)
AK65 M_D_CPU0_SA_DQ<25> DDR3_SA_DQ25 @S9S_MB_2U_LIB.S9S_MB_2U(SCH_1):M_D_CPU0_SA_DQ(25)
AL66 M_D_CPU0_SA_DQ<24> DDR3_SA_DQ24 @S9S_MB_2U_LIB.S9S_MB_2U(SCH_1):M_D_CPU0_SA_DQ(24)
AN68 M_D_CPU0_SA_DQ<23> DDR3_SA_DQ23 @S9S_MB_2U_LIB.S9S_MB_2U(SCH_1):M_D_CPU0_SA_DQ(23)
AP69 M_D_CPU0_SA_DQ<22> DDR3_SA_DQ22 @S9S_MB_2U_LIB.S9S_MB_2U(SCH_1):M_D_CPU0_SA_DQ(22)
AL68 M_D_CPU0_SA_DQ<21> DDR3_SA_DQ21 @S9S_MB_2U_LIB.S9S_MB_2U(SCH_1):M_D_CPU0_SA_DQ(21)
AK69 M_D_CPU0_SA_DQ<20> DDR3_SA_DQ20 @S9S_MB_2U_LIB.S9S_MB_2U(SCH_1):M_D_CPU0_SA_DQ(20)
AP71 M_D_CPU0_SA_DQ<19> DDR3_SA_DQ19 @S9S_MB_2U_LIB.S9S_MB_2U(SCH_1):M_D_CPU0_SA_DQ(19)
AN72 M_D_CPU0_SA_DQ<18> DDR3_SA_DQ18 @S9S_MB_2U_LIB.S9S_MB_2U(SCH_1):M_D_CPU0_SA_DQ(18)
AK71 M_D_CPU0_SA_DQ<17> DDR3_SA_DQ17 @S9S_MB_2U_LIB.S9S_MB_2U(SCH_1):M_D_CPU0_SA_DQ(17)
AL72 M_D_CPU0_SA_DQ<16> DDR3_SA_DQ16 @S9S_MB_2U_LIB.S9S_MB_2U(SCH_1):M_D_CPU0_SA_DQ(16)
AN74 M_D_CPU0_SA_DQ<15> DDR3_SA_DQ15 @S9S_MB_2U_LIB.S9S_MB_2U(SCH_1):M_D_CPU0_SA_DQ(15)
AP75 M_D_CPU0_SA_DQ<14> DDR3_SA_DQ14 @S9S_MB_2U_LIB.S9S_MB_2U(SCH_1):M_D_CPU0_SA_DQ(14)
AL74 M_D_CPU0_SA_DQ<13> DDR3_SA_DQ13 @S9S_MB_2U_LIB.S9S_MB_2U(SCH_1):M_D_CPU0_SA_DQ(13)
AK75 M_D_CPU0_SA_DQ<12> DDR3_SA_DQ12 @S9S_MB_2U_LIB.S9S_MB_2U(SCH_1):M_D_CPU0_SA_DQ(12)
AP77 M_D_CPU0_SA_DQ<11> DDR3_SA_DQ11 @S9S_MB_2U_LIB.S9S_MB_2U(SCH_1):M_D_CPU0_SA_DQ(11)
AN78 M_D_CPU0_SA_DQ<10> DDR3_SA_DQ10 @S9S_MB_2U_LIB.S9S_MB_2U(SCH_1):M_D_CPU0_SA_DQ(10)
AK77 M_D_CPU0_SA_DQ<9> DDR3_SA_DQ9 @S9S_MB_2U_LIB.S9S_MB_2U(SCH_1):M_D_CPU0_SA_DQ(9)
AL78 M_D_CPU0_SA_DQ<8> DDR3_SA_DQ8 @S9S_MB_2U_LIB.S9S_MB_2U(SCH_1):M_D_CPU0_SA_DQ(8)
AF71 M_D_CPU0_SA_DQ<7> DDR3_SA_DQ7 @S9S_MB_2U_LIB.S9S_MB_2U(SCH_1):M_D_CPU0_SA_DQ(7)
AG72 M_D_CPU0_SA_DQ<6> DDR3_SA_DQ6 @S9S_MB_2U_LIB.S9S_MB_2U(SCH_1):M_D_CPU0_SA_DQ(6)
AD71 M_D_CPU0_SA_DQ<5> DDR3_SA_DQ5 @S9S_MB_2U_LIB.S9S_MB_2U(SCH_1):M_D_CPU0_SA_DQ(5)
AC72 M_D_CPU0_SA_DQ<4> DDR3_SA_DQ4 @S9S_MB_2U_LIB.S9S_MB_2U(SCH_1):M_D_CPU0_SA_DQ(4)
AG74 M_D_CPU0_SA_DQ<3> DDR3_SA_DQ3 @S9S_MB_2U_LIB.S9S_MB_2U(SCH_1):M_D_CPU0_SA_DQ(3)
AF75 M_D_CPU0_SA_DQ<2> DDR3_SA_DQ2 @S9S_MB_2U_LIB.S9S_MB_2U(SCH_1):M_D_CPU0_SA_DQ(2)
AC74 M_D_CPU0_SA_DQ<1> DDR3_SA_DQ1 @S9S_MB_2U_LIB.S9S_MB_2U(SCH_1):M_D_CPU0_SA_DQ(1)
AD75 M_D_CPU0_SA_DQ<0> DDR3_SA_DQ0 @S9S_MB_2U_LIB.S9S_MB_2U(SCH_1):M_D_CPU0_SA_DQ(0)
AN58 M_D_CPU0_SA_DQS_DN<9> DDR3_SA_DQS_DN9 @S9S_MB_2U_LIB.S9S_MB_2U(SCH_1):M_D_CPU0_SA_DQS_DN(9)
AN64 M_D_CPU0_SA_DQS_DN<8> DDR3_SA_DQS_DN8 @S9S_MB_2U_LIB.S9S_MB_2U(SCH_1):M_D_CPU0_SA_DQS_DN(8)
AN70 M_D_CPU0_SA_DQS_DN<7> DDR3_SA_DQS_DN7 @S9S_MB_2U_LIB.S9S_MB_2U(SCH_1):M_D_CPU0_SA_DQS_DN(7)
AN76 M_D_CPU0_SA_DQS_DN<6> DDR3_SA_DQS_DN6 @S9S_MB_2U_LIB.S9S_MB_2U(SCH_1):M_D_CPU0_SA_DQS_DN(6)
AH73 M_D_CPU0_SA_DQS_DN<5> DDR3_SA_DQS_DN5 @S9S_MB_2U_LIB.S9S_MB_2U(SCH_1):M_D_CPU0_SA_DQS_DN(5)
AJ58 M_D_CPU0_SA_DQS_DN<4> DDR3_SA_DQS_DN4 @S9S_MB_2U_LIB.S9S_MB_2U(SCH_1):M_D_CPU0_SA_DQS_DN(4)
AJ64 M_D_CPU0_SA_DQS_DN<3> DDR3_SA_DQS_DN3 @S9S_MB_2U_LIB.S9S_MB_2U(SCH_1):M_D_CPU0_SA_DQS_DN(3)
AJ70 M_D_CPU0_SA_DQS_DN<2> DDR3_SA_DQS_DN2 @S9S_MB_2U_LIB.S9S_MB_2U(SCH_1):M_D_CPU0_SA_DQS_DN(2)
AJ76 M_D_CPU0_SA_DQS_DN<1> DDR3_SA_DQS_DN1 @S9S_MB_2U_LIB.S9S_MB_2U(SCH_1):M_D_CPU0_SA_DQS_DN(1)
AB73 M_D_CPU0_SA_DQS_DN<0> DDR3_SA_DQS_DN0 @S9S_MB_2U_LIB.S9S_MB_2U(SCH_1):M_D_CPU0_SA_DQS_DN(0)
AR58 M_D_CPU0_SA_DQS_DP<9> DDR3_SA_DQS_DP9 @S9S_MB_2U_LIB.S9S_MB_2U(SCH_1):M_D_CPU0_SA_DQS_DP(9)
AR64 M_D_CPU0_SA_DQS_DP<8> DDR3_SA_DQS_DP8 @S9S_MB_2U_LIB.S9S_MB_2U(SCH_1):M_D_CPU0_SA_DQS_DP(8)
AR70 M_D_CPU0_SA_DQS_DP<7> DDR3_SA_DQS_DP7 @S9S_MB_2U_LIB.S9S_MB_2U(SCH_1):M_D_CPU0_SA_DQS_DP(7)
AR76 M_D_CPU0_SA_DQS_DP<6> DDR3_SA_DQS_DP6 @S9S_MB_2U_LIB.S9S_MB_2U(SCH_1):M_D_CPU0_SA_DQS_DP(6)
AF73 M_D_CPU0_SA_DQS_DP<5> DDR3_SA_DQS_DP5 @S9S_MB_2U_LIB.S9S_MB_2U(SCH_1):M_D_CPU0_SA_DQS_DP(5)
AL58 M_D_CPU0_SA_DQS_DP<4> DDR3_SA_DQS_DP4 @S9S_MB_2U_LIB.S9S_MB_2U(SCH_1):M_D_CPU0_SA_DQS_DP(4)
AL64 M_D_CPU0_SA_DQS_DP<3> DDR3_SA_DQS_DP3 @S9S_MB_2U_LIB.S9S_MB_2U(SCH_1):M_D_CPU0_SA_DQS_DP(3)
AL70 M_D_CPU0_SA_DQS_DP<2> DDR3_SA_DQS_DP2 @S9S_MB_2U_LIB.S9S_MB_2U(SCH_1):M_D_CPU0_SA_DQS_DP(2)
AL76 M_D_CPU0_SA_DQS_DP<1> DDR3_SA_DQS_DP1 @S9S_MB_2U_LIB.S9S_MB_2U(SCH_1):M_D_CPU0_SA_DQS_DP(1)
AD73 M_D_CPU0_SA_DQS_DP<0> DDR3_SA_DQS_DP0 @S9S_MB_2U_LIB.S9S_MB_2U(SCH_1):M_D_CPU0_SA_DQS_DP(0)
AN56 M_D_CPU0_SA_CB<7> DDR3_SA_ECC7 @S9S_MB_2U_LIB.S9S_MB_2U(SCH_1):M_D_CPU0_SA_CB(7)
AP57 M_D_CPU0_SA_CB<6> DDR3_SA_ECC6 @S9S_MB_2U_LIB.S9S_MB_2U(SCH_1):M_D_CPU0_SA_CB(6)
AL56 M_D_CPU0_SA_CB<5> DDR3_SA_ECC5 @S9S_MB_2U_LIB.S9S_MB_2U(SCH_1):M_D_CPU0_SA_CB(5)
AK57 M_D_CPU0_SA_CB<4> DDR3_SA_ECC4 @S9S_MB_2U_LIB.S9S_MB_2U(SCH_1):M_D_CPU0_SA_CB(4)
AP59 M_D_CPU0_SA_CB<3> DDR3_SA_ECC3 @S9S_MB_2U_LIB.S9S_MB_2U(SCH_1):M_D_CPU0_SA_CB(3)
AN60 M_D_CPU0_SA_CB<2> DDR3_SA_ECC2 @S9S_MB_2U_LIB.S9S_MB_2U(SCH_1):M_D_CPU0_SA_CB(2)
AK59 M_D_CPU0_SA_CB<1> DDR3_SA_ECC1 @S9S_MB_2U_LIB.S9S_MB_2U(SCH_1):M_D_CPU0_SA_CB(1)
AL60 M_D_CPU0_SA_CB<0> DDR3_SA_ECC0 @S9S_MB_2U_LIB.S9S_MB_2U(SCH_1):M_D_CPU0_SA_CB(0)
AP44 M_D_CPU0_SA_PAR DDR3_SA_PAR @S9S_MB_2U_LIB.S9S_MB_2U(SCH_1):M_D_CPU0_SA_PAR
AB42 M_D_CPU0_SB_CA<6> DDR3_SB_CA6 @S9S_MB_2U_LIB.S9S_MB_2U(SCH_1):M_D_CPU0_SB_CA(6)
AG43 M_D_CPU0_SB_CA<5> DDR3_SB_CA5 @S9S_MB_2U_LIB.S9S_MB_2U(SCH_1):M_D_CPU0_SB_CA(5)
AC43 M_D_CPU0_SB_CA<4> DDR3_SB_CA4 @S9S_MB_2U_LIB.S9S_MB_2U(SCH_1):M_D_CPU0_SB_CA(4)
AF44 M_D_CPU0_SB_CA<3> DDR3_SB_CA3 @S9S_MB_2U_LIB.S9S_MB_2U(SCH_1):M_D_CPU0_SB_CA(3)
AD44 M_D_CPU0_SB_CA<2> DDR3_SB_CA2 @S9S_MB_2U_LIB.S9S_MB_2U(SCH_1):M_D_CPU0_SB_CA(2)
AL43 M_D_CPU0_SB_CA<1> DDR3_SB_CA1 @S9S_MB_2U_LIB.S9S_MB_2U(SCH_1):M_D_CPU0_SB_CA(1)
AK44 M_D_CPU0_SB_CA<0> DDR3_SB_CA0 @S9S_MB_2U_LIB.S9S_MB_2U(SCH_1):M_D_CPU0_SB_CA(0)
AD40 M_D_CPU0_SB_CS_N<3> DDR3_SB_CS_N3 @S9S_MB_2U_LIB.S9S_MB_2U(SCH_1):M_D_CPU0_SB_CS_N(3)
AF40 M_D_CPU0_SB_CS_N<2> DDR3_SB_CS_N2 @S9S_MB_2U_LIB.S9S_MB_2U(SCH_1):M_D_CPU0_SB_CS_N(2)
AG41 M_D_CPU0_SB_CS_N<1> DDR3_SB_CS_N1 @S9S_MB_2U_LIB.S9S_MB_2U(SCH_1):M_D_CPU0_SB_CS_N(1)
AC41 M_D_CPU0_SB_CS_N<0> DDR3_SB_CS_N0 @S9S_MB_2U_LIB.S9S_MB_2U(SCH_1):M_D_CPU0_SB_CS_N(0)
AN19 M_D_CPU0_SB_DQ<31> DDR3_SB_DQ31 @S9S_MB_2U_LIB.S9S_MB_2U(SCH_1):M_D_CPU0_SB_DQ(31)
AP20 M_D_CPU0_SB_DQ<30> DDR3_SB_DQ30 @S9S_MB_2U_LIB.S9S_MB_2U(SCH_1):M_D_CPU0_SB_DQ(30)
AL19 M_D_CPU0_SB_DQ<29> DDR3_SB_DQ29 @S9S_MB_2U_LIB.S9S_MB_2U(SCH_1):M_D_CPU0_SB_DQ(29)
AK20 M_D_CPU0_SB_DQ<28> DDR3_SB_DQ28 @S9S_MB_2U_LIB.S9S_MB_2U(SCH_1):M_D_CPU0_SB_DQ(28)
AP22 M_D_CPU0_SB_DQ<27> DDR3_SB_DQ27 @S9S_MB_2U_LIB.S9S_MB_2U(SCH_1):M_D_CPU0_SB_DQ(27)
AN23 M_D_CPU0_SB_DQ<26> DDR3_SB_DQ26 @S9S_MB_2U_LIB.S9S_MB_2U(SCH_1):M_D_CPU0_SB_DQ(26)
AK22 M_D_CPU0_SB_DQ<25> DDR3_SB_DQ25 @S9S_MB_2U_LIB.S9S_MB_2U(SCH_1):M_D_CPU0_SB_DQ(25)
AL23 M_D_CPU0_SB_DQ<24> DDR3_SB_DQ24 @S9S_MB_2U_LIB.S9S_MB_2U(SCH_1):M_D_CPU0_SB_DQ(24)
AF22 M_D_CPU0_SB_DQ<23> DDR3_SB_DQ23 @S9S_MB_2U_LIB.S9S_MB_2U(SCH_1):M_D_CPU0_SB_DQ(23)
AG23 M_D_CPU0_SB_DQ<22> DDR3_SB_DQ22 @S9S_MB_2U_LIB.S9S_MB_2U(SCH_1):M_D_CPU0_SB_DQ(22)
AD22 M_D_CPU0_SB_DQ<21> DDR3_SB_DQ21 @S9S_MB_2U_LIB.S9S_MB_2U(SCH_1):M_D_CPU0_SB_DQ(21)
AC23 M_D_CPU0_SB_DQ<20> DDR3_SB_DQ20 @S9S_MB_2U_LIB.S9S_MB_2U(SCH_1):M_D_CPU0_SB_DQ(20)
AG25 M_D_CPU0_SB_DQ<19> DDR3_SB_DQ19 @S9S_MB_2U_LIB.S9S_MB_2U(SCH_1):M_D_CPU0_SB_DQ(19)
AF26 M_D_CPU0_SB_DQ<18> DDR3_SB_DQ18 @S9S_MB_2U_LIB.S9S_MB_2U(SCH_1):M_D_CPU0_SB_DQ(18)
AC25 M_D_CPU0_SB_DQ<17> DDR3_SB_DQ17 @S9S_MB_2U_LIB.S9S_MB_2U(SCH_1):M_D_CPU0_SB_DQ(17)
AD26 M_D_CPU0_SB_DQ<16> DDR3_SB_DQ16 @S9S_MB_2U_LIB.S9S_MB_2U(SCH_1):M_D_CPU0_SB_DQ(16)
AN25 M_D_CPU0_SB_DQ<15> DDR3_SB_DQ15 @S9S_MB_2U_LIB.S9S_MB_2U(SCH_1):M_D_CPU0_SB_DQ(15)
AP26 M_D_CPU0_SB_DQ<14> DDR3_SB_DQ14 @S9S_MB_2U_LIB.S9S_MB_2U(SCH_1):M_D_CPU0_SB_DQ(14)
AL25 M_D_CPU0_SB_DQ<13> DDR3_SB_DQ13 @S9S_MB_2U_LIB.S9S_MB_2U(SCH_1):M_D_CPU0_SB_DQ(13)
AK26 M_D_CPU0_SB_DQ<12> DDR3_SB_DQ12 @S9S_MB_2U_LIB.S9S_MB_2U(SCH_1):M_D_CPU0_SB_DQ(12)
AP28 M_D_CPU0_SB_DQ<11> DDR3_SB_DQ11 @S9S_MB_2U_LIB.S9S_MB_2U(SCH_1):M_D_CPU0_SB_DQ(11)
AN29 M_D_CPU0_SB_DQ<10> DDR3_SB_DQ10 @S9S_MB_2U_LIB.S9S_MB_2U(SCH_1):M_D_CPU0_SB_DQ(10)
AK28 M_D_CPU0_SB_DQ<9> DDR3_SB_DQ9 @S9S_MB_2U_LIB.S9S_MB_2U(SCH_1):M_D_CPU0_SB_DQ(9)
AL29 M_D_CPU0_SB_DQ<8> DDR3_SB_DQ8 @S9S_MB_2U_LIB.S9S_MB_2U(SCH_1):M_D_CPU0_SB_DQ(8)
AN31 M_D_CPU0_SB_DQ<7> DDR3_SB_DQ7 @S9S_MB_2U_LIB.S9S_MB_2U(SCH_1):M_D_CPU0_SB_DQ(7)
AP32 M_D_CPU0_SB_DQ<6> DDR3_SB_DQ6 @S9S_MB_2U_LIB.S9S_MB_2U(SCH_1):M_D_CPU0_SB_DQ(6)
AL31 M_D_CPU0_SB_DQ<5> DDR3_SB_DQ5 @S9S_MB_2U_LIB.S9S_MB_2U(SCH_1):M_D_CPU0_SB_DQ(5)
AK32 M_D_CPU0_SB_DQ<4> DDR3_SB_DQ4 @S9S_MB_2U_LIB.S9S_MB_2U(SCH_1):M_D_CPU0_SB_DQ(4)
AP34 M_D_CPU0_SB_DQ<3> DDR3_SB_DQ3 @S9S_MB_2U_LIB.S9S_MB_2U(SCH_1):M_D_CPU0_SB_DQ(3)
AN35 M_D_CPU0_SB_DQ<2> DDR3_SB_DQ2 @S9S_MB_2U_LIB.S9S_MB_2U(SCH_1):M_D_CPU0_SB_DQ(2)
AK34 M_D_CPU0_SB_DQ<1> DDR3_SB_DQ1 @S9S_MB_2U_LIB.S9S_MB_2U(SCH_1):M_D_CPU0_SB_DQ(1)
AL35 M_D_CPU0_SB_DQ<0> DDR3_SB_DQ0 @S9S_MB_2U_LIB.S9S_MB_2U(SCH_1):M_D_CPU0_SB_DQ(0)
AJ39 M_D_CPU0_SB_DQS_DN<9> DDR3_SB_DQS_DN9 @S9S_MB_2U_LIB.S9S_MB_2U(SCH_1):M_D_CPU0_SB_DQS_DN(9)
AN21 M_D_CPU0_SB_DQS_DN<8> DDR3_SB_DQS_DN8 @S9S_MB_2U_LIB.S9S_MB_2U(SCH_1):M_D_CPU0_SB_DQS_DN(8)
AF24 M_D_CPU0_SB_DQS_DN<7> DDR3_SB_DQS_DN7 @S9S_MB_2U_LIB.S9S_MB_2U(SCH_1):M_D_CPU0_SB_DQS_DN(7)
AN27 M_D_CPU0_SB_DQS_DN<6> DDR3_SB_DQS_DN6 @S9S_MB_2U_LIB.S9S_MB_2U(SCH_1):M_D_CPU0_SB_DQS_DN(6)
AN33 M_D_CPU0_SB_DQS_DN<5> DDR3_SB_DQS_DN5 @S9S_MB_2U_LIB.S9S_MB_2U(SCH_1):M_D_CPU0_SB_DQS_DN(5)
AR39 M_D_CPU0_SB_DQS_DN<4> DDR3_SB_DQS_DN4 @S9S_MB_2U_LIB.S9S_MB_2U(SCH_1):M_D_CPU0_SB_DQS_DN(4)
AJ21 M_D_CPU0_SB_DQS_DN<3> DDR3_SB_DQS_DN3 @S9S_MB_2U_LIB.S9S_MB_2U(SCH_1):M_D_CPU0_SB_DQS_DN(3)
AB24 M_D_CPU0_SB_DQS_DN<2> DDR3_SB_DQS_DN2 @S9S_MB_2U_LIB.S9S_MB_2U(SCH_1):M_D_CPU0_SB_DQS_DN(2)
AJ27 M_D_CPU0_SB_DQS_DN<1> DDR3_SB_DQS_DN1 @S9S_MB_2U_LIB.S9S_MB_2U(SCH_1):M_D_CPU0_SB_DQS_DN(1)
AJ33 M_D_CPU0_SB_DQS_DN<0> DDR3_SB_DQS_DN0 @S9S_MB_2U_LIB.S9S_MB_2U(SCH_1):M_D_CPU0_SB_DQS_DN(0)
AL39 M_D_CPU0_SB_DQS_DP<9> DDR3_SB_DQS_DP9 @S9S_MB_2U_LIB.S9S_MB_2U(SCH_1):M_D_CPU0_SB_DQS_DP(9)
AR21 M_D_CPU0_SB_DQS_DP<8> DDR3_SB_DQS_DP8 @S9S_MB_2U_LIB.S9S_MB_2U(SCH_1):M_D_CPU0_SB_DQS_DP(8)
AH24 M_D_CPU0_SB_DQS_DP<7> DDR3_SB_DQS_DP7 @S9S_MB_2U_LIB.S9S_MB_2U(SCH_1):M_D_CPU0_SB_DQS_DP(7)
AR27 M_D_CPU0_SB_DQS_DP<6> DDR3_SB_DQS_DP6 @S9S_MB_2U_LIB.S9S_MB_2U(SCH_1):M_D_CPU0_SB_DQS_DP(6)
AR33 M_D_CPU0_SB_DQS_DP<5> DDR3_SB_DQS_DP5 @S9S_MB_2U_LIB.S9S_MB_2U(SCH_1):M_D_CPU0_SB_DQS_DP(5)
AN39 M_D_CPU0_SB_DQS_DP<4> DDR3_SB_DQS_DP4 @S9S_MB_2U_LIB.S9S_MB_2U(SCH_1):M_D_CPU0_SB_DQS_DP(4)
AL21 M_D_CPU0_SB_DQS_DP<3> DDR3_SB_DQS_DP3 @S9S_MB_2U_LIB.S9S_MB_2U(SCH_1):M_D_CPU0_SB_DQS_DP(3)
AD24 M_D_CPU0_SB_DQS_DP<2> DDR3_SB_DQS_DP2 @S9S_MB_2U_LIB.S9S_MB_2U(SCH_1):M_D_CPU0_SB_DQS_DP(2)
AL27 M_D_CPU0_SB_DQS_DP<1> DDR3_SB_DQS_DP1 @S9S_MB_2U_LIB.S9S_MB_2U(SCH_1):M_D_CPU0_SB_DQS_DP(1)
AL33 M_D_CPU0_SB_DQS_DP<0> DDR3_SB_DQS_DP0 @S9S_MB_2U_LIB.S9S_MB_2U(SCH_1):M_D_CPU0_SB_DQS_DP(0)
AP40 M_D_CPU0_SB_CB<7> DDR3_SB_ECC7 @S9S_MB_2U_LIB.S9S_MB_2U(SCH_1):M_D_CPU0_SB_CB(7)
AN41 M_D_CPU0_SB_CB<6> DDR3_SB_ECC6 @S9S_MB_2U_LIB.S9S_MB_2U(SCH_1):M_D_CPU0_SB_CB(6)
AK40 M_D_CPU0_SB_CB<5> DDR3_SB_ECC5 @S9S_MB_2U_LIB.S9S_MB_2U(SCH_1):M_D_CPU0_SB_CB(5)
AL41 M_D_CPU0_SB_CB<4> DDR3_SB_ECC4 @S9S_MB_2U_LIB.S9S_MB_2U(SCH_1):M_D_CPU0_SB_CB(4)
AN37 M_D_CPU0_SB_CB<3> DDR3_SB_ECC3 @S9S_MB_2U_LIB.S9S_MB_2U(SCH_1):M_D_CPU0_SB_CB(3)
AP38 M_D_CPU0_SB_CB<2> DDR3_SB_ECC2 @S9S_MB_2U_LIB.S9S_MB_2U(SCH_1):M_D_CPU0_SB_CB(2)
AL37 M_D_CPU0_SB_CB<1> DDR3_SB_ECC1 @S9S_MB_2U_LIB.S9S_MB_2U(SCH_1):M_D_CPU0_SB_CB(1)
AK38 M_D_CPU0_SB_CB<0> DDR3_SB_ECC0 @S9S_MB_2U_LIB.S9S_MB_2U(SCH_1):M_D_CPU0_SB_CB(0)
AH42 M_D_CPU0_SB_PAR DDR3_SB_PAR @S9S_MB_2U_LIB.S9S_MB_2U(SCH_1):M_D_CPU0_SB_PAR


DRAWING: @S9S_MB_2U_LIB.S9S_MB_2U(SCH_1):PAGE24 

SOCKET4677_AZIF0045P001C01CS-SA  I169  U2
CY47 M_E_CPU0_ALERT_N DDR4_ALERT_N @S9S_MB_2U_LIB.S9S_MB_2U(SCH_1):M_E_CPU0_ALERT_N
DC43 M_E_CPU0_SA_RSP<1> DDR4_A_RSP1 @S9S_MB_2U_LIB.S9S_MB_2U(SCH_1):M_E_CPU0_SA_RSP(1)
DD44 M_E_CPU0_SA_RSP<0> DDR4_A_RSP0 @S9S_MB_2U_LIB.S9S_MB_2U(SCH_1):M_E_CPU0_SA_RSP(0)
DG43 M_E_CPU0_SB_RSP<1> DDR4_B_RSP1 @S9S_MB_2U_LIB.S9S_MB_2U(SCH_1):M_E_CPU0_SB_RSP(1)
DF44 M_E_CPU0_SB_RSP<0> DDR4_B_RSP0 @S9S_MB_2U_LIB.S9S_MB_2U(SCH_1):M_E_CPU0_SB_RSP(0)
EE45 M_E_CPU0_CLK_DN<1> DDR4_CLK_DN1 @S9S_MB_2U_LIB.S9S_MB_2U(SCH_1):M_E_CPU0_CLK_DN(1)
EJ45 M_E_CPU0_CLK_DN<0> DDR4_CLK_DN0 @S9S_MB_2U_LIB.S9S_MB_2U(SCH_1):M_E_CPU0_CLK_DN(0)
EC45 M_E_CPU0_CLK_DP<1> DDR4_CLK_DP1 @S9S_MB_2U_LIB.S9S_MB_2U(SCH_1):M_E_CPU0_CLK_DP(1)
EG45 M_E_CPU0_CLK_DP<0> DDR4_CLK_DP0 @S9S_MB_2U_LIB.S9S_MB_2U(SCH_1):M_E_CPU0_CLK_DP(0)
ED44 M_E_CPU0_SA_CA<6> DDR4_SA_CA6 @S9S_MB_2U_LIB.S9S_MB_2U(SCH_1):M_E_CPU0_SA_CA(6)
EP47 M_E_CPU0_SA_CA<5> DDR4_SA_CA5 @S9S_MB_2U_LIB.S9S_MB_2U(SCH_1):M_E_CPU0_SA_CA(5)
EM47 M_E_CPU0_SA_CA<4> DDR4_SA_CA4 @S9S_MB_2U_LIB.S9S_MB_2U(SCH_1):M_E_CPU0_SA_CA(4)
EL48 M_E_CPU0_SA_CA<3> DDR4_SA_CA3 @S9S_MB_2U_LIB.S9S_MB_2U(SCH_1):M_E_CPU0_SA_CA(3)
EK49 M_E_CPU0_SA_CA<2> DDR4_SA_CA2 @S9S_MB_2U_LIB.S9S_MB_2U(SCH_1):M_E_CPU0_SA_CA(2)
ET49 M_E_CPU0_SA_CA<1> DDR4_SA_CA1 @S9S_MB_2U_LIB.S9S_MB_2U(SCH_1):M_E_CPU0_SA_CA(1)
EP49 M_E_CPU0_SA_CA<0> DDR4_SA_CA0 @S9S_MB_2U_LIB.S9S_MB_2U(SCH_1):M_E_CPU0_SA_CA(0)
EL50 M_E_CPU0_SA_CS_N<3> DDR4_SA_CS_N3 @S9S_MB_2U_LIB.S9S_MB_2U(SCH_1):M_E_CPU0_SA_CS_N(3)
EM51 M_E_CPU0_SA_CS_N<2> DDR4_SA_CS_N2 @S9S_MB_2U_LIB.S9S_MB_2U(SCH_1):M_E_CPU0_SA_CS_N(2)
ET51 M_E_CPU0_SA_CS_N<1> DDR4_SA_CS_N1 @S9S_MB_2U_LIB.S9S_MB_2U(SCH_1):M_E_CPU0_SA_CS_N(1)
EP51 M_E_CPU0_SA_CS_N<0> DDR4_SA_CS_N0 @S9S_MB_2U_LIB.S9S_MB_2U(SCH_1):M_E_CPU0_SA_CS_N(0)
EP59 M_E_CPU0_SA_DQ<31> DDR4_SA_DQ31 @S9S_MB_2U_LIB.S9S_MB_2U(SCH_1):M_E_CPU0_SA_DQ(31)
ER60 M_E_CPU0_SA_DQ<30> DDR4_SA_DQ30 @S9S_MB_2U_LIB.S9S_MB_2U(SCH_1):M_E_CPU0_SA_DQ(30)
EM59 M_E_CPU0_SA_DQ<29> DDR4_SA_DQ29 @S9S_MB_2U_LIB.S9S_MB_2U(SCH_1):M_E_CPU0_SA_DQ(29)
EL60 M_E_CPU0_SA_DQ<28> DDR4_SA_DQ28 @S9S_MB_2U_LIB.S9S_MB_2U(SCH_1):M_E_CPU0_SA_DQ(28)
ER62 M_E_CPU0_SA_DQ<27> DDR4_SA_DQ27 @S9S_MB_2U_LIB.S9S_MB_2U(SCH_1):M_E_CPU0_SA_DQ(27)
EP63 M_E_CPU0_SA_DQ<26> DDR4_SA_DQ26 @S9S_MB_2U_LIB.S9S_MB_2U(SCH_1):M_E_CPU0_SA_DQ(26)
EL62 M_E_CPU0_SA_DQ<25> DDR4_SA_DQ25 @S9S_MB_2U_LIB.S9S_MB_2U(SCH_1):M_E_CPU0_SA_DQ(25)
EM63 M_E_CPU0_SA_DQ<24> DDR4_SA_DQ24 @S9S_MB_2U_LIB.S9S_MB_2U(SCH_1):M_E_CPU0_SA_DQ(24)
EP65 M_E_CPU0_SA_DQ<23> DDR4_SA_DQ23 @S9S_MB_2U_LIB.S9S_MB_2U(SCH_1):M_E_CPU0_SA_DQ(23)
EL66 M_E_CPU0_SA_DQ<22> DDR4_SA_DQ22 @S9S_MB_2U_LIB.S9S_MB_2U(SCH_1):M_E_CPU0_SA_DQ(22)
EM65 M_E_CPU0_SA_DQ<21> DDR4_SA_DQ21 @S9S_MB_2U_LIB.S9S_MB_2U(SCH_1):M_E_CPU0_SA_DQ(21)
ER66 M_E_CPU0_SA_DQ<20> DDR4_SA_DQ20 @S9S_MB_2U_LIB.S9S_MB_2U(SCH_1):M_E_CPU0_SA_DQ(20)
ER68 M_E_CPU0_SA_DQ<19> DDR4_SA_DQ19 @S9S_MB_2U_LIB.S9S_MB_2U(SCH_1):M_E_CPU0_SA_DQ(19)
EN70 M_E_CPU0_SA_DQ<18> DDR4_SA_DQ18 @S9S_MB_2U_LIB.S9S_MB_2U(SCH_1):M_E_CPU0_SA_DQ(18)
EM69 M_E_CPU0_SA_DQ<17> DDR4_SA_DQ17 @S9S_MB_2U_LIB.S9S_MB_2U(SCH_1):M_E_CPU0_SA_DQ(17)
EM71 M_E_CPU0_SA_DQ<16> DDR4_SA_DQ16 @S9S_MB_2U_LIB.S9S_MB_2U(SCH_1):M_E_CPU0_SA_DQ(16)
EG68 M_E_CPU0_SA_DQ<15> DDR4_SA_DQ15 @S9S_MB_2U_LIB.S9S_MB_2U(SCH_1):M_E_CPU0_SA_DQ(15)
EH69 M_E_CPU0_SA_DQ<14> DDR4_SA_DQ14 @S9S_MB_2U_LIB.S9S_MB_2U(SCH_1):M_E_CPU0_SA_DQ(14)
EE68 M_E_CPU0_SA_DQ<13> DDR4_SA_DQ13 @S9S_MB_2U_LIB.S9S_MB_2U(SCH_1):M_E_CPU0_SA_DQ(13)
ED69 M_E_CPU0_SA_DQ<12> DDR4_SA_DQ12 @S9S_MB_2U_LIB.S9S_MB_2U(SCH_1):M_E_CPU0_SA_DQ(12)
EH71 M_E_CPU0_SA_DQ<11> DDR4_SA_DQ11 @S9S_MB_2U_LIB.S9S_MB_2U(SCH_1):M_E_CPU0_SA_DQ(11)
EG72 M_E_CPU0_SA_DQ<10> DDR4_SA_DQ10 @S9S_MB_2U_LIB.S9S_MB_2U(SCH_1):M_E_CPU0_SA_DQ(10)
ED71 M_E_CPU0_SA_DQ<9> DDR4_SA_DQ9 @S9S_MB_2U_LIB.S9S_MB_2U(SCH_1):M_E_CPU0_SA_DQ(9)
EE72 M_E_CPU0_SA_DQ<8> DDR4_SA_DQ8 @S9S_MB_2U_LIB.S9S_MB_2U(SCH_1):M_E_CPU0_SA_DQ(8)
ER72 M_E_CPU0_SA_DQ<7> DDR4_SA_DQ7 @S9S_MB_2U_LIB.S9S_MB_2U(SCH_1):M_E_CPU0_SA_DQ(7)
EP73 M_E_CPU0_SA_DQ<6> DDR4_SA_DQ6 @S9S_MB_2U_LIB.S9S_MB_2U(SCH_1):M_E_CPU0_SA_DQ(6)
EK73 M_E_CPU0_SA_DQ<5> DDR4_SA_DQ5 @S9S_MB_2U_LIB.S9S_MB_2U(SCH_1):M_E_CPU0_SA_DQ(5)
EL74 M_E_CPU0_SA_DQ<4> DDR4_SA_DQ4 @S9S_MB_2U_LIB.S9S_MB_2U(SCH_1):M_E_CPU0_SA_DQ(4)
ER76 M_E_CPU0_SA_DQ<3> DDR4_SA_DQ3 @S9S_MB_2U_LIB.S9S_MB_2U(SCH_1):M_E_CPU0_SA_DQ(3)
EP79 M_E_CPU0_SA_DQ<2> DDR4_SA_DQ2 @S9S_MB_2U_LIB.S9S_MB_2U(SCH_1):M_E_CPU0_SA_DQ(2)
EM77 M_E_CPU0_SA_DQ<1> DDR4_SA_DQ1 @S9S_MB_2U_LIB.S9S_MB_2U(SCH_1):M_E_CPU0_SA_DQ(1)
EL78 M_E_CPU0_SA_DQ<0> DDR4_SA_DQ0 @S9S_MB_2U_LIB.S9S_MB_2U(SCH_1):M_E_CPU0_SA_DQ(0)
ET55 M_E_CPU0_SA_DQS_DN<9> DDR4_SA_DQS_DN9 @S9S_MB_2U_LIB.S9S_MB_2U(SCH_1):M_E_CPU0_SA_DQS_DN(9)
ET61 M_E_CPU0_SA_DQS_DN<8> DDR4_SA_DQS_DN8 @S9S_MB_2U_LIB.S9S_MB_2U(SCH_1):M_E_CPU0_SA_DQS_DN(8)
EN68 M_E_CPU0_SA_DQS_DN<7> DDR4_SA_DQS_DN7 @S9S_MB_2U_LIB.S9S_MB_2U(SCH_1):M_E_CPU0_SA_DQS_DN(7)
EJ70 M_E_CPU0_SA_DQS_DN<6> DDR4_SA_DQS_DN6 @S9S_MB_2U_LIB.S9S_MB_2U(SCH_1):M_E_CPU0_SA_DQS_DN(6)
EM75 M_E_CPU0_SA_DQS_DN<5> DDR4_SA_DQS_DN5 @S9S_MB_2U_LIB.S9S_MB_2U(SCH_1):M_E_CPU0_SA_DQS_DN(5)
EM55 M_E_CPU0_SA_DQS_DN<4> DDR4_SA_DQS_DN4 @S9S_MB_2U_LIB.S9S_MB_2U(SCH_1):M_E_CPU0_SA_DQS_DN(4)
EK61 M_E_CPU0_SA_DQS_DN<3> DDR4_SA_DQS_DN3 @S9S_MB_2U_LIB.S9S_MB_2U(SCH_1):M_E_CPU0_SA_DQS_DN(3)
EK67 M_E_CPU0_SA_DQS_DN<2> DDR4_SA_DQS_DN2 @S9S_MB_2U_LIB.S9S_MB_2U(SCH_1):M_E_CPU0_SA_DQS_DN(2)
EC70 M_E_CPU0_SA_DQS_DN<1> DDR4_SA_DQS_DN1 @S9S_MB_2U_LIB.S9S_MB_2U(SCH_1):M_E_CPU0_SA_DQS_DN(1)
EP75 M_E_CPU0_SA_DQS_DN<0> DDR4_SA_DQS_DN0 @S9S_MB_2U_LIB.S9S_MB_2U(SCH_1):M_E_CPU0_SA_DQS_DN(0)
EP55 M_E_CPU0_SA_DQS_DP<9> DDR4_SA_DQS_DP9 @S9S_MB_2U_LIB.S9S_MB_2U(SCH_1):M_E_CPU0_SA_DQS_DP(9)
EP61 M_E_CPU0_SA_DQS_DP<8> DDR4_SA_DQS_DP8 @S9S_MB_2U_LIB.S9S_MB_2U(SCH_1):M_E_CPU0_SA_DQS_DP(8)
EM67 M_E_CPU0_SA_DQS_DP<7> DDR4_SA_DQS_DP7 @S9S_MB_2U_LIB.S9S_MB_2U(SCH_1):M_E_CPU0_SA_DQS_DP(7)
EG70 M_E_CPU0_SA_DQS_DP<6> DDR4_SA_DQS_DP6 @S9S_MB_2U_LIB.S9S_MB_2U(SCH_1):M_E_CPU0_SA_DQS_DP(6)
EN74 M_E_CPU0_SA_DQS_DP<5> DDR4_SA_DQS_DP5 @S9S_MB_2U_LIB.S9S_MB_2U(SCH_1):M_E_CPU0_SA_DQS_DP(5)
EK55 M_E_CPU0_SA_DQS_DP<4> DDR4_SA_DQS_DP4 @S9S_MB_2U_LIB.S9S_MB_2U(SCH_1):M_E_CPU0_SA_DQS_DP(4)
EM61 M_E_CPU0_SA_DQS_DP<3> DDR4_SA_DQS_DP3 @S9S_MB_2U_LIB.S9S_MB_2U(SCH_1):M_E_CPU0_SA_DQS_DP(3)
EL68 M_E_CPU0_SA_DQS_DP<2> DDR4_SA_DQS_DP2 @S9S_MB_2U_LIB.S9S_MB_2U(SCH_1):M_E_CPU0_SA_DQS_DP(2)
EE70 M_E_CPU0_SA_DQS_DP<1> DDR4_SA_DQS_DP1 @S9S_MB_2U_LIB.S9S_MB_2U(SCH_1):M_E_CPU0_SA_DQS_DP(1)
EN76 M_E_CPU0_SA_DQS_DP<0> DDR4_SA_DQS_DP0 @S9S_MB_2U_LIB.S9S_MB_2U(SCH_1):M_E_CPU0_SA_DQS_DP(0)
EP53 M_E_CPU0_SA_CB<7> DDR4_SA_ECC7 @S9S_MB_2U_LIB.S9S_MB_2U(SCH_1):M_E_CPU0_SA_CB(7)
ER54 M_E_CPU0_SA_CB<6> DDR4_SA_ECC6 @S9S_MB_2U_LIB.S9S_MB_2U(SCH_1):M_E_CPU0_SA_CB(6)
EM53 M_E_CPU0_SA_CB<5> DDR4_SA_ECC5 @S9S_MB_2U_LIB.S9S_MB_2U(SCH_1):M_E_CPU0_SA_CB(5)
EL54 M_E_CPU0_SA_CB<4> DDR4_SA_ECC4 @S9S_MB_2U_LIB.S9S_MB_2U(SCH_1):M_E_CPU0_SA_CB(4)
ER56 M_E_CPU0_SA_CB<3> DDR4_SA_ECC3 @S9S_MB_2U_LIB.S9S_MB_2U(SCH_1):M_E_CPU0_SA_CB(3)
EP57 M_E_CPU0_SA_CB<2> DDR4_SA_ECC2 @S9S_MB_2U_LIB.S9S_MB_2U(SCH_1):M_E_CPU0_SA_CB(2)
EL56 M_E_CPU0_SA_CB<1> DDR4_SA_ECC1 @S9S_MB_2U_LIB.S9S_MB_2U(SCH_1):M_E_CPU0_SA_CB(1)
EM57 M_E_CPU0_SA_CB<0> DDR4_SA_ECC0 @S9S_MB_2U_LIB.S9S_MB_2U(SCH_1):M_E_CPU0_SA_CB(0)
EE43 M_E_CPU0_SA_PAR DDR4_SA_PAR @S9S_MB_2U_LIB.S9S_MB_2U(SCH_1):M_E_CPU0_SA_PAR
EK42 M_E_CPU0_SB_CA<6> DDR4_SB_CA6 @S9S_MB_2U_LIB.S9S_MB_2U(SCH_1):M_E_CPU0_SB_CA(6)
ET42 M_E_CPU0_SB_CA<5> DDR4_SB_CA5 @S9S_MB_2U_LIB.S9S_MB_2U(SCH_1):M_E_CPU0_SB_CA(5)
EL43 M_E_CPU0_SB_CA<4> DDR4_SB_CA4 @S9S_MB_2U_LIB.S9S_MB_2U(SCH_1):M_E_CPU0_SB_CA(4)
EP44 M_E_CPU0_SB_CA<3> DDR4_SB_CA3 @S9S_MB_2U_LIB.S9S_MB_2U(SCH_1):M_E_CPU0_SB_CA(3)
EM44 M_E_CPU0_SB_CA<2> DDR4_SB_CA2 @S9S_MB_2U_LIB.S9S_MB_2U(SCH_1):M_E_CPU0_SB_CA(2)
EH44 M_E_CPU0_SB_CA<1> DDR4_SB_CA1 @S9S_MB_2U_LIB.S9S_MB_2U(SCH_1):M_E_CPU0_SB_CA(1)
EG43 M_E_CPU0_SB_CA<0> DDR4_SB_CA0 @S9S_MB_2U_LIB.S9S_MB_2U(SCH_1):M_E_CPU0_SB_CA(0)
EL41 M_E_CPU0_SB_CS_N<3> DDR4_SB_CS_N3 @S9S_MB_2U_LIB.S9S_MB_2U(SCH_1):M_E_CPU0_SB_CS_N(3)
EM40 M_E_CPU0_SB_CS_N<2> DDR4_SB_CS_N2 @S9S_MB_2U_LIB.S9S_MB_2U(SCH_1):M_E_CPU0_SB_CS_N(2)
ET40 M_E_CPU0_SB_CS_N<1> DDR4_SB_CS_N1 @S9S_MB_2U_LIB.S9S_MB_2U(SCH_1):M_E_CPU0_SB_CS_N(1)
EP40 M_E_CPU0_SB_CS_N<0> DDR4_SB_CS_N0 @S9S_MB_2U_LIB.S9S_MB_2U(SCH_1):M_E_CPU0_SB_CS_N(0)
EP16 M_E_CPU0_SB_DQ<31> DDR4_SB_DQ31 @S9S_MB_2U_LIB.S9S_MB_2U(SCH_1):M_E_CPU0_SB_DQ(31)
ER17 M_E_CPU0_SB_DQ<30> DDR4_SB_DQ30 @S9S_MB_2U_LIB.S9S_MB_2U(SCH_1):M_E_CPU0_SB_DQ(30)
EM16 M_E_CPU0_SB_DQ<29> DDR4_SB_DQ29 @S9S_MB_2U_LIB.S9S_MB_2U(SCH_1):M_E_CPU0_SB_DQ(29)
EL17 M_E_CPU0_SB_DQ<28> DDR4_SB_DQ28 @S9S_MB_2U_LIB.S9S_MB_2U(SCH_1):M_E_CPU0_SB_DQ(28)
ER19 M_E_CPU0_SB_DQ<27> DDR4_SB_DQ27 @S9S_MB_2U_LIB.S9S_MB_2U(SCH_1):M_E_CPU0_SB_DQ(27)
EP20 M_E_CPU0_SB_DQ<26> DDR4_SB_DQ26 @S9S_MB_2U_LIB.S9S_MB_2U(SCH_1):M_E_CPU0_SB_DQ(26)
EL19 M_E_CPU0_SB_DQ<25> DDR4_SB_DQ25 @S9S_MB_2U_LIB.S9S_MB_2U(SCH_1):M_E_CPU0_SB_DQ(25)
EM20 M_E_CPU0_SB_DQ<24> DDR4_SB_DQ24 @S9S_MB_2U_LIB.S9S_MB_2U(SCH_1):M_E_CPU0_SB_DQ(24)
EP22 M_E_CPU0_SB_DQ<23> DDR4_SB_DQ23 @S9S_MB_2U_LIB.S9S_MB_2U(SCH_1):M_E_CPU0_SB_DQ(23)
ER23 M_E_CPU0_SB_DQ<22> DDR4_SB_DQ22 @S9S_MB_2U_LIB.S9S_MB_2U(SCH_1):M_E_CPU0_SB_DQ(22)
EM22 M_E_CPU0_SB_DQ<21> DDR4_SB_DQ21 @S9S_MB_2U_LIB.S9S_MB_2U(SCH_1):M_E_CPU0_SB_DQ(21)
EL23 M_E_CPU0_SB_DQ<20> DDR4_SB_DQ20 @S9S_MB_2U_LIB.S9S_MB_2U(SCH_1):M_E_CPU0_SB_DQ(20)
ER25 M_E_CPU0_SB_DQ<19> DDR4_SB_DQ19 @S9S_MB_2U_LIB.S9S_MB_2U(SCH_1):M_E_CPU0_SB_DQ(19)
EP26 M_E_CPU0_SB_DQ<18> DDR4_SB_DQ18 @S9S_MB_2U_LIB.S9S_MB_2U(SCH_1):M_E_CPU0_SB_DQ(18)
EL25 M_E_CPU0_SB_DQ<17> DDR4_SB_DQ17 @S9S_MB_2U_LIB.S9S_MB_2U(SCH_1):M_E_CPU0_SB_DQ(17)
EM26 M_E_CPU0_SB_DQ<16> DDR4_SB_DQ16 @S9S_MB_2U_LIB.S9S_MB_2U(SCH_1):M_E_CPU0_SB_DQ(16)
EP28 M_E_CPU0_SB_DQ<15> DDR4_SB_DQ15 @S9S_MB_2U_LIB.S9S_MB_2U(SCH_1):M_E_CPU0_SB_DQ(15)
ER29 M_E_CPU0_SB_DQ<14> DDR4_SB_DQ14 @S9S_MB_2U_LIB.S9S_MB_2U(SCH_1):M_E_CPU0_SB_DQ(14)
EM28 M_E_CPU0_SB_DQ<13> DDR4_SB_DQ13 @S9S_MB_2U_LIB.S9S_MB_2U(SCH_1):M_E_CPU0_SB_DQ(13)
EL29 M_E_CPU0_SB_DQ<12> DDR4_SB_DQ12 @S9S_MB_2U_LIB.S9S_MB_2U(SCH_1):M_E_CPU0_SB_DQ(12)
ER31 M_E_CPU0_SB_DQ<11> DDR4_SB_DQ11 @S9S_MB_2U_LIB.S9S_MB_2U(SCH_1):M_E_CPU0_SB_DQ(11)
EP32 M_E_CPU0_SB_DQ<10> DDR4_SB_DQ10 @S9S_MB_2U_LIB.S9S_MB_2U(SCH_1):M_E_CPU0_SB_DQ(10)
EL31 M_E_CPU0_SB_DQ<9> DDR4_SB_DQ9 @S9S_MB_2U_LIB.S9S_MB_2U(SCH_1):M_E_CPU0_SB_DQ(9)
EM32 M_E_CPU0_SB_DQ<8> DDR4_SB_DQ8 @S9S_MB_2U_LIB.S9S_MB_2U(SCH_1):M_E_CPU0_SB_DQ(8)
EG25 M_E_CPU0_SB_DQ<7> DDR4_SB_DQ7 @S9S_MB_2U_LIB.S9S_MB_2U(SCH_1):M_E_CPU0_SB_DQ(7)
EH26 M_E_CPU0_SB_DQ<6> DDR4_SB_DQ6 @S9S_MB_2U_LIB.S9S_MB_2U(SCH_1):M_E_CPU0_SB_DQ(6)
EE25 M_E_CPU0_SB_DQ<5> DDR4_SB_DQ5 @S9S_MB_2U_LIB.S9S_MB_2U(SCH_1):M_E_CPU0_SB_DQ(5)
ED26 M_E_CPU0_SB_DQ<4> DDR4_SB_DQ4 @S9S_MB_2U_LIB.S9S_MB_2U(SCH_1):M_E_CPU0_SB_DQ(4)
EH28 M_E_CPU0_SB_DQ<3> DDR4_SB_DQ3 @S9S_MB_2U_LIB.S9S_MB_2U(SCH_1):M_E_CPU0_SB_DQ(3)
EG29 M_E_CPU0_SB_DQ<2> DDR4_SB_DQ2 @S9S_MB_2U_LIB.S9S_MB_2U(SCH_1):M_E_CPU0_SB_DQ(2)
ED28 M_E_CPU0_SB_DQ<1> DDR4_SB_DQ1 @S9S_MB_2U_LIB.S9S_MB_2U(SCH_1):M_E_CPU0_SB_DQ(1)
EE29 M_E_CPU0_SB_DQ<0> DDR4_SB_DQ0 @S9S_MB_2U_LIB.S9S_MB_2U(SCH_1):M_E_CPU0_SB_DQ(0)
EK36 M_E_CPU0_SB_DQS_DN<9> DDR4_SB_DQS_DN9 @S9S_MB_2U_LIB.S9S_MB_2U(SCH_1):M_E_CPU0_SB_DQS_DN(9)
ET18 M_E_CPU0_SB_DQS_DN<8> DDR4_SB_DQS_DN8 @S9S_MB_2U_LIB.S9S_MB_2U(SCH_1):M_E_CPU0_SB_DQS_DN(8)
ET24 M_E_CPU0_SB_DQS_DN<7> DDR4_SB_DQS_DN7 @S9S_MB_2U_LIB.S9S_MB_2U(SCH_1):M_E_CPU0_SB_DQS_DN(7)
ET30 M_E_CPU0_SB_DQS_DN<6> DDR4_SB_DQS_DN6 @S9S_MB_2U_LIB.S9S_MB_2U(SCH_1):M_E_CPU0_SB_DQS_DN(6)
EJ27 M_E_CPU0_SB_DQS_DN<5> DDR4_SB_DQS_DN5 @S9S_MB_2U_LIB.S9S_MB_2U(SCH_1):M_E_CPU0_SB_DQS_DN(5)
ET36 M_E_CPU0_SB_DQS_DN<4> DDR4_SB_DQS_DN4 @S9S_MB_2U_LIB.S9S_MB_2U(SCH_1):M_E_CPU0_SB_DQS_DN(4)
EK18 M_E_CPU0_SB_DQS_DN<3> DDR4_SB_DQS_DN3 @S9S_MB_2U_LIB.S9S_MB_2U(SCH_1):M_E_CPU0_SB_DQS_DN(3)
EK24 M_E_CPU0_SB_DQS_DN<2> DDR4_SB_DQS_DN2 @S9S_MB_2U_LIB.S9S_MB_2U(SCH_1):M_E_CPU0_SB_DQS_DN(2)
EK30 M_E_CPU0_SB_DQS_DN<1> DDR4_SB_DQS_DN1 @S9S_MB_2U_LIB.S9S_MB_2U(SCH_1):M_E_CPU0_SB_DQS_DN(1)
EE27 M_E_CPU0_SB_DQS_DN<0> DDR4_SB_DQS_DN0 @S9S_MB_2U_LIB.S9S_MB_2U(SCH_1):M_E_CPU0_SB_DQS_DN(0)
EM36 M_E_CPU0_SB_DQS_DP<9> DDR4_SB_DQS_DP9 @S9S_MB_2U_LIB.S9S_MB_2U(SCH_1):M_E_CPU0_SB_DQS_DP(9)
EP18 M_E_CPU0_SB_DQS_DP<8> DDR4_SB_DQS_DP8 @S9S_MB_2U_LIB.S9S_MB_2U(SCH_1):M_E_CPU0_SB_DQS_DP(8)
EP24 M_E_CPU0_SB_DQS_DP<7> DDR4_SB_DQS_DP7 @S9S_MB_2U_LIB.S9S_MB_2U(SCH_1):M_E_CPU0_SB_DQS_DP(7)
EP30 M_E_CPU0_SB_DQS_DP<6> DDR4_SB_DQS_DP6 @S9S_MB_2U_LIB.S9S_MB_2U(SCH_1):M_E_CPU0_SB_DQS_DP(6)
EG27 M_E_CPU0_SB_DQS_DP<5> DDR4_SB_DQS_DP5 @S9S_MB_2U_LIB.S9S_MB_2U(SCH_1):M_E_CPU0_SB_DQS_DP(5)
EP36 M_E_CPU0_SB_DQS_DP<4> DDR4_SB_DQS_DP4 @S9S_MB_2U_LIB.S9S_MB_2U(SCH_1):M_E_CPU0_SB_DQS_DP(4)
EM18 M_E_CPU0_SB_DQS_DP<3> DDR4_SB_DQS_DP3 @S9S_MB_2U_LIB.S9S_MB_2U(SCH_1):M_E_CPU0_SB_DQS_DP(3)
EM24 M_E_CPU0_SB_DQS_DP<2> DDR4_SB_DQS_DP2 @S9S_MB_2U_LIB.S9S_MB_2U(SCH_1):M_E_CPU0_SB_DQS_DP(2)
EM30 M_E_CPU0_SB_DQS_DP<1> DDR4_SB_DQS_DP1 @S9S_MB_2U_LIB.S9S_MB_2U(SCH_1):M_E_CPU0_SB_DQS_DP(1)
EC27 M_E_CPU0_SB_DQS_DP<0> DDR4_SB_DQS_DP0 @S9S_MB_2U_LIB.S9S_MB_2U(SCH_1):M_E_CPU0_SB_DQS_DP(0)
ER37 M_E_CPU0_SB_CB<7> DDR4_SB_ECC7 @S9S_MB_2U_LIB.S9S_MB_2U(SCH_1):M_E_CPU0_SB_CB(7)
EP38 M_E_CPU0_SB_CB<6> DDR4_SB_ECC6 @S9S_MB_2U_LIB.S9S_MB_2U(SCH_1):M_E_CPU0_SB_CB(6)
EL37 M_E_CPU0_SB_CB<5> DDR4_SB_ECC5 @S9S_MB_2U_LIB.S9S_MB_2U(SCH_1):M_E_CPU0_SB_CB(5)
EM38 M_E_CPU0_SB_CB<4> DDR4_SB_ECC4 @S9S_MB_2U_LIB.S9S_MB_2U(SCH_1):M_E_CPU0_SB_CB(4)
EP34 M_E_CPU0_SB_CB<3> DDR4_SB_ECC3 @S9S_MB_2U_LIB.S9S_MB_2U(SCH_1):M_E_CPU0_SB_CB(3)
ER35 M_E_CPU0_SB_CB<2> DDR4_SB_ECC2 @S9S_MB_2U_LIB.S9S_MB_2U(SCH_1):M_E_CPU0_SB_CB(2)
EM34 M_E_CPU0_SB_CB<1> DDR4_SB_ECC1 @S9S_MB_2U_LIB.S9S_MB_2U(SCH_1):M_E_CPU0_SB_CB(1)
EL35 M_E_CPU0_SB_CB<0> DDR4_SB_ECC0 @S9S_MB_2U_LIB.S9S_MB_2U(SCH_1):M_E_CPU0_SB_CB(0)
EP42 M_E_CPU0_SB_PAR DDR4_SB_PAR @S9S_MB_2U_LIB.S9S_MB_2U(SCH_1):M_E_CPU0_SB_PAR


DRAWING: @S9S_MB_2U_LIB.S9S_MB_2U(SCH_1):PAGE25 

SOCKET4677_AZIF0045P001C01CS-SA  I169  U2
CW48 M_F_CPU0_ALERT_N DDR5_ALERT_N @S9S_MB_2U_LIB.S9S_MB_2U(SCH_1):M_F_CPU0_ALERT_N
DP47 M_F_CPU0_SA_RSP<1> DDR5_A_RSP1 @S9S_MB_2U_LIB.S9S_MB_2U(SCH_1):M_F_CPU0_SA_RSP(1)
DN48 M_F_CPU0_SA_RSP<0> DDR5_A_RSP0 @S9S_MB_2U_LIB.S9S_MB_2U(SCH_1):M_F_CPU0_SA_RSP(0)
DK47 M_F_CPU0_SB_RSP<1> DDR5_B_RSP1 @S9S_MB_2U_LIB.S9S_MB_2U(SCH_1):M_F_CPU0_SB_RSP(1)
DL48 M_F_CPU0_SB_RSP<0> DDR5_B_RSP0 @S9S_MB_2U_LIB.S9S_MB_2U(SCH_1):M_F_CPU0_SB_RSP(0)
DV49 M_F_CPU0_CLK_DN<1> DDR5_CLK_DN1 @S9S_MB_2U_LIB.S9S_MB_2U(SCH_1):M_F_CPU0_CLK_DN(1)
DY49 M_F_CPU0_CLK_DN<0> DDR5_CLK_DN0 @S9S_MB_2U_LIB.S9S_MB_2U(SCH_1):M_F_CPU0_CLK_DN(0)
DT49 M_F_CPU0_CLK_DP<1> DDR5_CLK_DP1 @S9S_MB_2U_LIB.S9S_MB_2U(SCH_1):M_F_CPU0_CLK_DP(1)
EB49 M_F_CPU0_CLK_DP<0> DDR5_CLK_DP0 @S9S_MB_2U_LIB.S9S_MB_2U(SCH_1):M_F_CPU0_CLK_DP(0)
DY51 M_F_CPU0_SA_CA<6> DDR5_SA_CA6 @S9S_MB_2U_LIB.S9S_MB_2U(SCH_1):M_F_CPU0_SA_CA(6)
EG50 M_F_CPU0_SA_CA<5> DDR5_SA_CA5 @S9S_MB_2U_LIB.S9S_MB_2U(SCH_1):M_F_CPU0_SA_CA(5)
EE50 M_F_CPU0_SA_CA<4> DDR5_SA_CA4 @S9S_MB_2U_LIB.S9S_MB_2U(SCH_1):M_F_CPU0_SA_CA(4)
EH51 M_F_CPU0_SA_CA<3> DDR5_SA_CA3 @S9S_MB_2U_LIB.S9S_MB_2U(SCH_1):M_F_CPU0_SA_CA(3)
ED51 M_F_CPU0_SA_CA<2> DDR5_SA_CA2 @S9S_MB_2U_LIB.S9S_MB_2U(SCH_1):M_F_CPU0_SA_CA(2)
EJ52 M_F_CPU0_SA_CA<1> DDR5_SA_CA1 @S9S_MB_2U_LIB.S9S_MB_2U(SCH_1):M_F_CPU0_SA_CA(1)
EC52 M_F_CPU0_SA_CA<0> DDR5_SA_CA0 @S9S_MB_2U_LIB.S9S_MB_2U(SCH_1):M_F_CPU0_SA_CA(0)
ED53 M_F_CPU0_SA_CS_N<3> DDR5_SA_CS_N3 @S9S_MB_2U_LIB.S9S_MB_2U(SCH_1):M_F_CPU0_SA_CS_N(3)
EE54 M_F_CPU0_SA_CS_N<2> DDR5_SA_CS_N2 @S9S_MB_2U_LIB.S9S_MB_2U(SCH_1):M_F_CPU0_SA_CS_N(2)
EH53 M_F_CPU0_SA_CS_N<1> DDR5_SA_CS_N1 @S9S_MB_2U_LIB.S9S_MB_2U(SCH_1):M_F_CPU0_SA_CS_N(1)
EG54 M_F_CPU0_SA_CS_N<0> DDR5_SA_CS_N0 @S9S_MB_2U_LIB.S9S_MB_2U(SCH_1):M_F_CPU0_SA_CS_N(0)
DY53 M_F_CPU0_SA_DQ<31> DDR5_SA_DQ31 @S9S_MB_2U_LIB.S9S_MB_2U(SCH_1):M_F_CPU0_SA_DQ(31)
EA54 M_F_CPU0_SA_DQ<30> DDR5_SA_DQ30 @S9S_MB_2U_LIB.S9S_MB_2U(SCH_1):M_F_CPU0_SA_DQ(30)
DV53 M_F_CPU0_SA_DQ<29> DDR5_SA_DQ29 @S9S_MB_2U_LIB.S9S_MB_2U(SCH_1):M_F_CPU0_SA_DQ(29)
DU54 M_F_CPU0_SA_DQ<28> DDR5_SA_DQ28 @S9S_MB_2U_LIB.S9S_MB_2U(SCH_1):M_F_CPU0_SA_DQ(28)
EA56 M_F_CPU0_SA_DQ<27> DDR5_SA_DQ27 @S9S_MB_2U_LIB.S9S_MB_2U(SCH_1):M_F_CPU0_SA_DQ(27)
DY57 M_F_CPU0_SA_DQ<26> DDR5_SA_DQ26 @S9S_MB_2U_LIB.S9S_MB_2U(SCH_1):M_F_CPU0_SA_DQ(26)
DU56 M_F_CPU0_SA_DQ<25> DDR5_SA_DQ25 @S9S_MB_2U_LIB.S9S_MB_2U(SCH_1):M_F_CPU0_SA_DQ(25)
DV57 M_F_CPU0_SA_DQ<24> DDR5_SA_DQ24 @S9S_MB_2U_LIB.S9S_MB_2U(SCH_1):M_F_CPU0_SA_DQ(24)
EG62 M_F_CPU0_SA_DQ<23> DDR5_SA_DQ23 @S9S_MB_2U_LIB.S9S_MB_2U(SCH_1):M_F_CPU0_SA_DQ(23)
EH63 M_F_CPU0_SA_DQ<22> DDR5_SA_DQ22 @S9S_MB_2U_LIB.S9S_MB_2U(SCH_1):M_F_CPU0_SA_DQ(22)
EE62 M_F_CPU0_SA_DQ<21> DDR5_SA_DQ21 @S9S_MB_2U_LIB.S9S_MB_2U(SCH_1):M_F_CPU0_SA_DQ(21)
ED63 M_F_CPU0_SA_DQ<20> DDR5_SA_DQ20 @S9S_MB_2U_LIB.S9S_MB_2U(SCH_1):M_F_CPU0_SA_DQ(20)
EH65 M_F_CPU0_SA_DQ<19> DDR5_SA_DQ19 @S9S_MB_2U_LIB.S9S_MB_2U(SCH_1):M_F_CPU0_SA_DQ(19)
EG66 M_F_CPU0_SA_DQ<18> DDR5_SA_DQ18 @S9S_MB_2U_LIB.S9S_MB_2U(SCH_1):M_F_CPU0_SA_DQ(18)
ED65 M_F_CPU0_SA_DQ<17> DDR5_SA_DQ17 @S9S_MB_2U_LIB.S9S_MB_2U(SCH_1):M_F_CPU0_SA_DQ(17)
EE66 M_F_CPU0_SA_DQ<16> DDR5_SA_DQ16 @S9S_MB_2U_LIB.S9S_MB_2U(SCH_1):M_F_CPU0_SA_DQ(16)
DY65 M_F_CPU0_SA_DQ<15> DDR5_SA_DQ15 @S9S_MB_2U_LIB.S9S_MB_2U(SCH_1):M_F_CPU0_SA_DQ(15)
EA66 M_F_CPU0_SA_DQ<14> DDR5_SA_DQ14 @S9S_MB_2U_LIB.S9S_MB_2U(SCH_1):M_F_CPU0_SA_DQ(14)
DV65 M_F_CPU0_SA_DQ<13> DDR5_SA_DQ13 @S9S_MB_2U_LIB.S9S_MB_2U(SCH_1):M_F_CPU0_SA_DQ(13)
DU66 M_F_CPU0_SA_DQ<12> DDR5_SA_DQ12 @S9S_MB_2U_LIB.S9S_MB_2U(SCH_1):M_F_CPU0_SA_DQ(12)
EA68 M_F_CPU0_SA_DQ<11> DDR5_SA_DQ11 @S9S_MB_2U_LIB.S9S_MB_2U(SCH_1):M_F_CPU0_SA_DQ(11)
DY69 M_F_CPU0_SA_DQ<10> DDR5_SA_DQ10 @S9S_MB_2U_LIB.S9S_MB_2U(SCH_1):M_F_CPU0_SA_DQ(10)
DU68 M_F_CPU0_SA_DQ<9> DDR5_SA_DQ9 @S9S_MB_2U_LIB.S9S_MB_2U(SCH_1):M_F_CPU0_SA_DQ(9)
DV69 M_F_CPU0_SA_DQ<8> DDR5_SA_DQ8 @S9S_MB_2U_LIB.S9S_MB_2U(SCH_1):M_F_CPU0_SA_DQ(8)
EG74 M_F_CPU0_SA_DQ<7> DDR5_SA_DQ7 @S9S_MB_2U_LIB.S9S_MB_2U(SCH_1):M_F_CPU0_SA_DQ(7)
EH75 M_F_CPU0_SA_DQ<6> DDR5_SA_DQ6 @S9S_MB_2U_LIB.S9S_MB_2U(SCH_1):M_F_CPU0_SA_DQ(6)
EE74 M_F_CPU0_SA_DQ<5> DDR5_SA_DQ5 @S9S_MB_2U_LIB.S9S_MB_2U(SCH_1):M_F_CPU0_SA_DQ(5)
ED75 M_F_CPU0_SA_DQ<4> DDR5_SA_DQ4 @S9S_MB_2U_LIB.S9S_MB_2U(SCH_1):M_F_CPU0_SA_DQ(4)
EG78 M_F_CPU0_SA_DQ<3> DDR5_SA_DQ3 @S9S_MB_2U_LIB.S9S_MB_2U(SCH_1):M_F_CPU0_SA_DQ(3)
ED77 M_F_CPU0_SA_DQ<2> DDR5_SA_DQ2 @S9S_MB_2U_LIB.S9S_MB_2U(SCH_1):M_F_CPU0_SA_DQ(2)
EH77 M_F_CPU0_SA_DQ<1> DDR5_SA_DQ1 @S9S_MB_2U_LIB.S9S_MB_2U(SCH_1):M_F_CPU0_SA_DQ(1)
EB77 M_F_CPU0_SA_DQ<0> DDR5_SA_DQ0 @S9S_MB_2U_LIB.S9S_MB_2U(SCH_1):M_F_CPU0_SA_DQ(0)
EJ58 M_F_CPU0_SA_DQS_DN<9> DDR5_SA_DQS_DN9 @S9S_MB_2U_LIB.S9S_MB_2U(SCH_1):M_F_CPU0_SA_DQS_DN(9)
EB55 M_F_CPU0_SA_DQS_DN<8> DDR5_SA_DQS_DN8 @S9S_MB_2U_LIB.S9S_MB_2U(SCH_1):M_F_CPU0_SA_DQS_DN(8)
EJ64 M_F_CPU0_SA_DQS_DN<7> DDR5_SA_DQS_DN7 @S9S_MB_2U_LIB.S9S_MB_2U(SCH_1):M_F_CPU0_SA_DQS_DN(7)
EB67 M_F_CPU0_SA_DQS_DN<6> DDR5_SA_DQS_DN6 @S9S_MB_2U_LIB.S9S_MB_2U(SCH_1):M_F_CPU0_SA_DQS_DN(6)
EJ76 M_F_CPU0_SA_DQS_DN<5> DDR5_SA_DQS_DN5 @S9S_MB_2U_LIB.S9S_MB_2U(SCH_1):M_F_CPU0_SA_DQS_DN(5)
EE58 M_F_CPU0_SA_DQS_DN<4> DDR5_SA_DQS_DN4 @S9S_MB_2U_LIB.S9S_MB_2U(SCH_1):M_F_CPU0_SA_DQS_DN(4)
DV55 M_F_CPU0_SA_DQS_DN<3> DDR5_SA_DQS_DN3 @S9S_MB_2U_LIB.S9S_MB_2U(SCH_1):M_F_CPU0_SA_DQS_DN(3)
EC64 M_F_CPU0_SA_DQS_DN<2> DDR5_SA_DQS_DN2 @S9S_MB_2U_LIB.S9S_MB_2U(SCH_1):M_F_CPU0_SA_DQS_DN(2)
DT67 M_F_CPU0_SA_DQS_DN<1> DDR5_SA_DQS_DN1 @S9S_MB_2U_LIB.S9S_MB_2U(SCH_1):M_F_CPU0_SA_DQS_DN(1)
EE76 M_F_CPU0_SA_DQS_DN<0> DDR5_SA_DQS_DN0 @S9S_MB_2U_LIB.S9S_MB_2U(SCH_1):M_F_CPU0_SA_DQS_DN(0)
EG58 M_F_CPU0_SA_DQS_DP<9> DDR5_SA_DQS_DP9 @S9S_MB_2U_LIB.S9S_MB_2U(SCH_1):M_F_CPU0_SA_DQS_DP(9)
DY55 M_F_CPU0_SA_DQS_DP<8> DDR5_SA_DQS_DP8 @S9S_MB_2U_LIB.S9S_MB_2U(SCH_1):M_F_CPU0_SA_DQS_DP(8)
EG64 M_F_CPU0_SA_DQS_DP<7> DDR5_SA_DQS_DP7 @S9S_MB_2U_LIB.S9S_MB_2U(SCH_1):M_F_CPU0_SA_DQS_DP(7)
DY67 M_F_CPU0_SA_DQS_DP<6> DDR5_SA_DQS_DP6 @S9S_MB_2U_LIB.S9S_MB_2U(SCH_1):M_F_CPU0_SA_DQS_DP(6)
EG76 M_F_CPU0_SA_DQS_DP<5> DDR5_SA_DQS_DP5 @S9S_MB_2U_LIB.S9S_MB_2U(SCH_1):M_F_CPU0_SA_DQS_DP(5)
EC58 M_F_CPU0_SA_DQS_DP<4> DDR5_SA_DQS_DP4 @S9S_MB_2U_LIB.S9S_MB_2U(SCH_1):M_F_CPU0_SA_DQS_DP(4)
DT55 M_F_CPU0_SA_DQS_DP<3> DDR5_SA_DQS_DP3 @S9S_MB_2U_LIB.S9S_MB_2U(SCH_1):M_F_CPU0_SA_DQS_DP(3)
EE64 M_F_CPU0_SA_DQS_DP<2> DDR5_SA_DQS_DP2 @S9S_MB_2U_LIB.S9S_MB_2U(SCH_1):M_F_CPU0_SA_DQS_DP(2)
DV67 M_F_CPU0_SA_DQS_DP<1> DDR5_SA_DQS_DP1 @S9S_MB_2U_LIB.S9S_MB_2U(SCH_1):M_F_CPU0_SA_DQS_DP(1)
EC76 M_F_CPU0_SA_DQS_DP<0> DDR5_SA_DQS_DP0 @S9S_MB_2U_LIB.S9S_MB_2U(SCH_1):M_F_CPU0_SA_DQS_DP(0)
EG56 M_F_CPU0_SA_CB<7> DDR5_SA_ECC7 @S9S_MB_2U_LIB.S9S_MB_2U(SCH_1):M_F_CPU0_SA_CB(7)
EH57 M_F_CPU0_SA_CB<6> DDR5_SA_ECC6 @S9S_MB_2U_LIB.S9S_MB_2U(SCH_1):M_F_CPU0_SA_CB(6)
EE56 M_F_CPU0_SA_CB<5> DDR5_SA_ECC5 @S9S_MB_2U_LIB.S9S_MB_2U(SCH_1):M_F_CPU0_SA_CB(5)
ED57 M_F_CPU0_SA_CB<4> DDR5_SA_ECC4 @S9S_MB_2U_LIB.S9S_MB_2U(SCH_1):M_F_CPU0_SA_CB(4)
EH59 M_F_CPU0_SA_CB<3> DDR5_SA_ECC3 @S9S_MB_2U_LIB.S9S_MB_2U(SCH_1):M_F_CPU0_SA_CB(3)
EG60 M_F_CPU0_SA_CB<2> DDR5_SA_ECC2 @S9S_MB_2U_LIB.S9S_MB_2U(SCH_1):M_F_CPU0_SA_CB(2)
ED59 M_F_CPU0_SA_CB<1> DDR5_SA_ECC1 @S9S_MB_2U_LIB.S9S_MB_2U(SCH_1):M_F_CPU0_SA_CB(1)
EE60 M_F_CPU0_SA_CB<0> DDR5_SA_ECC0 @S9S_MB_2U_LIB.S9S_MB_2U(SCH_1):M_F_CPU0_SA_CB(0)
EA50 M_F_CPU0_SA_PAR DDR5_SA_PAR @S9S_MB_2U_LIB.S9S_MB_2U(SCH_1):M_F_CPU0_SA_PAR
EC39 M_F_CPU0_SB_CA<6> DDR5_SB_CA6 @S9S_MB_2U_LIB.S9S_MB_2U(SCH_1):M_F_CPU0_SB_CA(6)
EH40 M_F_CPU0_SB_CA<5> DDR5_SB_CA5 @S9S_MB_2U_LIB.S9S_MB_2U(SCH_1):M_F_CPU0_SB_CA(5)
ED40 M_F_CPU0_SB_CA<4> DDR5_SB_CA4 @S9S_MB_2U_LIB.S9S_MB_2U(SCH_1):M_F_CPU0_SB_CA(4)
EG41 M_F_CPU0_SB_CA<3> DDR5_SB_CA3 @S9S_MB_2U_LIB.S9S_MB_2U(SCH_1):M_F_CPU0_SB_CA(3)
EE41 M_F_CPU0_SB_CA<2> DDR5_SB_CA2 @S9S_MB_2U_LIB.S9S_MB_2U(SCH_1):M_F_CPU0_SB_CA(2)
DU50 M_F_CPU0_SB_CA<1> DDR5_SB_CA1 @S9S_MB_2U_LIB.S9S_MB_2U(SCH_1):M_F_CPU0_SB_CA(1)
DV51 M_F_CPU0_SB_CA<0> DDR5_SB_CA0 @S9S_MB_2U_LIB.S9S_MB_2U(SCH_1):M_F_CPU0_SB_CA(0)
EE37 M_F_CPU0_SB_CS_N<3> DDR5_SB_CS_N3 @S9S_MB_2U_LIB.S9S_MB_2U(SCH_1):M_F_CPU0_SB_CS_N(3)
ED38 M_F_CPU0_SB_CS_N<2> DDR5_SB_CS_N2 @S9S_MB_2U_LIB.S9S_MB_2U(SCH_1):M_F_CPU0_SB_CS_N(2)
EG37 M_F_CPU0_SB_CS_N<1> DDR5_SB_CS_N1 @S9S_MB_2U_LIB.S9S_MB_2U(SCH_1):M_F_CPU0_SB_CS_N(1)
EH38 M_F_CPU0_SB_CS_N<0> DDR5_SB_CS_N0 @S9S_MB_2U_LIB.S9S_MB_2U(SCH_1):M_F_CPU0_SB_CS_N(0)
DR17 M_F_CPU0_SB_DQ<31> DDR5_SB_DQ31 @S9S_MB_2U_LIB.S9S_MB_2U(SCH_1):M_F_CPU0_SB_DQ(31)
EC17 M_F_CPU0_SB_DQ<30> DDR5_SB_DQ30 @S9S_MB_2U_LIB.S9S_MB_2U(SCH_1):M_F_CPU0_SB_DQ(30)
DU17 M_F_CPU0_SB_DQ<29> DDR5_SB_DQ29 @S9S_MB_2U_LIB.S9S_MB_2U(SCH_1):M_F_CPU0_SB_DQ(29)
EA17 M_F_CPU0_SB_DQ<28> DDR5_SB_DQ28 @S9S_MB_2U_LIB.S9S_MB_2U(SCH_1):M_F_CPU0_SB_DQ(28)
EA19 M_F_CPU0_SB_DQ<27> DDR5_SB_DQ27 @S9S_MB_2U_LIB.S9S_MB_2U(SCH_1):M_F_CPU0_SB_DQ(27)
DY20 M_F_CPU0_SB_DQ<26> DDR5_SB_DQ26 @S9S_MB_2U_LIB.S9S_MB_2U(SCH_1):M_F_CPU0_SB_DQ(26)
DU19 M_F_CPU0_SB_DQ<25> DDR5_SB_DQ25 @S9S_MB_2U_LIB.S9S_MB_2U(SCH_1):M_F_CPU0_SB_DQ(25)
DV20 M_F_CPU0_SB_DQ<24> DDR5_SB_DQ24 @S9S_MB_2U_LIB.S9S_MB_2U(SCH_1):M_F_CPU0_SB_DQ(24)
EP10 M_F_CPU0_SB_DQ<23> DDR5_SB_DQ23 @S9S_MB_2U_LIB.S9S_MB_2U(SCH_1):M_F_CPU0_SB_DQ(23)
ER11 M_F_CPU0_SB_DQ<22> DDR5_SB_DQ22 @S9S_MB_2U_LIB.S9S_MB_2U(SCH_1):M_F_CPU0_SB_DQ(22)
EM10 M_F_CPU0_SB_DQ<21> DDR5_SB_DQ21 @S9S_MB_2U_LIB.S9S_MB_2U(SCH_1):M_F_CPU0_SB_DQ(21)
EL11 M_F_CPU0_SB_DQ<20> DDR5_SB_DQ20 @S9S_MB_2U_LIB.S9S_MB_2U(SCH_1):M_F_CPU0_SB_DQ(20)
ER13 M_F_CPU0_SB_DQ<19> DDR5_SB_DQ19 @S9S_MB_2U_LIB.S9S_MB_2U(SCH_1):M_F_CPU0_SB_DQ(19)
EP14 M_F_CPU0_SB_DQ<18> DDR5_SB_DQ18 @S9S_MB_2U_LIB.S9S_MB_2U(SCH_1):M_F_CPU0_SB_DQ(18)
EL13 M_F_CPU0_SB_DQ<17> DDR5_SB_DQ17 @S9S_MB_2U_LIB.S9S_MB_2U(SCH_1):M_F_CPU0_SB_DQ(17)
EM14 M_F_CPU0_SB_DQ<16> DDR5_SB_DQ16 @S9S_MB_2U_LIB.S9S_MB_2U(SCH_1):M_F_CPU0_SB_DQ(16)
EG19 M_F_CPU0_SB_DQ<15> DDR5_SB_DQ15 @S9S_MB_2U_LIB.S9S_MB_2U(SCH_1):M_F_CPU0_SB_DQ(15)
EH20 M_F_CPU0_SB_DQ<14> DDR5_SB_DQ14 @S9S_MB_2U_LIB.S9S_MB_2U(SCH_1):M_F_CPU0_SB_DQ(14)
EE19 M_F_CPU0_SB_DQ<13> DDR5_SB_DQ13 @S9S_MB_2U_LIB.S9S_MB_2U(SCH_1):M_F_CPU0_SB_DQ(13)
ED20 M_F_CPU0_SB_DQ<12> DDR5_SB_DQ12 @S9S_MB_2U_LIB.S9S_MB_2U(SCH_1):M_F_CPU0_SB_DQ(12)
EH22 M_F_CPU0_SB_DQ<11> DDR5_SB_DQ11 @S9S_MB_2U_LIB.S9S_MB_2U(SCH_1):M_F_CPU0_SB_DQ(11)
EG23 M_F_CPU0_SB_DQ<10> DDR5_SB_DQ10 @S9S_MB_2U_LIB.S9S_MB_2U(SCH_1):M_F_CPU0_SB_DQ(10)
ED22 M_F_CPU0_SB_DQ<9> DDR5_SB_DQ9 @S9S_MB_2U_LIB.S9S_MB_2U(SCH_1):M_F_CPU0_SB_DQ(9)
EE23 M_F_CPU0_SB_DQ<8> DDR5_SB_DQ8 @S9S_MB_2U_LIB.S9S_MB_2U(SCH_1):M_F_CPU0_SB_DQ(8)
DY28 M_F_CPU0_SB_DQ<7> DDR5_SB_DQ7 @S9S_MB_2U_LIB.S9S_MB_2U(SCH_1):M_F_CPU0_SB_DQ(7)
EA29 M_F_CPU0_SB_DQ<6> DDR5_SB_DQ6 @S9S_MB_2U_LIB.S9S_MB_2U(SCH_1):M_F_CPU0_SB_DQ(6)
DV28 M_F_CPU0_SB_DQ<5> DDR5_SB_DQ5 @S9S_MB_2U_LIB.S9S_MB_2U(SCH_1):M_F_CPU0_SB_DQ(5)
DU29 M_F_CPU0_SB_DQ<4> DDR5_SB_DQ4 @S9S_MB_2U_LIB.S9S_MB_2U(SCH_1):M_F_CPU0_SB_DQ(4)
EA31 M_F_CPU0_SB_DQ<3> DDR5_SB_DQ3 @S9S_MB_2U_LIB.S9S_MB_2U(SCH_1):M_F_CPU0_SB_DQ(3)
DY32 M_F_CPU0_SB_DQ<2> DDR5_SB_DQ2 @S9S_MB_2U_LIB.S9S_MB_2U(SCH_1):M_F_CPU0_SB_DQ(2)
DU31 M_F_CPU0_SB_DQ<1> DDR5_SB_DQ1 @S9S_MB_2U_LIB.S9S_MB_2U(SCH_1):M_F_CPU0_SB_DQ(1)
DV32 M_F_CPU0_SB_DQ<0> DDR5_SB_DQ0 @S9S_MB_2U_LIB.S9S_MB_2U(SCH_1):M_F_CPU0_SB_DQ(0)
EE33 M_F_CPU0_SB_DQS_DN<9> DDR5_SB_DQS_DN9 @S9S_MB_2U_LIB.S9S_MB_2U(SCH_1):M_F_CPU0_SB_DQS_DN(9)
DY18 M_F_CPU0_SB_DQS_DN<8> DDR5_SB_DQS_DN8 @S9S_MB_2U_LIB.S9S_MB_2U(SCH_1):M_F_CPU0_SB_DQS_DN(8)
ET12 M_F_CPU0_SB_DQS_DN<7> DDR5_SB_DQS_DN7 @S9S_MB_2U_LIB.S9S_MB_2U(SCH_1):M_F_CPU0_SB_DQS_DN(7)
EJ21 M_F_CPU0_SB_DQS_DN<6> DDR5_SB_DQS_DN6 @S9S_MB_2U_LIB.S9S_MB_2U(SCH_1):M_F_CPU0_SB_DQS_DN(6)
EB30 M_F_CPU0_SB_DQS_DN<5> DDR5_SB_DQS_DN5 @S9S_MB_2U_LIB.S9S_MB_2U(SCH_1):M_F_CPU0_SB_DQS_DN(5)
EJ33 M_F_CPU0_SB_DQS_DN<4> DDR5_SB_DQS_DN4 @S9S_MB_2U_LIB.S9S_MB_2U(SCH_1):M_F_CPU0_SB_DQS_DN(4)
DT18 M_F_CPU0_SB_DQS_DN<3> DDR5_SB_DQS_DN3 @S9S_MB_2U_LIB.S9S_MB_2U(SCH_1):M_F_CPU0_SB_DQS_DN(3)
EM12 M_F_CPU0_SB_DQS_DN<2> DDR5_SB_DQS_DN2 @S9S_MB_2U_LIB.S9S_MB_2U(SCH_1):M_F_CPU0_SB_DQS_DN(2)
EE21 M_F_CPU0_SB_DQS_DN<1> DDR5_SB_DQS_DN1 @S9S_MB_2U_LIB.S9S_MB_2U(SCH_1):M_F_CPU0_SB_DQS_DN(1)
DV30 M_F_CPU0_SB_DQS_DN<0> DDR5_SB_DQS_DN0 @S9S_MB_2U_LIB.S9S_MB_2U(SCH_1):M_F_CPU0_SB_DQS_DN(0)
EC33 M_F_CPU0_SB_DQS_DP<9> DDR5_SB_DQS_DP9 @S9S_MB_2U_LIB.S9S_MB_2U(SCH_1):M_F_CPU0_SB_DQS_DP(9)
EB18 M_F_CPU0_SB_DQS_DP<8> DDR5_SB_DQS_DP8 @S9S_MB_2U_LIB.S9S_MB_2U(SCH_1):M_F_CPU0_SB_DQS_DP(8)
EP12 M_F_CPU0_SB_DQS_DP<7> DDR5_SB_DQS_DP7 @S9S_MB_2U_LIB.S9S_MB_2U(SCH_1):M_F_CPU0_SB_DQS_DP(7)
EG21 M_F_CPU0_SB_DQS_DP<6> DDR5_SB_DQS_DP6 @S9S_MB_2U_LIB.S9S_MB_2U(SCH_1):M_F_CPU0_SB_DQS_DP(6)
DY30 M_F_CPU0_SB_DQS_DP<5> DDR5_SB_DQS_DP5 @S9S_MB_2U_LIB.S9S_MB_2U(SCH_1):M_F_CPU0_SB_DQS_DP(5)
EG33 M_F_CPU0_SB_DQS_DP<4> DDR5_SB_DQS_DP4 @S9S_MB_2U_LIB.S9S_MB_2U(SCH_1):M_F_CPU0_SB_DQS_DP(4)
DV18 M_F_CPU0_SB_DQS_DP<3> DDR5_SB_DQS_DP3 @S9S_MB_2U_LIB.S9S_MB_2U(SCH_1):M_F_CPU0_SB_DQS_DP(3)
EK12 M_F_CPU0_SB_DQS_DP<2> DDR5_SB_DQS_DP2 @S9S_MB_2U_LIB.S9S_MB_2U(SCH_1):M_F_CPU0_SB_DQS_DP(2)
EC21 M_F_CPU0_SB_DQS_DP<1> DDR5_SB_DQS_DP1 @S9S_MB_2U_LIB.S9S_MB_2U(SCH_1):M_F_CPU0_SB_DQS_DP(1)
DT30 M_F_CPU0_SB_DQS_DP<0> DDR5_SB_DQS_DP0 @S9S_MB_2U_LIB.S9S_MB_2U(SCH_1):M_F_CPU0_SB_DQS_DP(0)
EH34 M_F_CPU0_SB_CB<7> DDR5_SB_ECC7 @S9S_MB_2U_LIB.S9S_MB_2U(SCH_1):M_F_CPU0_SB_CB(7)
EG35 M_F_CPU0_SB_CB<6> DDR5_SB_ECC6 @S9S_MB_2U_LIB.S9S_MB_2U(SCH_1):M_F_CPU0_SB_CB(6)
ED34 M_F_CPU0_SB_CB<5> DDR5_SB_ECC5 @S9S_MB_2U_LIB.S9S_MB_2U(SCH_1):M_F_CPU0_SB_CB(5)
EE35 M_F_CPU0_SB_CB<4> DDR5_SB_ECC4 @S9S_MB_2U_LIB.S9S_MB_2U(SCH_1):M_F_CPU0_SB_CB(4)
EG31 M_F_CPU0_SB_CB<3> DDR5_SB_ECC3 @S9S_MB_2U_LIB.S9S_MB_2U(SCH_1):M_F_CPU0_SB_CB(3)
EH32 M_F_CPU0_SB_CB<2> DDR5_SB_ECC2 @S9S_MB_2U_LIB.S9S_MB_2U(SCH_1):M_F_CPU0_SB_CB(2)
EE31 M_F_CPU0_SB_CB<1> DDR5_SB_ECC1 @S9S_MB_2U_LIB.S9S_MB_2U(SCH_1):M_F_CPU0_SB_CB(1)
ED32 M_F_CPU0_SB_CB<0> DDR5_SB_ECC0 @S9S_MB_2U_LIB.S9S_MB_2U(SCH_1):M_F_CPU0_SB_CB(0)
EJ39 M_F_CPU0_SB_PAR DDR5_SB_PAR @S9S_MB_2U_LIB.S9S_MB_2U(SCH_1):M_F_CPU0_SB_PAR


DRAWING: @S9S_MB_2U_LIB.S9S_MB_2U(SCH_1):PAGE26 

SOCKET4677_AZIF0045P001C01CS-SA  I169  U2
CW50 M_G_CPU0_ALERT_N DDR6_ALERT_N @S9S_MB_2U_LIB.S9S_MB_2U(SCH_1):M_G_CPU0_ALERT_N
DY47 M_G_CPU0_SA_RSP<1> DDR6_A_RSP1 @S9S_MB_2U_LIB.S9S_MB_2U(SCH_1):M_G_CPU0_SA_RSP(1)
EA48 M_G_CPU0_SA_RSP<0> DDR6_A_RSP0 @S9S_MB_2U_LIB.S9S_MB_2U(SCH_1):M_G_CPU0_SA_RSP(0)
DV47 M_G_CPU0_SB_RSP<1> DDR6_B_RSP1 @S9S_MB_2U_LIB.S9S_MB_2U(SCH_1):M_G_CPU0_SB_RSP(1)
DU48 M_G_CPU0_SB_RSP<0> DDR6_B_RSP0 @S9S_MB_2U_LIB.S9S_MB_2U(SCH_1):M_G_CPU0_SB_RSP(0)
DL45 M_G_CPU0_CLK_DN<1> DDR6_CLK_DN1 @S9S_MB_2U_LIB.S9S_MB_2U(SCH_1):M_G_CPU0_CLK_DN(1)
DR45 M_G_CPU0_CLK_DN<0> DDR6_CLK_DN0 @S9S_MB_2U_LIB.S9S_MB_2U(SCH_1):M_G_CPU0_CLK_DN(0)
DJ45 M_G_CPU0_CLK_DP<1> DDR6_CLK_DP1 @S9S_MB_2U_LIB.S9S_MB_2U(SCH_1):M_G_CPU0_CLK_DP(1)
DN45 M_G_CPU0_CLK_DP<0> DDR6_CLK_DP0 @S9S_MB_2U_LIB.S9S_MB_2U(SCH_1):M_G_CPU0_CLK_DP(0)
DK44 M_G_CPU0_SA_CA<6> DDR6_SA_CA6 @S9S_MB_2U_LIB.S9S_MB_2U(SCH_1):M_G_CPU0_SA_CA(6)
DN50 M_G_CPU0_SA_CA<5> DDR6_SA_CA5 @S9S_MB_2U_LIB.S9S_MB_2U(SCH_1):M_G_CPU0_SA_CA(5)
DL50 M_G_CPU0_SA_CA<4> DDR6_SA_CA4 @S9S_MB_2U_LIB.S9S_MB_2U(SCH_1):M_G_CPU0_SA_CA(4)
DP51 M_G_CPU0_SA_CA<3> DDR6_SA_CA3 @S9S_MB_2U_LIB.S9S_MB_2U(SCH_1):M_G_CPU0_SA_CA(3)
DK51 M_G_CPU0_SA_CA<2> DDR6_SA_CA2 @S9S_MB_2U_LIB.S9S_MB_2U(SCH_1):M_G_CPU0_SA_CA(2)
DR52 M_G_CPU0_SA_CA<1> DDR6_SA_CA1 @S9S_MB_2U_LIB.S9S_MB_2U(SCH_1):M_G_CPU0_SA_CA(1)
DJ52 M_G_CPU0_SA_CA<0> DDR6_SA_CA0 @S9S_MB_2U_LIB.S9S_MB_2U(SCH_1):M_G_CPU0_SA_CA(0)
DK53 M_G_CPU0_SA_CS_N<3> DDR6_SA_CS_N3 @S9S_MB_2U_LIB.S9S_MB_2U(SCH_1):M_G_CPU0_SA_CS_N(3)
DL54 M_G_CPU0_SA_CS_N<2> DDR6_SA_CS_N2 @S9S_MB_2U_LIB.S9S_MB_2U(SCH_1):M_G_CPU0_SA_CS_N(2)
DP53 M_G_CPU0_SA_CS_N<1> DDR6_SA_CS_N1 @S9S_MB_2U_LIB.S9S_MB_2U(SCH_1):M_G_CPU0_SA_CS_N(1)
DN54 M_G_CPU0_SA_CS_N<0> DDR6_SA_CS_N0 @S9S_MB_2U_LIB.S9S_MB_2U(SCH_1):M_G_CPU0_SA_CS_N(0)
DN62 M_G_CPU0_SA_DQ<31> DDR6_SA_DQ31 @S9S_MB_2U_LIB.S9S_MB_2U(SCH_1):M_G_CPU0_SA_DQ(31)
DP63 M_G_CPU0_SA_DQ<30> DDR6_SA_DQ30 @S9S_MB_2U_LIB.S9S_MB_2U(SCH_1):M_G_CPU0_SA_DQ(30)
DL62 M_G_CPU0_SA_DQ<29> DDR6_SA_DQ29 @S9S_MB_2U_LIB.S9S_MB_2U(SCH_1):M_G_CPU0_SA_DQ(29)
DK63 M_G_CPU0_SA_DQ<28> DDR6_SA_DQ28 @S9S_MB_2U_LIB.S9S_MB_2U(SCH_1):M_G_CPU0_SA_DQ(28)
DP65 M_G_CPU0_SA_DQ<27> DDR6_SA_DQ27 @S9S_MB_2U_LIB.S9S_MB_2U(SCH_1):M_G_CPU0_SA_DQ(27)
DN66 M_G_CPU0_SA_DQ<26> DDR6_SA_DQ26 @S9S_MB_2U_LIB.S9S_MB_2U(SCH_1):M_G_CPU0_SA_DQ(26)
DK65 M_G_CPU0_SA_DQ<25> DDR6_SA_DQ25 @S9S_MB_2U_LIB.S9S_MB_2U(SCH_1):M_G_CPU0_SA_DQ(25)
DL66 M_G_CPU0_SA_DQ<24> DDR6_SA_DQ24 @S9S_MB_2U_LIB.S9S_MB_2U(SCH_1):M_G_CPU0_SA_DQ(24)
DY59 M_G_CPU0_SA_DQ<23> DDR6_SA_DQ23 @S9S_MB_2U_LIB.S9S_MB_2U(SCH_1):M_G_CPU0_SA_DQ(23)
EA60 M_G_CPU0_SA_DQ<22> DDR6_SA_DQ22 @S9S_MB_2U_LIB.S9S_MB_2U(SCH_1):M_G_CPU0_SA_DQ(22)
DV59 M_G_CPU0_SA_DQ<21> DDR6_SA_DQ21 @S9S_MB_2U_LIB.S9S_MB_2U(SCH_1):M_G_CPU0_SA_DQ(21)
DU60 M_G_CPU0_SA_DQ<20> DDR6_SA_DQ20 @S9S_MB_2U_LIB.S9S_MB_2U(SCH_1):M_G_CPU0_SA_DQ(20)
EA62 M_G_CPU0_SA_DQ<19> DDR6_SA_DQ19 @S9S_MB_2U_LIB.S9S_MB_2U(SCH_1):M_G_CPU0_SA_DQ(19)
DY63 M_G_CPU0_SA_DQ<18> DDR6_SA_DQ18 @S9S_MB_2U_LIB.S9S_MB_2U(SCH_1):M_G_CPU0_SA_DQ(18)
DU62 M_G_CPU0_SA_DQ<17> DDR6_SA_DQ17 @S9S_MB_2U_LIB.S9S_MB_2U(SCH_1):M_G_CPU0_SA_DQ(17)
DV63 M_G_CPU0_SA_DQ<16> DDR6_SA_DQ16 @S9S_MB_2U_LIB.S9S_MB_2U(SCH_1):M_G_CPU0_SA_DQ(16)
DN68 M_G_CPU0_SA_DQ<15> DDR6_SA_DQ15 @S9S_MB_2U_LIB.S9S_MB_2U(SCH_1):M_G_CPU0_SA_DQ(15)
DP69 M_G_CPU0_SA_DQ<14> DDR6_SA_DQ14 @S9S_MB_2U_LIB.S9S_MB_2U(SCH_1):M_G_CPU0_SA_DQ(14)
DL68 M_G_CPU0_SA_DQ<13> DDR6_SA_DQ13 @S9S_MB_2U_LIB.S9S_MB_2U(SCH_1):M_G_CPU0_SA_DQ(13)
DK69 M_G_CPU0_SA_DQ<12> DDR6_SA_DQ12 @S9S_MB_2U_LIB.S9S_MB_2U(SCH_1):M_G_CPU0_SA_DQ(12)
DP71 M_G_CPU0_SA_DQ<11> DDR6_SA_DQ11 @S9S_MB_2U_LIB.S9S_MB_2U(SCH_1):M_G_CPU0_SA_DQ(11)
DN72 M_G_CPU0_SA_DQ<10> DDR6_SA_DQ10 @S9S_MB_2U_LIB.S9S_MB_2U(SCH_1):M_G_CPU0_SA_DQ(10)
DK71 M_G_CPU0_SA_DQ<9> DDR6_SA_DQ9 @S9S_MB_2U_LIB.S9S_MB_2U(SCH_1):M_G_CPU0_SA_DQ(9)
DL72 M_G_CPU0_SA_DQ<8> DDR6_SA_DQ8 @S9S_MB_2U_LIB.S9S_MB_2U(SCH_1):M_G_CPU0_SA_DQ(8)
DY71 M_G_CPU0_SA_DQ<7> DDR6_SA_DQ7 @S9S_MB_2U_LIB.S9S_MB_2U(SCH_1):M_G_CPU0_SA_DQ(7)
EA72 M_G_CPU0_SA_DQ<6> DDR6_SA_DQ6 @S9S_MB_2U_LIB.S9S_MB_2U(SCH_1):M_G_CPU0_SA_DQ(6)
DV71 M_G_CPU0_SA_DQ<5> DDR6_SA_DQ5 @S9S_MB_2U_LIB.S9S_MB_2U(SCH_1):M_G_CPU0_SA_DQ(5)
DU72 M_G_CPU0_SA_DQ<4> DDR6_SA_DQ4 @S9S_MB_2U_LIB.S9S_MB_2U(SCH_1):M_G_CPU0_SA_DQ(4)
EA74 M_G_CPU0_SA_DQ<3> DDR6_SA_DQ3 @S9S_MB_2U_LIB.S9S_MB_2U(SCH_1):M_G_CPU0_SA_DQ(3)
DY75 M_G_CPU0_SA_DQ<2> DDR6_SA_DQ2 @S9S_MB_2U_LIB.S9S_MB_2U(SCH_1):M_G_CPU0_SA_DQ(2)
DU74 M_G_CPU0_SA_DQ<1> DDR6_SA_DQ1 @S9S_MB_2U_LIB.S9S_MB_2U(SCH_1):M_G_CPU0_SA_DQ(1)
DV75 M_G_CPU0_SA_DQ<0> DDR6_SA_DQ0 @S9S_MB_2U_LIB.S9S_MB_2U(SCH_1):M_G_CPU0_SA_DQ(0)
DR58 M_G_CPU0_SA_DQS_DN<9> DDR6_SA_DQS_DN9 @S9S_MB_2U_LIB.S9S_MB_2U(SCH_1):M_G_CPU0_SA_DQS_DN(9)
DR64 M_G_CPU0_SA_DQS_DN<8> DDR6_SA_DQS_DN8 @S9S_MB_2U_LIB.S9S_MB_2U(SCH_1):M_G_CPU0_SA_DQS_DN(8)
EB61 M_G_CPU0_SA_DQS_DN<7> DDR6_SA_DQS_DN7 @S9S_MB_2U_LIB.S9S_MB_2U(SCH_1):M_G_CPU0_SA_DQS_DN(7)
DR70 M_G_CPU0_SA_DQS_DN<6> DDR6_SA_DQS_DN6 @S9S_MB_2U_LIB.S9S_MB_2U(SCH_1):M_G_CPU0_SA_DQS_DN(6)
EB73 M_G_CPU0_SA_DQS_DN<5> DDR6_SA_DQS_DN5 @S9S_MB_2U_LIB.S9S_MB_2U(SCH_1):M_G_CPU0_SA_DQS_DN(5)
DL58 M_G_CPU0_SA_DQS_DN<4> DDR6_SA_DQS_DN4 @S9S_MB_2U_LIB.S9S_MB_2U(SCH_1):M_G_CPU0_SA_DQS_DN(4)
DL64 M_G_CPU0_SA_DQS_DN<3> DDR6_SA_DQS_DN3 @S9S_MB_2U_LIB.S9S_MB_2U(SCH_1):M_G_CPU0_SA_DQS_DN(3)
DT61 M_G_CPU0_SA_DQS_DN<2> DDR6_SA_DQS_DN2 @S9S_MB_2U_LIB.S9S_MB_2U(SCH_1):M_G_CPU0_SA_DQS_DN(2)
DJ70 M_G_CPU0_SA_DQS_DN<1> DDR6_SA_DQS_DN1 @S9S_MB_2U_LIB.S9S_MB_2U(SCH_1):M_G_CPU0_SA_DQS_DN(1)
DV73 M_G_CPU0_SA_DQS_DN<0> DDR6_SA_DQS_DN0 @S9S_MB_2U_LIB.S9S_MB_2U(SCH_1):M_G_CPU0_SA_DQS_DN(0)
DN58 M_G_CPU0_SA_DQS_DP<9> DDR6_SA_DQS_DP9 @S9S_MB_2U_LIB.S9S_MB_2U(SCH_1):M_G_CPU0_SA_DQS_DP(9)
DN64 M_G_CPU0_SA_DQS_DP<8> DDR6_SA_DQS_DP8 @S9S_MB_2U_LIB.S9S_MB_2U(SCH_1):M_G_CPU0_SA_DQS_DP(8)
DY61 M_G_CPU0_SA_DQS_DP<7> DDR6_SA_DQS_DP7 @S9S_MB_2U_LIB.S9S_MB_2U(SCH_1):M_G_CPU0_SA_DQS_DP(7)
DN70 M_G_CPU0_SA_DQS_DP<6> DDR6_SA_DQS_DP6 @S9S_MB_2U_LIB.S9S_MB_2U(SCH_1):M_G_CPU0_SA_DQS_DP(6)
DY73 M_G_CPU0_SA_DQS_DP<5> DDR6_SA_DQS_DP5 @S9S_MB_2U_LIB.S9S_MB_2U(SCH_1):M_G_CPU0_SA_DQS_DP(5)
DJ58 M_G_CPU0_SA_DQS_DP<4> DDR6_SA_DQS_DP4 @S9S_MB_2U_LIB.S9S_MB_2U(SCH_1):M_G_CPU0_SA_DQS_DP(4)
DJ64 M_G_CPU0_SA_DQS_DP<3> DDR6_SA_DQS_DP3 @S9S_MB_2U_LIB.S9S_MB_2U(SCH_1):M_G_CPU0_SA_DQS_DP(3)
DV61 M_G_CPU0_SA_DQS_DP<2> DDR6_SA_DQS_DP2 @S9S_MB_2U_LIB.S9S_MB_2U(SCH_1):M_G_CPU0_SA_DQS_DP(2)
DL70 M_G_CPU0_SA_DQS_DP<1> DDR6_SA_DQS_DP1 @S9S_MB_2U_LIB.S9S_MB_2U(SCH_1):M_G_CPU0_SA_DQS_DP(1)
DT73 M_G_CPU0_SA_DQS_DP<0> DDR6_SA_DQS_DP0 @S9S_MB_2U_LIB.S9S_MB_2U(SCH_1):M_G_CPU0_SA_DQS_DP(0)
DN56 M_G_CPU0_SA_CB<7> DDR6_SA_ECC7 @S9S_MB_2U_LIB.S9S_MB_2U(SCH_1):M_G_CPU0_SA_CB(7)
DP57 M_G_CPU0_SA_CB<6> DDR6_SA_ECC6 @S9S_MB_2U_LIB.S9S_MB_2U(SCH_1):M_G_CPU0_SA_CB(6)
DL56 M_G_CPU0_SA_CB<5> DDR6_SA_ECC5 @S9S_MB_2U_LIB.S9S_MB_2U(SCH_1):M_G_CPU0_SA_CB(5)
DK57 M_G_CPU0_SA_CB<4> DDR6_SA_ECC4 @S9S_MB_2U_LIB.S9S_MB_2U(SCH_1):M_G_CPU0_SA_CB(4)
DP59 M_G_CPU0_SA_CB<3> DDR6_SA_ECC3 @S9S_MB_2U_LIB.S9S_MB_2U(SCH_1):M_G_CPU0_SA_CB(3)
DN60 M_G_CPU0_SA_CB<2> DDR6_SA_ECC2 @S9S_MB_2U_LIB.S9S_MB_2U(SCH_1):M_G_CPU0_SA_CB(2)
DK59 M_G_CPU0_SA_CB<1> DDR6_SA_ECC1 @S9S_MB_2U_LIB.S9S_MB_2U(SCH_1):M_G_CPU0_SA_CB(1)
DL60 M_G_CPU0_SA_CB<0> DDR6_SA_ECC0 @S9S_MB_2U_LIB.S9S_MB_2U(SCH_1):M_G_CPU0_SA_CB(0)
DL43 M_G_CPU0_SA_PAR DDR6_SA_PAR @S9S_MB_2U_LIB.S9S_MB_2U(SCH_1):M_G_CPU0_SA_PAR
DT42 M_G_CPU0_SB_CA<6> DDR6_SB_CA6 @S9S_MB_2U_LIB.S9S_MB_2U(SCH_1):M_G_CPU0_SB_CA(6)
EA43 M_G_CPU0_SB_CA<5> DDR6_SB_CA5 @S9S_MB_2U_LIB.S9S_MB_2U(SCH_1):M_G_CPU0_SB_CA(5)
DU43 M_G_CPU0_SB_CA<4> DDR6_SB_CA4 @S9S_MB_2U_LIB.S9S_MB_2U(SCH_1):M_G_CPU0_SB_CA(4)
DY44 M_G_CPU0_SB_CA<3> DDR6_SB_CA3 @S9S_MB_2U_LIB.S9S_MB_2U(SCH_1):M_G_CPU0_SB_CA(3)
DV44 M_G_CPU0_SB_CA<2> DDR6_SB_CA2 @S9S_MB_2U_LIB.S9S_MB_2U(SCH_1):M_G_CPU0_SB_CA(2)
DP44 M_G_CPU0_SB_CA<1> DDR6_SB_CA1 @S9S_MB_2U_LIB.S9S_MB_2U(SCH_1):M_G_CPU0_SB_CA(1)
DN43 M_G_CPU0_SB_CA<0> DDR6_SB_CA0 @S9S_MB_2U_LIB.S9S_MB_2U(SCH_1):M_G_CPU0_SB_CA(0)
DV40 M_G_CPU0_SB_CS_N<3> DDR6_SB_CS_N3 @S9S_MB_2U_LIB.S9S_MB_2U(SCH_1):M_G_CPU0_SB_CS_N(3)
DU41 M_G_CPU0_SB_CS_N<2> DDR6_SB_CS_N2 @S9S_MB_2U_LIB.S9S_MB_2U(SCH_1):M_G_CPU0_SB_CS_N(2)
DY40 M_G_CPU0_SB_CS_N<1> DDR6_SB_CS_N1 @S9S_MB_2U_LIB.S9S_MB_2U(SCH_1):M_G_CPU0_SB_CS_N(1)
EA41 M_G_CPU0_SB_CS_N<0> DDR6_SB_CS_N0 @S9S_MB_2U_LIB.S9S_MB_2U(SCH_1):M_G_CPU0_SB_CS_N(0)
 EM4 M_G_CPU0_SB_DQ<31> DDR6_SB_DQ31 @S9S_MB_2U_LIB.S9S_MB_2U(SCH_1):M_G_CPU0_SB_DQ(31)
 EP4 M_G_CPU0_SB_DQ<30> DDR6_SB_DQ30 @S9S_MB_2U_LIB.S9S_MB_2U(SCH_1):M_G_CPU0_SB_DQ(30)
 EJ5 M_G_CPU0_SB_DQ<29> DDR6_SB_DQ29 @S9S_MB_2U_LIB.S9S_MB_2U(SCH_1):M_G_CPU0_SB_DQ(29)
 EK6 M_G_CPU0_SB_DQ<28> DDR6_SB_DQ28 @S9S_MB_2U_LIB.S9S_MB_2U(SCH_1):M_G_CPU0_SB_DQ(28)
 ET8 M_G_CPU0_SB_DQ<27> DDR6_SB_DQ27 @S9S_MB_2U_LIB.S9S_MB_2U(SCH_1):M_G_CPU0_SB_DQ(27)
 EP8 M_G_CPU0_SB_DQ<26> DDR6_SB_DQ26 @S9S_MB_2U_LIB.S9S_MB_2U(SCH_1):M_G_CPU0_SB_DQ(26)
 EH8 M_G_CPU0_SB_DQ<25> DDR6_SB_DQ25 @S9S_MB_2U_LIB.S9S_MB_2U(SCH_1):M_G_CPU0_SB_DQ(25)
 EK8 M_G_CPU0_SB_DQ<24> DDR6_SB_DQ24 @S9S_MB_2U_LIB.S9S_MB_2U(SCH_1):M_G_CPU0_SB_DQ(24)
DY22 M_G_CPU0_SB_DQ<23> DDR6_SB_DQ23 @S9S_MB_2U_LIB.S9S_MB_2U(SCH_1):M_G_CPU0_SB_DQ(23)
EA23 M_G_CPU0_SB_DQ<22> DDR6_SB_DQ22 @S9S_MB_2U_LIB.S9S_MB_2U(SCH_1):M_G_CPU0_SB_DQ(22)
DV22 M_G_CPU0_SB_DQ<21> DDR6_SB_DQ21 @S9S_MB_2U_LIB.S9S_MB_2U(SCH_1):M_G_CPU0_SB_DQ(21)
DU23 M_G_CPU0_SB_DQ<20> DDR6_SB_DQ20 @S9S_MB_2U_LIB.S9S_MB_2U(SCH_1):M_G_CPU0_SB_DQ(20)
EA25 M_G_CPU0_SB_DQ<19> DDR6_SB_DQ19 @S9S_MB_2U_LIB.S9S_MB_2U(SCH_1):M_G_CPU0_SB_DQ(19)
DY26 M_G_CPU0_SB_DQ<18> DDR6_SB_DQ18 @S9S_MB_2U_LIB.S9S_MB_2U(SCH_1):M_G_CPU0_SB_DQ(18)
DU25 M_G_CPU0_SB_DQ<17> DDR6_SB_DQ17 @S9S_MB_2U_LIB.S9S_MB_2U(SCH_1):M_G_CPU0_SB_DQ(17)
DV26 M_G_CPU0_SB_DQ<16> DDR6_SB_DQ16 @S9S_MB_2U_LIB.S9S_MB_2U(SCH_1):M_G_CPU0_SB_DQ(16)
DN25 M_G_CPU0_SB_DQ<15> DDR6_SB_DQ15 @S9S_MB_2U_LIB.S9S_MB_2U(SCH_1):M_G_CPU0_SB_DQ(15)
DP26 M_G_CPU0_SB_DQ<14> DDR6_SB_DQ14 @S9S_MB_2U_LIB.S9S_MB_2U(SCH_1):M_G_CPU0_SB_DQ(14)
DL25 M_G_CPU0_SB_DQ<13> DDR6_SB_DQ13 @S9S_MB_2U_LIB.S9S_MB_2U(SCH_1):M_G_CPU0_SB_DQ(13)
DK26 M_G_CPU0_SB_DQ<12> DDR6_SB_DQ12 @S9S_MB_2U_LIB.S9S_MB_2U(SCH_1):M_G_CPU0_SB_DQ(12)
DP28 M_G_CPU0_SB_DQ<11> DDR6_SB_DQ11 @S9S_MB_2U_LIB.S9S_MB_2U(SCH_1):M_G_CPU0_SB_DQ(11)
DL29 M_G_CPU0_SB_DQ<10> DDR6_SB_DQ10 @S9S_MB_2U_LIB.S9S_MB_2U(SCH_1):M_G_CPU0_SB_DQ(10)
DK28 M_G_CPU0_SB_DQ<9> DDR6_SB_DQ9 @S9S_MB_2U_LIB.S9S_MB_2U(SCH_1):M_G_CPU0_SB_DQ(9)
DN29 M_G_CPU0_SB_DQ<8> DDR6_SB_DQ8 @S9S_MB_2U_LIB.S9S_MB_2U(SCH_1):M_G_CPU0_SB_DQ(8)
DN31 M_G_CPU0_SB_DQ<7> DDR6_SB_DQ7 @S9S_MB_2U_LIB.S9S_MB_2U(SCH_1):M_G_CPU0_SB_DQ(7)
DP32 M_G_CPU0_SB_DQ<6> DDR6_SB_DQ6 @S9S_MB_2U_LIB.S9S_MB_2U(SCH_1):M_G_CPU0_SB_DQ(6)
DL31 M_G_CPU0_SB_DQ<5> DDR6_SB_DQ5 @S9S_MB_2U_LIB.S9S_MB_2U(SCH_1):M_G_CPU0_SB_DQ(5)
DK32 M_G_CPU0_SB_DQ<4> DDR6_SB_DQ4 @S9S_MB_2U_LIB.S9S_MB_2U(SCH_1):M_G_CPU0_SB_DQ(4)
DP34 M_G_CPU0_SB_DQ<3> DDR6_SB_DQ3 @S9S_MB_2U_LIB.S9S_MB_2U(SCH_1):M_G_CPU0_SB_DQ(3)
DN35 M_G_CPU0_SB_DQ<2> DDR6_SB_DQ2 @S9S_MB_2U_LIB.S9S_MB_2U(SCH_1):M_G_CPU0_SB_DQ(2)
DK34 M_G_CPU0_SB_DQ<1> DDR6_SB_DQ1 @S9S_MB_2U_LIB.S9S_MB_2U(SCH_1):M_G_CPU0_SB_DQ(1)
DL35 M_G_CPU0_SB_DQ<0> DDR6_SB_DQ0 @S9S_MB_2U_LIB.S9S_MB_2U(SCH_1):M_G_CPU0_SB_DQ(0)
DV36 M_G_CPU0_SB_DQS_DN<9> DDR6_SB_DQS_DN9 @S9S_MB_2U_LIB.S9S_MB_2U(SCH_1):M_G_CPU0_SB_DQS_DN(9)
 EM6 M_G_CPU0_SB_DQS_DN<8> DDR6_SB_DQS_DN8 @S9S_MB_2U_LIB.S9S_MB_2U(SCH_1):M_G_CPU0_SB_DQS_DN(8)
EB24 M_G_CPU0_SB_DQS_DN<7> DDR6_SB_DQS_DN7 @S9S_MB_2U_LIB.S9S_MB_2U(SCH_1):M_G_CPU0_SB_DQS_DN(7)
DN27 M_G_CPU0_SB_DQS_DN<6> DDR6_SB_DQS_DN6 @S9S_MB_2U_LIB.S9S_MB_2U(SCH_1):M_G_CPU0_SB_DQS_DN(6)
DR33 M_G_CPU0_SB_DQS_DN<5> DDR6_SB_DQS_DN5 @S9S_MB_2U_LIB.S9S_MB_2U(SCH_1):M_G_CPU0_SB_DQS_DN(5)
EB36 M_G_CPU0_SB_DQS_DN<4> DDR6_SB_DQS_DN4 @S9S_MB_2U_LIB.S9S_MB_2U(SCH_1):M_G_CPU0_SB_DQS_DN(4)
 EP6 M_G_CPU0_SB_DQS_DN<3> DDR6_SB_DQS_DN3 @S9S_MB_2U_LIB.S9S_MB_2U(SCH_1):M_G_CPU0_SB_DQS_DN(3)
DV24 M_G_CPU0_SB_DQS_DN<2> DDR6_SB_DQS_DN2 @S9S_MB_2U_LIB.S9S_MB_2U(SCH_1):M_G_CPU0_SB_DQS_DN(2)
DJ27 M_G_CPU0_SB_DQS_DN<1> DDR6_SB_DQS_DN1 @S9S_MB_2U_LIB.S9S_MB_2U(SCH_1):M_G_CPU0_SB_DQS_DN(1)
DJ33 M_G_CPU0_SB_DQS_DN<0> DDR6_SB_DQS_DN0 @S9S_MB_2U_LIB.S9S_MB_2U(SCH_1):M_G_CPU0_SB_DQS_DN(0)
DT36 M_G_CPU0_SB_DQS_DP<9> DDR6_SB_DQS_DP9 @S9S_MB_2U_LIB.S9S_MB_2U(SCH_1):M_G_CPU0_SB_DQS_DP(9)
 EN5 M_G_CPU0_SB_DQS_DP<8> DDR6_SB_DQS_DP8 @S9S_MB_2U_LIB.S9S_MB_2U(SCH_1):M_G_CPU0_SB_DQS_DP(8)
DY24 M_G_CPU0_SB_DQS_DP<7> DDR6_SB_DQS_DP7 @S9S_MB_2U_LIB.S9S_MB_2U(SCH_1):M_G_CPU0_SB_DQS_DP(7)
DR27 M_G_CPU0_SB_DQS_DP<6> DDR6_SB_DQS_DP6 @S9S_MB_2U_LIB.S9S_MB_2U(SCH_1):M_G_CPU0_SB_DQS_DP(6)
DN33 M_G_CPU0_SB_DQS_DP<5> DDR6_SB_DQS_DP5 @S9S_MB_2U_LIB.S9S_MB_2U(SCH_1):M_G_CPU0_SB_DQS_DP(5)
DY36 M_G_CPU0_SB_DQS_DP<4> DDR6_SB_DQS_DP4 @S9S_MB_2U_LIB.S9S_MB_2U(SCH_1):M_G_CPU0_SB_DQS_DP(4)
 EN7 M_G_CPU0_SB_DQS_DP<3> DDR6_SB_DQS_DP3 @S9S_MB_2U_LIB.S9S_MB_2U(SCH_1):M_G_CPU0_SB_DQS_DP(3)
DT24 M_G_CPU0_SB_DQS_DP<2> DDR6_SB_DQS_DP2 @S9S_MB_2U_LIB.S9S_MB_2U(SCH_1):M_G_CPU0_SB_DQS_DP(2)
DL27 M_G_CPU0_SB_DQS_DP<1> DDR6_SB_DQS_DP1 @S9S_MB_2U_LIB.S9S_MB_2U(SCH_1):M_G_CPU0_SB_DQS_DP(1)
DL33 M_G_CPU0_SB_DQS_DP<0> DDR6_SB_DQS_DP0 @S9S_MB_2U_LIB.S9S_MB_2U(SCH_1):M_G_CPU0_SB_DQS_DP(0)
EA37 M_G_CPU0_SB_CB<7> DDR6_SB_ECC7 @S9S_MB_2U_LIB.S9S_MB_2U(SCH_1):M_G_CPU0_SB_CB(7)
DY38 M_G_CPU0_SB_CB<6> DDR6_SB_ECC6 @S9S_MB_2U_LIB.S9S_MB_2U(SCH_1):M_G_CPU0_SB_CB(6)
DU37 M_G_CPU0_SB_CB<5> DDR6_SB_ECC5 @S9S_MB_2U_LIB.S9S_MB_2U(SCH_1):M_G_CPU0_SB_CB(5)
DV38 M_G_CPU0_SB_CB<4> DDR6_SB_ECC4 @S9S_MB_2U_LIB.S9S_MB_2U(SCH_1):M_G_CPU0_SB_CB(4)
DY34 M_G_CPU0_SB_CB<3> DDR6_SB_ECC3 @S9S_MB_2U_LIB.S9S_MB_2U(SCH_1):M_G_CPU0_SB_CB(3)
EA35 M_G_CPU0_SB_CB<2> DDR6_SB_ECC2 @S9S_MB_2U_LIB.S9S_MB_2U(SCH_1):M_G_CPU0_SB_CB(2)
DV34 M_G_CPU0_SB_CB<1> DDR6_SB_ECC1 @S9S_MB_2U_LIB.S9S_MB_2U(SCH_1):M_G_CPU0_SB_CB(1)
DU35 M_G_CPU0_SB_CB<0> DDR6_SB_ECC0 @S9S_MB_2U_LIB.S9S_MB_2U(SCH_1):M_G_CPU0_SB_CB(0)
EB42 M_G_CPU0_SB_PAR DDR6_SB_PAR @S9S_MB_2U_LIB.S9S_MB_2U(SCH_1):M_G_CPU0_SB_PAR


DRAWING: @S9S_MB_2U_LIB.S9S_MB_2U(SCH_1):PAGE27 

SOCKET4677_AZIF0045P001C01CS-SA  I169  U2
CY51 M_H_CPU0_ALERT_N DDR7_ALERT_N @S9S_MB_2U_LIB.S9S_MB_2U(SCH_1):M_H_CPU0_ALERT_N
EH47 M_H_CPU0_SA_RSP<1> DDR7_A_RSP1 @S9S_MB_2U_LIB.S9S_MB_2U(SCH_1):M_H_CPU0_SA_RSP(1)
EG48 M_H_CPU0_SA_RSP<0> DDR7_A_RSP0 @S9S_MB_2U_LIB.S9S_MB_2U(SCH_1):M_H_CPU0_SA_RSP(0)
ED47 M_H_CPU0_SB_RSP<1> DDR7_B_RSP1 @S9S_MB_2U_LIB.S9S_MB_2U(SCH_1):M_H_CPU0_SB_RSP(1)
EE48 M_H_CPU0_SB_RSP<0> DDR7_B_RSP0 @S9S_MB_2U_LIB.S9S_MB_2U(SCH_1):M_H_CPU0_SB_RSP(0)
DD42 M_H_CPU0_CLK_DN<1> DDR7_CLK_DN1 @S9S_MB_2U_LIB.S9S_MB_2U(SCH_1):M_H_CPU0_CLK_DN(1)
DH42 M_H_CPU0_CLK_DN<0> DDR7_CLK_DN0 @S9S_MB_2U_LIB.S9S_MB_2U(SCH_1):M_H_CPU0_CLK_DN(0)
DB42 M_H_CPU0_CLK_DP<1> DDR7_CLK_DP1 @S9S_MB_2U_LIB.S9S_MB_2U(SCH_1):M_H_CPU0_CLK_DP(1)
DF42 M_H_CPU0_CLK_DP<0> DDR7_CLK_DP0 @S9S_MB_2U_LIB.S9S_MB_2U(SCH_1):M_H_CPU0_CLK_DP(0)
DC41 M_H_CPU0_SA_CA<6> DDR7_SA_CA6 @S9S_MB_2U_LIB.S9S_MB_2U(SCH_1):M_H_CPU0_SA_CA(6)
DF47 M_H_CPU0_SA_CA<5> DDR7_SA_CA5 @S9S_MB_2U_LIB.S9S_MB_2U(SCH_1):M_H_CPU0_SA_CA(5)
DD47 M_H_CPU0_SA_CA<4> DDR7_SA_CA4 @S9S_MB_2U_LIB.S9S_MB_2U(SCH_1):M_H_CPU0_SA_CA(4)
DG48 M_H_CPU0_SA_CA<3> DDR7_SA_CA3 @S9S_MB_2U_LIB.S9S_MB_2U(SCH_1):M_H_CPU0_SA_CA(3)
DC48 M_H_CPU0_SA_CA<2> DDR7_SA_CA2 @S9S_MB_2U_LIB.S9S_MB_2U(SCH_1):M_H_CPU0_SA_CA(2)
DH49 M_H_CPU0_SA_CA<1> DDR7_SA_CA1 @S9S_MB_2U_LIB.S9S_MB_2U(SCH_1):M_H_CPU0_SA_CA(1)
DB49 M_H_CPU0_SA_CA<0> DDR7_SA_CA0 @S9S_MB_2U_LIB.S9S_MB_2U(SCH_1):M_H_CPU0_SA_CA(0)
DC50 M_H_CPU0_SA_CS_N<3> DDR7_SA_CS_N3 @S9S_MB_2U_LIB.S9S_MB_2U(SCH_1):M_H_CPU0_SA_CS_N(3)
DD51 M_H_CPU0_SA_CS_N<2> DDR7_SA_CS_N2 @S9S_MB_2U_LIB.S9S_MB_2U(SCH_1):M_H_CPU0_SA_CS_N(2)
DG50 M_H_CPU0_SA_CS_N<1> DDR7_SA_CS_N1 @S9S_MB_2U_LIB.S9S_MB_2U(SCH_1):M_H_CPU0_SA_CS_N(1)
DF51 M_H_CPU0_SA_CS_N<0> DDR7_SA_CS_N0 @S9S_MB_2U_LIB.S9S_MB_2U(SCH_1):M_H_CPU0_SA_CS_N(0)
DF59 M_H_CPU0_SA_DQ<31> DDR7_SA_DQ31 @S9S_MB_2U_LIB.S9S_MB_2U(SCH_1):M_H_CPU0_SA_DQ(31)
DG60 M_H_CPU0_SA_DQ<30> DDR7_SA_DQ30 @S9S_MB_2U_LIB.S9S_MB_2U(SCH_1):M_H_CPU0_SA_DQ(30)
DD59 M_H_CPU0_SA_DQ<29> DDR7_SA_DQ29 @S9S_MB_2U_LIB.S9S_MB_2U(SCH_1):M_H_CPU0_SA_DQ(29)
DC60 M_H_CPU0_SA_DQ<28> DDR7_SA_DQ28 @S9S_MB_2U_LIB.S9S_MB_2U(SCH_1):M_H_CPU0_SA_DQ(28)
DG62 M_H_CPU0_SA_DQ<27> DDR7_SA_DQ27 @S9S_MB_2U_LIB.S9S_MB_2U(SCH_1):M_H_CPU0_SA_DQ(27)
DF63 M_H_CPU0_SA_DQ<26> DDR7_SA_DQ26 @S9S_MB_2U_LIB.S9S_MB_2U(SCH_1):M_H_CPU0_SA_DQ(26)
DC62 M_H_CPU0_SA_DQ<25> DDR7_SA_DQ25 @S9S_MB_2U_LIB.S9S_MB_2U(SCH_1):M_H_CPU0_SA_DQ(25)
DD63 M_H_CPU0_SA_DQ<24> DDR7_SA_DQ24 @S9S_MB_2U_LIB.S9S_MB_2U(SCH_1):M_H_CPU0_SA_DQ(24)
DF65 M_H_CPU0_SA_DQ<23> DDR7_SA_DQ23 @S9S_MB_2U_LIB.S9S_MB_2U(SCH_1):M_H_CPU0_SA_DQ(23)
DG66 M_H_CPU0_SA_DQ<22> DDR7_SA_DQ22 @S9S_MB_2U_LIB.S9S_MB_2U(SCH_1):M_H_CPU0_SA_DQ(22)
DD65 M_H_CPU0_SA_DQ<21> DDR7_SA_DQ21 @S9S_MB_2U_LIB.S9S_MB_2U(SCH_1):M_H_CPU0_SA_DQ(21)
DC66 M_H_CPU0_SA_DQ<20> DDR7_SA_DQ20 @S9S_MB_2U_LIB.S9S_MB_2U(SCH_1):M_H_CPU0_SA_DQ(20)
DG68 M_H_CPU0_SA_DQ<19> DDR7_SA_DQ19 @S9S_MB_2U_LIB.S9S_MB_2U(SCH_1):M_H_CPU0_SA_DQ(19)
DF69 M_H_CPU0_SA_DQ<18> DDR7_SA_DQ18 @S9S_MB_2U_LIB.S9S_MB_2U(SCH_1):M_H_CPU0_SA_DQ(18)
DC68 M_H_CPU0_SA_DQ<17> DDR7_SA_DQ17 @S9S_MB_2U_LIB.S9S_MB_2U(SCH_1):M_H_CPU0_SA_DQ(17)
DD69 M_H_CPU0_SA_DQ<16> DDR7_SA_DQ16 @S9S_MB_2U_LIB.S9S_MB_2U(SCH_1):M_H_CPU0_SA_DQ(16)
DF71 M_H_CPU0_SA_DQ<15> DDR7_SA_DQ15 @S9S_MB_2U_LIB.S9S_MB_2U(SCH_1):M_H_CPU0_SA_DQ(15)
DG72 M_H_CPU0_SA_DQ<14> DDR7_SA_DQ14 @S9S_MB_2U_LIB.S9S_MB_2U(SCH_1):M_H_CPU0_SA_DQ(14)
DD71 M_H_CPU0_SA_DQ<13> DDR7_SA_DQ13 @S9S_MB_2U_LIB.S9S_MB_2U(SCH_1):M_H_CPU0_SA_DQ(13)
DC72 M_H_CPU0_SA_DQ<12> DDR7_SA_DQ12 @S9S_MB_2U_LIB.S9S_MB_2U(SCH_1):M_H_CPU0_SA_DQ(12)
DG74 M_H_CPU0_SA_DQ<11> DDR7_SA_DQ11 @S9S_MB_2U_LIB.S9S_MB_2U(SCH_1):M_H_CPU0_SA_DQ(11)
DF75 M_H_CPU0_SA_DQ<10> DDR7_SA_DQ10 @S9S_MB_2U_LIB.S9S_MB_2U(SCH_1):M_H_CPU0_SA_DQ(10)
DC74 M_H_CPU0_SA_DQ<9> DDR7_SA_DQ9 @S9S_MB_2U_LIB.S9S_MB_2U(SCH_1):M_H_CPU0_SA_DQ(9)
DD75 M_H_CPU0_SA_DQ<8> DDR7_SA_DQ8 @S9S_MB_2U_LIB.S9S_MB_2U(SCH_1):M_H_CPU0_SA_DQ(8)
DN74 M_H_CPU0_SA_DQ<7> DDR7_SA_DQ7 @S9S_MB_2U_LIB.S9S_MB_2U(SCH_1):M_H_CPU0_SA_DQ(7)
DP75 M_H_CPU0_SA_DQ<6> DDR7_SA_DQ6 @S9S_MB_2U_LIB.S9S_MB_2U(SCH_1):M_H_CPU0_SA_DQ(6)
DL74 M_H_CPU0_SA_DQ<5> DDR7_SA_DQ5 @S9S_MB_2U_LIB.S9S_MB_2U(SCH_1):M_H_CPU0_SA_DQ(5)
DK75 M_H_CPU0_SA_DQ<4> DDR7_SA_DQ4 @S9S_MB_2U_LIB.S9S_MB_2U(SCH_1):M_H_CPU0_SA_DQ(4)
DP77 M_H_CPU0_SA_DQ<3> DDR7_SA_DQ3 @S9S_MB_2U_LIB.S9S_MB_2U(SCH_1):M_H_CPU0_SA_DQ(3)
DW78 M_H_CPU0_SA_DQ<2> DDR7_SA_DQ2 @S9S_MB_2U_LIB.S9S_MB_2U(SCH_1):M_H_CPU0_SA_DQ(2)
DT77 M_H_CPU0_SA_DQ<1> DDR7_SA_DQ1 @S9S_MB_2U_LIB.S9S_MB_2U(SCH_1):M_H_CPU0_SA_DQ(1)
DY79 M_H_CPU0_SA_DQ<0> DDR7_SA_DQ0 @S9S_MB_2U_LIB.S9S_MB_2U(SCH_1):M_H_CPU0_SA_DQ(0)
DH55 M_H_CPU0_SA_DQS_DN<9> DDR7_SA_DQS_DN9 @S9S_MB_2U_LIB.S9S_MB_2U(SCH_1):M_H_CPU0_SA_DQS_DN(9)
DH61 M_H_CPU0_SA_DQS_DN<8> DDR7_SA_DQS_DN8 @S9S_MB_2U_LIB.S9S_MB_2U(SCH_1):M_H_CPU0_SA_DQS_DN(8)
DH67 M_H_CPU0_SA_DQS_DN<7> DDR7_SA_DQS_DN7 @S9S_MB_2U_LIB.S9S_MB_2U(SCH_1):M_H_CPU0_SA_DQS_DN(7)
DH73 M_H_CPU0_SA_DQS_DN<6> DDR7_SA_DQS_DN6 @S9S_MB_2U_LIB.S9S_MB_2U(SCH_1):M_H_CPU0_SA_DQS_DN(6)
DR76 M_H_CPU0_SA_DQS_DN<5> DDR7_SA_DQS_DN5 @S9S_MB_2U_LIB.S9S_MB_2U(SCH_1):M_H_CPU0_SA_DQS_DN(5)
DD55 M_H_CPU0_SA_DQS_DN<4> DDR7_SA_DQS_DN4 @S9S_MB_2U_LIB.S9S_MB_2U(SCH_1):M_H_CPU0_SA_DQS_DN(4)
DD61 M_H_CPU0_SA_DQS_DN<3> DDR7_SA_DQS_DN3 @S9S_MB_2U_LIB.S9S_MB_2U(SCH_1):M_H_CPU0_SA_DQS_DN(3)
DD67 M_H_CPU0_SA_DQS_DN<2> DDR7_SA_DQS_DN2 @S9S_MB_2U_LIB.S9S_MB_2U(SCH_1):M_H_CPU0_SA_DQS_DN(2)
DB73 M_H_CPU0_SA_DQS_DN<1> DDR7_SA_DQS_DN1 @S9S_MB_2U_LIB.S9S_MB_2U(SCH_1):M_H_CPU0_SA_DQS_DN(1)
DJ76 M_H_CPU0_SA_DQS_DN<0> DDR7_SA_DQS_DN0 @S9S_MB_2U_LIB.S9S_MB_2U(SCH_1):M_H_CPU0_SA_DQS_DN(0)
DF55 M_H_CPU0_SA_DQS_DP<9> DDR7_SA_DQS_DP9 @S9S_MB_2U_LIB.S9S_MB_2U(SCH_1):M_H_CPU0_SA_DQS_DP(9)
DF61 M_H_CPU0_SA_DQS_DP<8> DDR7_SA_DQS_DP8 @S9S_MB_2U_LIB.S9S_MB_2U(SCH_1):M_H_CPU0_SA_DQS_DP(8)
DF67 M_H_CPU0_SA_DQS_DP<7> DDR7_SA_DQS_DP7 @S9S_MB_2U_LIB.S9S_MB_2U(SCH_1):M_H_CPU0_SA_DQS_DP(7)
DF73 M_H_CPU0_SA_DQS_DP<6> DDR7_SA_DQS_DP6 @S9S_MB_2U_LIB.S9S_MB_2U(SCH_1):M_H_CPU0_SA_DQS_DP(6)
DN76 M_H_CPU0_SA_DQS_DP<5> DDR7_SA_DQS_DP5 @S9S_MB_2U_LIB.S9S_MB_2U(SCH_1):M_H_CPU0_SA_DQS_DP(5)
DB55 M_H_CPU0_SA_DQS_DP<4> DDR7_SA_DQS_DP4 @S9S_MB_2U_LIB.S9S_MB_2U(SCH_1):M_H_CPU0_SA_DQS_DP(4)
DB61 M_H_CPU0_SA_DQS_DP<3> DDR7_SA_DQS_DP3 @S9S_MB_2U_LIB.S9S_MB_2U(SCH_1):M_H_CPU0_SA_DQS_DP(3)
DB67 M_H_CPU0_SA_DQS_DP<2> DDR7_SA_DQS_DP2 @S9S_MB_2U_LIB.S9S_MB_2U(SCH_1):M_H_CPU0_SA_DQS_DP(2)
DD73 M_H_CPU0_SA_DQS_DP<1> DDR7_SA_DQS_DP1 @S9S_MB_2U_LIB.S9S_MB_2U(SCH_1):M_H_CPU0_SA_DQS_DP(1)
DL76 M_H_CPU0_SA_DQS_DP<0> DDR7_SA_DQS_DP0 @S9S_MB_2U_LIB.S9S_MB_2U(SCH_1):M_H_CPU0_SA_DQS_DP(0)
DF53 M_H_CPU0_SA_CB<7> DDR7_SA_ECC7 @S9S_MB_2U_LIB.S9S_MB_2U(SCH_1):M_H_CPU0_SA_CB(7)
DG54 M_H_CPU0_SA_CB<6> DDR7_SA_ECC6 @S9S_MB_2U_LIB.S9S_MB_2U(SCH_1):M_H_CPU0_SA_CB(6)
DD53 M_H_CPU0_SA_CB<5> DDR7_SA_ECC5 @S9S_MB_2U_LIB.S9S_MB_2U(SCH_1):M_H_CPU0_SA_CB(5)
DC54 M_H_CPU0_SA_CB<4> DDR7_SA_ECC4 @S9S_MB_2U_LIB.S9S_MB_2U(SCH_1):M_H_CPU0_SA_CB(4)
DG56 M_H_CPU0_SA_CB<3> DDR7_SA_ECC3 @S9S_MB_2U_LIB.S9S_MB_2U(SCH_1):M_H_CPU0_SA_CB(3)
DF57 M_H_CPU0_SA_CB<2> DDR7_SA_ECC2 @S9S_MB_2U_LIB.S9S_MB_2U(SCH_1):M_H_CPU0_SA_CB(2)
DC56 M_H_CPU0_SA_CB<1> DDR7_SA_ECC1 @S9S_MB_2U_LIB.S9S_MB_2U(SCH_1):M_H_CPU0_SA_CB(1)
DD57 M_H_CPU0_SA_CB<0> DDR7_SA_ECC0 @S9S_MB_2U_LIB.S9S_MB_2U(SCH_1):M_H_CPU0_SA_CB(0)
DD40 M_H_CPU0_SA_PAR DDR7_SA_PAR @S9S_MB_2U_LIB.S9S_MB_2U(SCH_1):M_H_CPU0_SA_PAR
DJ39 M_H_CPU0_SB_CA<6> DDR7_SB_CA6 @S9S_MB_2U_LIB.S9S_MB_2U(SCH_1):M_H_CPU0_SB_CA(6)
DP40 M_H_CPU0_SB_CA<5> DDR7_SB_CA5 @S9S_MB_2U_LIB.S9S_MB_2U(SCH_1):M_H_CPU0_SB_CA(5)
DK40 M_H_CPU0_SB_CA<4> DDR7_SB_CA4 @S9S_MB_2U_LIB.S9S_MB_2U(SCH_1):M_H_CPU0_SB_CA(4)
DN41 M_H_CPU0_SB_CA<3> DDR7_SB_CA3 @S9S_MB_2U_LIB.S9S_MB_2U(SCH_1):M_H_CPU0_SB_CA(3)
DL41 M_H_CPU0_SB_CA<2> DDR7_SB_CA2 @S9S_MB_2U_LIB.S9S_MB_2U(SCH_1):M_H_CPU0_SB_CA(2)
DG41 M_H_CPU0_SB_CA<1> DDR7_SB_CA1 @S9S_MB_2U_LIB.S9S_MB_2U(SCH_1):M_H_CPU0_SB_CA(1)
DF40 M_H_CPU0_SB_CA<0> DDR7_SB_CA0 @S9S_MB_2U_LIB.S9S_MB_2U(SCH_1):M_H_CPU0_SB_CA(0)
DP38 M_H_CPU0_SB_CS_N<3> DDR7_SB_CS_N3 @S9S_MB_2U_LIB.S9S_MB_2U(SCH_1):M_H_CPU0_SB_CS_N(3)
DK38 M_H_CPU0_SB_CS_N<2> DDR7_SB_CS_N2 @S9S_MB_2U_LIB.S9S_MB_2U(SCH_1):M_H_CPU0_SB_CS_N(2)
DN37 M_H_CPU0_SB_CS_N<1> DDR7_SB_CS_N1 @S9S_MB_2U_LIB.S9S_MB_2U(SCH_1):M_H_CPU0_SB_CS_N(1)
DL37 M_H_CPU0_SB_CS_N<0> DDR7_SB_CS_N0 @S9S_MB_2U_LIB.S9S_MB_2U(SCH_1):M_H_CPU0_SB_CS_N(0)
DC17 M_H_CPU0_SB_DQ<31> DDR7_SB_DQ31 @S9S_MB_2U_LIB.S9S_MB_2U(SCH_1):M_H_CPU0_SB_DQ(31)
DJ17 M_H_CPU0_SB_DQ<30> DDR7_SB_DQ30 @S9S_MB_2U_LIB.S9S_MB_2U(SCH_1):M_H_CPU0_SB_DQ(30)
DA17 M_H_CPU0_SB_DQ<29> DDR7_SB_DQ29 @S9S_MB_2U_LIB.S9S_MB_2U(SCH_1):M_H_CPU0_SB_DQ(29)
DG17 M_H_CPU0_SB_DQ<28> DDR7_SB_DQ28 @S9S_MB_2U_LIB.S9S_MB_2U(SCH_1):M_H_CPU0_SB_DQ(28)
DG19 M_H_CPU0_SB_DQ<27> DDR7_SB_DQ27 @S9S_MB_2U_LIB.S9S_MB_2U(SCH_1):M_H_CPU0_SB_DQ(27)
DF20 M_H_CPU0_SB_DQ<26> DDR7_SB_DQ26 @S9S_MB_2U_LIB.S9S_MB_2U(SCH_1):M_H_CPU0_SB_DQ(26)
DC19 M_H_CPU0_SB_DQ<25> DDR7_SB_DQ25 @S9S_MB_2U_LIB.S9S_MB_2U(SCH_1):M_H_CPU0_SB_DQ(25)
DD20 M_H_CPU0_SB_DQ<24> DDR7_SB_DQ24 @S9S_MB_2U_LIB.S9S_MB_2U(SCH_1):M_H_CPU0_SB_DQ(24)
DN19 M_H_CPU0_SB_DQ<23> DDR7_SB_DQ23 @S9S_MB_2U_LIB.S9S_MB_2U(SCH_1):M_H_CPU0_SB_DQ(23)
DP20 M_H_CPU0_SB_DQ<22> DDR7_SB_DQ22 @S9S_MB_2U_LIB.S9S_MB_2U(SCH_1):M_H_CPU0_SB_DQ(22)
DL19 M_H_CPU0_SB_DQ<21> DDR7_SB_DQ21 @S9S_MB_2U_LIB.S9S_MB_2U(SCH_1):M_H_CPU0_SB_DQ(21)
DK20 M_H_CPU0_SB_DQ<20> DDR7_SB_DQ20 @S9S_MB_2U_LIB.S9S_MB_2U(SCH_1):M_H_CPU0_SB_DQ(20)
DP22 M_H_CPU0_SB_DQ<19> DDR7_SB_DQ19 @S9S_MB_2U_LIB.S9S_MB_2U(SCH_1):M_H_CPU0_SB_DQ(19)
DN23 M_H_CPU0_SB_DQ<18> DDR7_SB_DQ18 @S9S_MB_2U_LIB.S9S_MB_2U(SCH_1):M_H_CPU0_SB_DQ(18)
DK22 M_H_CPU0_SB_DQ<17> DDR7_SB_DQ17 @S9S_MB_2U_LIB.S9S_MB_2U(SCH_1):M_H_CPU0_SB_DQ(17)
DL23 M_H_CPU0_SB_DQ<16> DDR7_SB_DQ16 @S9S_MB_2U_LIB.S9S_MB_2U(SCH_1):M_H_CPU0_SB_DQ(16)
DF22 M_H_CPU0_SB_DQ<15> DDR7_SB_DQ15 @S9S_MB_2U_LIB.S9S_MB_2U(SCH_1):M_H_CPU0_SB_DQ(15)
DG23 M_H_CPU0_SB_DQ<14> DDR7_SB_DQ14 @S9S_MB_2U_LIB.S9S_MB_2U(SCH_1):M_H_CPU0_SB_DQ(14)
DD22 M_H_CPU0_SB_DQ<13> DDR7_SB_DQ13 @S9S_MB_2U_LIB.S9S_MB_2U(SCH_1):M_H_CPU0_SB_DQ(13)
DC23 M_H_CPU0_SB_DQ<12> DDR7_SB_DQ12 @S9S_MB_2U_LIB.S9S_MB_2U(SCH_1):M_H_CPU0_SB_DQ(12)
DG25 M_H_CPU0_SB_DQ<11> DDR7_SB_DQ11 @S9S_MB_2U_LIB.S9S_MB_2U(SCH_1):M_H_CPU0_SB_DQ(11)
DF26 M_H_CPU0_SB_DQ<10> DDR7_SB_DQ10 @S9S_MB_2U_LIB.S9S_MB_2U(SCH_1):M_H_CPU0_SB_DQ(10)
DC25 M_H_CPU0_SB_DQ<9> DDR7_SB_DQ9 @S9S_MB_2U_LIB.S9S_MB_2U(SCH_1):M_H_CPU0_SB_DQ(9)
DD26 M_H_CPU0_SB_DQ<8> DDR7_SB_DQ8 @S9S_MB_2U_LIB.S9S_MB_2U(SCH_1):M_H_CPU0_SB_DQ(8)
DD28 M_H_CPU0_SB_DQ<7> DDR7_SB_DQ7 @S9S_MB_2U_LIB.S9S_MB_2U(SCH_1):M_H_CPU0_SB_DQ(7)
DG29 M_H_CPU0_SB_DQ<6> DDR7_SB_DQ6 @S9S_MB_2U_LIB.S9S_MB_2U(SCH_1):M_H_CPU0_SB_DQ(6)
DF28 M_H_CPU0_SB_DQ<5> DDR7_SB_DQ5 @S9S_MB_2U_LIB.S9S_MB_2U(SCH_1):M_H_CPU0_SB_DQ(5)
DC29 M_H_CPU0_SB_DQ<4> DDR7_SB_DQ4 @S9S_MB_2U_LIB.S9S_MB_2U(SCH_1):M_H_CPU0_SB_DQ(4)
DG31 M_H_CPU0_SB_DQ<3> DDR7_SB_DQ3 @S9S_MB_2U_LIB.S9S_MB_2U(SCH_1):M_H_CPU0_SB_DQ(3)
DF32 M_H_CPU0_SB_DQ<2> DDR7_SB_DQ2 @S9S_MB_2U_LIB.S9S_MB_2U(SCH_1):M_H_CPU0_SB_DQ(2)
DC31 M_H_CPU0_SB_DQ<1> DDR7_SB_DQ1 @S9S_MB_2U_LIB.S9S_MB_2U(SCH_1):M_H_CPU0_SB_DQ(1)
DD32 M_H_CPU0_SB_DQ<0> DDR7_SB_DQ0 @S9S_MB_2U_LIB.S9S_MB_2U(SCH_1):M_H_CPU0_SB_DQ(0)
DD36 M_H_CPU0_SB_DQS_DN<9> DDR7_SB_DQS_DN9 @S9S_MB_2U_LIB.S9S_MB_2U(SCH_1):M_H_CPU0_SB_DQS_DN(9)
DF18 M_H_CPU0_SB_DQS_DN<8> DDR7_SB_DQS_DN8 @S9S_MB_2U_LIB.S9S_MB_2U(SCH_1):M_H_CPU0_SB_DQS_DN(8)
DR21 M_H_CPU0_SB_DQS_DN<7> DDR7_SB_DQS_DN7 @S9S_MB_2U_LIB.S9S_MB_2U(SCH_1):M_H_CPU0_SB_DQS_DN(7)
DH24 M_H_CPU0_SB_DQS_DN<6> DDR7_SB_DQS_DN6 @S9S_MB_2U_LIB.S9S_MB_2U(SCH_1):M_H_CPU0_SB_DQS_DN(6)
DH30 M_H_CPU0_SB_DQS_DN<5> DDR7_SB_DQS_DN5 @S9S_MB_2U_LIB.S9S_MB_2U(SCH_1):M_H_CPU0_SB_DQS_DN(5)
DH36 M_H_CPU0_SB_DQS_DN<4> DDR7_SB_DQS_DN4 @S9S_MB_2U_LIB.S9S_MB_2U(SCH_1):M_H_CPU0_SB_DQS_DN(4)
DB18 M_H_CPU0_SB_DQS_DN<3> DDR7_SB_DQS_DN3 @S9S_MB_2U_LIB.S9S_MB_2U(SCH_1):M_H_CPU0_SB_DQS_DN(3)
DL21 M_H_CPU0_SB_DQS_DN<2> DDR7_SB_DQS_DN2 @S9S_MB_2U_LIB.S9S_MB_2U(SCH_1):M_H_CPU0_SB_DQS_DN(2)
DD24 M_H_CPU0_SB_DQS_DN<1> DDR7_SB_DQS_DN1 @S9S_MB_2U_LIB.S9S_MB_2U(SCH_1):M_H_CPU0_SB_DQS_DN(1)
DD30 M_H_CPU0_SB_DQS_DN<0> DDR7_SB_DQS_DN0 @S9S_MB_2U_LIB.S9S_MB_2U(SCH_1):M_H_CPU0_SB_DQS_DN(0)
DB36 M_H_CPU0_SB_DQS_DP<9> DDR7_SB_DQS_DP9 @S9S_MB_2U_LIB.S9S_MB_2U(SCH_1):M_H_CPU0_SB_DQS_DP(9)
DH18 M_H_CPU0_SB_DQS_DP<8> DDR7_SB_DQS_DP8 @S9S_MB_2U_LIB.S9S_MB_2U(SCH_1):M_H_CPU0_SB_DQS_DP(8)
DN21 M_H_CPU0_SB_DQS_DP<7> DDR7_SB_DQS_DP7 @S9S_MB_2U_LIB.S9S_MB_2U(SCH_1):M_H_CPU0_SB_DQS_DP(7)
DF24 M_H_CPU0_SB_DQS_DP<6> DDR7_SB_DQS_DP6 @S9S_MB_2U_LIB.S9S_MB_2U(SCH_1):M_H_CPU0_SB_DQS_DP(6)
DF30 M_H_CPU0_SB_DQS_DP<5> DDR7_SB_DQS_DP5 @S9S_MB_2U_LIB.S9S_MB_2U(SCH_1):M_H_CPU0_SB_DQS_DP(5)
DF36 M_H_CPU0_SB_DQS_DP<4> DDR7_SB_DQS_DP4 @S9S_MB_2U_LIB.S9S_MB_2U(SCH_1):M_H_CPU0_SB_DQS_DP(4)
DD18 M_H_CPU0_SB_DQS_DP<3> DDR7_SB_DQS_DP3 @S9S_MB_2U_LIB.S9S_MB_2U(SCH_1):M_H_CPU0_SB_DQS_DP(3)
DJ21 M_H_CPU0_SB_DQS_DP<2> DDR7_SB_DQS_DP2 @S9S_MB_2U_LIB.S9S_MB_2U(SCH_1):M_H_CPU0_SB_DQS_DP(2)
DB24 M_H_CPU0_SB_DQS_DP<1> DDR7_SB_DQS_DP1 @S9S_MB_2U_LIB.S9S_MB_2U(SCH_1):M_H_CPU0_SB_DQS_DP(1)
DB30 M_H_CPU0_SB_DQS_DP<0> DDR7_SB_DQS_DP0 @S9S_MB_2U_LIB.S9S_MB_2U(SCH_1):M_H_CPU0_SB_DQS_DP(0)
DC37 M_H_CPU0_SB_CB<7> DDR7_SB_ECC7 @S9S_MB_2U_LIB.S9S_MB_2U(SCH_1):M_H_CPU0_SB_CB(7)
DD38 M_H_CPU0_SB_CB<6> DDR7_SB_ECC6 @S9S_MB_2U_LIB.S9S_MB_2U(SCH_1):M_H_CPU0_SB_CB(6)
DG37 M_H_CPU0_SB_CB<5> DDR7_SB_ECC5 @S9S_MB_2U_LIB.S9S_MB_2U(SCH_1):M_H_CPU0_SB_CB(5)
DF38 M_H_CPU0_SB_CB<4> DDR7_SB_ECC4 @S9S_MB_2U_LIB.S9S_MB_2U(SCH_1):M_H_CPU0_SB_CB(4)
DF34 M_H_CPU0_SB_CB<3> DDR7_SB_ECC3 @S9S_MB_2U_LIB.S9S_MB_2U(SCH_1):M_H_CPU0_SB_CB(3)
DG35 M_H_CPU0_SB_CB<2> DDR7_SB_ECC2 @S9S_MB_2U_LIB.S9S_MB_2U(SCH_1):M_H_CPU0_SB_CB(2)
DD34 M_H_CPU0_SB_CB<1> DDR7_SB_ECC1 @S9S_MB_2U_LIB.S9S_MB_2U(SCH_1):M_H_CPU0_SB_CB(1)
DC35 M_H_CPU0_SB_CB<0> DDR7_SB_ECC0 @S9S_MB_2U_LIB.S9S_MB_2U(SCH_1):M_H_CPU0_SB_CB(0)
DR39 M_H_CPU0_SB_PAR DDR7_SB_PAR @S9S_MB_2U_LIB.S9S_MB_2U(SCH_1):M_H_CPU0_SB_PAR


DRAWING: @S9S_MB_2U_LIB.S9S_MB_2U(SCH_1):PAGE28 

SOCKET4677_AZIF0045P001C01CS-SA  I169  U2
BU17 DMI_CPU0_PCH_RX_C_DN<7> DMI_RX_DN7 @S9S_MB_2U_LIB.S9S_MB_2U(SCH_1):DMI_CPU0_PCH_RX_C_DN(7)
BP18 DMI_CPU0_PCH_RX_C_DP<6> DMI_RX_DN6 @S9S_MB_2U_LIB.S9S_MB_2U(SCH_1):DMI_CPU0_PCH_RX_C_DP(6)
BN17 DMI_CPU0_PCH_RX_C_DP<5> DMI_RX_DN5 @S9S_MB_2U_LIB.S9S_MB_2U(SCH_1):DMI_CPU0_PCH_RX_C_DP(5)
BK18 DMI_CPU0_PCH_RX_C_DP<4> DMI_RX_DN4 @S9S_MB_2U_LIB.S9S_MB_2U(SCH_1):DMI_CPU0_PCH_RX_C_DP(4)
BJ17 DMI_CPU0_PCH_RX_C_DP<3> DMI_RX_DN3 @S9S_MB_2U_LIB.S9S_MB_2U(SCH_1):DMI_CPU0_PCH_RX_C_DP(3)
BF18 DMI_CPU0_PCH_RX_C_DN<2> DMI_RX_DN2 @S9S_MB_2U_LIB.S9S_MB_2U(SCH_1):DMI_CPU0_PCH_RX_C_DN(2)
BE17 DMI_CPU0_PCH_RX_C_DP<1> DMI_RX_DN1 @S9S_MB_2U_LIB.S9S_MB_2U(SCH_1):DMI_CPU0_PCH_RX_C_DP(1)
BB18 DMI_CPU0_PCH_RX_C_DN<0> DMI_RX_DN0 @S9S_MB_2U_LIB.S9S_MB_2U(SCH_1):DMI_CPU0_PCH_RX_C_DN(0)
BT18 DMI_CPU0_PCH_RX_C_DP<7> DMI_RX_DP7 @S9S_MB_2U_LIB.S9S_MB_2U(SCH_1):DMI_CPU0_PCH_RX_C_DP(7)
BR19 DMI_CPU0_PCH_RX_C_DN<6> DMI_RX_DP6 @S9S_MB_2U_LIB.S9S_MB_2U(SCH_1):DMI_CPU0_PCH_RX_C_DN(6)
BM18 DMI_CPU0_PCH_RX_C_DN<5> DMI_RX_DP5 @S9S_MB_2U_LIB.S9S_MB_2U(SCH_1):DMI_CPU0_PCH_RX_C_DN(5)
BL19 DMI_CPU0_PCH_RX_C_DN<4> DMI_RX_DP4 @S9S_MB_2U_LIB.S9S_MB_2U(SCH_1):DMI_CPU0_PCH_RX_C_DN(4)
BH18 DMI_CPU0_PCH_RX_C_DN<3> DMI_RX_DP3 @S9S_MB_2U_LIB.S9S_MB_2U(SCH_1):DMI_CPU0_PCH_RX_C_DN(3)
BG19 DMI_CPU0_PCH_RX_C_DP<2> DMI_RX_DP2 @S9S_MB_2U_LIB.S9S_MB_2U(SCH_1):DMI_CPU0_PCH_RX_C_DP(2)
BD18 DMI_CPU0_PCH_RX_C_DN<1> DMI_RX_DP1 @S9S_MB_2U_LIB.S9S_MB_2U(SCH_1):DMI_CPU0_PCH_RX_C_DN(1)
BC19 DMI_CPU0_PCH_RX_C_DP<0> DMI_RX_DP0 @S9S_MB_2U_LIB.S9S_MB_2U(SCH_1):DMI_CPU0_PCH_RX_C_DP(0)
CN17 DMI_CPU0_PCH_TX_DP<7> DMI_TX_DN7 @S9S_MB_2U_LIB.S9S_MB_2U(SCH_1):DMI_CPU0_PCH_TX_DP(7)
CK18 DMI_CPU0_PCH_TX_DN<6> DMI_TX_DN6 @S9S_MB_2U_LIB.S9S_MB_2U(SCH_1):DMI_CPU0_PCH_TX_DN(6)
CJ17 DMI_CPU0_PCH_TX_DN<5> DMI_TX_DN5 @S9S_MB_2U_LIB.S9S_MB_2U(SCH_1):DMI_CPU0_PCH_TX_DN(5)
CF18 DMI_CPU0_PCH_TX_DN<4> DMI_TX_DN4 @S9S_MB_2U_LIB.S9S_MB_2U(SCH_1):DMI_CPU0_PCH_TX_DN(4)
CE17 DMI_CPU0_PCH_TX_DP<3> DMI_TX_DN3 @S9S_MB_2U_LIB.S9S_MB_2U(SCH_1):DMI_CPU0_PCH_TX_DP(3)
CB18 DMI_CPU0_PCH_TX_DP<2> DMI_TX_DN2 @S9S_MB_2U_LIB.S9S_MB_2U(SCH_1):DMI_CPU0_PCH_TX_DP(2)
CA17 DMI_CPU0_PCH_TX_DP<1> DMI_TX_DN1 @S9S_MB_2U_LIB.S9S_MB_2U(SCH_1):DMI_CPU0_PCH_TX_DP(1)
BW19 DMI_CPU0_PCH_TX_DP<0> DMI_TX_DN0 @S9S_MB_2U_LIB.S9S_MB_2U(SCH_1):DMI_CPU0_PCH_TX_DP(0)
CM18 DMI_CPU0_PCH_TX_DN<7> DMI_TX_DP7 @S9S_MB_2U_LIB.S9S_MB_2U(SCH_1):DMI_CPU0_PCH_TX_DN(7)
CL19 DMI_CPU0_PCH_TX_DP<6> DMI_TX_DP6 @S9S_MB_2U_LIB.S9S_MB_2U(SCH_1):DMI_CPU0_PCH_TX_DP(6)
CH18 DMI_CPU0_PCH_TX_DP<5> DMI_TX_DP5 @S9S_MB_2U_LIB.S9S_MB_2U(SCH_1):DMI_CPU0_PCH_TX_DP(5)
CG19 DMI_CPU0_PCH_TX_DP<4> DMI_TX_DP4 @S9S_MB_2U_LIB.S9S_MB_2U(SCH_1):DMI_CPU0_PCH_TX_DP(4)
CD18 DMI_CPU0_PCH_TX_DN<3> DMI_TX_DP3 @S9S_MB_2U_LIB.S9S_MB_2U(SCH_1):DMI_CPU0_PCH_TX_DN(3)
CC19 DMI_CPU0_PCH_TX_DN<2> DMI_TX_DP2 @S9S_MB_2U_LIB.S9S_MB_2U(SCH_1):DMI_CPU0_PCH_TX_DN(2)
BY18 DMI_CPU0_PCH_TX_DN<1> DMI_TX_DP1 @S9S_MB_2U_LIB.S9S_MB_2U(SCH_1):DMI_CPU0_PCH_TX_DN(1)
CA19 DMI_CPU0_PCH_TX_DN<0> DMI_TX_DP0 @S9S_MB_2U_LIB.S9S_MB_2U(SCH_1):DMI_CPU0_PCH_TX_DN(0)


DRAWING: @S9S_MB_2U_LIB.S9S_MB_2U(SCH_1):PAGE29 

SOCKET4677_AZIF0045P001C01CS-SA  I37  U2
 BA9 P5E_CPU0_PE0_RX_DN<15> PE0_RX_DN15 @S9S_MB_2U_LIB.S9S_MB_2U(SCH_1):P5E_CPU0_PE0_RX_DN(15)
AV10 P5E_CPU0_PE0_RX_DN<14> PE0_RX_DN14 @S9S_MB_2U_LIB.S9S_MB_2U(SCH_1):P5E_CPU0_PE0_RX_DN(14)
 AU9 P5E_CPU0_PE0_RX_DN<13> PE0_RX_DN13 @S9S_MB_2U_LIB.S9S_MB_2U(SCH_1):P5E_CPU0_PE0_RX_DN(13)
AP10 P5E_CPU0_PE0_RX_DN<12> PE0_RX_DN12 @S9S_MB_2U_LIB.S9S_MB_2U(SCH_1):P5E_CPU0_PE0_RX_DN(12)
AM10 P5E_CPU0_PE0_RX_DN<11> PE0_RX_DN11 @S9S_MB_2U_LIB.S9S_MB_2U(SCH_1):P5E_CPU0_PE0_RX_DN(11)
AK10 P5E_CPU0_PE0_RX_DN<10> PE0_RX_DN10 @S9S_MB_2U_LIB.S9S_MB_2U(SCH_1):P5E_CPU0_PE0_RX_DN(10)
 AJ9 P5E_CPU0_PE0_RX_DN<9> PE0_RX_DN9 @S9S_MB_2U_LIB.S9S_MB_2U(SCH_1):P5E_CPU0_PE0_RX_DN(9)
AF10 P5E_CPU0_PE0_RX_DN<8> PE0_RX_DN8 @S9S_MB_2U_LIB.S9S_MB_2U(SCH_1):P5E_CPU0_PE0_RX_DN(8)
 AE9 P5E_CPU0_PE0_RX_DN<7> PE0_RX_DN7 @S9S_MB_2U_LIB.S9S_MB_2U(SCH_1):P5E_CPU0_PE0_RX_DN(7)
AB10 P5E_CPU0_PE0_RX_DN<6> PE0_RX_DN6 @S9S_MB_2U_LIB.S9S_MB_2U(SCH_1):P5E_CPU0_PE0_RX_DN(6)
 AA9 P5E_CPU0_PE0_RX_DN<5> PE0_RX_DN5 @S9S_MB_2U_LIB.S9S_MB_2U(SCH_1):P5E_CPU0_PE0_RX_DN(5)
 V10 P5E_CPU0_PE0_RX_DN<4> PE0_RX_DN4 @S9S_MB_2U_LIB.S9S_MB_2U(SCH_1):P5E_CPU0_PE0_RX_DN(4)
 T10 P5E_CPU0_PE0_RX_DN<3> PE0_RX_DN3 @S9S_MB_2U_LIB.S9S_MB_2U(SCH_1):P5E_CPU0_PE0_RX_DN(3)
 P10 P5E_CPU0_PE0_RX_DN<2> PE0_RX_DN2 @S9S_MB_2U_LIB.S9S_MB_2U(SCH_1):P5E_CPU0_PE0_RX_DN(2)
 M10 P5E_CPU0_PE0_RX_DN<1> PE0_RX_DN1 @S9S_MB_2U_LIB.S9S_MB_2U(SCH_1):P5E_CPU0_PE0_RX_DN(1)
 K10 P5E_CPU0_PE0_RX_DN<0> PE0_RX_DN0 @S9S_MB_2U_LIB.S9S_MB_2U(SCH_1):P5E_CPU0_PE0_RX_DN(0)
AY10 P5E_CPU0_PE0_RX_DP<15> PE0_RX_DP15 @S9S_MB_2U_LIB.S9S_MB_2U(SCH_1):P5E_CPU0_PE0_RX_DP(15)
AW11 P5E_CPU0_PE0_RX_DP<14> PE0_RX_DP14 @S9S_MB_2U_LIB.S9S_MB_2U(SCH_1):P5E_CPU0_PE0_RX_DP(14)
AT10 P5E_CPU0_PE0_RX_DP<13> PE0_RX_DP13 @S9S_MB_2U_LIB.S9S_MB_2U(SCH_1):P5E_CPU0_PE0_RX_DP(13)
AR11 P5E_CPU0_PE0_RX_DP<12> PE0_RX_DP12 @S9S_MB_2U_LIB.S9S_MB_2U(SCH_1):P5E_CPU0_PE0_RX_DP(12)
 AN9 P5E_CPU0_PE0_RX_DP<11> PE0_RX_DP11 @S9S_MB_2U_LIB.S9S_MB_2U(SCH_1):P5E_CPU0_PE0_RX_DP(11)
AL11 P5E_CPU0_PE0_RX_DP<10> PE0_RX_DP10 @S9S_MB_2U_LIB.S9S_MB_2U(SCH_1):P5E_CPU0_PE0_RX_DP(10)
AH10 P5E_CPU0_PE0_RX_DP<9> PE0_RX_DP9 @S9S_MB_2U_LIB.S9S_MB_2U(SCH_1):P5E_CPU0_PE0_RX_DP(9)
AG11 P5E_CPU0_PE0_RX_DP<8> PE0_RX_DP8 @S9S_MB_2U_LIB.S9S_MB_2U(SCH_1):P5E_CPU0_PE0_RX_DP(8)
AD10 P5E_CPU0_PE0_RX_DP<7> PE0_RX_DP7 @S9S_MB_2U_LIB.S9S_MB_2U(SCH_1):P5E_CPU0_PE0_RX_DP(7)
AC11 P5E_CPU0_PE0_RX_DP<6> PE0_RX_DP6 @S9S_MB_2U_LIB.S9S_MB_2U(SCH_1):P5E_CPU0_PE0_RX_DP(6)
 Y10 P5E_CPU0_PE0_RX_DP<5> PE0_RX_DP5 @S9S_MB_2U_LIB.S9S_MB_2U(SCH_1):P5E_CPU0_PE0_RX_DP(5)
 W11 P5E_CPU0_PE0_RX_DP<4> PE0_RX_DP4 @S9S_MB_2U_LIB.S9S_MB_2U(SCH_1):P5E_CPU0_PE0_RX_DP(4)
  U9 P5E_CPU0_PE0_RX_DP<3> PE0_RX_DP3 @S9S_MB_2U_LIB.S9S_MB_2U(SCH_1):P5E_CPU0_PE0_RX_DP(3)
 R11 P5E_CPU0_PE0_RX_DP<2> PE0_RX_DP2 @S9S_MB_2U_LIB.S9S_MB_2U(SCH_1):P5E_CPU0_PE0_RX_DP(2)
  N9 P5E_CPU0_PE0_RX_DP<1> PE0_RX_DP1 @S9S_MB_2U_LIB.S9S_MB_2U(SCH_1):P5E_CPU0_PE0_RX_DP(1)
 L11 P5E_CPU0_PE0_RX_DP<0> PE0_RX_DP0 @S9S_MB_2U_LIB.S9S_MB_2U(SCH_1):P5E_CPU0_PE0_RX_DP(0)
BB14 P5E_CPU0_PE0_TX_DN<15> PE0_TX_DN15 @S9S_MB_2U_LIB.S9S_MB_2U(SCH_1):P5E_CPU0_PE0_TX_DN(15)
BA13 P5E_CPU0_PE0_TX_DN<14> PE0_TX_DN14 @S9S_MB_2U_LIB.S9S_MB_2U(SCH_1):P5E_CPU0_PE0_TX_DN(14)
AV14 P5E_CPU0_PE0_TX_DN<13> PE0_TX_DN13 @S9S_MB_2U_LIB.S9S_MB_2U(SCH_1):P5E_CPU0_PE0_TX_DN(13)
AU13 P5E_CPU0_PE0_TX_DN<12> PE0_TX_DN12 @S9S_MB_2U_LIB.S9S_MB_2U(SCH_1):P5E_CPU0_PE0_TX_DN(12)
AP14 P5E_CPU0_PE0_TX_DN<11> PE0_TX_DN11 @S9S_MB_2U_LIB.S9S_MB_2U(SCH_1):P5E_CPU0_PE0_TX_DN(11)
AN13 P5E_CPU0_PE0_TX_DN<10> PE0_TX_DN10 @S9S_MB_2U_LIB.S9S_MB_2U(SCH_1):P5E_CPU0_PE0_TX_DN(10)
AK14 P5E_CPU0_PE0_TX_DN<9> PE0_TX_DN9 @S9S_MB_2U_LIB.S9S_MB_2U(SCH_1):P5E_CPU0_PE0_TX_DN(9)
AJ13 P5E_CPU0_PE0_TX_DN<8> PE0_TX_DN8 @S9S_MB_2U_LIB.S9S_MB_2U(SCH_1):P5E_CPU0_PE0_TX_DN(8)
AF14 P5E_CPU0_PE0_TX_DN<7> PE0_TX_DN7 @S9S_MB_2U_LIB.S9S_MB_2U(SCH_1):P5E_CPU0_PE0_TX_DN(7)
AE13 P5E_CPU0_PE0_TX_DN<6> PE0_TX_DN6 @S9S_MB_2U_LIB.S9S_MB_2U(SCH_1):P5E_CPU0_PE0_TX_DN(6)
AB14 P5E_CPU0_PE0_TX_DN<5> PE0_TX_DN5 @S9S_MB_2U_LIB.S9S_MB_2U(SCH_1):P5E_CPU0_PE0_TX_DN(5)
AA13 P5E_CPU0_PE0_TX_DN<4> PE0_TX_DN4 @S9S_MB_2U_LIB.S9S_MB_2U(SCH_1):P5E_CPU0_PE0_TX_DN(4)
 V14 P5E_CPU0_PE0_TX_DN<3> PE0_TX_DN3 @S9S_MB_2U_LIB.S9S_MB_2U(SCH_1):P5E_CPU0_PE0_TX_DN(3)
 U13 P5E_CPU0_PE0_TX_DN<2> PE0_TX_DN2 @S9S_MB_2U_LIB.S9S_MB_2U(SCH_1):P5E_CPU0_PE0_TX_DN(2)
 P14 P5E_CPU0_PE0_TX_DN<1> PE0_TX_DN1 @S9S_MB_2U_LIB.S9S_MB_2U(SCH_1):P5E_CPU0_PE0_TX_DN(1)
 N13 P5E_CPU0_PE0_TX_DN<0> PE0_TX_DN0 @S9S_MB_2U_LIB.S9S_MB_2U(SCH_1):P5E_CPU0_PE0_TX_DN(0)
BC15 P5E_CPU0_PE0_TX_DP<15> PE0_TX_DP15 @S9S_MB_2U_LIB.S9S_MB_2U(SCH_1):P5E_CPU0_PE0_TX_DP(15)
AY14 P5E_CPU0_PE0_TX_DP<14> PE0_TX_DP14 @S9S_MB_2U_LIB.S9S_MB_2U(SCH_1):P5E_CPU0_PE0_TX_DP(14)
AW15 P5E_CPU0_PE0_TX_DP<13> PE0_TX_DP13 @S9S_MB_2U_LIB.S9S_MB_2U(SCH_1):P5E_CPU0_PE0_TX_DP(13)
AT14 P5E_CPU0_PE0_TX_DP<12> PE0_TX_DP12 @S9S_MB_2U_LIB.S9S_MB_2U(SCH_1):P5E_CPU0_PE0_TX_DP(12)
AR15 P5E_CPU0_PE0_TX_DP<11> PE0_TX_DP11 @S9S_MB_2U_LIB.S9S_MB_2U(SCH_1):P5E_CPU0_PE0_TX_DP(11)
AM14 P5E_CPU0_PE0_TX_DP<10> PE0_TX_DP10 @S9S_MB_2U_LIB.S9S_MB_2U(SCH_1):P5E_CPU0_PE0_TX_DP(10)
AL15 P5E_CPU0_PE0_TX_DP<9> PE0_TX_DP9 @S9S_MB_2U_LIB.S9S_MB_2U(SCH_1):P5E_CPU0_PE0_TX_DP(9)
AH14 P5E_CPU0_PE0_TX_DP<8> PE0_TX_DP8 @S9S_MB_2U_LIB.S9S_MB_2U(SCH_1):P5E_CPU0_PE0_TX_DP(8)
AG15 P5E_CPU0_PE0_TX_DP<7> PE0_TX_DP7 @S9S_MB_2U_LIB.S9S_MB_2U(SCH_1):P5E_CPU0_PE0_TX_DP(7)
AD14 P5E_CPU0_PE0_TX_DP<6> PE0_TX_DP6 @S9S_MB_2U_LIB.S9S_MB_2U(SCH_1):P5E_CPU0_PE0_TX_DP(6)
AC15 P5E_CPU0_PE0_TX_DP<5> PE0_TX_DP5 @S9S_MB_2U_LIB.S9S_MB_2U(SCH_1):P5E_CPU0_PE0_TX_DP(5)
 Y14 P5E_CPU0_PE0_TX_DP<4> PE0_TX_DP4 @S9S_MB_2U_LIB.S9S_MB_2U(SCH_1):P5E_CPU0_PE0_TX_DP(4)
 W15 P5E_CPU0_PE0_TX_DP<3> PE0_TX_DP3 @S9S_MB_2U_LIB.S9S_MB_2U(SCH_1):P5E_CPU0_PE0_TX_DP(3)
 T14 P5E_CPU0_PE0_TX_DP<2> PE0_TX_DP2 @S9S_MB_2U_LIB.S9S_MB_2U(SCH_1):P5E_CPU0_PE0_TX_DP(2)
 R15 P5E_CPU0_PE0_TX_DP<1> PE0_TX_DP1 @S9S_MB_2U_LIB.S9S_MB_2U(SCH_1):P5E_CPU0_PE0_TX_DP(1)
 M14 P5E_CPU0_PE0_TX_DP<0> PE0_TX_DP0 @S9S_MB_2U_LIB.S9S_MB_2U(SCH_1):P5E_CPU0_PE0_TX_DP(0)

SOCKET4677_AZIF0045P001C01CS-SA  I176  U2
BC11 P5E_CPU0_PE1_RX_DN<15> PE1_RX_DN15 @S9S_MB_2U_LIB.S9S_MB_2U(SCH_1):P5E_CPU0_PE1_RX_DN(15)
BF10 P5E_CPU0_PE1_RX_DN<14> PE1_RX_DN14 @S9S_MB_2U_LIB.S9S_MB_2U(SCH_1):P5E_CPU0_PE1_RX_DN(14)
BG11 P5E_CPU0_PE1_RX_DN<13> PE1_RX_DN13 @S9S_MB_2U_LIB.S9S_MB_2U(SCH_1):P5E_CPU0_PE1_RX_DN(13)
BK10 P5E_CPU0_PE1_RX_DN<12> PE1_RX_DN12 @S9S_MB_2U_LIB.S9S_MB_2U(SCH_1):P5E_CPU0_PE1_RX_DN(12)
BL11 P5E_CPU0_PE1_RX_DN<11> PE1_RX_DN11 @S9S_MB_2U_LIB.S9S_MB_2U(SCH_1):P5E_CPU0_PE1_RX_DN(11)
BP10 P5E_CPU0_PE1_RX_DN<10> PE1_RX_DN10 @S9S_MB_2U_LIB.S9S_MB_2U(SCH_1):P5E_CPU0_PE1_RX_DN(10)
BR11 P5E_CPU0_PE1_RX_DN<9> PE1_RX_DN9 @S9S_MB_2U_LIB.S9S_MB_2U(SCH_1):P5E_CPU0_PE1_RX_DN(9)
BV10 P5E_CPU0_PE1_RX_DN<8> PE1_RX_DN8 @S9S_MB_2U_LIB.S9S_MB_2U(SCH_1):P5E_CPU0_PE1_RX_DN(8)
BW11 P5E_CPU0_PE1_RX_DN<7> PE1_RX_DN7 @S9S_MB_2U_LIB.S9S_MB_2U(SCH_1):P5E_CPU0_PE1_RX_DN(7)
CB10 P5E_CPU0_PE1_RX_DN<6> PE1_RX_DN6 @S9S_MB_2U_LIB.S9S_MB_2U(SCH_1):P5E_CPU0_PE1_RX_DN(6)
CC11 P5E_CPU0_PE1_RX_DN<5> PE1_RX_DN5 @S9S_MB_2U_LIB.S9S_MB_2U(SCH_1):P5E_CPU0_PE1_RX_DN(5)
CF10 P5E_CPU0_PE1_RX_DN<4> PE1_RX_DN4 @S9S_MB_2U_LIB.S9S_MB_2U(SCH_1):P5E_CPU0_PE1_RX_DN(4)
CG11 P5E_CPU0_PE1_RX_DN<3> PE1_RX_DN3 @S9S_MB_2U_LIB.S9S_MB_2U(SCH_1):P5E_CPU0_PE1_RX_DN(3)
CK10 P5E_CPU0_PE1_RX_DN<2> PE1_RX_DN2 @S9S_MB_2U_LIB.S9S_MB_2U(SCH_1):P5E_CPU0_PE1_RX_DN(2)
CL11 P5E_CPU0_PE1_RX_DN<1> PE1_RX_DN1 @S9S_MB_2U_LIB.S9S_MB_2U(SCH_1):P5E_CPU0_PE1_RX_DN(1)
CP10 P5E_CPU0_PE1_RX_DN<0> PE1_RX_DN0 @S9S_MB_2U_LIB.S9S_MB_2U(SCH_1):P5E_CPU0_PE1_RX_DN(0)
BD10 P5E_CPU0_PE1_RX_DP<15> PE1_RX_DP15 @S9S_MB_2U_LIB.S9S_MB_2U(SCH_1):P5E_CPU0_PE1_RX_DP(15)
 BE9 P5E_CPU0_PE1_RX_DP<14> PE1_RX_DP14 @S9S_MB_2U_LIB.S9S_MB_2U(SCH_1):P5E_CPU0_PE1_RX_DP(14)
BH10 P5E_CPU0_PE1_RX_DP<13> PE1_RX_DP13 @S9S_MB_2U_LIB.S9S_MB_2U(SCH_1):P5E_CPU0_PE1_RX_DP(13)
 BJ9 P5E_CPU0_PE1_RX_DP<12> PE1_RX_DP12 @S9S_MB_2U_LIB.S9S_MB_2U(SCH_1):P5E_CPU0_PE1_RX_DP(12)
BM10 P5E_CPU0_PE1_RX_DP<11> PE1_RX_DP11 @S9S_MB_2U_LIB.S9S_MB_2U(SCH_1):P5E_CPU0_PE1_RX_DP(11)
 BN9 P5E_CPU0_PE1_RX_DP<10> PE1_RX_DP10 @S9S_MB_2U_LIB.S9S_MB_2U(SCH_1):P5E_CPU0_PE1_RX_DP(10)
BT10 P5E_CPU0_PE1_RX_DP<9> PE1_RX_DP9 @S9S_MB_2U_LIB.S9S_MB_2U(SCH_1):P5E_CPU0_PE1_RX_DP(9)
 BU9 P5E_CPU0_PE1_RX_DP<8> PE1_RX_DP8 @S9S_MB_2U_LIB.S9S_MB_2U(SCH_1):P5E_CPU0_PE1_RX_DP(8)
BY10 P5E_CPU0_PE1_RX_DP<7> PE1_RX_DP7 @S9S_MB_2U_LIB.S9S_MB_2U(SCH_1):P5E_CPU0_PE1_RX_DP(7)
 CA9 P5E_CPU0_PE1_RX_DP<6> PE1_RX_DP6 @S9S_MB_2U_LIB.S9S_MB_2U(SCH_1):P5E_CPU0_PE1_RX_DP(6)
CD10 P5E_CPU0_PE1_RX_DP<5> PE1_RX_DP5 @S9S_MB_2U_LIB.S9S_MB_2U(SCH_1):P5E_CPU0_PE1_RX_DP(5)
 CE9 P5E_CPU0_PE1_RX_DP<4> PE1_RX_DP4 @S9S_MB_2U_LIB.S9S_MB_2U(SCH_1):P5E_CPU0_PE1_RX_DP(4)
CH10 P5E_CPU0_PE1_RX_DP<3> PE1_RX_DP3 @S9S_MB_2U_LIB.S9S_MB_2U(SCH_1):P5E_CPU0_PE1_RX_DP(3)
 CJ9 P5E_CPU0_PE1_RX_DP<2> PE1_RX_DP2 @S9S_MB_2U_LIB.S9S_MB_2U(SCH_1):P5E_CPU0_PE1_RX_DP(2)
CM10 P5E_CPU0_PE1_RX_DP<1> PE1_RX_DP1 @S9S_MB_2U_LIB.S9S_MB_2U(SCH_1):P5E_CPU0_PE1_RX_DP(1)
 CN9 P5E_CPU0_PE1_RX_DP<0> PE1_RX_DP0 @S9S_MB_2U_LIB.S9S_MB_2U(SCH_1):P5E_CPU0_PE1_RX_DP(0)
BE13 P5E_CPU0_PE1_TX_DN<15> PE1_TX_DN15 @S9S_MB_2U_LIB.S9S_MB_2U(SCH_1):P5E_CPU0_PE1_TX_DN(15)
BF14 P5E_CPU0_PE1_TX_DN<14> PE1_TX_DN14 @S9S_MB_2U_LIB.S9S_MB_2U(SCH_1):P5E_CPU0_PE1_TX_DN(14)
BJ13 P5E_CPU0_PE1_TX_DN<13> PE1_TX_DN13 @S9S_MB_2U_LIB.S9S_MB_2U(SCH_1):P5E_CPU0_PE1_TX_DN(13)
BK14 P5E_CPU0_PE1_TX_DN<12> PE1_TX_DN12 @S9S_MB_2U_LIB.S9S_MB_2U(SCH_1):P5E_CPU0_PE1_TX_DN(12)
BN13 P5E_CPU0_PE1_TX_DN<11> PE1_TX_DN11 @S9S_MB_2U_LIB.S9S_MB_2U(SCH_1):P5E_CPU0_PE1_TX_DN(11)
BP14 P5E_CPU0_PE1_TX_DN<10> PE1_TX_DN10 @S9S_MB_2U_LIB.S9S_MB_2U(SCH_1):P5E_CPU0_PE1_TX_DN(10)
BU13 P5E_CPU0_PE1_TX_DN<9> PE1_TX_DN9 @S9S_MB_2U_LIB.S9S_MB_2U(SCH_1):P5E_CPU0_PE1_TX_DN(9)
BV14 P5E_CPU0_PE1_TX_DN<8> PE1_TX_DN8 @S9S_MB_2U_LIB.S9S_MB_2U(SCH_1):P5E_CPU0_PE1_TX_DN(8)
CA13 P5E_CPU0_PE1_TX_DN<7> PE1_TX_DN7 @S9S_MB_2U_LIB.S9S_MB_2U(SCH_1):P5E_CPU0_PE1_TX_DN(7)
CB14 P5E_CPU0_PE1_TX_DN<6> PE1_TX_DN6 @S9S_MB_2U_LIB.S9S_MB_2U(SCH_1):P5E_CPU0_PE1_TX_DN(6)
CE13 P5E_CPU0_PE1_TX_DN<5> PE1_TX_DN5 @S9S_MB_2U_LIB.S9S_MB_2U(SCH_1):P5E_CPU0_PE1_TX_DN(5)
CF14 P5E_CPU0_PE1_TX_DN<4> PE1_TX_DN4 @S9S_MB_2U_LIB.S9S_MB_2U(SCH_1):P5E_CPU0_PE1_TX_DN(4)
CJ13 P5E_CPU0_PE1_TX_DN<3> PE1_TX_DN3 @S9S_MB_2U_LIB.S9S_MB_2U(SCH_1):P5E_CPU0_PE1_TX_DN(3)
CK14 P5E_CPU0_PE1_TX_DN<2> PE1_TX_DN2 @S9S_MB_2U_LIB.S9S_MB_2U(SCH_1):P5E_CPU0_PE1_TX_DN(2)
CN13 P5E_CPU0_PE1_TX_DN<1> PE1_TX_DN1 @S9S_MB_2U_LIB.S9S_MB_2U(SCH_1):P5E_CPU0_PE1_TX_DN(1)
CP14 P5E_CPU0_PE1_TX_DN<0> PE1_TX_DN0 @S9S_MB_2U_LIB.S9S_MB_2U(SCH_1):P5E_CPU0_PE1_TX_DN(0)
BD14 P5E_CPU0_PE1_TX_DP<15> PE1_TX_DP15 @S9S_MB_2U_LIB.S9S_MB_2U(SCH_1):P5E_CPU0_PE1_TX_DP(15)
BG15 P5E_CPU0_PE1_TX_DP<14> PE1_TX_DP14 @S9S_MB_2U_LIB.S9S_MB_2U(SCH_1):P5E_CPU0_PE1_TX_DP(14)
BH14 P5E_CPU0_PE1_TX_DP<13> PE1_TX_DP13 @S9S_MB_2U_LIB.S9S_MB_2U(SCH_1):P5E_CPU0_PE1_TX_DP(13)
BL15 P5E_CPU0_PE1_TX_DP<12> PE1_TX_DP12 @S9S_MB_2U_LIB.S9S_MB_2U(SCH_1):P5E_CPU0_PE1_TX_DP(12)
BM14 P5E_CPU0_PE1_TX_DP<11> PE1_TX_DP11 @S9S_MB_2U_LIB.S9S_MB_2U(SCH_1):P5E_CPU0_PE1_TX_DP(11)
BR15 P5E_CPU0_PE1_TX_DP<10> PE1_TX_DP10 @S9S_MB_2U_LIB.S9S_MB_2U(SCH_1):P5E_CPU0_PE1_TX_DP(10)
BT14 P5E_CPU0_PE1_TX_DP<9> PE1_TX_DP9 @S9S_MB_2U_LIB.S9S_MB_2U(SCH_1):P5E_CPU0_PE1_TX_DP(9)
BW15 P5E_CPU0_PE1_TX_DP<8> PE1_TX_DP8 @S9S_MB_2U_LIB.S9S_MB_2U(SCH_1):P5E_CPU0_PE1_TX_DP(8)
BY14 P5E_CPU0_PE1_TX_DP<7> PE1_TX_DP7 @S9S_MB_2U_LIB.S9S_MB_2U(SCH_1):P5E_CPU0_PE1_TX_DP(7)
CC15 P5E_CPU0_PE1_TX_DP<6> PE1_TX_DP6 @S9S_MB_2U_LIB.S9S_MB_2U(SCH_1):P5E_CPU0_PE1_TX_DP(6)
CD14 P5E_CPU0_PE1_TX_DP<5> PE1_TX_DP5 @S9S_MB_2U_LIB.S9S_MB_2U(SCH_1):P5E_CPU0_PE1_TX_DP(5)
CG15 P5E_CPU0_PE1_TX_DP<4> PE1_TX_DP4 @S9S_MB_2U_LIB.S9S_MB_2U(SCH_1):P5E_CPU0_PE1_TX_DP(4)
CH14 P5E_CPU0_PE1_TX_DP<3> PE1_TX_DP3 @S9S_MB_2U_LIB.S9S_MB_2U(SCH_1):P5E_CPU0_PE1_TX_DP(3)
CL15 P5E_CPU0_PE1_TX_DP<2> PE1_TX_DP2 @S9S_MB_2U_LIB.S9S_MB_2U(SCH_1):P5E_CPU0_PE1_TX_DP(2)
CM14 P5E_CPU0_PE1_TX_DP<1> PE1_TX_DP1 @S9S_MB_2U_LIB.S9S_MB_2U(SCH_1):P5E_CPU0_PE1_TX_DP(1)
CR15 P5E_CPU0_PE1_TX_DP<0> PE1_TX_DP0 @S9S_MB_2U_LIB.S9S_MB_2U(SCH_1):P5E_CPU0_PE1_TX_DP(0)


DRAWING: @S9S_MB_2U_LIB.S9S_MB_2U(SCH_1):PAGE30 

SOCKET4677_AZIF0045P001C01CS-SA  I139  U2
EH10 P5E_CPU0_PE2_RX_DN<15> PE2_RX_DN15 @S9S_MB_2U_LIB.S9S_MB_2U(SCH_1):P5E_CPU0_PE2_RX_DN(15)
 EE9 P5E_CPU0_PE2_RX_DN<14> PE2_RX_DN14 @S9S_MB_2U_LIB.S9S_MB_2U(SCH_1):P5E_CPU0_PE2_RX_DN(14)
ED10 P5E_CPU0_PE2_RX_DN<13> PE2_RX_DN13 @S9S_MB_2U_LIB.S9S_MB_2U(SCH_1):P5E_CPU0_PE2_RX_DN(13)
 EA9 P5E_CPU0_PE2_RX_DN<12> PE2_RX_DN12 @S9S_MB_2U_LIB.S9S_MB_2U(SCH_1):P5E_CPU0_PE2_RX_DN(12)
DY10 P5E_CPU0_PE2_RX_DN<11> PE2_RX_DN11 @S9S_MB_2U_LIB.S9S_MB_2U(SCH_1):P5E_CPU0_PE2_RX_DN(11)
 DU9 P5E_CPU0_PE2_RX_DN<10> PE2_RX_DN10 @S9S_MB_2U_LIB.S9S_MB_2U(SCH_1):P5E_CPU0_PE2_RX_DN(10)
DT10 P5E_CPU0_PE2_RX_DN<9> PE2_RX_DN9 @S9S_MB_2U_LIB.S9S_MB_2U(SCH_1):P5E_CPU0_PE2_RX_DN(9)
 DN9 P5E_CPU0_PE2_RX_DN<8> PE2_RX_DN8 @S9S_MB_2U_LIB.S9S_MB_2U(SCH_1):P5E_CPU0_PE2_RX_DN(8)
DM10 P5E_CPU0_PE2_RX_DN<7> PE2_RX_DN7 @S9S_MB_2U_LIB.S9S_MB_2U(SCH_1):P5E_CPU0_PE2_RX_DN(7)
 DJ9 P5E_CPU0_PE2_RX_DN<6> PE2_RX_DN6 @S9S_MB_2U_LIB.S9S_MB_2U(SCH_1):P5E_CPU0_PE2_RX_DN(6)
DH10 P5E_CPU0_PE2_RX_DN<5> PE2_RX_DN5 @S9S_MB_2U_LIB.S9S_MB_2U(SCH_1):P5E_CPU0_PE2_RX_DN(5)
 DE9 P5E_CPU0_PE2_RX_DN<4> PE2_RX_DN4 @S9S_MB_2U_LIB.S9S_MB_2U(SCH_1):P5E_CPU0_PE2_RX_DN(4)
DD10 P5E_CPU0_PE2_RX_DN<3> PE2_RX_DN3 @S9S_MB_2U_LIB.S9S_MB_2U(SCH_1):P5E_CPU0_PE2_RX_DN(3)
 DA9 P5E_CPU0_PE2_RX_DN<2> PE2_RX_DN2 @S9S_MB_2U_LIB.S9S_MB_2U(SCH_1):P5E_CPU0_PE2_RX_DN(2)
CY10 P5E_CPU0_PE2_RX_DN<1> PE2_RX_DN1 @S9S_MB_2U_LIB.S9S_MB_2U(SCH_1):P5E_CPU0_PE2_RX_DN(1)
 CU9 P5E_CPU0_PE2_RX_DN<0> PE2_RX_DN0 @S9S_MB_2U_LIB.S9S_MB_2U(SCH_1):P5E_CPU0_PE2_RX_DN(0)
EG11 P5E_CPU0_PE2_RX_DP<15> PE2_RX_DP15 @S9S_MB_2U_LIB.S9S_MB_2U(SCH_1):P5E_CPU0_PE2_RX_DP(15)
EF10 P5E_CPU0_PE2_RX_DP<14> PE2_RX_DP14 @S9S_MB_2U_LIB.S9S_MB_2U(SCH_1):P5E_CPU0_PE2_RX_DP(14)
EC11 P5E_CPU0_PE2_RX_DP<13> PE2_RX_DP13 @S9S_MB_2U_LIB.S9S_MB_2U(SCH_1):P5E_CPU0_PE2_RX_DP(13)
EB10 P5E_CPU0_PE2_RX_DP<12> PE2_RX_DP12 @S9S_MB_2U_LIB.S9S_MB_2U(SCH_1):P5E_CPU0_PE2_RX_DP(12)
DW11 P5E_CPU0_PE2_RX_DP<11> PE2_RX_DP11 @S9S_MB_2U_LIB.S9S_MB_2U(SCH_1):P5E_CPU0_PE2_RX_DP(11)
DV10 P5E_CPU0_PE2_RX_DP<10> PE2_RX_DP10 @S9S_MB_2U_LIB.S9S_MB_2U(SCH_1):P5E_CPU0_PE2_RX_DP(10)
DR11 P5E_CPU0_PE2_RX_DP<9> PE2_RX_DP9 @S9S_MB_2U_LIB.S9S_MB_2U(SCH_1):P5E_CPU0_PE2_RX_DP(9)
DP10 P5E_CPU0_PE2_RX_DP<8> PE2_RX_DP8 @S9S_MB_2U_LIB.S9S_MB_2U(SCH_1):P5E_CPU0_PE2_RX_DP(8)
DL11 P5E_CPU0_PE2_RX_DP<7> PE2_RX_DP7 @S9S_MB_2U_LIB.S9S_MB_2U(SCH_1):P5E_CPU0_PE2_RX_DP(7)
DK10 P5E_CPU0_PE2_RX_DP<6> PE2_RX_DP6 @S9S_MB_2U_LIB.S9S_MB_2U(SCH_1):P5E_CPU0_PE2_RX_DP(6)
DG11 P5E_CPU0_PE2_RX_DP<5> PE2_RX_DP5 @S9S_MB_2U_LIB.S9S_MB_2U(SCH_1):P5E_CPU0_PE2_RX_DP(5)
DF10 P5E_CPU0_PE2_RX_DP<4> PE2_RX_DP4 @S9S_MB_2U_LIB.S9S_MB_2U(SCH_1):P5E_CPU0_PE2_RX_DP(4)
DC11 P5E_CPU0_PE2_RX_DP<3> PE2_RX_DP3 @S9S_MB_2U_LIB.S9S_MB_2U(SCH_1):P5E_CPU0_PE2_RX_DP(3)
DB10 P5E_CPU0_PE2_RX_DP<2> PE2_RX_DP2 @S9S_MB_2U_LIB.S9S_MB_2U(SCH_1):P5E_CPU0_PE2_RX_DP(2)
CW11 P5E_CPU0_PE2_RX_DP<1> PE2_RX_DP1 @S9S_MB_2U_LIB.S9S_MB_2U(SCH_1):P5E_CPU0_PE2_RX_DP(1)
CV10 P5E_CPU0_PE2_RX_DP<0> PE2_RX_DP0 @S9S_MB_2U_LIB.S9S_MB_2U(SCH_1):P5E_CPU0_PE2_RX_DP(0)
EF14 P5E_CPU0_PE2_TX_DN<15> PE2_TX_DN15 @S9S_MB_2U_LIB.S9S_MB_2U(SCH_1):P5E_CPU0_PE2_TX_DN(15)
EE13 P5E_CPU0_PE2_TX_DN<14> PE2_TX_DN14 @S9S_MB_2U_LIB.S9S_MB_2U(SCH_1):P5E_CPU0_PE2_TX_DN(14)
EB14 P5E_CPU0_PE2_TX_DN<13> PE2_TX_DN13 @S9S_MB_2U_LIB.S9S_MB_2U(SCH_1):P5E_CPU0_PE2_TX_DN(13)
EA13 P5E_CPU0_PE2_TX_DN<12> PE2_TX_DN12 @S9S_MB_2U_LIB.S9S_MB_2U(SCH_1):P5E_CPU0_PE2_TX_DN(12)
DV14 P5E_CPU0_PE2_TX_DN<11> PE2_TX_DN11 @S9S_MB_2U_LIB.S9S_MB_2U(SCH_1):P5E_CPU0_PE2_TX_DN(11)
DU13 P5E_CPU0_PE2_TX_DN<10> PE2_TX_DN10 @S9S_MB_2U_LIB.S9S_MB_2U(SCH_1):P5E_CPU0_PE2_TX_DN(10)
DP14 P5E_CPU0_PE2_TX_DN<9> PE2_TX_DN9 @S9S_MB_2U_LIB.S9S_MB_2U(SCH_1):P5E_CPU0_PE2_TX_DN(9)
DN13 P5E_CPU0_PE2_TX_DN<8> PE2_TX_DN8 @S9S_MB_2U_LIB.S9S_MB_2U(SCH_1):P5E_CPU0_PE2_TX_DN(8)
DK14 P5E_CPU0_PE2_TX_DN<7> PE2_TX_DN7 @S9S_MB_2U_LIB.S9S_MB_2U(SCH_1):P5E_CPU0_PE2_TX_DN(7)
DJ13 P5E_CPU0_PE2_TX_DN<6> PE2_TX_DN6 @S9S_MB_2U_LIB.S9S_MB_2U(SCH_1):P5E_CPU0_PE2_TX_DN(6)
DF14 P5E_CPU0_PE2_TX_DN<5> PE2_TX_DN5 @S9S_MB_2U_LIB.S9S_MB_2U(SCH_1):P5E_CPU0_PE2_TX_DN(5)
DE13 P5E_CPU0_PE2_TX_DN<4> PE2_TX_DN4 @S9S_MB_2U_LIB.S9S_MB_2U(SCH_1):P5E_CPU0_PE2_TX_DN(4)
DB14 P5E_CPU0_PE2_TX_DN<3> PE2_TX_DN3 @S9S_MB_2U_LIB.S9S_MB_2U(SCH_1):P5E_CPU0_PE2_TX_DN(3)
DA13 P5E_CPU0_PE2_TX_DN<2> PE2_TX_DN2 @S9S_MB_2U_LIB.S9S_MB_2U(SCH_1):P5E_CPU0_PE2_TX_DN(2)
CV14 P5E_CPU0_PE2_TX_DN<1> PE2_TX_DN1 @S9S_MB_2U_LIB.S9S_MB_2U(SCH_1):P5E_CPU0_PE2_TX_DN(1)
CU13 P5E_CPU0_PE2_TX_DN<0> PE2_TX_DN0 @S9S_MB_2U_LIB.S9S_MB_2U(SCH_1):P5E_CPU0_PE2_TX_DN(0)
EG15 P5E_CPU0_PE2_TX_DP<15> PE2_TX_DP15 @S9S_MB_2U_LIB.S9S_MB_2U(SCH_1):P5E_CPU0_PE2_TX_DP(15)
ED14 P5E_CPU0_PE2_TX_DP<14> PE2_TX_DP14 @S9S_MB_2U_LIB.S9S_MB_2U(SCH_1):P5E_CPU0_PE2_TX_DP(14)
EC15 P5E_CPU0_PE2_TX_DP<13> PE2_TX_DP13 @S9S_MB_2U_LIB.S9S_MB_2U(SCH_1):P5E_CPU0_PE2_TX_DP(13)
DY14 P5E_CPU0_PE2_TX_DP<12> PE2_TX_DP12 @S9S_MB_2U_LIB.S9S_MB_2U(SCH_1):P5E_CPU0_PE2_TX_DP(12)
DW15 P5E_CPU0_PE2_TX_DP<11> PE2_TX_DP11 @S9S_MB_2U_LIB.S9S_MB_2U(SCH_1):P5E_CPU0_PE2_TX_DP(11)
DT14 P5E_CPU0_PE2_TX_DP<10> PE2_TX_DP10 @S9S_MB_2U_LIB.S9S_MB_2U(SCH_1):P5E_CPU0_PE2_TX_DP(10)
DR15 P5E_CPU0_PE2_TX_DP<9> PE2_TX_DP9 @S9S_MB_2U_LIB.S9S_MB_2U(SCH_1):P5E_CPU0_PE2_TX_DP(9)
DM14 P5E_CPU0_PE2_TX_DP<8> PE2_TX_DP8 @S9S_MB_2U_LIB.S9S_MB_2U(SCH_1):P5E_CPU0_PE2_TX_DP(8)
DL15 P5E_CPU0_PE2_TX_DP<7> PE2_TX_DP7 @S9S_MB_2U_LIB.S9S_MB_2U(SCH_1):P5E_CPU0_PE2_TX_DP(7)
DH14 P5E_CPU0_PE2_TX_DP<6> PE2_TX_DP6 @S9S_MB_2U_LIB.S9S_MB_2U(SCH_1):P5E_CPU0_PE2_TX_DP(6)
DG15 P5E_CPU0_PE2_TX_DP<5> PE2_TX_DP5 @S9S_MB_2U_LIB.S9S_MB_2U(SCH_1):P5E_CPU0_PE2_TX_DP(5)
DD14 P5E_CPU0_PE2_TX_DP<4> PE2_TX_DP4 @S9S_MB_2U_LIB.S9S_MB_2U(SCH_1):P5E_CPU0_PE2_TX_DP(4)
DC15 P5E_CPU0_PE2_TX_DP<3> PE2_TX_DP3 @S9S_MB_2U_LIB.S9S_MB_2U(SCH_1):P5E_CPU0_PE2_TX_DP(3)
CY14 P5E_CPU0_PE2_TX_DP<2> PE2_TX_DP2 @S9S_MB_2U_LIB.S9S_MB_2U(SCH_1):P5E_CPU0_PE2_TX_DP(2)
CW15 P5E_CPU0_PE2_TX_DP<1> PE2_TX_DP1 @S9S_MB_2U_LIB.S9S_MB_2U(SCH_1):P5E_CPU0_PE2_TX_DP(1)
CT14 P5E_CPU0_PE2_TX_DP<0> PE2_TX_DP0 @S9S_MB_2U_LIB.S9S_MB_2U(SCH_1):P5E_CPU0_PE2_TX_DP(0)

SOCKET4677_AZIF0045P001C01CS-SA  I140  U2
CU90 P5E_CPU0_PE3_RX_DN<15> PE3_RX_DN15 @S9S_MB_2U_LIB.S9S_MB_2U(SCH_1):P5E_CPU0_PE3_RX_DN(15)
CV89 P5E_CPU0_PE3_RX_DN<14> PE3_RX_DN14 @S9S_MB_2U_LIB.S9S_MB_2U(SCH_1):P5E_CPU0_PE3_RX_DN(14)
DA90 P5E_CPU0_PE3_RX_DN<13> PE3_RX_DN13 @S9S_MB_2U_LIB.S9S_MB_2U(SCH_1):P5E_CPU0_PE3_RX_DN(13)
DB89 P5E_CPU0_PE3_RX_DN<12> PE3_RX_DN12 @S9S_MB_2U_LIB.S9S_MB_2U(SCH_1):P5E_CPU0_PE3_RX_DN(12)
DD91 P5E_CPU0_PE3_RX_DN<11> PE3_RX_DN11 @S9S_MB_2U_LIB.S9S_MB_2U(SCH_1):P5E_CPU0_PE3_RX_DN(11)
DG90 P5E_CPU0_PE3_RX_DN<10> PE3_RX_DN10 @S9S_MB_2U_LIB.S9S_MB_2U(SCH_1):P5E_CPU0_PE3_RX_DN(10)
DH91 P5E_CPU0_PE3_RX_DN<9> PE3_RX_DN9 @S9S_MB_2U_LIB.S9S_MB_2U(SCH_1):P5E_CPU0_PE3_RX_DN(9)
DL90 P5E_CPU0_PE3_RX_DN<8> PE3_RX_DN8 @S9S_MB_2U_LIB.S9S_MB_2U(SCH_1):P5E_CPU0_PE3_RX_DN(8)
DN90 P5E_CPU0_PE3_RX_DN<7> PE3_RX_DN7 @S9S_MB_2U_LIB.S9S_MB_2U(SCH_1):P5E_CPU0_PE3_RX_DN(7)
DP89 P5E_CPU0_PE3_RX_DN<6> PE3_RX_DN6 @S9S_MB_2U_LIB.S9S_MB_2U(SCH_1):P5E_CPU0_PE3_RX_DN(6)
DU90 P5E_CPU0_PE3_RX_DN<5> PE3_RX_DN5 @S9S_MB_2U_LIB.S9S_MB_2U(SCH_1):P5E_CPU0_PE3_RX_DN(5)
DV89 P5E_CPU0_PE3_RX_DN<4> PE3_RX_DN4 @S9S_MB_2U_LIB.S9S_MB_2U(SCH_1):P5E_CPU0_PE3_RX_DN(4)
DY91 P5E_CPU0_PE3_RX_DN<3> PE3_RX_DN3 @S9S_MB_2U_LIB.S9S_MB_2U(SCH_1):P5E_CPU0_PE3_RX_DN(3)
EC90 P5E_CPU0_PE3_RX_DN<2> PE3_RX_DN2 @S9S_MB_2U_LIB.S9S_MB_2U(SCH_1):P5E_CPU0_PE3_RX_DN(2)
ED91 P5E_CPU0_PE3_RX_DN<1> PE3_RX_DN1 @S9S_MB_2U_LIB.S9S_MB_2U(SCH_1):P5E_CPU0_PE3_RX_DN(1)
EH89 P5E_CPU0_PE3_RX_DN<0> PE3_RX_DN0 @S9S_MB_2U_LIB.S9S_MB_2U(SCH_1):P5E_CPU0_PE3_RX_DN(0)
CT91 P5E_CPU0_PE3_RX_DP<15> PE3_RX_DP15 @S9S_MB_2U_LIB.S9S_MB_2U(SCH_1):P5E_CPU0_PE3_RX_DP(15)
CW90 P5E_CPU0_PE3_RX_DP<14> PE3_RX_DP14 @S9S_MB_2U_LIB.S9S_MB_2U(SCH_1):P5E_CPU0_PE3_RX_DP(14)
CY91 P5E_CPU0_PE3_RX_DP<13> PE3_RX_DP13 @S9S_MB_2U_LIB.S9S_MB_2U(SCH_1):P5E_CPU0_PE3_RX_DP(13)
DC90 P5E_CPU0_PE3_RX_DP<12> PE3_RX_DP12 @S9S_MB_2U_LIB.S9S_MB_2U(SCH_1):P5E_CPU0_PE3_RX_DP(12)
DE90 P5E_CPU0_PE3_RX_DP<11> PE3_RX_DP11 @S9S_MB_2U_LIB.S9S_MB_2U(SCH_1):P5E_CPU0_PE3_RX_DP(11)
DF89 P5E_CPU0_PE3_RX_DP<10> PE3_RX_DP10 @S9S_MB_2U_LIB.S9S_MB_2U(SCH_1):P5E_CPU0_PE3_RX_DP(10)
DJ90 P5E_CPU0_PE3_RX_DP<9> PE3_RX_DP9 @S9S_MB_2U_LIB.S9S_MB_2U(SCH_1):P5E_CPU0_PE3_RX_DP(9)
DK89 P5E_CPU0_PE3_RX_DP<8> PE3_RX_DP8 @S9S_MB_2U_LIB.S9S_MB_2U(SCH_1):P5E_CPU0_PE3_RX_DP(8)
DM91 P5E_CPU0_PE3_RX_DP<7> PE3_RX_DP7 @S9S_MB_2U_LIB.S9S_MB_2U(SCH_1):P5E_CPU0_PE3_RX_DP(7)
DR90 P5E_CPU0_PE3_RX_DP<6> PE3_RX_DP6 @S9S_MB_2U_LIB.S9S_MB_2U(SCH_1):P5E_CPU0_PE3_RX_DP(6)
DT91 P5E_CPU0_PE3_RX_DP<5> PE3_RX_DP5 @S9S_MB_2U_LIB.S9S_MB_2U(SCH_1):P5E_CPU0_PE3_RX_DP(5)
DW90 P5E_CPU0_PE3_RX_DP<4> PE3_RX_DP4 @S9S_MB_2U_LIB.S9S_MB_2U(SCH_1):P5E_CPU0_PE3_RX_DP(4)
EA90 P5E_CPU0_PE3_RX_DP<3> PE3_RX_DP3 @S9S_MB_2U_LIB.S9S_MB_2U(SCH_1):P5E_CPU0_PE3_RX_DP(3)
EB89 P5E_CPU0_PE3_RX_DP<2> PE3_RX_DP2 @S9S_MB_2U_LIB.S9S_MB_2U(SCH_1):P5E_CPU0_PE3_RX_DP(2)
EE90 P5E_CPU0_PE3_RX_DP<1> PE3_RX_DP1 @S9S_MB_2U_LIB.S9S_MB_2U(SCH_1):P5E_CPU0_PE3_RX_DP(1)
EJ90 P5E_CPU0_PE3_RX_DP<0> PE3_RX_DP0 @S9S_MB_2U_LIB.S9S_MB_2U(SCH_1):P5E_CPU0_PE3_RX_DP(0)
CP85 P5E_CPU0_PE3_TX_DN<15> PE3_TX_DN15 @S9S_MB_2U_LIB.S9S_MB_2U(SCH_1):P5E_CPU0_PE3_TX_DN(15)
CT87 P5E_CPU0_PE3_TX_DN<14> PE3_TX_DN14 @S9S_MB_2U_LIB.S9S_MB_2U(SCH_1):P5E_CPU0_PE3_TX_DN(14)
CV85 P5E_CPU0_PE3_TX_DN<13> PE3_TX_DN13 @S9S_MB_2U_LIB.S9S_MB_2U(SCH_1):P5E_CPU0_PE3_TX_DN(13)
CY87 P5E_CPU0_PE3_TX_DN<12> PE3_TX_DN12 @S9S_MB_2U_LIB.S9S_MB_2U(SCH_1):P5E_CPU0_PE3_TX_DN(12)
DB85 P5E_CPU0_PE3_TX_DN<11> PE3_TX_DN11 @S9S_MB_2U_LIB.S9S_MB_2U(SCH_1):P5E_CPU0_PE3_TX_DN(11)
DD87 P5E_CPU0_PE3_TX_DN<10> PE3_TX_DN10 @S9S_MB_2U_LIB.S9S_MB_2U(SCH_1):P5E_CPU0_PE3_TX_DN(10)
DF85 P5E_CPU0_PE3_TX_DN<9> PE3_TX_DN9 @S9S_MB_2U_LIB.S9S_MB_2U(SCH_1):P5E_CPU0_PE3_TX_DN(9)
DH87 P5E_CPU0_PE3_TX_DN<8> PE3_TX_DN8 @S9S_MB_2U_LIB.S9S_MB_2U(SCH_1):P5E_CPU0_PE3_TX_DN(8)
DK85 P5E_CPU0_PE3_TX_DN<7> PE3_TX_DN7 @S9S_MB_2U_LIB.S9S_MB_2U(SCH_1):P5E_CPU0_PE3_TX_DN(7)
DM87 P5E_CPU0_PE3_TX_DN<6> PE3_TX_DN6 @S9S_MB_2U_LIB.S9S_MB_2U(SCH_1):P5E_CPU0_PE3_TX_DN(6)
DP85 P5E_CPU0_PE3_TX_DN<5> PE3_TX_DN5 @S9S_MB_2U_LIB.S9S_MB_2U(SCH_1):P5E_CPU0_PE3_TX_DN(5)
DT87 P5E_CPU0_PE3_TX_DN<4> PE3_TX_DN4 @S9S_MB_2U_LIB.S9S_MB_2U(SCH_1):P5E_CPU0_PE3_TX_DN(4)
DV85 P5E_CPU0_PE3_TX_DN<3> PE3_TX_DN3 @S9S_MB_2U_LIB.S9S_MB_2U(SCH_1):P5E_CPU0_PE3_TX_DN(3)
DY87 P5E_CPU0_PE3_TX_DN<2> PE3_TX_DN2 @S9S_MB_2U_LIB.S9S_MB_2U(SCH_1):P5E_CPU0_PE3_TX_DN(2)
EB85 P5E_CPU0_PE3_TX_DN<1> PE3_TX_DN1 @S9S_MB_2U_LIB.S9S_MB_2U(SCH_1):P5E_CPU0_PE3_TX_DN(1)
EE86 P5E_CPU0_PE3_TX_DN<0> PE3_TX_DN0 @S9S_MB_2U_LIB.S9S_MB_2U(SCH_1):P5E_CPU0_PE3_TX_DN(0)
CR86 P5E_CPU0_PE3_TX_DP<15> PE3_TX_DP15 @S9S_MB_2U_LIB.S9S_MB_2U(SCH_1):P5E_CPU0_PE3_TX_DP(15)
CU86 P5E_CPU0_PE3_TX_DP<14> PE3_TX_DP14 @S9S_MB_2U_LIB.S9S_MB_2U(SCH_1):P5E_CPU0_PE3_TX_DP(14)
CW86 P5E_CPU0_PE3_TX_DP<13> PE3_TX_DP13 @S9S_MB_2U_LIB.S9S_MB_2U(SCH_1):P5E_CPU0_PE3_TX_DP(13)
DA86 P5E_CPU0_PE3_TX_DP<12> PE3_TX_DP12 @S9S_MB_2U_LIB.S9S_MB_2U(SCH_1):P5E_CPU0_PE3_TX_DP(12)
DC86 P5E_CPU0_PE3_TX_DP<11> PE3_TX_DP11 @S9S_MB_2U_LIB.S9S_MB_2U(SCH_1):P5E_CPU0_PE3_TX_DP(11)
DE86 P5E_CPU0_PE3_TX_DP<10> PE3_TX_DP10 @S9S_MB_2U_LIB.S9S_MB_2U(SCH_1):P5E_CPU0_PE3_TX_DP(10)
DG86 P5E_CPU0_PE3_TX_DP<9> PE3_TX_DP9 @S9S_MB_2U_LIB.S9S_MB_2U(SCH_1):P5E_CPU0_PE3_TX_DP(9)
DJ86 P5E_CPU0_PE3_TX_DP<8> PE3_TX_DP8 @S9S_MB_2U_LIB.S9S_MB_2U(SCH_1):P5E_CPU0_PE3_TX_DP(8)
DL86 P5E_CPU0_PE3_TX_DP<7> PE3_TX_DP7 @S9S_MB_2U_LIB.S9S_MB_2U(SCH_1):P5E_CPU0_PE3_TX_DP(7)
DN86 P5E_CPU0_PE3_TX_DP<6> PE3_TX_DP6 @S9S_MB_2U_LIB.S9S_MB_2U(SCH_1):P5E_CPU0_PE3_TX_DP(6)
DR86 P5E_CPU0_PE3_TX_DP<5> PE3_TX_DP5 @S9S_MB_2U_LIB.S9S_MB_2U(SCH_1):P5E_CPU0_PE3_TX_DP(5)
DU86 P5E_CPU0_PE3_TX_DP<4> PE3_TX_DP4 @S9S_MB_2U_LIB.S9S_MB_2U(SCH_1):P5E_CPU0_PE3_TX_DP(4)
DW86 P5E_CPU0_PE3_TX_DP<3> PE3_TX_DP3 @S9S_MB_2U_LIB.S9S_MB_2U(SCH_1):P5E_CPU0_PE3_TX_DP(3)
EA86 P5E_CPU0_PE3_TX_DP<2> PE3_TX_DP2 @S9S_MB_2U_LIB.S9S_MB_2U(SCH_1):P5E_CPU0_PE3_TX_DP(2)
EC86 P5E_CPU0_PE3_TX_DP<1> PE3_TX_DP1 @S9S_MB_2U_LIB.S9S_MB_2U(SCH_1):P5E_CPU0_PE3_TX_DP(1)
ED87 P5E_CPU0_PE3_TX_DP<0> PE3_TX_DP0 @S9S_MB_2U_LIB.S9S_MB_2U(SCH_1):P5E_CPU0_PE3_TX_DP(0)


DRAWING: @S9S_MB_2U_LIB.S9S_MB_2U(SCH_1):PAGE31 

SOCKET4677_AZIF0045P001C01CS-SA  I139  U2
BB89 P5E_CPU0_PE4_RX_DN<15> PE4_RX_DN15 @S9S_MB_2U_LIB.S9S_MB_2U(SCH_1):P5E_CPU0_PE4_RX_DN(15)
AY91 P5E_CPU0_PE4_RX_DN<14> PE4_RX_DN14 @S9S_MB_2U_LIB.S9S_MB_2U(SCH_1):P5E_CPU0_PE4_RX_DN(14)
AV89 P5E_CPU0_PE4_RX_DN<13> PE4_RX_DN13 @S9S_MB_2U_LIB.S9S_MB_2U(SCH_1):P5E_CPU0_PE4_RX_DN(13)
AT91 P5E_CPU0_PE4_RX_DN<12> PE4_RX_DN12 @S9S_MB_2U_LIB.S9S_MB_2U(SCH_1):P5E_CPU0_PE4_RX_DN(12)
AP89 P5E_CPU0_PE4_RX_DN<11> PE4_RX_DN11 @S9S_MB_2U_LIB.S9S_MB_2U(SCH_1):P5E_CPU0_PE4_RX_DN(11)
AM91 P5E_CPU0_PE4_RX_DN<10> PE4_RX_DN10 @S9S_MB_2U_LIB.S9S_MB_2U(SCH_1):P5E_CPU0_PE4_RX_DN(10)
AK89 P5E_CPU0_PE4_RX_DN<9> PE4_RX_DN9 @S9S_MB_2U_LIB.S9S_MB_2U(SCH_1):P5E_CPU0_PE4_RX_DN(9)
AH91 P5E_CPU0_PE4_RX_DN<8> PE4_RX_DN8 @S9S_MB_2U_LIB.S9S_MB_2U(SCH_1):P5E_CPU0_PE4_RX_DN(8)
AF89 P5E_CPU0_PE4_RX_DN<7> PE4_RX_DN7 @S9S_MB_2U_LIB.S9S_MB_2U(SCH_1):P5E_CPU0_PE4_RX_DN(7)
AD91 P5E_CPU0_PE4_RX_DN<6> PE4_RX_DN6 @S9S_MB_2U_LIB.S9S_MB_2U(SCH_1):P5E_CPU0_PE4_RX_DN(6)
AB89 P5E_CPU0_PE4_RX_DN<5> PE4_RX_DN5 @S9S_MB_2U_LIB.S9S_MB_2U(SCH_1):P5E_CPU0_PE4_RX_DN(5)
 Y91 P5E_CPU0_PE4_RX_DN<4> PE4_RX_DN4 @S9S_MB_2U_LIB.S9S_MB_2U(SCH_1):P5E_CPU0_PE4_RX_DN(4)
 V89 P5E_CPU0_PE4_RX_DN<3> PE4_RX_DN3 @S9S_MB_2U_LIB.S9S_MB_2U(SCH_1):P5E_CPU0_PE4_RX_DN(3)
 T91 P5E_CPU0_PE4_RX_DN<2> PE4_RX_DN2 @S9S_MB_2U_LIB.S9S_MB_2U(SCH_1):P5E_CPU0_PE4_RX_DN(2)
 P89 P5E_CPU0_PE4_RX_DN<1> PE4_RX_DN1 @S9S_MB_2U_LIB.S9S_MB_2U(SCH_1):P5E_CPU0_PE4_RX_DN(1)
 J90 P5E_CPU0_PE4_RX_DN<0> PE4_RX_DN0 @S9S_MB_2U_LIB.S9S_MB_2U(SCH_1):P5E_CPU0_PE4_RX_DN(0)
BA90 P5E_CPU0_PE4_RX_DP<15> PE4_RX_DP15 @S9S_MB_2U_LIB.S9S_MB_2U(SCH_1):P5E_CPU0_PE4_RX_DP(15)
AW90 P5E_CPU0_PE4_RX_DP<14> PE4_RX_DP14 @S9S_MB_2U_LIB.S9S_MB_2U(SCH_1):P5E_CPU0_PE4_RX_DP(14)
AU90 P5E_CPU0_PE4_RX_DP<13> PE4_RX_DP13 @S9S_MB_2U_LIB.S9S_MB_2U(SCH_1):P5E_CPU0_PE4_RX_DP(13)
AR90 P5E_CPU0_PE4_RX_DP<12> PE4_RX_DP12 @S9S_MB_2U_LIB.S9S_MB_2U(SCH_1):P5E_CPU0_PE4_RX_DP(12)
AN90 P5E_CPU0_PE4_RX_DP<11> PE4_RX_DP11 @S9S_MB_2U_LIB.S9S_MB_2U(SCH_1):P5E_CPU0_PE4_RX_DP(11)
AL90 P5E_CPU0_PE4_RX_DP<10> PE4_RX_DP10 @S9S_MB_2U_LIB.S9S_MB_2U(SCH_1):P5E_CPU0_PE4_RX_DP(10)
AJ90 P5E_CPU0_PE4_RX_DP<9> PE4_RX_DP9 @S9S_MB_2U_LIB.S9S_MB_2U(SCH_1):P5E_CPU0_PE4_RX_DP(9)
AG90 P5E_CPU0_PE4_RX_DP<8> PE4_RX_DP8 @S9S_MB_2U_LIB.S9S_MB_2U(SCH_1):P5E_CPU0_PE4_RX_DP(8)
AE90 P5E_CPU0_PE4_RX_DP<7> PE4_RX_DP7 @S9S_MB_2U_LIB.S9S_MB_2U(SCH_1):P5E_CPU0_PE4_RX_DP(7)
AC90 P5E_CPU0_PE4_RX_DP<6> PE4_RX_DP6 @S9S_MB_2U_LIB.S9S_MB_2U(SCH_1):P5E_CPU0_PE4_RX_DP(6)
AA90 P5E_CPU0_PE4_RX_DP<5> PE4_RX_DP5 @S9S_MB_2U_LIB.S9S_MB_2U(SCH_1):P5E_CPU0_PE4_RX_DP(5)
 W90 P5E_CPU0_PE4_RX_DP<4> PE4_RX_DP4 @S9S_MB_2U_LIB.S9S_MB_2U(SCH_1):P5E_CPU0_PE4_RX_DP(4)
 U90 P5E_CPU0_PE4_RX_DP<3> PE4_RX_DP3 @S9S_MB_2U_LIB.S9S_MB_2U(SCH_1):P5E_CPU0_PE4_RX_DP(3)
 R90 P5E_CPU0_PE4_RX_DP<2> PE4_RX_DP2 @S9S_MB_2U_LIB.S9S_MB_2U(SCH_1):P5E_CPU0_PE4_RX_DP(2)
 N90 P5E_CPU0_PE4_RX_DP<1> PE4_RX_DP1 @S9S_MB_2U_LIB.S9S_MB_2U(SCH_1):P5E_CPU0_PE4_RX_DP(1)
 K89 P5E_CPU0_PE4_RX_DP<0> PE4_RX_DP0 @S9S_MB_2U_LIB.S9S_MB_2U(SCH_1):P5E_CPU0_PE4_RX_DP(0)
BA86 P5E_CPU0_PE4_TX_DN<15> PE4_TX_DN15 @S9S_MB_2U_LIB.S9S_MB_2U(SCH_1):P5E_CPU0_PE4_TX_DN(15)
AW86 P5E_CPU0_PE4_TX_DN<14> PE4_TX_DN14 @S9S_MB_2U_LIB.S9S_MB_2U(SCH_1):P5E_CPU0_PE4_TX_DN(14)
AU86 P5E_CPU0_PE4_TX_DN<13> PE4_TX_DN13 @S9S_MB_2U_LIB.S9S_MB_2U(SCH_1):P5E_CPU0_PE4_TX_DN(13)
AR86 P5E_CPU0_PE4_TX_DN<12> PE4_TX_DN12 @S9S_MB_2U_LIB.S9S_MB_2U(SCH_1):P5E_CPU0_PE4_TX_DN(12)
AP85 P5E_CPU0_PE4_TX_DN<11> PE4_TX_DN11 @S9S_MB_2U_LIB.S9S_MB_2U(SCH_1):P5E_CPU0_PE4_TX_DN(11)
AL86 P5E_CPU0_PE4_TX_DN<10> PE4_TX_DN10 @S9S_MB_2U_LIB.S9S_MB_2U(SCH_1):P5E_CPU0_PE4_TX_DN(10)
AJ86 P5E_CPU0_PE4_TX_DN<9> PE4_TX_DN9 @S9S_MB_2U_LIB.S9S_MB_2U(SCH_1):P5E_CPU0_PE4_TX_DN(9)
AG86 P5E_CPU0_PE4_TX_DN<8> PE4_TX_DN8 @S9S_MB_2U_LIB.S9S_MB_2U(SCH_1):P5E_CPU0_PE4_TX_DN(8)
AE86 P5E_CPU0_PE4_TX_DN<7> PE4_TX_DN7 @S9S_MB_2U_LIB.S9S_MB_2U(SCH_1):P5E_CPU0_PE4_TX_DN(7)
AC86 P5E_CPU0_PE4_TX_DN<6> PE4_TX_DN6 @S9S_MB_2U_LIB.S9S_MB_2U(SCH_1):P5E_CPU0_PE4_TX_DN(6)
AA86 P5E_CPU0_PE4_TX_DN<5> PE4_TX_DN5 @S9S_MB_2U_LIB.S9S_MB_2U(SCH_1):P5E_CPU0_PE4_TX_DN(5)
 W86 P5E_CPU0_PE4_TX_DN<4> PE4_TX_DN4 @S9S_MB_2U_LIB.S9S_MB_2U(SCH_1):P5E_CPU0_PE4_TX_DN(4)
 U86 P5E_CPU0_PE4_TX_DN<3> PE4_TX_DN3 @S9S_MB_2U_LIB.S9S_MB_2U(SCH_1):P5E_CPU0_PE4_TX_DN(3)
 R86 P5E_CPU0_PE4_TX_DN<2> PE4_TX_DN2 @S9S_MB_2U_LIB.S9S_MB_2U(SCH_1):P5E_CPU0_PE4_TX_DN(2)
 P85 P5E_CPU0_PE4_TX_DN<1> PE4_TX_DN1 @S9S_MB_2U_LIB.S9S_MB_2U(SCH_1):P5E_CPU0_PE4_TX_DN(1)
 L86 P5E_CPU0_PE4_TX_DN<0> PE4_TX_DN0 @S9S_MB_2U_LIB.S9S_MB_2U(SCH_1):P5E_CPU0_PE4_TX_DN(0)
BB85 P5E_CPU0_PE4_TX_DP<15> PE4_TX_DP15 @S9S_MB_2U_LIB.S9S_MB_2U(SCH_1):P5E_CPU0_PE4_TX_DP(15)
AY87 P5E_CPU0_PE4_TX_DP<14> PE4_TX_DP14 @S9S_MB_2U_LIB.S9S_MB_2U(SCH_1):P5E_CPU0_PE4_TX_DP(14)
AV85 P5E_CPU0_PE4_TX_DP<13> PE4_TX_DP13 @S9S_MB_2U_LIB.S9S_MB_2U(SCH_1):P5E_CPU0_PE4_TX_DP(13)
AT87 P5E_CPU0_PE4_TX_DP<12> PE4_TX_DP12 @S9S_MB_2U_LIB.S9S_MB_2U(SCH_1):P5E_CPU0_PE4_TX_DP(12)
AN86 P5E_CPU0_PE4_TX_DP<11> PE4_TX_DP11 @S9S_MB_2U_LIB.S9S_MB_2U(SCH_1):P5E_CPU0_PE4_TX_DP(11)
AM87 P5E_CPU0_PE4_TX_DP<10> PE4_TX_DP10 @S9S_MB_2U_LIB.S9S_MB_2U(SCH_1):P5E_CPU0_PE4_TX_DP(10)
AK85 P5E_CPU0_PE4_TX_DP<9> PE4_TX_DP9 @S9S_MB_2U_LIB.S9S_MB_2U(SCH_1):P5E_CPU0_PE4_TX_DP(9)
AH87 P5E_CPU0_PE4_TX_DP<8> PE4_TX_DP8 @S9S_MB_2U_LIB.S9S_MB_2U(SCH_1):P5E_CPU0_PE4_TX_DP(8)
AF85 P5E_CPU0_PE4_TX_DP<7> PE4_TX_DP7 @S9S_MB_2U_LIB.S9S_MB_2U(SCH_1):P5E_CPU0_PE4_TX_DP(7)
AD87 P5E_CPU0_PE4_TX_DP<6> PE4_TX_DP6 @S9S_MB_2U_LIB.S9S_MB_2U(SCH_1):P5E_CPU0_PE4_TX_DP(6)
AB85 P5E_CPU0_PE4_TX_DP<5> PE4_TX_DP5 @S9S_MB_2U_LIB.S9S_MB_2U(SCH_1):P5E_CPU0_PE4_TX_DP(5)
 Y87 P5E_CPU0_PE4_TX_DP<4> PE4_TX_DP4 @S9S_MB_2U_LIB.S9S_MB_2U(SCH_1):P5E_CPU0_PE4_TX_DP(4)
 V85 P5E_CPU0_PE4_TX_DP<3> PE4_TX_DP3 @S9S_MB_2U_LIB.S9S_MB_2U(SCH_1):P5E_CPU0_PE4_TX_DP(3)
 T87 P5E_CPU0_PE4_TX_DP<2> PE4_TX_DP2 @S9S_MB_2U_LIB.S9S_MB_2U(SCH_1):P5E_CPU0_PE4_TX_DP(2)
 N86 P5E_CPU0_PE4_TX_DP<1> PE4_TX_DP1 @S9S_MB_2U_LIB.S9S_MB_2U(SCH_1):P5E_CPU0_PE4_TX_DP(1)
 M87 P5E_CPU0_PE4_TX_DP<0> PE4_TX_DP0 @S9S_MB_2U_LIB.S9S_MB_2U(SCH_1):P5E_CPU0_PE4_TX_DP(0)


DRAWING: @S9S_MB_2U_LIB.S9S_MB_2U(SCH_1):PAGE32 

SOCKET4677_AZIF0045P001C01CS-SA  I70  U2
 BU5 UPI_CPU1_CPU0_P1P0_DP<23> UPI0_RX_DN23 @S9S_MB_2U_LIB.S9S_MB_2U(SCH_1):UPI_CPU1_CPU0_P1P0_DP(23)
 BR7 UPI_CPU1_CPU0_P1P0_DN<22> UPI0_RX_DN22 @S9S_MB_2U_LIB.S9S_MB_2U(SCH_1):UPI_CPU1_CPU0_P1P0_DN(22)
 BN5 UPI_CPU1_CPU0_P1P0_DP<21> UPI0_RX_DN21 @S9S_MB_2U_LIB.S9S_MB_2U(SCH_1):UPI_CPU1_CPU0_P1P0_DP(21)
 BK6 UPI_CPU1_CPU0_P1P0_DP<20> UPI0_RX_DN20 @S9S_MB_2U_LIB.S9S_MB_2U(SCH_1):UPI_CPU1_CPU0_P1P0_DP(20)
 BJ5 UPI_CPU1_CPU0_P1P0_DP<19> UPI0_RX_DN19 @S9S_MB_2U_LIB.S9S_MB_2U(SCH_1):UPI_CPU1_CPU0_P1P0_DP(19)
 BF6 UPI_CPU1_CPU0_P1P0_DP<18> UPI0_RX_DN18 @S9S_MB_2U_LIB.S9S_MB_2U(SCH_1):UPI_CPU1_CPU0_P1P0_DP(18)
 BE5 UPI_CPU1_CPU0_P1P0_DP<17> UPI0_RX_DN17 @S9S_MB_2U_LIB.S9S_MB_2U(SCH_1):UPI_CPU1_CPU0_P1P0_DP(17)
 BB6 UPI_CPU1_CPU0_P1P0_DP<16> UPI0_RX_DN16 @S9S_MB_2U_LIB.S9S_MB_2U(SCH_1):UPI_CPU1_CPU0_P1P0_DP(16)
 BA5 UPI_CPU1_CPU0_P1P0_DP<15> UPI0_RX_DN15 @S9S_MB_2U_LIB.S9S_MB_2U(SCH_1):UPI_CPU1_CPU0_P1P0_DP(15)
 AV6 UPI_CPU1_CPU0_P1P0_DP<14> UPI0_RX_DN14 @S9S_MB_2U_LIB.S9S_MB_2U(SCH_1):UPI_CPU1_CPU0_P1P0_DP(14)
 AU5 UPI_CPU1_CPU0_P1P0_DP<13> UPI0_RX_DN13 @S9S_MB_2U_LIB.S9S_MB_2U(SCH_1):UPI_CPU1_CPU0_P1P0_DP(13)
 AP6 UPI_CPU1_CPU0_P1P0_DP<12> UPI0_RX_DN12 @S9S_MB_2U_LIB.S9S_MB_2U(SCH_1):UPI_CPU1_CPU0_P1P0_DP(12)
 AN5 UPI_CPU1_CPU0_P1P0_DP<11> UPI0_RX_DN11 @S9S_MB_2U_LIB.S9S_MB_2U(SCH_1):UPI_CPU1_CPU0_P1P0_DP(11)
 AK6 UPI_CPU1_CPU0_P1P0_DP<10> UPI0_RX_DN10 @S9S_MB_2U_LIB.S9S_MB_2U(SCH_1):UPI_CPU1_CPU0_P1P0_DP(10)
 AH6 UPI_CPU1_CPU0_P1P0_DN<9> UPI0_RX_DN9 @S9S_MB_2U_LIB.S9S_MB_2U(SCH_1):UPI_CPU1_CPU0_P1P0_DN(9)
 AF6 UPI_CPU1_CPU0_P1P0_DN<8> UPI0_RX_DN8 @S9S_MB_2U_LIB.S9S_MB_2U(SCH_1):UPI_CPU1_CPU0_P1P0_DN(8)
 AE5 UPI_CPU1_CPU0_P1P0_DN<7> UPI0_RX_DN7 @S9S_MB_2U_LIB.S9S_MB_2U(SCH_1):UPI_CPU1_CPU0_P1P0_DN(7)
 AB6 UPI_CPU1_CPU0_P1P0_DN<6> UPI0_RX_DN6 @S9S_MB_2U_LIB.S9S_MB_2U(SCH_1):UPI_CPU1_CPU0_P1P0_DN(6)
 AA5 UPI_CPU1_CPU0_P1P0_DP<5> UPI0_RX_DN5 @S9S_MB_2U_LIB.S9S_MB_2U(SCH_1):UPI_CPU1_CPU0_P1P0_DP(5)
  V6 UPI_CPU1_CPU0_P1P0_DN<4> UPI0_RX_DN4 @S9S_MB_2U_LIB.S9S_MB_2U(SCH_1):UPI_CPU1_CPU0_P1P0_DN(4)
  U5 UPI_CPU1_CPU0_P1P0_DP<3> UPI0_RX_DN3 @S9S_MB_2U_LIB.S9S_MB_2U(SCH_1):UPI_CPU1_CPU0_P1P0_DP(3)
  P6 UPI_CPU1_CPU0_P1P0_DN<2> UPI0_RX_DN2 @S9S_MB_2U_LIB.S9S_MB_2U(SCH_1):UPI_CPU1_CPU0_P1P0_DN(2)
  N5 UPI_CPU1_CPU0_P1P0_DN<1> UPI0_RX_DN1 @S9S_MB_2U_LIB.S9S_MB_2U(SCH_1):UPI_CPU1_CPU0_P1P0_DN(1)
  K6 UPI_CPU1_CPU0_P1P0_DN<0> UPI0_RX_DN0 @S9S_MB_2U_LIB.S9S_MB_2U(SCH_1):UPI_CPU1_CPU0_P1P0_DN(0)
 BT6 UPI_CPU1_CPU0_P1P0_DN<23> UPI0_RX_DP23 @S9S_MB_2U_LIB.S9S_MB_2U(SCH_1):UPI_CPU1_CPU0_P1P0_DN(23)
 BP6 UPI_CPU1_CPU0_P1P0_DP<22> UPI0_RX_DP22 @S9S_MB_2U_LIB.S9S_MB_2U(SCH_1):UPI_CPU1_CPU0_P1P0_DP(22)
 BM6 UPI_CPU1_CPU0_P1P0_DN<21> UPI0_RX_DP21 @S9S_MB_2U_LIB.S9S_MB_2U(SCH_1):UPI_CPU1_CPU0_P1P0_DN(21)
 BL7 UPI_CPU1_CPU0_P1P0_DN<20> UPI0_RX_DP20 @S9S_MB_2U_LIB.S9S_MB_2U(SCH_1):UPI_CPU1_CPU0_P1P0_DN(20)
 BH6 UPI_CPU1_CPU0_P1P0_DN<19> UPI0_RX_DP19 @S9S_MB_2U_LIB.S9S_MB_2U(SCH_1):UPI_CPU1_CPU0_P1P0_DN(19)
 BG7 UPI_CPU1_CPU0_P1P0_DN<18> UPI0_RX_DP18 @S9S_MB_2U_LIB.S9S_MB_2U(SCH_1):UPI_CPU1_CPU0_P1P0_DN(18)
 BD6 UPI_CPU1_CPU0_P1P0_DN<17> UPI0_RX_DP17 @S9S_MB_2U_LIB.S9S_MB_2U(SCH_1):UPI_CPU1_CPU0_P1P0_DN(17)
 BC7 UPI_CPU1_CPU0_P1P0_DN<16> UPI0_RX_DP16 @S9S_MB_2U_LIB.S9S_MB_2U(SCH_1):UPI_CPU1_CPU0_P1P0_DN(16)
 AY6 UPI_CPU1_CPU0_P1P0_DN<15> UPI0_RX_DP15 @S9S_MB_2U_LIB.S9S_MB_2U(SCH_1):UPI_CPU1_CPU0_P1P0_DN(15)
 AW7 UPI_CPU1_CPU0_P1P0_DN<14> UPI0_RX_DP14 @S9S_MB_2U_LIB.S9S_MB_2U(SCH_1):UPI_CPU1_CPU0_P1P0_DN(14)
 AT6 UPI_CPU1_CPU0_P1P0_DN<13> UPI0_RX_DP13 @S9S_MB_2U_LIB.S9S_MB_2U(SCH_1):UPI_CPU1_CPU0_P1P0_DN(13)
 AR7 UPI_CPU1_CPU0_P1P0_DN<12> UPI0_RX_DP12 @S9S_MB_2U_LIB.S9S_MB_2U(SCH_1):UPI_CPU1_CPU0_P1P0_DN(12)
 AM6 UPI_CPU1_CPU0_P1P0_DN<11> UPI0_RX_DP11 @S9S_MB_2U_LIB.S9S_MB_2U(SCH_1):UPI_CPU1_CPU0_P1P0_DN(11)
 AL7 UPI_CPU1_CPU0_P1P0_DN<10> UPI0_RX_DP10 @S9S_MB_2U_LIB.S9S_MB_2U(SCH_1):UPI_CPU1_CPU0_P1P0_DN(10)
 AJ5 UPI_CPU1_CPU0_P1P0_DP<9> UPI0_RX_DP9 @S9S_MB_2U_LIB.S9S_MB_2U(SCH_1):UPI_CPU1_CPU0_P1P0_DP(9)
 AG7 UPI_CPU1_CPU0_P1P0_DP<8> UPI0_RX_DP8 @S9S_MB_2U_LIB.S9S_MB_2U(SCH_1):UPI_CPU1_CPU0_P1P0_DP(8)
 AD6 UPI_CPU1_CPU0_P1P0_DP<7> UPI0_RX_DP7 @S9S_MB_2U_LIB.S9S_MB_2U(SCH_1):UPI_CPU1_CPU0_P1P0_DP(7)
 AC7 UPI_CPU1_CPU0_P1P0_DP<6> UPI0_RX_DP6 @S9S_MB_2U_LIB.S9S_MB_2U(SCH_1):UPI_CPU1_CPU0_P1P0_DP(6)
  Y6 UPI_CPU1_CPU0_P1P0_DN<5> UPI0_RX_DP5 @S9S_MB_2U_LIB.S9S_MB_2U(SCH_1):UPI_CPU1_CPU0_P1P0_DN(5)
  W7 UPI_CPU1_CPU0_P1P0_DP<4> UPI0_RX_DP4 @S9S_MB_2U_LIB.S9S_MB_2U(SCH_1):UPI_CPU1_CPU0_P1P0_DP(4)
  T6 UPI_CPU1_CPU0_P1P0_DN<3> UPI0_RX_DP3 @S9S_MB_2U_LIB.S9S_MB_2U(SCH_1):UPI_CPU1_CPU0_P1P0_DN(3)
  R7 UPI_CPU1_CPU0_P1P0_DP<2> UPI0_RX_DP2 @S9S_MB_2U_LIB.S9S_MB_2U(SCH_1):UPI_CPU1_CPU0_P1P0_DP(2)
  M6 UPI_CPU1_CPU0_P1P0_DP<1> UPI0_RX_DP1 @S9S_MB_2U_LIB.S9S_MB_2U(SCH_1):UPI_CPU1_CPU0_P1P0_DP(1)
  L7 UPI_CPU1_CPU0_P1P0_DP<0> UPI0_RX_DP0 @S9S_MB_2U_LIB.S9S_MB_2U(SCH_1):UPI_CPU1_CPU0_P1P0_DP(0)
 BT2 UPI_CPU0_CPU1_P0P1_DN<23> UPI0_TX_DN23 @S9S_MB_2U_LIB.S9S_MB_2U(SCH_1):UPI_CPU0_CPU1_P0P1_DN(23)
 BR3 UPI_CPU0_CPU1_P0P1_DP<22> UPI0_TX_DN22 @S9S_MB_2U_LIB.S9S_MB_2U(SCH_1):UPI_CPU0_CPU1_P0P1_DP(22)
 BM2 UPI_CPU0_CPU1_P0P1_DP<21> UPI0_TX_DN21 @S9S_MB_2U_LIB.S9S_MB_2U(SCH_1):UPI_CPU0_CPU1_P0P1_DP(21)
 BK2 UPI_CPU0_CPU1_P0P1_DP<20> UPI0_TX_DN20 @S9S_MB_2U_LIB.S9S_MB_2U(SCH_1):UPI_CPU0_CPU1_P0P1_DP(20)
 BH2 UPI_CPU0_CPU1_P0P1_DN<19> UPI0_TX_DN19 @S9S_MB_2U_LIB.S9S_MB_2U(SCH_1):UPI_CPU0_CPU1_P0P1_DN(19)
 BF2 UPI_CPU0_CPU1_P0P1_DN<18> UPI0_TX_DN18 @S9S_MB_2U_LIB.S9S_MB_2U(SCH_1):UPI_CPU0_CPU1_P0P1_DN(18)
 BD2 UPI_CPU0_CPU1_P0P1_DN<17> UPI0_TX_DN17 @S9S_MB_2U_LIB.S9S_MB_2U(SCH_1):UPI_CPU0_CPU1_P0P1_DN(17)
 BB2 UPI_CPU0_CPU1_P0P1_DN<16> UPI0_TX_DN16 @S9S_MB_2U_LIB.S9S_MB_2U(SCH_1):UPI_CPU0_CPU1_P0P1_DN(16)
 AY2 UPI_CPU0_CPU1_P0P1_DP<15> UPI0_TX_DN15 @S9S_MB_2U_LIB.S9S_MB_2U(SCH_1):UPI_CPU0_CPU1_P0P1_DP(15)
 AU1 UPI_CPU0_CPU1_P0P1_DN<14> UPI0_TX_DN14 @S9S_MB_2U_LIB.S9S_MB_2U(SCH_1):UPI_CPU0_CPU1_P0P1_DN(14)
 AT2 UPI_CPU0_CPU1_P0P1_DP<13> UPI0_TX_DN13 @S9S_MB_2U_LIB.S9S_MB_2U(SCH_1):UPI_CPU0_CPU1_P0P1_DP(13)
 AP2 UPI_CPU0_CPU1_P0P1_DP<12> UPI0_TX_DN12 @S9S_MB_2U_LIB.S9S_MB_2U(SCH_1):UPI_CPU0_CPU1_P0P1_DP(12)
 AM2 UPI_CPU0_CPU1_P0P1_DN<11> UPI0_TX_DN11 @S9S_MB_2U_LIB.S9S_MB_2U(SCH_1):UPI_CPU0_CPU1_P0P1_DN(11)
 AK2 UPI_CPU0_CPU1_P0P1_DN<10> UPI0_TX_DN10 @S9S_MB_2U_LIB.S9S_MB_2U(SCH_1):UPI_CPU0_CPU1_P0P1_DN(10)
 AH2 UPI_CPU0_CPU1_P0P1_DN<9> UPI0_TX_DN9 @S9S_MB_2U_LIB.S9S_MB_2U(SCH_1):UPI_CPU0_CPU1_P0P1_DN(9)
 AF2 UPI_CPU0_CPU1_P0P1_DN<8> UPI0_TX_DN8 @S9S_MB_2U_LIB.S9S_MB_2U(SCH_1):UPI_CPU0_CPU1_P0P1_DN(8)
 AD2 UPI_CPU0_CPU1_P0P1_DN<7> UPI0_TX_DN7 @S9S_MB_2U_LIB.S9S_MB_2U(SCH_1):UPI_CPU0_CPU1_P0P1_DN(7)
 AA1 UPI_CPU0_CPU1_P0P1_DN<6> UPI0_TX_DN6 @S9S_MB_2U_LIB.S9S_MB_2U(SCH_1):UPI_CPU0_CPU1_P0P1_DN(6)
  Y2 UPI_CPU0_CPU1_P0P1_DN<5> UPI0_TX_DN5 @S9S_MB_2U_LIB.S9S_MB_2U(SCH_1):UPI_CPU0_CPU1_P0P1_DN(5)
  U1 UPI_CPU0_CPU1_P0P1_DN<4> UPI0_TX_DN4 @S9S_MB_2U_LIB.S9S_MB_2U(SCH_1):UPI_CPU0_CPU1_P0P1_DN(4)
  T2 UPI_CPU0_CPU1_P0P1_DN<3> UPI0_TX_DN3 @S9S_MB_2U_LIB.S9S_MB_2U(SCH_1):UPI_CPU0_CPU1_P0P1_DN(3)
  N1 UPI_CPU0_CPU1_P0P1_DN<2> UPI0_TX_DN2 @S9S_MB_2U_LIB.S9S_MB_2U(SCH_1):UPI_CPU0_CPU1_P0P1_DN(2)
  M2 UPI_CPU0_CPU1_P0P1_DN<1> UPI0_TX_DN1 @S9S_MB_2U_LIB.S9S_MB_2U(SCH_1):UPI_CPU0_CPU1_P0P1_DN(1)
  K4 UPI_CPU0_CPU1_P0P1_DN<0> UPI0_TX_DN0 @S9S_MB_2U_LIB.S9S_MB_2U(SCH_1):UPI_CPU0_CPU1_P0P1_DN(0)
 BU3 UPI_CPU0_CPU1_P0P1_DP<23> UPI0_TX_DP23 @S9S_MB_2U_LIB.S9S_MB_2U(SCH_1):UPI_CPU0_CPU1_P0P1_DP(23)
 BN3 UPI_CPU0_CPU1_P0P1_DN<22> UPI0_TX_DP22 @S9S_MB_2U_LIB.S9S_MB_2U(SCH_1):UPI_CPU0_CPU1_P0P1_DN(22)
 BL3 UPI_CPU0_CPU1_P0P1_DN<21> UPI0_TX_DP21 @S9S_MB_2U_LIB.S9S_MB_2U(SCH_1):UPI_CPU0_CPU1_P0P1_DN(21)
 BJ1 UPI_CPU0_CPU1_P0P1_DN<20> UPI0_TX_DP20 @S9S_MB_2U_LIB.S9S_MB_2U(SCH_1):UPI_CPU0_CPU1_P0P1_DN(20)
 BG3 UPI_CPU0_CPU1_P0P1_DP<19> UPI0_TX_DP19 @S9S_MB_2U_LIB.S9S_MB_2U(SCH_1):UPI_CPU0_CPU1_P0P1_DP(19)
 BE1 UPI_CPU0_CPU1_P0P1_DP<18> UPI0_TX_DP18 @S9S_MB_2U_LIB.S9S_MB_2U(SCH_1):UPI_CPU0_CPU1_P0P1_DP(18)
 BC3 UPI_CPU0_CPU1_P0P1_DP<17> UPI0_TX_DP17 @S9S_MB_2U_LIB.S9S_MB_2U(SCH_1):UPI_CPU0_CPU1_P0P1_DP(17)
 BA1 UPI_CPU0_CPU1_P0P1_DP<16> UPI0_TX_DP16 @S9S_MB_2U_LIB.S9S_MB_2U(SCH_1):UPI_CPU0_CPU1_P0P1_DP(16)
 AW3 UPI_CPU0_CPU1_P0P1_DN<15> UPI0_TX_DP15 @S9S_MB_2U_LIB.S9S_MB_2U(SCH_1):UPI_CPU0_CPU1_P0P1_DN(15)
 AV2 UPI_CPU0_CPU1_P0P1_DP<14> UPI0_TX_DP14 @S9S_MB_2U_LIB.S9S_MB_2U(SCH_1):UPI_CPU0_CPU1_P0P1_DP(14)
 AR3 UPI_CPU0_CPU1_P0P1_DN<13> UPI0_TX_DP13 @S9S_MB_2U_LIB.S9S_MB_2U(SCH_1):UPI_CPU0_CPU1_P0P1_DN(13)
 AN1 UPI_CPU0_CPU1_P0P1_DN<12> UPI0_TX_DP12 @S9S_MB_2U_LIB.S9S_MB_2U(SCH_1):UPI_CPU0_CPU1_P0P1_DN(12)
 AL3 UPI_CPU0_CPU1_P0P1_DP<11> UPI0_TX_DP11 @S9S_MB_2U_LIB.S9S_MB_2U(SCH_1):UPI_CPU0_CPU1_P0P1_DP(11)
 AJ1 UPI_CPU0_CPU1_P0P1_DP<10> UPI0_TX_DP10 @S9S_MB_2U_LIB.S9S_MB_2U(SCH_1):UPI_CPU0_CPU1_P0P1_DP(10)
 AG3 UPI_CPU0_CPU1_P0P1_DP<9> UPI0_TX_DP9 @S9S_MB_2U_LIB.S9S_MB_2U(SCH_1):UPI_CPU0_CPU1_P0P1_DP(9)
 AE1 UPI_CPU0_CPU1_P0P1_DP<8> UPI0_TX_DP8 @S9S_MB_2U_LIB.S9S_MB_2U(SCH_1):UPI_CPU0_CPU1_P0P1_DP(8)
 AC3 UPI_CPU0_CPU1_P0P1_DP<7> UPI0_TX_DP7 @S9S_MB_2U_LIB.S9S_MB_2U(SCH_1):UPI_CPU0_CPU1_P0P1_DP(7)
 AB2 UPI_CPU0_CPU1_P0P1_DP<6> UPI0_TX_DP6 @S9S_MB_2U_LIB.S9S_MB_2U(SCH_1):UPI_CPU0_CPU1_P0P1_DP(6)
  W3 UPI_CPU0_CPU1_P0P1_DP<5> UPI0_TX_DP5 @S9S_MB_2U_LIB.S9S_MB_2U(SCH_1):UPI_CPU0_CPU1_P0P1_DP(5)
  V2 UPI_CPU0_CPU1_P0P1_DP<4> UPI0_TX_DP4 @S9S_MB_2U_LIB.S9S_MB_2U(SCH_1):UPI_CPU0_CPU1_P0P1_DP(4)
  R3 UPI_CPU0_CPU1_P0P1_DP<3> UPI0_TX_DP3 @S9S_MB_2U_LIB.S9S_MB_2U(SCH_1):UPI_CPU0_CPU1_P0P1_DP(3)
  P2 UPI_CPU0_CPU1_P0P1_DP<2> UPI0_TX_DP2 @S9S_MB_2U_LIB.S9S_MB_2U(SCH_1):UPI_CPU0_CPU1_P0P1_DP(2)
  L3 UPI_CPU0_CPU1_P0P1_DP<1> UPI0_TX_DP1 @S9S_MB_2U_LIB.S9S_MB_2U(SCH_1):UPI_CPU0_CPU1_P0P1_DP(1)
  J3 UPI_CPU0_CPU1_P0P1_DP<0> UPI0_TX_DP0 @S9S_MB_2U_LIB.S9S_MB_2U(SCH_1):UPI_CPU0_CPU1_P0P1_DP(0)


DRAWING: @S9S_MB_2U_LIB.S9S_MB_2U(SCH_1):PAGE33 

SOCKET4677_AZIF0045P001C01CS-SA  I102  U2
 CB2 UPI_CPU1_CPU0_P0P1_DP<23> UPI1_RX_DN23 @S9S_MB_2U_LIB.S9S_MB_2U(SCH_1):UPI_CPU1_CPU0_P0P1_DP(23)
 CD2 UPI_CPU1_CPU0_P0P1_DP<22> UPI1_RX_DN22 @S9S_MB_2U_LIB.S9S_MB_2U(SCH_1):UPI_CPU1_CPU0_P0P1_DP(22)
 CF2 UPI_CPU1_CPU0_P0P1_DN<21> UPI1_RX_DN21 @S9S_MB_2U_LIB.S9S_MB_2U(SCH_1):UPI_CPU1_CPU0_P0P1_DN(21)
 CH2 UPI_CPU1_CPU0_P0P1_DP<20> UPI1_RX_DN20 @S9S_MB_2U_LIB.S9S_MB_2U(SCH_1):UPI_CPU1_CPU0_P0P1_DP(20)
 CJ1 UPI_CPU1_CPU0_P0P1_DP<19> UPI1_RX_DN19 @S9S_MB_2U_LIB.S9S_MB_2U(SCH_1):UPI_CPU1_CPU0_P0P1_DP(19)
 CL3 UPI_CPU1_CPU0_P0P1_DN<18> UPI1_RX_DN18 @S9S_MB_2U_LIB.S9S_MB_2U(SCH_1):UPI_CPU1_CPU0_P0P1_DN(18)
 CN1 UPI_CPU1_CPU0_P0P1_DP<17> UPI1_RX_DN17 @S9S_MB_2U_LIB.S9S_MB_2U(SCH_1):UPI_CPU1_CPU0_P0P1_DP(17)
 CR3 UPI_CPU1_CPU0_P0P1_DN<16> UPI1_RX_DN16 @S9S_MB_2U_LIB.S9S_MB_2U(SCH_1):UPI_CPU1_CPU0_P0P1_DN(16)
 CV2 UPI_CPU1_CPU0_P0P1_DN<15> UPI1_RX_DN15 @S9S_MB_2U_LIB.S9S_MB_2U(SCH_1):UPI_CPU1_CPU0_P0P1_DN(15)
 CY2 UPI_CPU1_CPU0_P0P1_DN<14> UPI1_RX_DN14 @S9S_MB_2U_LIB.S9S_MB_2U(SCH_1):UPI_CPU1_CPU0_P0P1_DN(14)
 DB2 UPI_CPU1_CPU0_P0P1_DN<13> UPI1_RX_DN13 @S9S_MB_2U_LIB.S9S_MB_2U(SCH_1):UPI_CPU1_CPU0_P0P1_DN(13)
 DD2 UPI_CPU1_CPU0_P0P1_DP<12> UPI1_RX_DN12 @S9S_MB_2U_LIB.S9S_MB_2U(SCH_1):UPI_CPU1_CPU0_P0P1_DP(12)
 DE1 UPI_CPU1_CPU0_P0P1_DN<11> UPI1_RX_DN11 @S9S_MB_2U_LIB.S9S_MB_2U(SCH_1):UPI_CPU1_CPU0_P0P1_DN(11)
 DG3 UPI_CPU1_CPU0_P0P1_DN<10> UPI1_RX_DN10 @S9S_MB_2U_LIB.S9S_MB_2U(SCH_1):UPI_CPU1_CPU0_P0P1_DN(10)
 DJ1 UPI_CPU1_CPU0_P0P1_DN<9> UPI1_RX_DN9 @S9S_MB_2U_LIB.S9S_MB_2U(SCH_1):UPI_CPU1_CPU0_P0P1_DN(9)
 DL3 UPI_CPU1_CPU0_P0P1_DN<8> UPI1_RX_DN8 @S9S_MB_2U_LIB.S9S_MB_2U(SCH_1):UPI_CPU1_CPU0_P0P1_DN(8)
 DN1 UPI_CPU1_CPU0_P0P1_DN<7> UPI1_RX_DN7 @S9S_MB_2U_LIB.S9S_MB_2U(SCH_1):UPI_CPU1_CPU0_P0P1_DN(7)
 DT2 UPI_CPU1_CPU0_P0P1_DN<6> UPI1_RX_DN6 @S9S_MB_2U_LIB.S9S_MB_2U(SCH_1):UPI_CPU1_CPU0_P0P1_DN(6)
 DU1 UPI_CPU1_CPU0_P0P1_DN<5> UPI1_RX_DN5 @S9S_MB_2U_LIB.S9S_MB_2U(SCH_1):UPI_CPU1_CPU0_P0P1_DN(5)
 DY2 UPI_CPU1_CPU0_P0P1_DN<4> UPI1_RX_DN4 @S9S_MB_2U_LIB.S9S_MB_2U(SCH_1):UPI_CPU1_CPU0_P0P1_DN(4)
 EA1 UPI_CPU1_CPU0_P0P1_DN<3> UPI1_RX_DN3 @S9S_MB_2U_LIB.S9S_MB_2U(SCH_1):UPI_CPU1_CPU0_P0P1_DN(3)
 ED2 UPI_CPU1_CPU0_P0P1_DP<2> UPI1_RX_DN2 @S9S_MB_2U_LIB.S9S_MB_2U(SCH_1):UPI_CPU1_CPU0_P0P1_DP(2)
 EE3 UPI_CPU1_CPU0_P0P1_DN<1> UPI1_RX_DN1 @S9S_MB_2U_LIB.S9S_MB_2U(SCH_1):UPI_CPU1_CPU0_P0P1_DN(1)
 EH2 UPI_CPU1_CPU0_P0P1_DN<0> UPI1_RX_DN0 @S9S_MB_2U_LIB.S9S_MB_2U(SCH_1):UPI_CPU1_CPU0_P0P1_DN(0)
 BY2 UPI_CPU1_CPU0_P0P1_DN<23> UPI1_RX_DP23 @S9S_MB_2U_LIB.S9S_MB_2U(SCH_1):UPI_CPU1_CPU0_P0P1_DN(23)
 CC3 UPI_CPU1_CPU0_P0P1_DN<22> UPI1_RX_DP22 @S9S_MB_2U_LIB.S9S_MB_2U(SCH_1):UPI_CPU1_CPU0_P0P1_DN(22)
 CE1 UPI_CPU1_CPU0_P0P1_DP<21> UPI1_RX_DP21 @S9S_MB_2U_LIB.S9S_MB_2U(SCH_1):UPI_CPU1_CPU0_P0P1_DP(21)
 CG3 UPI_CPU1_CPU0_P0P1_DN<20> UPI1_RX_DP20 @S9S_MB_2U_LIB.S9S_MB_2U(SCH_1):UPI_CPU1_CPU0_P0P1_DN(20)
 CK2 UPI_CPU1_CPU0_P0P1_DN<19> UPI1_RX_DP19 @S9S_MB_2U_LIB.S9S_MB_2U(SCH_1):UPI_CPU1_CPU0_P0P1_DN(19)
 CM2 UPI_CPU1_CPU0_P0P1_DP<18> UPI1_RX_DP18 @S9S_MB_2U_LIB.S9S_MB_2U(SCH_1):UPI_CPU1_CPU0_P0P1_DP(18)
 CP2 UPI_CPU1_CPU0_P0P1_DN<17> UPI1_RX_DP17 @S9S_MB_2U_LIB.S9S_MB_2U(SCH_1):UPI_CPU1_CPU0_P0P1_DN(17)
 CT2 UPI_CPU1_CPU0_P0P1_DP<16> UPI1_RX_DP16 @S9S_MB_2U_LIB.S9S_MB_2U(SCH_1):UPI_CPU1_CPU0_P0P1_DP(16)
 CU1 UPI_CPU1_CPU0_P0P1_DP<15> UPI1_RX_DP15 @S9S_MB_2U_LIB.S9S_MB_2U(SCH_1):UPI_CPU1_CPU0_P0P1_DP(15)
 CW3 UPI_CPU1_CPU0_P0P1_DP<14> UPI1_RX_DP14 @S9S_MB_2U_LIB.S9S_MB_2U(SCH_1):UPI_CPU1_CPU0_P0P1_DP(14)
 DA1 UPI_CPU1_CPU0_P0P1_DP<13> UPI1_RX_DP13 @S9S_MB_2U_LIB.S9S_MB_2U(SCH_1):UPI_CPU1_CPU0_P0P1_DP(13)
 DC3 UPI_CPU1_CPU0_P0P1_DN<12> UPI1_RX_DP12 @S9S_MB_2U_LIB.S9S_MB_2U(SCH_1):UPI_CPU1_CPU0_P0P1_DN(12)
 DF2 UPI_CPU1_CPU0_P0P1_DP<11> UPI1_RX_DP11 @S9S_MB_2U_LIB.S9S_MB_2U(SCH_1):UPI_CPU1_CPU0_P0P1_DP(11)
 DH2 UPI_CPU1_CPU0_P0P1_DP<10> UPI1_RX_DP10 @S9S_MB_2U_LIB.S9S_MB_2U(SCH_1):UPI_CPU1_CPU0_P0P1_DP(10)
 DK2 UPI_CPU1_CPU0_P0P1_DP<9> UPI1_RX_DP9 @S9S_MB_2U_LIB.S9S_MB_2U(SCH_1):UPI_CPU1_CPU0_P0P1_DP(9)
 DM2 UPI_CPU1_CPU0_P0P1_DP<8> UPI1_RX_DP8 @S9S_MB_2U_LIB.S9S_MB_2U(SCH_1):UPI_CPU1_CPU0_P0P1_DP(8)
 DP2 UPI_CPU1_CPU0_P0P1_DP<7> UPI1_RX_DP7 @S9S_MB_2U_LIB.S9S_MB_2U(SCH_1):UPI_CPU1_CPU0_P0P1_DP(7)
 DR3 UPI_CPU1_CPU0_P0P1_DP<6> UPI1_RX_DP6 @S9S_MB_2U_LIB.S9S_MB_2U(SCH_1):UPI_CPU1_CPU0_P0P1_DP(6)
 DV2 UPI_CPU1_CPU0_P0P1_DP<5> UPI1_RX_DP5 @S9S_MB_2U_LIB.S9S_MB_2U(SCH_1):UPI_CPU1_CPU0_P0P1_DP(5)
 DW3 UPI_CPU1_CPU0_P0P1_DP<4> UPI1_RX_DP4 @S9S_MB_2U_LIB.S9S_MB_2U(SCH_1):UPI_CPU1_CPU0_P0P1_DP(4)
 EB2 UPI_CPU1_CPU0_P0P1_DP<3> UPI1_RX_DP3 @S9S_MB_2U_LIB.S9S_MB_2U(SCH_1):UPI_CPU1_CPU0_P0P1_DP(3)
 EC3 UPI_CPU1_CPU0_P0P1_DN<2> UPI1_RX_DP2 @S9S_MB_2U_LIB.S9S_MB_2U(SCH_1):UPI_CPU1_CPU0_P0P1_DN(2)
 EG3 UPI_CPU1_CPU0_P0P1_DP<1> UPI1_RX_DP1 @S9S_MB_2U_LIB.S9S_MB_2U(SCH_1):UPI_CPU1_CPU0_P0P1_DP(1)
 EJ3 UPI_CPU1_CPU0_P0P1_DP<0> UPI1_RX_DP0 @S9S_MB_2U_LIB.S9S_MB_2U(SCH_1):UPI_CPU1_CPU0_P0P1_DP(0)
 BY6 UPI_CPU0_CPU1_P1P0_DP<23> UPI1_TX_DN23 @S9S_MB_2U_LIB.S9S_MB_2U(SCH_1):UPI_CPU0_CPU1_P1P0_DP(23)
 CA5 UPI_CPU0_CPU1_P1P0_DN<22> UPI1_TX_DN22 @S9S_MB_2U_LIB.S9S_MB_2U(SCH_1):UPI_CPU0_CPU1_P1P0_DN(22)
 CD6 UPI_CPU0_CPU1_P1P0_DP<21> UPI1_TX_DN21 @S9S_MB_2U_LIB.S9S_MB_2U(SCH_1):UPI_CPU0_CPU1_P1P0_DP(21)
 CE5 UPI_CPU0_CPU1_P1P0_DP<20> UPI1_TX_DN20 @S9S_MB_2U_LIB.S9S_MB_2U(SCH_1):UPI_CPU0_CPU1_P1P0_DP(20)
 CH6 UPI_CPU0_CPU1_P1P0_DP<19> UPI1_TX_DN19 @S9S_MB_2U_LIB.S9S_MB_2U(SCH_1):UPI_CPU0_CPU1_P1P0_DP(19)
 CJ5 UPI_CPU0_CPU1_P1P0_DP<18> UPI1_TX_DN18 @S9S_MB_2U_LIB.S9S_MB_2U(SCH_1):UPI_CPU0_CPU1_P1P0_DP(18)
 CM6 UPI_CPU0_CPU1_P1P0_DP<17> UPI1_TX_DN17 @S9S_MB_2U_LIB.S9S_MB_2U(SCH_1):UPI_CPU0_CPU1_P1P0_DP(17)
 CN5 UPI_CPU0_CPU1_P1P0_DP<16> UPI1_TX_DN16 @S9S_MB_2U_LIB.S9S_MB_2U(SCH_1):UPI_CPU0_CPU1_P1P0_DP(16)
 CT6 UPI_CPU0_CPU1_P1P0_DP<15> UPI1_TX_DN15 @S9S_MB_2U_LIB.S9S_MB_2U(SCH_1):UPI_CPU0_CPU1_P1P0_DP(15)
 CU5 UPI_CPU0_CPU1_P1P0_DP<14> UPI1_TX_DN14 @S9S_MB_2U_LIB.S9S_MB_2U(SCH_1):UPI_CPU0_CPU1_P1P0_DP(14)
 CY6 UPI_CPU0_CPU1_P1P0_DP<13> UPI1_TX_DN13 @S9S_MB_2U_LIB.S9S_MB_2U(SCH_1):UPI_CPU0_CPU1_P1P0_DP(13)
 DA5 UPI_CPU0_CPU1_P1P0_DP<12> UPI1_TX_DN12 @S9S_MB_2U_LIB.S9S_MB_2U(SCH_1):UPI_CPU0_CPU1_P1P0_DP(12)
 DD6 UPI_CPU0_CPU1_P1P0_DP<11> UPI1_TX_DN11 @S9S_MB_2U_LIB.S9S_MB_2U(SCH_1):UPI_CPU0_CPU1_P1P0_DP(11)
 DE5 UPI_CPU0_CPU1_P1P0_DP<10> UPI1_TX_DN10 @S9S_MB_2U_LIB.S9S_MB_2U(SCH_1):UPI_CPU0_CPU1_P1P0_DP(10)
 DH6 UPI_CPU0_CPU1_P1P0_DN<9> UPI1_TX_DN9 @S9S_MB_2U_LIB.S9S_MB_2U(SCH_1):UPI_CPU0_CPU1_P1P0_DN(9)
 DK6 UPI_CPU0_CPU1_P1P0_DN<8> UPI1_TX_DN8 @S9S_MB_2U_LIB.S9S_MB_2U(SCH_1):UPI_CPU0_CPU1_P1P0_DN(8)
 DL7 UPI_CPU0_CPU1_P1P0_DN<7> UPI1_TX_DN7 @S9S_MB_2U_LIB.S9S_MB_2U(SCH_1):UPI_CPU0_CPU1_P1P0_DN(7)
 DP6 UPI_CPU0_CPU1_P1P0_DN<6> UPI1_TX_DN6 @S9S_MB_2U_LIB.S9S_MB_2U(SCH_1):UPI_CPU0_CPU1_P1P0_DN(6)
 DT6 UPI_CPU0_CPU1_P1P0_DP<5> UPI1_TX_DN5 @S9S_MB_2U_LIB.S9S_MB_2U(SCH_1):UPI_CPU0_CPU1_P1P0_DP(5)
 DV6 UPI_CPU0_CPU1_P1P0_DN<4> UPI1_TX_DN4 @S9S_MB_2U_LIB.S9S_MB_2U(SCH_1):UPI_CPU0_CPU1_P1P0_DN(4)
 DY6 UPI_CPU0_CPU1_P1P0_DP<3> UPI1_TX_DN3 @S9S_MB_2U_LIB.S9S_MB_2U(SCH_1):UPI_CPU0_CPU1_P1P0_DP(3)
 EB6 UPI_CPU0_CPU1_P1P0_DN<2> UPI1_TX_DN2 @S9S_MB_2U_LIB.S9S_MB_2U(SCH_1):UPI_CPU0_CPU1_P1P0_DN(2)
 EC7 UPI_CPU0_CPU1_P1P0_DN<1> UPI1_TX_DN1 @S9S_MB_2U_LIB.S9S_MB_2U(SCH_1):UPI_CPU0_CPU1_P1P0_DN(1)
 EF6 UPI_CPU0_CPU1_P1P0_DN<0> UPI1_TX_DN0 @S9S_MB_2U_LIB.S9S_MB_2U(SCH_1):UPI_CPU0_CPU1_P1P0_DN(0)
 BW7 UPI_CPU0_CPU1_P1P0_DN<23> UPI1_TX_DP23 @S9S_MB_2U_LIB.S9S_MB_2U(SCH_1):UPI_CPU0_CPU1_P1P0_DN(23)
 CB6 UPI_CPU0_CPU1_P1P0_DP<22> UPI1_TX_DP22 @S9S_MB_2U_LIB.S9S_MB_2U(SCH_1):UPI_CPU0_CPU1_P1P0_DP(22)
 CC7 UPI_CPU0_CPU1_P1P0_DN<21> UPI1_TX_DP21 @S9S_MB_2U_LIB.S9S_MB_2U(SCH_1):UPI_CPU0_CPU1_P1P0_DN(21)
 CF6 UPI_CPU0_CPU1_P1P0_DN<20> UPI1_TX_DP20 @S9S_MB_2U_LIB.S9S_MB_2U(SCH_1):UPI_CPU0_CPU1_P1P0_DN(20)
 CG7 UPI_CPU0_CPU1_P1P0_DN<19> UPI1_TX_DP19 @S9S_MB_2U_LIB.S9S_MB_2U(SCH_1):UPI_CPU0_CPU1_P1P0_DN(19)
 CK6 UPI_CPU0_CPU1_P1P0_DN<18> UPI1_TX_DP18 @S9S_MB_2U_LIB.S9S_MB_2U(SCH_1):UPI_CPU0_CPU1_P1P0_DN(18)
 CL7 UPI_CPU0_CPU1_P1P0_DN<17> UPI1_TX_DP17 @S9S_MB_2U_LIB.S9S_MB_2U(SCH_1):UPI_CPU0_CPU1_P1P0_DN(17)
 CP6 UPI_CPU0_CPU1_P1P0_DN<16> UPI1_TX_DP16 @S9S_MB_2U_LIB.S9S_MB_2U(SCH_1):UPI_CPU0_CPU1_P1P0_DN(16)
 CR7 UPI_CPU0_CPU1_P1P0_DN<15> UPI1_TX_DP15 @S9S_MB_2U_LIB.S9S_MB_2U(SCH_1):UPI_CPU0_CPU1_P1P0_DN(15)
 CV6 UPI_CPU0_CPU1_P1P0_DN<14> UPI1_TX_DP14 @S9S_MB_2U_LIB.S9S_MB_2U(SCH_1):UPI_CPU0_CPU1_P1P0_DN(14)
 CW7 UPI_CPU0_CPU1_P1P0_DN<13> UPI1_TX_DP13 @S9S_MB_2U_LIB.S9S_MB_2U(SCH_1):UPI_CPU0_CPU1_P1P0_DN(13)
 DB6 UPI_CPU0_CPU1_P1P0_DN<12> UPI1_TX_DP12 @S9S_MB_2U_LIB.S9S_MB_2U(SCH_1):UPI_CPU0_CPU1_P1P0_DN(12)
 DC7 UPI_CPU0_CPU1_P1P0_DN<11> UPI1_TX_DP11 @S9S_MB_2U_LIB.S9S_MB_2U(SCH_1):UPI_CPU0_CPU1_P1P0_DN(11)
 DF6 UPI_CPU0_CPU1_P1P0_DN<10> UPI1_TX_DP10 @S9S_MB_2U_LIB.S9S_MB_2U(SCH_1):UPI_CPU0_CPU1_P1P0_DN(10)
 DG7 UPI_CPU0_CPU1_P1P0_DP<9> UPI1_TX_DP9 @S9S_MB_2U_LIB.S9S_MB_2U(SCH_1):UPI_CPU0_CPU1_P1P0_DP(9)
 DJ5 UPI_CPU0_CPU1_P1P0_DP<8> UPI1_TX_DP8 @S9S_MB_2U_LIB.S9S_MB_2U(SCH_1):UPI_CPU0_CPU1_P1P0_DP(8)
 DM6 UPI_CPU0_CPU1_P1P0_DP<7> UPI1_TX_DP7 @S9S_MB_2U_LIB.S9S_MB_2U(SCH_1):UPI_CPU0_CPU1_P1P0_DP(7)
 DN5 UPI_CPU0_CPU1_P1P0_DP<6> UPI1_TX_DP6 @S9S_MB_2U_LIB.S9S_MB_2U(SCH_1):UPI_CPU0_CPU1_P1P0_DP(6)
 DR7 UPI_CPU0_CPU1_P1P0_DN<5> UPI1_TX_DP5 @S9S_MB_2U_LIB.S9S_MB_2U(SCH_1):UPI_CPU0_CPU1_P1P0_DN(5)
 DU5 UPI_CPU0_CPU1_P1P0_DP<4> UPI1_TX_DP4 @S9S_MB_2U_LIB.S9S_MB_2U(SCH_1):UPI_CPU0_CPU1_P1P0_DP(4)
 DW7 UPI_CPU0_CPU1_P1P0_DN<3> UPI1_TX_DP3 @S9S_MB_2U_LIB.S9S_MB_2U(SCH_1):UPI_CPU0_CPU1_P1P0_DN(3)
 EA5 UPI_CPU0_CPU1_P1P0_DP<2> UPI1_TX_DP2 @S9S_MB_2U_LIB.S9S_MB_2U(SCH_1):UPI_CPU0_CPU1_P1P0_DP(2)
 ED6 UPI_CPU0_CPU1_P1P0_DP<1> UPI1_TX_DP1 @S9S_MB_2U_LIB.S9S_MB_2U(SCH_1):UPI_CPU0_CPU1_P1P0_DP(1)
 EE5 UPI_CPU0_CPU1_P1P0_DP<0> UPI1_TX_DP0 @S9S_MB_2U_LIB.S9S_MB_2U(SCH_1):UPI_CPU0_CPU1_P1P0_DP(0)


DRAWING: @S9S_MB_2U_LIB.S9S_MB_2U(SCH_1):PAGE34 

SOCKET4677_AZIF0045P001C01CS-SA  I102  U2
BD73 UPI_CPU1_CPU0_P2P2_DP<0> UPI2_RX_DN23 @S9S_MB_2U_LIB.S9S_MB_2U(SCH_1):UPI_CPU1_CPU0_P2P2_DP(0)
BK73 UPI_CPU1_CPU0_P2P2_DN<1> UPI2_RX_DN22 @S9S_MB_2U_LIB.S9S_MB_2U(SCH_1):UPI_CPU1_CPU0_P2P2_DN(1)
BN74 UPI_CPU1_CPU0_P2P2_DP<2> UPI2_RX_DN21 @S9S_MB_2U_LIB.S9S_MB_2U(SCH_1):UPI_CPU1_CPU0_P2P2_DP(2)
BG74 UPI_CPU1_CPU0_P2P2_DP<3> UPI2_RX_DN20 @S9S_MB_2U_LIB.S9S_MB_2U(SCH_1):UPI_CPU1_CPU0_P2P2_DP(3)
BL76 UPI_CPU1_CPU0_P2P2_DP<4> UPI2_RX_DN19 @S9S_MB_2U_LIB.S9S_MB_2U(SCH_1):UPI_CPU1_CPU0_P2P2_DP(4)
BJ76 UPI_CPU1_CPU0_P2P2_DN<5> UPI2_RX_DN18 @S9S_MB_2U_LIB.S9S_MB_2U(SCH_1):UPI_CPU1_CPU0_P2P2_DN(5)
BH75 UPI_CPU1_CPU0_P2P2_DN<6> UPI2_RX_DN17 @S9S_MB_2U_LIB.S9S_MB_2U(SCH_1):UPI_CPU1_CPU0_P2P2_DN(6)
AW74 UPI_CPU1_CPU0_P2P2_DP<7> UPI2_RX_DN16 @S9S_MB_2U_LIB.S9S_MB_2U(SCH_1):UPI_CPU1_CPU0_P2P2_DP(7)
BB75 UPI_CPU1_CPU0_P2P2_DP<8> UPI2_RX_DN15 @S9S_MB_2U_LIB.S9S_MB_2U(SCH_1):UPI_CPU1_CPU0_P2P2_DP(8)
AY75 UPI_CPU1_CPU0_P2P2_DN<9> UPI2_RX_DN14 @S9S_MB_2U_LIB.S9S_MB_2U(SCH_1):UPI_CPU1_CPU0_P2P2_DN(9)
AV73 UPI_CPU1_CPU0_P2P2_DN<10> UPI2_RX_DN13 @S9S_MB_2U_LIB.S9S_MB_2U(SCH_1):UPI_CPU1_CPU0_P2P2_DN(10)
BA72 UPI_CPU1_CPU0_P2P2_DP<11> UPI2_RX_DN12 @S9S_MB_2U_LIB.S9S_MB_2U(SCH_1):UPI_CPU1_CPU0_P2P2_DP(11)
AG82 UPI_CPU1_CPU0_P2P2_DP<12> UPI2_RX_DN11 @S9S_MB_2U_LIB.S9S_MB_2U(SCH_1):UPI_CPU1_CPU0_P2P2_DP(12)
AJ80 UPI_CPU1_CPU0_P2P2_DN<13> UPI2_RX_DN10 @S9S_MB_2U_LIB.S9S_MB_2U(SCH_1):UPI_CPU1_CPU0_P2P2_DN(13)
AE82 UPI_CPU1_CPU0_P2P2_DP<14> UPI2_RX_DN9 @S9S_MB_2U_LIB.S9S_MB_2U(SCH_1):UPI_CPU1_CPU0_P2P2_DP(14)
AF79 UPI_CPU1_CPU0_P2P2_DP<15> UPI2_RX_DN8 @S9S_MB_2U_LIB.S9S_MB_2U(SCH_1):UPI_CPU1_CPU0_P2P2_DP(15)
AD81 UPI_CPU1_CPU0_P2P2_DP<16> UPI2_RX_DN7 @S9S_MB_2U_LIB.S9S_MB_2U(SCH_1):UPI_CPU1_CPU0_P2P2_DP(16)
AC80 UPI_CPU1_CPU0_P2P2_DN<17> UPI2_RX_DN6 @S9S_MB_2U_LIB.S9S_MB_2U(SCH_1):UPI_CPU1_CPU0_P2P2_DN(17)
 L80 UPI_CPU1_CPU0_P2P2_DN<18> UPI2_RX_DN5 @S9S_MB_2U_LIB.S9S_MB_2U(SCH_1):UPI_CPU1_CPU0_P2P2_DN(18)
 J82 UPI_CPU1_CPU0_P2P2_DN<19> UPI2_RX_DN4 @S9S_MB_2U_LIB.S9S_MB_2U(SCH_1):UPI_CPU1_CPU0_P2P2_DN(19)
 K79 UPI_CPU1_CPU0_P2P2_DN<20> UPI2_RX_DN3 @S9S_MB_2U_LIB.S9S_MB_2U(SCH_1):UPI_CPU1_CPU0_P2P2_DN(20)
 G82 UPI_CPU1_CPU0_P2P2_DN<21> UPI2_RX_DN2 @S9S_MB_2U_LIB.S9S_MB_2U(SCH_1):UPI_CPU1_CPU0_P2P2_DN(21)
 F81 UPI_CPU1_CPU0_P2P2_DP<22> UPI2_RX_DN1 @S9S_MB_2U_LIB.S9S_MB_2U(SCH_1):UPI_CPU1_CPU0_P2P2_DP(22)
 E80 UPI_CPU1_CPU0_P2P2_DN<23> UPI2_RX_DN0 @S9S_MB_2U_LIB.S9S_MB_2U(SCH_1):UPI_CPU1_CPU0_P2P2_DN(23)
BC74 UPI_CPU1_CPU0_P2P2_DN<0> UPI2_RX_DP23 @S9S_MB_2U_LIB.S9S_MB_2U(SCH_1):UPI_CPU1_CPU0_P2P2_DN(0)
BL74 UPI_CPU1_CPU0_P2P2_DP<1> UPI2_RX_DP22 @S9S_MB_2U_LIB.S9S_MB_2U(SCH_1):UPI_CPU1_CPU0_P2P2_DP(1)
BM75 UPI_CPU1_CPU0_P2P2_DN<2> UPI2_RX_DP21 @S9S_MB_2U_LIB.S9S_MB_2U(SCH_1):UPI_CPU1_CPU0_P2P2_DN(2)
BJ74 UPI_CPU1_CPU0_P2P2_DN<3> UPI2_RX_DP20 @S9S_MB_2U_LIB.S9S_MB_2U(SCH_1):UPI_CPU1_CPU0_P2P2_DN(3)
BN76 UPI_CPU1_CPU0_P2P2_DN<4> UPI2_RX_DP19 @S9S_MB_2U_LIB.S9S_MB_2U(SCH_1):UPI_CPU1_CPU0_P2P2_DN(4)
BK77 UPI_CPU1_CPU0_P2P2_DP<5> UPI2_RX_DP18 @S9S_MB_2U_LIB.S9S_MB_2U(SCH_1):UPI_CPU1_CPU0_P2P2_DP(5)
BG76 UPI_CPU1_CPU0_P2P2_DP<6> UPI2_RX_DP17 @S9S_MB_2U_LIB.S9S_MB_2U(SCH_1):UPI_CPU1_CPU0_P2P2_DP(6)
AV75 UPI_CPU1_CPU0_P2P2_DN<7> UPI2_RX_DP16 @S9S_MB_2U_LIB.S9S_MB_2U(SCH_1):UPI_CPU1_CPU0_P2P2_DN(7)
BD75 UPI_CPU1_CPU0_P2P2_DN<8> UPI2_RX_DP15 @S9S_MB_2U_LIB.S9S_MB_2U(SCH_1):UPI_CPU1_CPU0_P2P2_DN(8)
BA76 UPI_CPU1_CPU0_P2P2_DP<9> UPI2_RX_DP14 @S9S_MB_2U_LIB.S9S_MB_2U(SCH_1):UPI_CPU1_CPU0_P2P2_DP(9)
AY73 UPI_CPU1_CPU0_P2P2_DP<10> UPI2_RX_DP13 @S9S_MB_2U_LIB.S9S_MB_2U(SCH_1):UPI_CPU1_CPU0_P2P2_DP(10)
BB73 UPI_CPU1_CPU0_P2P2_DN<11> UPI2_RX_DP12 @S9S_MB_2U_LIB.S9S_MB_2U(SCH_1):UPI_CPU1_CPU0_P2P2_DN(11)
AJ82 UPI_CPU1_CPU0_P2P2_DN<12> UPI2_RX_DP11 @S9S_MB_2U_LIB.S9S_MB_2U(SCH_1):UPI_CPU1_CPU0_P2P2_DN(12)
AH81 UPI_CPU1_CPU0_P2P2_DP<13> UPI2_RX_DP10 @S9S_MB_2U_LIB.S9S_MB_2U(SCH_1):UPI_CPU1_CPU0_P2P2_DP(13)
AF83 UPI_CPU1_CPU0_P2P2_DN<14> UPI2_RX_DP9 @S9S_MB_2U_LIB.S9S_MB_2U(SCH_1):UPI_CPU1_CPU0_P2P2_DN(14)
AG80 UPI_CPU1_CPU0_P2P2_DN<15> UPI2_RX_DP8 @S9S_MB_2U_LIB.S9S_MB_2U(SCH_1):UPI_CPU1_CPU0_P2P2_DN(15)
AC82 UPI_CPU1_CPU0_P2P2_DN<16> UPI2_RX_DP7 @S9S_MB_2U_LIB.S9S_MB_2U(SCH_1):UPI_CPU1_CPU0_P2P2_DN(16)
AE80 UPI_CPU1_CPU0_P2P2_DP<17> UPI2_RX_DP6 @S9S_MB_2U_LIB.S9S_MB_2U(SCH_1):UPI_CPU1_CPU0_P2P2_DP(17)
 K81 UPI_CPU1_CPU0_P2P2_DP<18> UPI2_RX_DP5 @S9S_MB_2U_LIB.S9S_MB_2U(SCH_1):UPI_CPU1_CPU0_P2P2_DP(18)
 L82 UPI_CPU1_CPU0_P2P2_DP<19> UPI2_RX_DP4 @S9S_MB_2U_LIB.S9S_MB_2U(SCH_1):UPI_CPU1_CPU0_P2P2_DP(19)
 M79 UPI_CPU1_CPU0_P2P2_DP<20> UPI2_RX_DP3 @S9S_MB_2U_LIB.S9S_MB_2U(SCH_1):UPI_CPU1_CPU0_P2P2_DP(20)
 H83 UPI_CPU1_CPU0_P2P2_DP<21> UPI2_RX_DP2 @S9S_MB_2U_LIB.S9S_MB_2U(SCH_1):UPI_CPU1_CPU0_P2P2_DP(21)
 E82 UPI_CPU1_CPU0_P2P2_DN<22> UPI2_RX_DP1 @S9S_MB_2U_LIB.S9S_MB_2U(SCH_1):UPI_CPU1_CPU0_P2P2_DN(22)
 G80 UPI_CPU1_CPU0_P2P2_DP<23> UPI2_RX_DP0 @S9S_MB_2U_LIB.S9S_MB_2U(SCH_1):UPI_CPU1_CPU0_P2P2_DP(23)
BM71 UPI_CPU0_CPU1_P2P2_DN<0> UPI2_TX_DN23 @S9S_MB_2U_LIB.S9S_MB_2U(SCH_1):UPI_CPU0_CPU1_P2P2_DN(0)
BG80 UPI_CPU0_CPU1_P2P2_DN<1> UPI2_TX_DN22 @S9S_MB_2U_LIB.S9S_MB_2U(SCH_1):UPI_CPU0_CPU1_P2P2_DN(1)
BF81 UPI_CPU0_CPU1_P2P2_DN<2> UPI2_TX_DN21 @S9S_MB_2U_LIB.S9S_MB_2U(SCH_1):UPI_CPU0_CPU1_P2P2_DN(2)
BD79 UPI_CPU0_CPU1_P2P2_DN<3> UPI2_TX_DN20 @S9S_MB_2U_LIB.S9S_MB_2U(SCH_1):UPI_CPU0_CPU1_P2P2_DN(3)
BE82 UPI_CPU0_CPU1_P2P2_DN<4> UPI2_TX_DN19 @S9S_MB_2U_LIB.S9S_MB_2U(SCH_1):UPI_CPU0_CPU1_P2P2_DN(4)
BC82 UPI_CPU0_CPU1_P2P2_DN<5> UPI2_TX_DN18 @S9S_MB_2U_LIB.S9S_MB_2U(SCH_1):UPI_CPU0_CPU1_P2P2_DN(5)
BA80 UPI_CPU0_CPU1_P2P2_DN<6> UPI2_TX_DN17 @S9S_MB_2U_LIB.S9S_MB_2U(SCH_1):UPI_CPU0_CPU1_P2P2_DN(6)
AV81 UPI_CPU0_CPU1_P2P2_DN<7> UPI2_TX_DN16 @S9S_MB_2U_LIB.S9S_MB_2U(SCH_1):UPI_CPU0_CPU1_P2P2_DN(7)
AT83 UPI_CPU0_CPU1_P2P2_DN<8> UPI2_TX_DN15 @S9S_MB_2U_LIB.S9S_MB_2U(SCH_1):UPI_CPU0_CPU1_P2P2_DN(8)
AR80 UPI_CPU0_CPU1_P2P2_DN<9> UPI2_TX_DN14 @S9S_MB_2U_LIB.S9S_MB_2U(SCH_1):UPI_CPU0_CPU1_P2P2_DN(9)
AN82 UPI_CPU0_CPU1_P2P2_DN<10> UPI2_TX_DN13 @S9S_MB_2U_LIB.S9S_MB_2U(SCH_1):UPI_CPU0_CPU1_P2P2_DN(10)
AM81 UPI_CPU0_CPU1_P2P2_DN<11> UPI2_TX_DN12 @S9S_MB_2U_LIB.S9S_MB_2U(SCH_1):UPI_CPU0_CPU1_P2P2_DN(11)
AU78 UPI_CPU0_CPU1_P2P2_DN<12> UPI2_TX_DN11 @S9S_MB_2U_LIB.S9S_MB_2U(SCH_1):UPI_CPU0_CPU1_P2P2_DN(12)
AW78 UPI_CPU0_CPU1_P2P2_DN<13> UPI2_TX_DN10 @S9S_MB_2U_LIB.S9S_MB_2U(SCH_1):UPI_CPU0_CPU1_P2P2_DN(13)
 Y81 UPI_CPU0_CPU1_P2P2_DN<14> UPI2_TX_DN9 @S9S_MB_2U_LIB.S9S_MB_2U(SCH_1):UPI_CPU0_CPU1_P2P2_DN(14)
 V83 UPI_CPU0_CPU1_P2P2_DN<15> UPI2_TX_DN8 @S9S_MB_2U_LIB.S9S_MB_2U(SCH_1):UPI_CPU0_CPU1_P2P2_DN(15)
 U80 UPI_CPU0_CPU1_P2P2_DN<16> UPI2_TX_DN7 @S9S_MB_2U_LIB.S9S_MB_2U(SCH_1):UPI_CPU0_CPU1_P2P2_DN(16)
 R82 UPI_CPU0_CPU1_P2P2_DN<17> UPI2_TX_DN6 @S9S_MB_2U_LIB.S9S_MB_2U(SCH_1):UPI_CPU0_CPU1_P2P2_DN(17)
 P81 UPI_CPU0_CPU1_P2P2_DN<18> UPI2_TX_DN5 @S9S_MB_2U_LIB.S9S_MB_2U(SCH_1):UPI_CPU0_CPU1_P2P2_DN(18)
 H85 UPI_CPU0_CPU1_P2P2_DN<19> UPI2_TX_DN4 @S9S_MB_2U_LIB.S9S_MB_2U(SCH_1):UPI_CPU0_CPU1_P2P2_DN(19)
 F87 UPI_CPU0_CPU1_P2P2_DN<20> UPI2_TX_DN3 @S9S_MB_2U_LIB.S9S_MB_2U(SCH_1):UPI_CPU0_CPU1_P2P2_DN(20)
 D87 UPI_CPU0_CPU1_P2P2_DN<21> UPI2_TX_DN2 @S9S_MB_2U_LIB.S9S_MB_2U(SCH_1):UPI_CPU0_CPU1_P2P2_DN(21)
 E84 UPI_CPU0_CPU1_P2P2_DN<22> UPI2_TX_DN1 @S9S_MB_2U_LIB.S9S_MB_2U(SCH_1):UPI_CPU0_CPU1_P2P2_DN(22)
 B85 UPI_CPU0_CPU1_P2P2_DN<23> UPI2_TX_DN0 @S9S_MB_2U_LIB.S9S_MB_2U(SCH_1):UPI_CPU0_CPU1_P2P2_DN(23)
BN72 UPI_CPU0_CPU1_P2P2_DP<0> UPI2_TX_DP23 @S9S_MB_2U_LIB.S9S_MB_2U(SCH_1):UPI_CPU0_CPU1_P2P2_DP(0)
BE80 UPI_CPU0_CPU1_P2P2_DP<1> UPI2_TX_DP22 @S9S_MB_2U_LIB.S9S_MB_2U(SCH_1):UPI_CPU0_CPU1_P2P2_DP(1)
BG82 UPI_CPU0_CPU1_P2P2_DP<2> UPI2_TX_DP21 @S9S_MB_2U_LIB.S9S_MB_2U(SCH_1):UPI_CPU0_CPU1_P2P2_DP(2)
BC80 UPI_CPU0_CPU1_P2P2_DP<3> UPI2_TX_DP20 @S9S_MB_2U_LIB.S9S_MB_2U(SCH_1):UPI_CPU0_CPU1_P2P2_DP(3)
BD83 UPI_CPU0_CPU1_P2P2_DP<4> UPI2_TX_DP19 @S9S_MB_2U_LIB.S9S_MB_2U(SCH_1):UPI_CPU0_CPU1_P2P2_DP(4)
BA82 UPI_CPU0_CPU1_P2P2_DP<5> UPI2_TX_DP18 @S9S_MB_2U_LIB.S9S_MB_2U(SCH_1):UPI_CPU0_CPU1_P2P2_DP(5)
BB81 UPI_CPU0_CPU1_P2P2_DP<6> UPI2_TX_DP17 @S9S_MB_2U_LIB.S9S_MB_2U(SCH_1):UPI_CPU0_CPU1_P2P2_DP(6)
AU82 UPI_CPU0_CPU1_P2P2_DP<7> UPI2_TX_DP16 @S9S_MB_2U_LIB.S9S_MB_2U(SCH_1):UPI_CPU0_CPU1_P2P2_DP(7)
AV83 UPI_CPU0_CPU1_P2P2_DP<8> UPI2_TX_DP15 @S9S_MB_2U_LIB.S9S_MB_2U(SCH_1):UPI_CPU0_CPU1_P2P2_DP(8)
AT81 UPI_CPU0_CPU1_P2P2_DP<9> UPI2_TX_DP14 @S9S_MB_2U_LIB.S9S_MB_2U(SCH_1):UPI_CPU0_CPU1_P2P2_DP(9)
AM83 UPI_CPU0_CPU1_P2P2_DP<10> UPI2_TX_DP13 @S9S_MB_2U_LIB.S9S_MB_2U(SCH_1):UPI_CPU0_CPU1_P2P2_DP(10)
AP81 UPI_CPU0_CPU1_P2P2_DP<11> UPI2_TX_DP12 @S9S_MB_2U_LIB.S9S_MB_2U(SCH_1):UPI_CPU0_CPU1_P2P2_DP(11)
AV79 UPI_CPU0_CPU1_P2P2_DP<12> UPI2_TX_DP11 @S9S_MB_2U_LIB.S9S_MB_2U(SCH_1):UPI_CPU0_CPU1_P2P2_DP(12)
BA78 UPI_CPU0_CPU1_P2P2_DP<13> UPI2_TX_DP10 @S9S_MB_2U_LIB.S9S_MB_2U(SCH_1):UPI_CPU0_CPU1_P2P2_DP(13)
 W82 UPI_CPU0_CPU1_P2P2_DP<14> UPI2_TX_DP9 @S9S_MB_2U_LIB.S9S_MB_2U(SCH_1):UPI_CPU0_CPU1_P2P2_DP(14)
 Y83 UPI_CPU0_CPU1_P2P2_DP<15> UPI2_TX_DP8 @S9S_MB_2U_LIB.S9S_MB_2U(SCH_1):UPI_CPU0_CPU1_P2P2_DP(15)
 V81 UPI_CPU0_CPU1_P2P2_DP<16> UPI2_TX_DP7 @S9S_MB_2U_LIB.S9S_MB_2U(SCH_1):UPI_CPU0_CPU1_P2P2_DP(16)
 P83 UPI_CPU0_CPU1_P2P2_DP<17> UPI2_TX_DP6 @S9S_MB_2U_LIB.S9S_MB_2U(SCH_1):UPI_CPU0_CPU1_P2P2_DP(17)
 T81 UPI_CPU0_CPU1_P2P2_DP<18> UPI2_TX_DP5 @S9S_MB_2U_LIB.S9S_MB_2U(SCH_1):UPI_CPU0_CPU1_P2P2_DP(18)
 G86 UPI_CPU0_CPU1_P2P2_DP<19> UPI2_TX_DP4 @S9S_MB_2U_LIB.S9S_MB_2U(SCH_1):UPI_CPU0_CPU1_P2P2_DP(19)
 H87 UPI_CPU0_CPU1_P2P2_DP<20> UPI2_TX_DP3 @S9S_MB_2U_LIB.S9S_MB_2U(SCH_1):UPI_CPU0_CPU1_P2P2_DP(20)
 E88 UPI_CPU0_CPU1_P2P2_DP<21> UPI2_TX_DP2 @S9S_MB_2U_LIB.S9S_MB_2U(SCH_1):UPI_CPU0_CPU1_P2P2_DP(21)
 F85 UPI_CPU0_CPU1_P2P2_DP<22> UPI2_TX_DP1 @S9S_MB_2U_LIB.S9S_MB_2U(SCH_1):UPI_CPU0_CPU1_P2P2_DP(22)
 D85 UPI_CPU0_CPU1_P2P2_DP<23> UPI2_TX_DP0 @S9S_MB_2U_LIB.S9S_MB_2U(SCH_1):UPI_CPU0_CPU1_P2P2_DP(23)


DRAWING: @S9S_MB_2U_LIB.S9S_MB_2U(SCH_1):PAGE35 

SOCKET4677_AZIF0045P001C01CS-SA  I102  U2
DA78    GND UPI3_RX_DN23 @S9S_MB_2U_LIB.S9S_MB_2U(SCH_1):GND
CT79    GND UPI3_RX_DN22 @S9S_MB_2U_LIB.S9S_MB_2U(SCH_1):GND
CN80    GND UPI3_RX_DN21 @S9S_MB_2U_LIB.S9S_MB_2U(SCH_1):GND
CP81    GND UPI3_RX_DN20 @S9S_MB_2U_LIB.S9S_MB_2U(SCH_1):GND
CW80    GND UPI3_RX_DN19 @S9S_MB_2U_LIB.S9S_MB_2U(SCH_1):GND
CR82    GND UPI3_RX_DN18 @S9S_MB_2U_LIB.S9S_MB_2U(SCH_1):GND
CU82    GND UPI3_RX_DN17 @S9S_MB_2U_LIB.S9S_MB_2U(SCH_1):GND
DF77    GND UPI3_RX_DN16 @S9S_MB_2U_LIB.S9S_MB_2U(SCH_1):GND
DB81    GND UPI3_RX_DN15 @S9S_MB_2U_LIB.S9S_MB_2U(SCH_1):GND
DC82    GND UPI3_RX_DN14 @S9S_MB_2U_LIB.S9S_MB_2U(SCH_1):GND
DE80    GND UPI3_RX_DN13 @S9S_MB_2U_LIB.S9S_MB_2U(SCH_1):GND
DF83    GND UPI3_RX_DN12 @S9S_MB_2U_LIB.S9S_MB_2U(SCH_1):GND
DH81    GND UPI3_RX_DN11 @S9S_MB_2U_LIB.S9S_MB_2U(SCH_1):GND
DG78    GND UPI3_RX_DN10 @S9S_MB_2U_LIB.S9S_MB_2U(SCH_1):GND
DJ78    GND UPI3_RX_DN9 @S9S_MB_2U_LIB.S9S_MB_2U(SCH_1):GND
DY81    GND UPI3_RX_DN8 @S9S_MB_2U_LIB.S9S_MB_2U(SCH_1):GND
EA82    GND UPI3_RX_DN7 @S9S_MB_2U_LIB.S9S_MB_2U(SCH_1):GND
EC80    GND UPI3_RX_DN6 @S9S_MB_2U_LIB.S9S_MB_2U(SCH_1):GND
ED83    GND UPI3_RX_DN5 @S9S_MB_2U_LIB.S9S_MB_2U(SCH_1):GND
EF81    GND UPI3_RX_DN4 @S9S_MB_2U_LIB.S9S_MB_2U(SCH_1):GND
EK81    GND UPI3_RX_DN3 @S9S_MB_2U_LIB.S9S_MB_2U(SCH_1):GND
EL82    GND UPI3_RX_DN2 @S9S_MB_2U_LIB.S9S_MB_2U(SCH_1):GND
EP81    GND UPI3_RX_DN1 @S9S_MB_2U_LIB.S9S_MB_2U(SCH_1):GND
EJ80    GND UPI3_RX_DN0 @S9S_MB_2U_LIB.S9S_MB_2U(SCH_1):GND
DB79    GND UPI3_RX_DP23 @S9S_MB_2U_LIB.S9S_MB_2U(SCH_1):GND
CU80    GND UPI3_RX_DP22 @S9S_MB_2U_LIB.S9S_MB_2U(SCH_1):GND
CR80    GND UPI3_RX_DP21 @S9S_MB_2U_LIB.S9S_MB_2U(SCH_1):GND
CN82    GND UPI3_RX_DP20 @S9S_MB_2U_LIB.S9S_MB_2U(SCH_1):GND
CV81    GND UPI3_RX_DP19 @S9S_MB_2U_LIB.S9S_MB_2U(SCH_1):GND
CT83    GND UPI3_RX_DP18 @S9S_MB_2U_LIB.S9S_MB_2U(SCH_1):GND
CW82    GND UPI3_RX_DP17 @S9S_MB_2U_LIB.S9S_MB_2U(SCH_1):GND
DE78    GND UPI3_RX_DP16 @S9S_MB_2U_LIB.S9S_MB_2U(SCH_1):GND
DD81    GND UPI3_RX_DP15 @S9S_MB_2U_LIB.S9S_MB_2U(SCH_1):GND
DB83    GND UPI3_RX_DP14 @S9S_MB_2U_LIB.S9S_MB_2U(SCH_1):GND
DF81    GND UPI3_RX_DP13 @S9S_MB_2U_LIB.S9S_MB_2U(SCH_1):GND
DH83    GND UPI3_RX_DP12 @S9S_MB_2U_LIB.S9S_MB_2U(SCH_1):GND
DG82    GND UPI3_RX_DP11 @S9S_MB_2U_LIB.S9S_MB_2U(SCH_1):GND
DH79    GND UPI3_RX_DP10 @S9S_MB_2U_LIB.S9S_MB_2U(SCH_1):GND
DL78    GND UPI3_RX_DP9 @S9S_MB_2U_LIB.S9S_MB_2U(SCH_1):GND
EB81    GND UPI3_RX_DP8 @S9S_MB_2U_LIB.S9S_MB_2U(SCH_1):GND
DY83    GND UPI3_RX_DP7 @S9S_MB_2U_LIB.S9S_MB_2U(SCH_1):GND
ED81    GND UPI3_RX_DP6 @S9S_MB_2U_LIB.S9S_MB_2U(SCH_1):GND
EF83    GND UPI3_RX_DP5 @S9S_MB_2U_LIB.S9S_MB_2U(SCH_1):GND
EE82    GND UPI3_RX_DP4 @S9S_MB_2U_LIB.S9S_MB_2U(SCH_1):GND
EJ82    GND UPI3_RX_DP3 @S9S_MB_2U_LIB.S9S_MB_2U(SCH_1):GND
EN82    GND UPI3_RX_DP2 @S9S_MB_2U_LIB.S9S_MB_2U(SCH_1):GND
ER82    GND UPI3_RX_DP1 @S9S_MB_2U_LIB.S9S_MB_2U(SCH_1):GND
EL80    GND UPI3_RX_DP0 @S9S_MB_2U_LIB.S9S_MB_2U(SCH_1):GND
CF73     NC UPI3_TX_DN23     NC
CV73     NC UPI3_TX_DN22     NC
CJ74     NC UPI3_TX_DN21     NC
CF75     NC UPI3_TX_DN20     NC
CG76     NC UPI3_TX_DN19     NC
CM75     NC UPI3_TX_DN18     NC
CH77     NC UPI3_TX_DN17     NC
CK77     NC UPI3_TX_DN16     NC
CR74     NC UPI3_TX_DN15     NC
CT75     NC UPI3_TX_DN14     NC
CU76     NC UPI3_TX_DN13     NC
CW76     NC UPI3_TX_DN12     NC
DL80     NC UPI3_TX_DN11     NC
DM81     NC UPI3_TX_DN10     NC
DN82     NC UPI3_TX_DN9     NC
DP79     NC UPI3_TX_DN8     NC
DR82     NC UPI3_TX_DN7     NC
DU80     NC UPI3_TX_DN6     NC
EK87     NC UPI3_TX_DN5     NC
EJ86     NC UPI3_TX_DN4     NC
EM87     NC UPI3_TX_DN3     NC
EP85     NC UPI3_TX_DN2     NC
EL84     NC UPI3_TX_DN1     NC
EH85     NC UPI3_TX_DN0     NC
CD73     NC UPI3_TX_DP23     NC
CW74     NC UPI3_TX_DP22     NC
CK75     NC UPI3_TX_DP21     NC
CH75     NC UPI3_TX_DP20     NC
CF77     NC UPI3_TX_DP19     NC
CL76     NC UPI3_TX_DP18     NC
CJ78     NC UPI3_TX_DP17     NC
CM77     NC UPI3_TX_DP16     NC
CU74     NC UPI3_TX_DP15     NC
CR76     NC UPI3_TX_DP14     NC
CV77     NC UPI3_TX_DP13     NC
DA76     NC UPI3_TX_DP12     NC
DN80     NC UPI3_TX_DP11     NC
DL82     NC UPI3_TX_DP10     NC
DP83     NC UPI3_TX_DP9     NC
DR80     NC UPI3_TX_DP8     NC
DU82     NC UPI3_TX_DP7     NC
DT81     NC UPI3_TX_DP6     NC
EL88     NC UPI3_TX_DP5     NC
EH87     NC UPI3_TX_DP4     NC
EP87     NC UPI3_TX_DP3     NC
EN86     NC UPI3_TX_DP2     NC
EM85     NC UPI3_TX_DP1     NC
EK85     NC UPI3_TX_DP0     NC


DRAWING: @S9S_MB_2U_LIB.S9S_MB_2U(SCH_1):PAGE36 

SOCKET4677_AZIF0045P001C01CS-SA  I1  U2
CM89 PVCCIN_CPU0 VCCIN339 @S9S_MB_2U_LIB.S9S_MB_2U(SCH_1):PVCCIN_CPU0
CP89 PVCCIN_CPU0 VCCIN338 @S9S_MB_2U_LIB.S9S_MB_2U(SCH_1):PVCCIN_CPU0
CN90 PVCCIN_CPU0 VCCIN337 @S9S_MB_2U_LIB.S9S_MB_2U(SCH_1):PVCCIN_CPU0
CN88 PVCCIN_CPU0 VCCIN336 @S9S_MB_2U_LIB.S9S_MB_2U(SCH_1):PVCCIN_CPU0
CM91 PVCCIN_CPU0 VCCIN335 @S9S_MB_2U_LIB.S9S_MB_2U(SCH_1):PVCCIN_CPU0
CM87 PVCCIN_CPU0 VCCIN334 @S9S_MB_2U_LIB.S9S_MB_2U(SCH_1):PVCCIN_CPU0
CL90 PVCCIN_CPU0 VCCIN333 @S9S_MB_2U_LIB.S9S_MB_2U(SCH_1):PVCCIN_CPU0
CL88 PVCCIN_CPU0 VCCIN332 @S9S_MB_2U_LIB.S9S_MB_2U(SCH_1):PVCCIN_CPU0
CL86 PVCCIN_CPU0 VCCIN331 @S9S_MB_2U_LIB.S9S_MB_2U(SCH_1):PVCCIN_CPU0
CL84 PVCCIN_CPU0 VCCIN330 @S9S_MB_2U_LIB.S9S_MB_2U(SCH_1):PVCCIN_CPU0
CK91 PVCCIN_CPU0 VCCIN329 @S9S_MB_2U_LIB.S9S_MB_2U(SCH_1):PVCCIN_CPU0
CK89 PVCCIN_CPU0 VCCIN328 @S9S_MB_2U_LIB.S9S_MB_2U(SCH_1):PVCCIN_CPU0
CK87 PVCCIN_CPU0 VCCIN327 @S9S_MB_2U_LIB.S9S_MB_2U(SCH_1):PVCCIN_CPU0
CK85 PVCCIN_CPU0 VCCIN326 @S9S_MB_2U_LIB.S9S_MB_2U(SCH_1):PVCCIN_CPU0
CK83 PVCCIN_CPU0 VCCIN325 @S9S_MB_2U_LIB.S9S_MB_2U(SCH_1):PVCCIN_CPU0
CJ90 PVCCIN_CPU0 VCCIN324 @S9S_MB_2U_LIB.S9S_MB_2U(SCH_1):PVCCIN_CPU0
CJ88 PVCCIN_CPU0 VCCIN323 @S9S_MB_2U_LIB.S9S_MB_2U(SCH_1):PVCCIN_CPU0
CJ86 PVCCIN_CPU0 VCCIN322 @S9S_MB_2U_LIB.S9S_MB_2U(SCH_1):PVCCIN_CPU0
CJ84 PVCCIN_CPU0 VCCIN321 @S9S_MB_2U_LIB.S9S_MB_2U(SCH_1):PVCCIN_CPU0
CJ82 PVCCIN_CPU0 VCCIN320 @S9S_MB_2U_LIB.S9S_MB_2U(SCH_1):PVCCIN_CPU0
CH91 PVCCIN_CPU0 VCCIN319 @S9S_MB_2U_LIB.S9S_MB_2U(SCH_1):PVCCIN_CPU0
CH81 PVCCIN_CPU0 VCCIN318 @S9S_MB_2U_LIB.S9S_MB_2U(SCH_1):PVCCIN_CPU0
CG90 PVCCIN_CPU0 VCCIN317 @S9S_MB_2U_LIB.S9S_MB_2U(SCH_1):PVCCIN_CPU0
CG88 PVCCIN_CPU0 VCCIN316 @S9S_MB_2U_LIB.S9S_MB_2U(SCH_1):PVCCIN_CPU0
CG86 PVCCIN_CPU0 VCCIN315 @S9S_MB_2U_LIB.S9S_MB_2U(SCH_1):PVCCIN_CPU0
CG84 PVCCIN_CPU0 VCCIN314 @S9S_MB_2U_LIB.S9S_MB_2U(SCH_1):PVCCIN_CPU0
CG82 PVCCIN_CPU0 VCCIN313 @S9S_MB_2U_LIB.S9S_MB_2U(SCH_1):PVCCIN_CPU0
CG80 PVCCIN_CPU0 VCCIN312 @S9S_MB_2U_LIB.S9S_MB_2U(SCH_1):PVCCIN_CPU0
CF91 PVCCIN_CPU0 VCCIN311 @S9S_MB_2U_LIB.S9S_MB_2U(SCH_1):PVCCIN_CPU0
CF89 PVCCIN_CPU0 VCCIN310 @S9S_MB_2U_LIB.S9S_MB_2U(SCH_1):PVCCIN_CPU0
CF87 PVCCIN_CPU0 VCCIN309 @S9S_MB_2U_LIB.S9S_MB_2U(SCH_1):PVCCIN_CPU0
CF85 PVCCIN_CPU0 VCCIN308 @S9S_MB_2U_LIB.S9S_MB_2U(SCH_1):PVCCIN_CPU0
CF83 PVCCIN_CPU0 VCCIN307 @S9S_MB_2U_LIB.S9S_MB_2U(SCH_1):PVCCIN_CPU0
CF81 PVCCIN_CPU0 VCCIN306 @S9S_MB_2U_LIB.S9S_MB_2U(SCH_1):PVCCIN_CPU0
CF79 PVCCIN_CPU0 VCCIN305 @S9S_MB_2U_LIB.S9S_MB_2U(SCH_1):PVCCIN_CPU0
CE90 PVCCIN_CPU0 VCCIN304 @S9S_MB_2U_LIB.S9S_MB_2U(SCH_1):PVCCIN_CPU0
CE88 PVCCIN_CPU0 VCCIN303 @S9S_MB_2U_LIB.S9S_MB_2U(SCH_1):PVCCIN_CPU0
CE86 PVCCIN_CPU0 VCCIN302 @S9S_MB_2U_LIB.S9S_MB_2U(SCH_1):PVCCIN_CPU0
CE84 PVCCIN_CPU0 VCCIN301 @S9S_MB_2U_LIB.S9S_MB_2U(SCH_1):PVCCIN_CPU0
CE82 PVCCIN_CPU0 VCCIN300 @S9S_MB_2U_LIB.S9S_MB_2U(SCH_1):PVCCIN_CPU0
CE80 PVCCIN_CPU0 VCCIN299 @S9S_MB_2U_LIB.S9S_MB_2U(SCH_1):PVCCIN_CPU0
CD89 PVCCIN_CPU0 VCCIN298 @S9S_MB_2U_LIB.S9S_MB_2U(SCH_1):PVCCIN_CPU0
CD87 PVCCIN_CPU0 VCCIN297 @S9S_MB_2U_LIB.S9S_MB_2U(SCH_1):PVCCIN_CPU0
CD85 PVCCIN_CPU0 VCCIN296 @S9S_MB_2U_LIB.S9S_MB_2U(SCH_1):PVCCIN_CPU0
CD83 PVCCIN_CPU0 VCCIN295 @S9S_MB_2U_LIB.S9S_MB_2U(SCH_1):PVCCIN_CPU0
CD81 PVCCIN_CPU0 VCCIN294 @S9S_MB_2U_LIB.S9S_MB_2U(SCH_1):PVCCIN_CPU0
CD79 PVCCIN_CPU0 VCCIN293 @S9S_MB_2U_LIB.S9S_MB_2U(SCH_1):PVCCIN_CPU0
CD59 PVCCIN_CPU0 VCCIN292 @S9S_MB_2U_LIB.S9S_MB_2U(SCH_1):PVCCIN_CPU0
CD57 PVCCIN_CPU0 VCCIN291 @S9S_MB_2U_LIB.S9S_MB_2U(SCH_1):PVCCIN_CPU0
CD55 PVCCIN_CPU0 VCCIN290 @S9S_MB_2U_LIB.S9S_MB_2U(SCH_1):PVCCIN_CPU0
CD53 PVCCIN_CPU0 VCCIN289 @S9S_MB_2U_LIB.S9S_MB_2U(SCH_1):PVCCIN_CPU0
CD51 PVCCIN_CPU0 VCCIN288 @S9S_MB_2U_LIB.S9S_MB_2U(SCH_1):PVCCIN_CPU0
CD49 PVCCIN_CPU0 VCCIN287 @S9S_MB_2U_LIB.S9S_MB_2U(SCH_1):PVCCIN_CPU0
CD47 PVCCIN_CPU0 VCCIN286 @S9S_MB_2U_LIB.S9S_MB_2U(SCH_1):PVCCIN_CPU0
CD44 PVCCIN_CPU0 VCCIN285 @S9S_MB_2U_LIB.S9S_MB_2U(SCH_1):PVCCIN_CPU0
CD42 PVCCIN_CPU0 VCCIN284 @S9S_MB_2U_LIB.S9S_MB_2U(SCH_1):PVCCIN_CPU0
CD40 PVCCIN_CPU0 VCCIN283 @S9S_MB_2U_LIB.S9S_MB_2U(SCH_1):PVCCIN_CPU0
CD38 PVCCIN_CPU0 VCCIN282 @S9S_MB_2U_LIB.S9S_MB_2U(SCH_1):PVCCIN_CPU0
CD36 PVCCIN_CPU0 VCCIN281 @S9S_MB_2U_LIB.S9S_MB_2U(SCH_1):PVCCIN_CPU0
CD34 PVCCIN_CPU0 VCCIN280 @S9S_MB_2U_LIB.S9S_MB_2U(SCH_1):PVCCIN_CPU0
CD32 PVCCIN_CPU0 VCCIN279 @S9S_MB_2U_LIB.S9S_MB_2U(SCH_1):PVCCIN_CPU0
CC90 PVCCIN_CPU0 VCCIN278 @S9S_MB_2U_LIB.S9S_MB_2U(SCH_1):PVCCIN_CPU0
CC88 PVCCIN_CPU0 VCCIN277 @S9S_MB_2U_LIB.S9S_MB_2U(SCH_1):PVCCIN_CPU0
CC86 PVCCIN_CPU0 VCCIN276 @S9S_MB_2U_LIB.S9S_MB_2U(SCH_1):PVCCIN_CPU0
CC84 PVCCIN_CPU0 VCCIN275 @S9S_MB_2U_LIB.S9S_MB_2U(SCH_1):PVCCIN_CPU0
CC82 PVCCIN_CPU0 VCCIN274 @S9S_MB_2U_LIB.S9S_MB_2U(SCH_1):PVCCIN_CPU0
CC80 PVCCIN_CPU0 VCCIN273 @S9S_MB_2U_LIB.S9S_MB_2U(SCH_1):PVCCIN_CPU0
CC78 PVCCIN_CPU0 VCCIN272 @S9S_MB_2U_LIB.S9S_MB_2U(SCH_1):PVCCIN_CPU0
CC76 PVCCIN_CPU0 VCCIN271 @S9S_MB_2U_LIB.S9S_MB_2U(SCH_1):PVCCIN_CPU0
CC60 PVCCIN_CPU0 VCCIN270 @S9S_MB_2U_LIB.S9S_MB_2U(SCH_1):PVCCIN_CPU0
CC58 PVCCIN_CPU0 VCCIN269 @S9S_MB_2U_LIB.S9S_MB_2U(SCH_1):PVCCIN_CPU0
CC56 PVCCIN_CPU0 VCCIN268 @S9S_MB_2U_LIB.S9S_MB_2U(SCH_1):PVCCIN_CPU0
CC54 PVCCIN_CPU0 VCCIN267 @S9S_MB_2U_LIB.S9S_MB_2U(SCH_1):PVCCIN_CPU0
CC52 PVCCIN_CPU0 VCCIN266 @S9S_MB_2U_LIB.S9S_MB_2U(SCH_1):PVCCIN_CPU0
CC50 PVCCIN_CPU0 VCCIN265 @S9S_MB_2U_LIB.S9S_MB_2U(SCH_1):PVCCIN_CPU0
CC48 PVCCIN_CPU0 VCCIN264 @S9S_MB_2U_LIB.S9S_MB_2U(SCH_1):PVCCIN_CPU0
CC45 PVCCIN_CPU0 VCCIN263 @S9S_MB_2U_LIB.S9S_MB_2U(SCH_1):PVCCIN_CPU0
CC43 PVCCIN_CPU0 VCCIN262 @S9S_MB_2U_LIB.S9S_MB_2U(SCH_1):PVCCIN_CPU0
CC41 PVCCIN_CPU0 VCCIN261 @S9S_MB_2U_LIB.S9S_MB_2U(SCH_1):PVCCIN_CPU0
CC39 PVCCIN_CPU0 VCCIN260 @S9S_MB_2U_LIB.S9S_MB_2U(SCH_1):PVCCIN_CPU0
CC37 PVCCIN_CPU0 VCCIN259 @S9S_MB_2U_LIB.S9S_MB_2U(SCH_1):PVCCIN_CPU0
CC35 PVCCIN_CPU0 VCCIN258 @S9S_MB_2U_LIB.S9S_MB_2U(SCH_1):PVCCIN_CPU0
CC33 PVCCIN_CPU0 VCCIN257 @S9S_MB_2U_LIB.S9S_MB_2U(SCH_1):PVCCIN_CPU0
CB77 PVCCIN_CPU0 VCCIN256 @S9S_MB_2U_LIB.S9S_MB_2U(SCH_1):PVCCIN_CPU0
CB75 PVCCIN_CPU0 VCCIN255 @S9S_MB_2U_LIB.S9S_MB_2U(SCH_1):PVCCIN_CPU0
CB61 PVCCIN_CPU0 VCCIN254 @S9S_MB_2U_LIB.S9S_MB_2U(SCH_1):PVCCIN_CPU0
CA90 PVCCIN_CPU0 VCCIN253 @S9S_MB_2U_LIB.S9S_MB_2U(SCH_1):PVCCIN_CPU0
CA88 PVCCIN_CPU0 VCCIN252 @S9S_MB_2U_LIB.S9S_MB_2U(SCH_1):PVCCIN_CPU0
CA86 PVCCIN_CPU0 VCCIN251 @S9S_MB_2U_LIB.S9S_MB_2U(SCH_1):PVCCIN_CPU0
CA84 PVCCIN_CPU0 VCCIN250 @S9S_MB_2U_LIB.S9S_MB_2U(SCH_1):PVCCIN_CPU0
CA82 PVCCIN_CPU0 VCCIN249 @S9S_MB_2U_LIB.S9S_MB_2U(SCH_1):PVCCIN_CPU0
CA80 PVCCIN_CPU0 VCCIN248 @S9S_MB_2U_LIB.S9S_MB_2U(SCH_1):PVCCIN_CPU0
CA78 PVCCIN_CPU0 VCCIN247 @S9S_MB_2U_LIB.S9S_MB_2U(SCH_1):PVCCIN_CPU0
CA76 PVCCIN_CPU0 VCCIN246 @S9S_MB_2U_LIB.S9S_MB_2U(SCH_1):PVCCIN_CPU0
CA74 PVCCIN_CPU0 VCCIN245 @S9S_MB_2U_LIB.S9S_MB_2U(SCH_1):PVCCIN_CPU0
CA72 PVCCIN_CPU0 VCCIN244 @S9S_MB_2U_LIB.S9S_MB_2U(SCH_1):PVCCIN_CPU0
CA70 PVCCIN_CPU0 VCCIN243 @S9S_MB_2U_LIB.S9S_MB_2U(SCH_1):PVCCIN_CPU0
CA68 PVCCIN_CPU0 VCCIN242 @S9S_MB_2U_LIB.S9S_MB_2U(SCH_1):PVCCIN_CPU0
CA66 PVCCIN_CPU0 VCCIN241 @S9S_MB_2U_LIB.S9S_MB_2U(SCH_1):PVCCIN_CPU0
CA64 PVCCIN_CPU0 VCCIN240 @S9S_MB_2U_LIB.S9S_MB_2U(SCH_1):PVCCIN_CPU0
CA62 PVCCIN_CPU0 VCCIN239 @S9S_MB_2U_LIB.S9S_MB_2U(SCH_1):PVCCIN_CPU0
CA60 PVCCIN_CPU0 VCCIN238 @S9S_MB_2U_LIB.S9S_MB_2U(SCH_1):PVCCIN_CPU0
CA58 PVCCIN_CPU0 VCCIN237 @S9S_MB_2U_LIB.S9S_MB_2U(SCH_1):PVCCIN_CPU0
CA56 PVCCIN_CPU0 VCCIN236 @S9S_MB_2U_LIB.S9S_MB_2U(SCH_1):PVCCIN_CPU0
CA54 PVCCIN_CPU0 VCCIN235 @S9S_MB_2U_LIB.S9S_MB_2U(SCH_1):PVCCIN_CPU0
CA52 PVCCIN_CPU0 VCCIN234 @S9S_MB_2U_LIB.S9S_MB_2U(SCH_1):PVCCIN_CPU0
CA50 PVCCIN_CPU0 VCCIN233 @S9S_MB_2U_LIB.S9S_MB_2U(SCH_1):PVCCIN_CPU0
CA48 PVCCIN_CPU0 VCCIN232 @S9S_MB_2U_LIB.S9S_MB_2U(SCH_1):PVCCIN_CPU0
CA45 PVCCIN_CPU0 VCCIN231 @S9S_MB_2U_LIB.S9S_MB_2U(SCH_1):PVCCIN_CPU0
CA43 PVCCIN_CPU0 VCCIN230 @S9S_MB_2U_LIB.S9S_MB_2U(SCH_1):PVCCIN_CPU0
CA41 PVCCIN_CPU0 VCCIN229 @S9S_MB_2U_LIB.S9S_MB_2U(SCH_1):PVCCIN_CPU0
CA39 PVCCIN_CPU0 VCCIN228 @S9S_MB_2U_LIB.S9S_MB_2U(SCH_1):PVCCIN_CPU0
CA37 PVCCIN_CPU0 VCCIN227 @S9S_MB_2U_LIB.S9S_MB_2U(SCH_1):PVCCIN_CPU0
CA35 PVCCIN_CPU0 VCCIN226 @S9S_MB_2U_LIB.S9S_MB_2U(SCH_1):PVCCIN_CPU0
CA33 PVCCIN_CPU0 VCCIN225 @S9S_MB_2U_LIB.S9S_MB_2U(SCH_1):PVCCIN_CPU0
BY89 PVCCIN_CPU0 VCCIN224 @S9S_MB_2U_LIB.S9S_MB_2U(SCH_1):PVCCIN_CPU0
BY87 PVCCIN_CPU0 VCCIN223 @S9S_MB_2U_LIB.S9S_MB_2U(SCH_1):PVCCIN_CPU0
BY85 PVCCIN_CPU0 VCCIN222 @S9S_MB_2U_LIB.S9S_MB_2U(SCH_1):PVCCIN_CPU0
BY83 PVCCIN_CPU0 VCCIN221 @S9S_MB_2U_LIB.S9S_MB_2U(SCH_1):PVCCIN_CPU0
BY81 PVCCIN_CPU0 VCCIN220 @S9S_MB_2U_LIB.S9S_MB_2U(SCH_1):PVCCIN_CPU0
BY79 PVCCIN_CPU0 VCCIN219 @S9S_MB_2U_LIB.S9S_MB_2U(SCH_1):PVCCIN_CPU0
BY77 PVCCIN_CPU0 VCCIN218 @S9S_MB_2U_LIB.S9S_MB_2U(SCH_1):PVCCIN_CPU0
BY75 PVCCIN_CPU0 VCCIN217 @S9S_MB_2U_LIB.S9S_MB_2U(SCH_1):PVCCIN_CPU0
BY73 PVCCIN_CPU0 VCCIN216 @S9S_MB_2U_LIB.S9S_MB_2U(SCH_1):PVCCIN_CPU0
BY71 PVCCIN_CPU0 VCCIN215 @S9S_MB_2U_LIB.S9S_MB_2U(SCH_1):PVCCIN_CPU0
BY69 PVCCIN_CPU0 VCCIN214 @S9S_MB_2U_LIB.S9S_MB_2U(SCH_1):PVCCIN_CPU0
BY67 PVCCIN_CPU0 VCCIN213 @S9S_MB_2U_LIB.S9S_MB_2U(SCH_1):PVCCIN_CPU0
BY65 PVCCIN_CPU0 VCCIN212 @S9S_MB_2U_LIB.S9S_MB_2U(SCH_1):PVCCIN_CPU0
BY63 PVCCIN_CPU0 VCCIN211 @S9S_MB_2U_LIB.S9S_MB_2U(SCH_1):PVCCIN_CPU0
BY61 PVCCIN_CPU0 VCCIN210 @S9S_MB_2U_LIB.S9S_MB_2U(SCH_1):PVCCIN_CPU0
BY59 PVCCIN_CPU0 VCCIN209 @S9S_MB_2U_LIB.S9S_MB_2U(SCH_1):PVCCIN_CPU0
BY57 PVCCIN_CPU0 VCCIN208 @S9S_MB_2U_LIB.S9S_MB_2U(SCH_1):PVCCIN_CPU0
BY55 PVCCIN_CPU0 VCCIN207 @S9S_MB_2U_LIB.S9S_MB_2U(SCH_1):PVCCIN_CPU0
BY53 PVCCIN_CPU0 VCCIN206 @S9S_MB_2U_LIB.S9S_MB_2U(SCH_1):PVCCIN_CPU0
BY51 PVCCIN_CPU0 VCCIN205 @S9S_MB_2U_LIB.S9S_MB_2U(SCH_1):PVCCIN_CPU0
BY49 PVCCIN_CPU0 VCCIN204 @S9S_MB_2U_LIB.S9S_MB_2U(SCH_1):PVCCIN_CPU0
BY47 PVCCIN_CPU0 VCCIN203 @S9S_MB_2U_LIB.S9S_MB_2U(SCH_1):PVCCIN_CPU0
BY44 PVCCIN_CPU0 VCCIN202 @S9S_MB_2U_LIB.S9S_MB_2U(SCH_1):PVCCIN_CPU0
BY42 PVCCIN_CPU0 VCCIN201 @S9S_MB_2U_LIB.S9S_MB_2U(SCH_1):PVCCIN_CPU0
BY40 PVCCIN_CPU0 VCCIN200 @S9S_MB_2U_LIB.S9S_MB_2U(SCH_1):PVCCIN_CPU0
BY38 PVCCIN_CPU0 VCCIN199 @S9S_MB_2U_LIB.S9S_MB_2U(SCH_1):PVCCIN_CPU0
BY36 PVCCIN_CPU0 VCCIN198 @S9S_MB_2U_LIB.S9S_MB_2U(SCH_1):PVCCIN_CPU0
BY34 PVCCIN_CPU0 VCCIN197 @S9S_MB_2U_LIB.S9S_MB_2U(SCH_1):PVCCIN_CPU0
BY32 PVCCIN_CPU0 VCCIN196 @S9S_MB_2U_LIB.S9S_MB_2U(SCH_1):PVCCIN_CPU0
BW90 PVCCIN_CPU0 VCCIN195 @S9S_MB_2U_LIB.S9S_MB_2U(SCH_1):PVCCIN_CPU0
BW88 PVCCIN_CPU0 VCCIN194 @S9S_MB_2U_LIB.S9S_MB_2U(SCH_1):PVCCIN_CPU0
BW86 PVCCIN_CPU0 VCCIN193 @S9S_MB_2U_LIB.S9S_MB_2U(SCH_1):PVCCIN_CPU0
BW84 PVCCIN_CPU0 VCCIN192 @S9S_MB_2U_LIB.S9S_MB_2U(SCH_1):PVCCIN_CPU0
BW82 PVCCIN_CPU0 VCCIN191 @S9S_MB_2U_LIB.S9S_MB_2U(SCH_1):PVCCIN_CPU0
BW80 PVCCIN_CPU0 VCCIN190 @S9S_MB_2U_LIB.S9S_MB_2U(SCH_1):PVCCIN_CPU0

SOCKET4677_AZIF0045P001C01CS-SA  I7  U2
BW78 PVCCIN_CPU0 VCCIN189 @S9S_MB_2U_LIB.S9S_MB_2U(SCH_1):PVCCIN_CPU0
BW76 PVCCIN_CPU0 VCCIN188 @S9S_MB_2U_LIB.S9S_MB_2U(SCH_1):PVCCIN_CPU0
BW74 PVCCIN_CPU0 VCCIN187 @S9S_MB_2U_LIB.S9S_MB_2U(SCH_1):PVCCIN_CPU0
BW72 PVCCIN_CPU0 VCCIN186 @S9S_MB_2U_LIB.S9S_MB_2U(SCH_1):PVCCIN_CPU0
BW70 PVCCIN_CPU0 VCCIN185 @S9S_MB_2U_LIB.S9S_MB_2U(SCH_1):PVCCIN_CPU0
BW68 PVCCIN_CPU0 VCCIN184 @S9S_MB_2U_LIB.S9S_MB_2U(SCH_1):PVCCIN_CPU0
BW66 PVCCIN_CPU0 VCCIN183 @S9S_MB_2U_LIB.S9S_MB_2U(SCH_1):PVCCIN_CPU0
BW64 PVCCIN_CPU0 VCCIN182 @S9S_MB_2U_LIB.S9S_MB_2U(SCH_1):PVCCIN_CPU0
BW62 PVCCIN_CPU0 VCCIN181 @S9S_MB_2U_LIB.S9S_MB_2U(SCH_1):PVCCIN_CPU0
BW60 PVCCIN_CPU0 VCCIN180 @S9S_MB_2U_LIB.S9S_MB_2U(SCH_1):PVCCIN_CPU0
BW58 PVCCIN_CPU0 VCCIN179 @S9S_MB_2U_LIB.S9S_MB_2U(SCH_1):PVCCIN_CPU0
BW56 PVCCIN_CPU0 VCCIN178 @S9S_MB_2U_LIB.S9S_MB_2U(SCH_1):PVCCIN_CPU0
BW54 PVCCIN_CPU0 VCCIN177 @S9S_MB_2U_LIB.S9S_MB_2U(SCH_1):PVCCIN_CPU0
BW52 PVCCIN_CPU0 VCCIN176 @S9S_MB_2U_LIB.S9S_MB_2U(SCH_1):PVCCIN_CPU0
BW50 PVCCIN_CPU0 VCCIN175 @S9S_MB_2U_LIB.S9S_MB_2U(SCH_1):PVCCIN_CPU0
BW48 PVCCIN_CPU0 VCCIN174 @S9S_MB_2U_LIB.S9S_MB_2U(SCH_1):PVCCIN_CPU0
BW45 PVCCIN_CPU0 VCCIN173 @S9S_MB_2U_LIB.S9S_MB_2U(SCH_1):PVCCIN_CPU0
BW43 PVCCIN_CPU0 VCCIN172 @S9S_MB_2U_LIB.S9S_MB_2U(SCH_1):PVCCIN_CPU0
BW41 PVCCIN_CPU0 VCCIN171 @S9S_MB_2U_LIB.S9S_MB_2U(SCH_1):PVCCIN_CPU0
BW39 PVCCIN_CPU0 VCCIN170 @S9S_MB_2U_LIB.S9S_MB_2U(SCH_1):PVCCIN_CPU0
BW37 PVCCIN_CPU0 VCCIN169 @S9S_MB_2U_LIB.S9S_MB_2U(SCH_1):PVCCIN_CPU0
BW35 PVCCIN_CPU0 VCCIN168 @S9S_MB_2U_LIB.S9S_MB_2U(SCH_1):PVCCIN_CPU0
BW33 PVCCIN_CPU0 VCCIN167 @S9S_MB_2U_LIB.S9S_MB_2U(SCH_1):PVCCIN_CPU0
BV89 PVCCIN_CPU0 VCCIN166 @S9S_MB_2U_LIB.S9S_MB_2U(SCH_1):PVCCIN_CPU0
BV87 PVCCIN_CPU0 VCCIN165 @S9S_MB_2U_LIB.S9S_MB_2U(SCH_1):PVCCIN_CPU0
BV85 PVCCIN_CPU0 VCCIN164 @S9S_MB_2U_LIB.S9S_MB_2U(SCH_1):PVCCIN_CPU0
BV83 PVCCIN_CPU0 VCCIN163 @S9S_MB_2U_LIB.S9S_MB_2U(SCH_1):PVCCIN_CPU0
BV81 PVCCIN_CPU0 VCCIN162 @S9S_MB_2U_LIB.S9S_MB_2U(SCH_1):PVCCIN_CPU0
BV79 PVCCIN_CPU0 VCCIN161 @S9S_MB_2U_LIB.S9S_MB_2U(SCH_1):PVCCIN_CPU0
BV77 PVCCIN_CPU0 VCCIN160 @S9S_MB_2U_LIB.S9S_MB_2U(SCH_1):PVCCIN_CPU0
BV75 PVCCIN_CPU0 VCCIN159 @S9S_MB_2U_LIB.S9S_MB_2U(SCH_1):PVCCIN_CPU0
BV73 PVCCIN_CPU0 VCCIN158 @S9S_MB_2U_LIB.S9S_MB_2U(SCH_1):PVCCIN_CPU0
BV71 PVCCIN_CPU0 VCCIN157 @S9S_MB_2U_LIB.S9S_MB_2U(SCH_1):PVCCIN_CPU0
BV69 PVCCIN_CPU0 VCCIN156 @S9S_MB_2U_LIB.S9S_MB_2U(SCH_1):PVCCIN_CPU0
BV67 PVCCIN_CPU0 VCCIN155 @S9S_MB_2U_LIB.S9S_MB_2U(SCH_1):PVCCIN_CPU0
BV65 PVCCIN_CPU0 VCCIN154 @S9S_MB_2U_LIB.S9S_MB_2U(SCH_1):PVCCIN_CPU0
BV63 PVCCIN_CPU0 VCCIN153 @S9S_MB_2U_LIB.S9S_MB_2U(SCH_1):PVCCIN_CPU0
BV61 PVCCIN_CPU0 VCCIN152 @S9S_MB_2U_LIB.S9S_MB_2U(SCH_1):PVCCIN_CPU0
BV59 PVCCIN_CPU0 VCCIN151 @S9S_MB_2U_LIB.S9S_MB_2U(SCH_1):PVCCIN_CPU0
BV57 PVCCIN_CPU0 VCCIN150 @S9S_MB_2U_LIB.S9S_MB_2U(SCH_1):PVCCIN_CPU0
BV55 PVCCIN_CPU0 VCCIN149 @S9S_MB_2U_LIB.S9S_MB_2U(SCH_1):PVCCIN_CPU0
BV53 PVCCIN_CPU0 VCCIN148 @S9S_MB_2U_LIB.S9S_MB_2U(SCH_1):PVCCIN_CPU0
BV51 PVCCIN_CPU0 VCCIN147 @S9S_MB_2U_LIB.S9S_MB_2U(SCH_1):PVCCIN_CPU0
BV49 PVCCIN_CPU0 VCCIN146 @S9S_MB_2U_LIB.S9S_MB_2U(SCH_1):PVCCIN_CPU0
BV47 PVCCIN_CPU0 VCCIN145 @S9S_MB_2U_LIB.S9S_MB_2U(SCH_1):PVCCIN_CPU0
BV44 PVCCIN_CPU0 VCCIN144 @S9S_MB_2U_LIB.S9S_MB_2U(SCH_1):PVCCIN_CPU0
BV42 PVCCIN_CPU0 VCCIN143 @S9S_MB_2U_LIB.S9S_MB_2U(SCH_1):PVCCIN_CPU0
BV40 PVCCIN_CPU0 VCCIN142 @S9S_MB_2U_LIB.S9S_MB_2U(SCH_1):PVCCIN_CPU0
BV38 PVCCIN_CPU0 VCCIN141 @S9S_MB_2U_LIB.S9S_MB_2U(SCH_1):PVCCIN_CPU0
BV36 PVCCIN_CPU0 VCCIN140 @S9S_MB_2U_LIB.S9S_MB_2U(SCH_1):PVCCIN_CPU0
BV34 PVCCIN_CPU0 VCCIN139 @S9S_MB_2U_LIB.S9S_MB_2U(SCH_1):PVCCIN_CPU0
BV32 PVCCIN_CPU0 VCCIN138 @S9S_MB_2U_LIB.S9S_MB_2U(SCH_1):PVCCIN_CPU0
BU90 PVCCIN_CPU0 VCCIN137 @S9S_MB_2U_LIB.S9S_MB_2U(SCH_1):PVCCIN_CPU0
BU88 PVCCIN_CPU0 VCCIN136 @S9S_MB_2U_LIB.S9S_MB_2U(SCH_1):PVCCIN_CPU0
BU86 PVCCIN_CPU0 VCCIN135 @S9S_MB_2U_LIB.S9S_MB_2U(SCH_1):PVCCIN_CPU0
BU84 PVCCIN_CPU0 VCCIN134 @S9S_MB_2U_LIB.S9S_MB_2U(SCH_1):PVCCIN_CPU0
BU82 PVCCIN_CPU0 VCCIN133 @S9S_MB_2U_LIB.S9S_MB_2U(SCH_1):PVCCIN_CPU0
BU80 PVCCIN_CPU0 VCCIN132 @S9S_MB_2U_LIB.S9S_MB_2U(SCH_1):PVCCIN_CPU0
BU78 PVCCIN_CPU0 VCCIN131 @S9S_MB_2U_LIB.S9S_MB_2U(SCH_1):PVCCIN_CPU0
BU76 PVCCIN_CPU0 VCCIN130 @S9S_MB_2U_LIB.S9S_MB_2U(SCH_1):PVCCIN_CPU0
BU74 PVCCIN_CPU0 VCCIN129 @S9S_MB_2U_LIB.S9S_MB_2U(SCH_1):PVCCIN_CPU0
BU72 PVCCIN_CPU0 VCCIN128 @S9S_MB_2U_LIB.S9S_MB_2U(SCH_1):PVCCIN_CPU0
BU70 PVCCIN_CPU0 VCCIN127 @S9S_MB_2U_LIB.S9S_MB_2U(SCH_1):PVCCIN_CPU0
BU68 PVCCIN_CPU0 VCCIN126 @S9S_MB_2U_LIB.S9S_MB_2U(SCH_1):PVCCIN_CPU0
BU66 PVCCIN_CPU0 VCCIN125 @S9S_MB_2U_LIB.S9S_MB_2U(SCH_1):PVCCIN_CPU0
BU64 PVCCIN_CPU0 VCCIN124 @S9S_MB_2U_LIB.S9S_MB_2U(SCH_1):PVCCIN_CPU0
BU62 PVCCIN_CPU0 VCCIN123 @S9S_MB_2U_LIB.S9S_MB_2U(SCH_1):PVCCIN_CPU0
BU60 PVCCIN_CPU0 VCCIN122 @S9S_MB_2U_LIB.S9S_MB_2U(SCH_1):PVCCIN_CPU0
BU58 PVCCIN_CPU0 VCCIN121 @S9S_MB_2U_LIB.S9S_MB_2U(SCH_1):PVCCIN_CPU0
BU56 PVCCIN_CPU0 VCCIN120 @S9S_MB_2U_LIB.S9S_MB_2U(SCH_1):PVCCIN_CPU0
BU54 PVCCIN_CPU0 VCCIN119 @S9S_MB_2U_LIB.S9S_MB_2U(SCH_1):PVCCIN_CPU0
BU52 PVCCIN_CPU0 VCCIN118 @S9S_MB_2U_LIB.S9S_MB_2U(SCH_1):PVCCIN_CPU0
BU50 PVCCIN_CPU0 VCCIN117 @S9S_MB_2U_LIB.S9S_MB_2U(SCH_1):PVCCIN_CPU0
BU48 PVCCIN_CPU0 VCCIN116 @S9S_MB_2U_LIB.S9S_MB_2U(SCH_1):PVCCIN_CPU0
BU45 PVCCIN_CPU0 VCCIN115 @S9S_MB_2U_LIB.S9S_MB_2U(SCH_1):PVCCIN_CPU0
BU43 PVCCIN_CPU0 VCCIN114 @S9S_MB_2U_LIB.S9S_MB_2U(SCH_1):PVCCIN_CPU0
BU41 PVCCIN_CPU0 VCCIN113 @S9S_MB_2U_LIB.S9S_MB_2U(SCH_1):PVCCIN_CPU0
BU39 PVCCIN_CPU0 VCCIN112 @S9S_MB_2U_LIB.S9S_MB_2U(SCH_1):PVCCIN_CPU0
BU37 PVCCIN_CPU0 VCCIN111 @S9S_MB_2U_LIB.S9S_MB_2U(SCH_1):PVCCIN_CPU0
BU35 PVCCIN_CPU0 VCCIN110 @S9S_MB_2U_LIB.S9S_MB_2U(SCH_1):PVCCIN_CPU0
BU33 PVCCIN_CPU0 VCCIN109 @S9S_MB_2U_LIB.S9S_MB_2U(SCH_1):PVCCIN_CPU0
BT89 PVCCIN_CPU0 VCCIN108 @S9S_MB_2U_LIB.S9S_MB_2U(SCH_1):PVCCIN_CPU0
BT87 PVCCIN_CPU0 VCCIN107 @S9S_MB_2U_LIB.S9S_MB_2U(SCH_1):PVCCIN_CPU0
BT85 PVCCIN_CPU0 VCCIN106 @S9S_MB_2U_LIB.S9S_MB_2U(SCH_1):PVCCIN_CPU0
BT83 PVCCIN_CPU0 VCCIN105 @S9S_MB_2U_LIB.S9S_MB_2U(SCH_1):PVCCIN_CPU0
BT81 PVCCIN_CPU0 VCCIN104 @S9S_MB_2U_LIB.S9S_MB_2U(SCH_1):PVCCIN_CPU0
BT79 PVCCIN_CPU0 VCCIN103 @S9S_MB_2U_LIB.S9S_MB_2U(SCH_1):PVCCIN_CPU0
BT77 PVCCIN_CPU0 VCCIN102 @S9S_MB_2U_LIB.S9S_MB_2U(SCH_1):PVCCIN_CPU0
BT75 PVCCIN_CPU0 VCCIN101 @S9S_MB_2U_LIB.S9S_MB_2U(SCH_1):PVCCIN_CPU0
BT73 PVCCIN_CPU0 VCCIN100 @S9S_MB_2U_LIB.S9S_MB_2U(SCH_1):PVCCIN_CPU0
BT71 PVCCIN_CPU0 VCCIN99 @S9S_MB_2U_LIB.S9S_MB_2U(SCH_1):PVCCIN_CPU0
BT69 PVCCIN_CPU0 VCCIN98 @S9S_MB_2U_LIB.S9S_MB_2U(SCH_1):PVCCIN_CPU0
BT67 PVCCIN_CPU0 VCCIN97 @S9S_MB_2U_LIB.S9S_MB_2U(SCH_1):PVCCIN_CPU0
BT65 PVCCIN_CPU0 VCCIN96 @S9S_MB_2U_LIB.S9S_MB_2U(SCH_1):PVCCIN_CPU0
BT63 PVCCIN_CPU0 VCCIN95 @S9S_MB_2U_LIB.S9S_MB_2U(SCH_1):PVCCIN_CPU0
BT61 PVCCIN_CPU0 VCCIN94 @S9S_MB_2U_LIB.S9S_MB_2U(SCH_1):PVCCIN_CPU0
BT59 PVCCIN_CPU0 VCCIN93 @S9S_MB_2U_LIB.S9S_MB_2U(SCH_1):PVCCIN_CPU0
BT57 PVCCIN_CPU0 VCCIN92 @S9S_MB_2U_LIB.S9S_MB_2U(SCH_1):PVCCIN_CPU0
BT55 PVCCIN_CPU0 VCCIN91 @S9S_MB_2U_LIB.S9S_MB_2U(SCH_1):PVCCIN_CPU0
BT53 PVCCIN_CPU0 VCCIN90 @S9S_MB_2U_LIB.S9S_MB_2U(SCH_1):PVCCIN_CPU0
BT51 PVCCIN_CPU0 VCCIN89 @S9S_MB_2U_LIB.S9S_MB_2U(SCH_1):PVCCIN_CPU0
BT49 PVCCIN_CPU0 VCCIN88 @S9S_MB_2U_LIB.S9S_MB_2U(SCH_1):PVCCIN_CPU0
BT47 PVCCIN_CPU0 VCCIN87 @S9S_MB_2U_LIB.S9S_MB_2U(SCH_1):PVCCIN_CPU0
BT44 PVCCIN_CPU0 VCCIN86 @S9S_MB_2U_LIB.S9S_MB_2U(SCH_1):PVCCIN_CPU0
BT42 PVCCIN_CPU0 VCCIN85 @S9S_MB_2U_LIB.S9S_MB_2U(SCH_1):PVCCIN_CPU0
BT40 PVCCIN_CPU0 VCCIN84 @S9S_MB_2U_LIB.S9S_MB_2U(SCH_1):PVCCIN_CPU0
BT38 PVCCIN_CPU0 VCCIN83 @S9S_MB_2U_LIB.S9S_MB_2U(SCH_1):PVCCIN_CPU0
BT36 PVCCIN_CPU0 VCCIN82 @S9S_MB_2U_LIB.S9S_MB_2U(SCH_1):PVCCIN_CPU0
BT34 PVCCIN_CPU0 VCCIN81 @S9S_MB_2U_LIB.S9S_MB_2U(SCH_1):PVCCIN_CPU0
BT32 PVCCIN_CPU0 VCCIN80 @S9S_MB_2U_LIB.S9S_MB_2U(SCH_1):PVCCIN_CPU0
BR78 PVCCIN_CPU0 VCCIN79 @S9S_MB_2U_LIB.S9S_MB_2U(SCH_1):PVCCIN_CPU0
BR62 PVCCIN_CPU0 VCCIN78 @S9S_MB_2U_LIB.S9S_MB_2U(SCH_1):PVCCIN_CPU0
BR60 PVCCIN_CPU0 VCCIN77 @S9S_MB_2U_LIB.S9S_MB_2U(SCH_1):PVCCIN_CPU0
BP89 PVCCIN_CPU0 VCCIN76 @S9S_MB_2U_LIB.S9S_MB_2U(SCH_1):PVCCIN_CPU0
BP87 PVCCIN_CPU0 VCCIN75 @S9S_MB_2U_LIB.S9S_MB_2U(SCH_1):PVCCIN_CPU0
BP85 PVCCIN_CPU0 VCCIN74 @S9S_MB_2U_LIB.S9S_MB_2U(SCH_1):PVCCIN_CPU0
BP83 PVCCIN_CPU0 VCCIN73 @S9S_MB_2U_LIB.S9S_MB_2U(SCH_1):PVCCIN_CPU0
BP81 PVCCIN_CPU0 VCCIN72 @S9S_MB_2U_LIB.S9S_MB_2U(SCH_1):PVCCIN_CPU0
BP79 PVCCIN_CPU0 VCCIN71 @S9S_MB_2U_LIB.S9S_MB_2U(SCH_1):PVCCIN_CPU0
BP61 PVCCIN_CPU0 VCCIN70 @S9S_MB_2U_LIB.S9S_MB_2U(SCH_1):PVCCIN_CPU0
BP59 PVCCIN_CPU0 VCCIN69 @S9S_MB_2U_LIB.S9S_MB_2U(SCH_1):PVCCIN_CPU0
BP57 PVCCIN_CPU0 VCCIN68 @S9S_MB_2U_LIB.S9S_MB_2U(SCH_1):PVCCIN_CPU0
BP55 PVCCIN_CPU0 VCCIN67 @S9S_MB_2U_LIB.S9S_MB_2U(SCH_1):PVCCIN_CPU0
BP53 PVCCIN_CPU0 VCCIN66 @S9S_MB_2U_LIB.S9S_MB_2U(SCH_1):PVCCIN_CPU0
BP51 PVCCIN_CPU0 VCCIN65 @S9S_MB_2U_LIB.S9S_MB_2U(SCH_1):PVCCIN_CPU0
BP49 PVCCIN_CPU0 VCCIN64 @S9S_MB_2U_LIB.S9S_MB_2U(SCH_1):PVCCIN_CPU0
BP47 PVCCIN_CPU0 VCCIN63 @S9S_MB_2U_LIB.S9S_MB_2U(SCH_1):PVCCIN_CPU0
BP44 PVCCIN_CPU0 VCCIN62 @S9S_MB_2U_LIB.S9S_MB_2U(SCH_1):PVCCIN_CPU0
BP42 PVCCIN_CPU0 VCCIN61 @S9S_MB_2U_LIB.S9S_MB_2U(SCH_1):PVCCIN_CPU0
BP40 PVCCIN_CPU0 VCCIN60 @S9S_MB_2U_LIB.S9S_MB_2U(SCH_1):PVCCIN_CPU0
BP38 PVCCIN_CPU0 VCCIN59 @S9S_MB_2U_LIB.S9S_MB_2U(SCH_1):PVCCIN_CPU0
BP36 PVCCIN_CPU0 VCCIN58 @S9S_MB_2U_LIB.S9S_MB_2U(SCH_1):PVCCIN_CPU0
BP34 PVCCIN_CPU0 VCCIN57 @S9S_MB_2U_LIB.S9S_MB_2U(SCH_1):PVCCIN_CPU0
BP32 PVCCIN_CPU0 VCCIN56 @S9S_MB_2U_LIB.S9S_MB_2U(SCH_1):PVCCIN_CPU0
BN90 PVCCIN_CPU0 VCCIN55 @S9S_MB_2U_LIB.S9S_MB_2U(SCH_1):PVCCIN_CPU0
BN88 PVCCIN_CPU0 VCCIN54 @S9S_MB_2U_LIB.S9S_MB_2U(SCH_1):PVCCIN_CPU0
BN86 PVCCIN_CPU0 VCCIN53 @S9S_MB_2U_LIB.S9S_MB_2U(SCH_1):PVCCIN_CPU0
BN84 PVCCIN_CPU0 VCCIN52 @S9S_MB_2U_LIB.S9S_MB_2U(SCH_1):PVCCIN_CPU0
BN82 PVCCIN_CPU0 VCCIN51 @S9S_MB_2U_LIB.S9S_MB_2U(SCH_1):PVCCIN_CPU0
BN80 PVCCIN_CPU0 VCCIN50 @S9S_MB_2U_LIB.S9S_MB_2U(SCH_1):PVCCIN_CPU0
BN78 PVCCIN_CPU0 VCCIN49 @S9S_MB_2U_LIB.S9S_MB_2U(SCH_1):PVCCIN_CPU0
BN60 PVCCIN_CPU0 VCCIN48 @S9S_MB_2U_LIB.S9S_MB_2U(SCH_1):PVCCIN_CPU0
BN58 PVCCIN_CPU0 VCCIN47 @S9S_MB_2U_LIB.S9S_MB_2U(SCH_1):PVCCIN_CPU0
BN56 PVCCIN_CPU0 VCCIN46 @S9S_MB_2U_LIB.S9S_MB_2U(SCH_1):PVCCIN_CPU0
BN54 PVCCIN_CPU0 VCCIN45 @S9S_MB_2U_LIB.S9S_MB_2U(SCH_1):PVCCIN_CPU0
BN52 PVCCIN_CPU0 VCCIN44 @S9S_MB_2U_LIB.S9S_MB_2U(SCH_1):PVCCIN_CPU0
BN50 PVCCIN_CPU0 VCCIN43 @S9S_MB_2U_LIB.S9S_MB_2U(SCH_1):PVCCIN_CPU0
BN48 PVCCIN_CPU0 VCCIN42 @S9S_MB_2U_LIB.S9S_MB_2U(SCH_1):PVCCIN_CPU0
BN45 PVCCIN_CPU0 VCCIN41 @S9S_MB_2U_LIB.S9S_MB_2U(SCH_1):PVCCIN_CPU0
BN43 PVCCIN_CPU0 VCCIN40 @S9S_MB_2U_LIB.S9S_MB_2U(SCH_1):PVCCIN_CPU0


DRAWING: @S9S_MB_2U_LIB.S9S_MB_2U(SCH_1):PAGE37 

SOCKET4677_AZIF0045P001C01CS-SA  I7  U2
BN41 PVCCIN_CPU0 VCCIN39 @S9S_MB_2U_LIB.S9S_MB_2U(SCH_1):PVCCIN_CPU0
BN39 PVCCIN_CPU0 VCCIN38 @S9S_MB_2U_LIB.S9S_MB_2U(SCH_1):PVCCIN_CPU0
BN37 PVCCIN_CPU0 VCCIN37 @S9S_MB_2U_LIB.S9S_MB_2U(SCH_1):PVCCIN_CPU0
BN35 PVCCIN_CPU0 VCCIN36 @S9S_MB_2U_LIB.S9S_MB_2U(SCH_1):PVCCIN_CPU0
BN33 PVCCIN_CPU0 VCCIN35 @S9S_MB_2U_LIB.S9S_MB_2U(SCH_1):PVCCIN_CPU0
BM91 PVCCIN_CPU0 VCCIN34 @S9S_MB_2U_LIB.S9S_MB_2U(SCH_1):PVCCIN_CPU0
BM89 PVCCIN_CPU0 VCCIN33 @S9S_MB_2U_LIB.S9S_MB_2U(SCH_1):PVCCIN_CPU0
BM87 PVCCIN_CPU0 VCCIN32 @S9S_MB_2U_LIB.S9S_MB_2U(SCH_1):PVCCIN_CPU0
BM85 PVCCIN_CPU0 VCCIN31 @S9S_MB_2U_LIB.S9S_MB_2U(SCH_1):PVCCIN_CPU0
BM83 PVCCIN_CPU0 VCCIN30 @S9S_MB_2U_LIB.S9S_MB_2U(SCH_1):PVCCIN_CPU0
BM81 PVCCIN_CPU0 VCCIN29 @S9S_MB_2U_LIB.S9S_MB_2U(SCH_1):PVCCIN_CPU0
BM79 PVCCIN_CPU0 VCCIN28 @S9S_MB_2U_LIB.S9S_MB_2U(SCH_1):PVCCIN_CPU0
BL90 PVCCIN_CPU0 VCCIN27 @S9S_MB_2U_LIB.S9S_MB_2U(SCH_1):PVCCIN_CPU0
BL88 PVCCIN_CPU0 VCCIN26 @S9S_MB_2U_LIB.S9S_MB_2U(SCH_1):PVCCIN_CPU0
BL86 PVCCIN_CPU0 VCCIN25 @S9S_MB_2U_LIB.S9S_MB_2U(SCH_1):PVCCIN_CPU0
BL84 PVCCIN_CPU0 VCCIN24 @S9S_MB_2U_LIB.S9S_MB_2U(SCH_1):PVCCIN_CPU0
BL82 PVCCIN_CPU0 VCCIN23 @S9S_MB_2U_LIB.S9S_MB_2U(SCH_1):PVCCIN_CPU0
BL80 PVCCIN_CPU0 VCCIN22 @S9S_MB_2U_LIB.S9S_MB_2U(SCH_1):PVCCIN_CPU0
BK91 PVCCIN_CPU0 VCCIN21 @S9S_MB_2U_LIB.S9S_MB_2U(SCH_1):PVCCIN_CPU0
BK89 PVCCIN_CPU0 VCCIN20 @S9S_MB_2U_LIB.S9S_MB_2U(SCH_1):PVCCIN_CPU0
BK87 PVCCIN_CPU0 VCCIN19 @S9S_MB_2U_LIB.S9S_MB_2U(SCH_1):PVCCIN_CPU0
BK85 PVCCIN_CPU0 VCCIN18 @S9S_MB_2U_LIB.S9S_MB_2U(SCH_1):PVCCIN_CPU0
BK83 PVCCIN_CPU0 VCCIN17 @S9S_MB_2U_LIB.S9S_MB_2U(SCH_1):PVCCIN_CPU0
BK81 PVCCIN_CPU0 VCCIN16 @S9S_MB_2U_LIB.S9S_MB_2U(SCH_1):PVCCIN_CPU0
BH91 PVCCIN_CPU0 VCCIN15 @S9S_MB_2U_LIB.S9S_MB_2U(SCH_1):PVCCIN_CPU0
BH89 PVCCIN_CPU0 VCCIN14 @S9S_MB_2U_LIB.S9S_MB_2U(SCH_1):PVCCIN_CPU0
BH87 PVCCIN_CPU0 VCCIN13 @S9S_MB_2U_LIB.S9S_MB_2U(SCH_1):PVCCIN_CPU0
BH85 PVCCIN_CPU0 VCCIN12 @S9S_MB_2U_LIB.S9S_MB_2U(SCH_1):PVCCIN_CPU0
BG90 PVCCIN_CPU0 VCCIN11 @S9S_MB_2U_LIB.S9S_MB_2U(SCH_1):PVCCIN_CPU0
BG88 PVCCIN_CPU0 VCCIN10 @S9S_MB_2U_LIB.S9S_MB_2U(SCH_1):PVCCIN_CPU0
BG86 PVCCIN_CPU0 VCCIN9 @S9S_MB_2U_LIB.S9S_MB_2U(SCH_1):PVCCIN_CPU0
BG84 PVCCIN_CPU0 VCCIN8 @S9S_MB_2U_LIB.S9S_MB_2U(SCH_1):PVCCIN_CPU0
BF91 PVCCIN_CPU0 VCCIN7 @S9S_MB_2U_LIB.S9S_MB_2U(SCH_1):PVCCIN_CPU0
BF89 PVCCIN_CPU0 VCCIN6 @S9S_MB_2U_LIB.S9S_MB_2U(SCH_1):PVCCIN_CPU0
BF87 PVCCIN_CPU0 VCCIN5 @S9S_MB_2U_LIB.S9S_MB_2U(SCH_1):PVCCIN_CPU0
BF85 PVCCIN_CPU0 VCCIN4 @S9S_MB_2U_LIB.S9S_MB_2U(SCH_1):PVCCIN_CPU0
BE90 PVCCIN_CPU0 VCCIN3 @S9S_MB_2U_LIB.S9S_MB_2U(SCH_1):PVCCIN_CPU0
BE88 PVCCIN_CPU0 VCCIN2 @S9S_MB_2U_LIB.S9S_MB_2U(SCH_1):PVCCIN_CPU0
BE86 PVCCIN_CPU0 VCCIN1 @S9S_MB_2U_LIB.S9S_MB_2U(SCH_1):PVCCIN_CPU0
BD91 PVCCIN_CPU0 VCCIN0 @S9S_MB_2U_LIB.S9S_MB_2U(SCH_1):PVCCIN_CPU0
DA21 PVCCINFAON_CPU0 VCCINFAON53 @S9S_MB_2U_LIB.S9S_MB_2U(SCH_1):PVCCINFAON_CPU0
CW62 PVCCINFAON_CPU0 VCCINFAON52 @S9S_MB_2U_LIB.S9S_MB_2U(SCH_1):PVCCINFAON_CPU0
CV63 PVCCINFAON_CPU0 VCCINFAON51 @S9S_MB_2U_LIB.S9S_MB_2U(SCH_1):PVCCINFAON_CPU0
CV61 PVCCINFAON_CPU0 VCCINFAON50 @S9S_MB_2U_LIB.S9S_MB_2U(SCH_1):PVCCINFAON_CPU0
CT63 PVCCINFAON_CPU0 VCCINFAON49 @S9S_MB_2U_LIB.S9S_MB_2U(SCH_1):PVCCINFAON_CPU0
CP63 PVCCINFAON_CPU0 VCCINFAON48 @S9S_MB_2U_LIB.S9S_MB_2U(SCH_1):PVCCINFAON_CPU0
CN19 PVCCINFAON_CPU0 VCCINFAON47 @S9S_MB_2U_LIB.S9S_MB_2U(SCH_1):PVCCINFAON_CPU0
CJ19 PVCCINFAON_CPU0 VCCINFAON46 @S9S_MB_2U_LIB.S9S_MB_2U(SCH_1):PVCCINFAON_CPU0
CJ11 PVCCINFAON_CPU0 VCCINFAON45 @S9S_MB_2U_LIB.S9S_MB_2U(SCH_1):PVCCINFAON_CPU0
CE19 PVCCINFAON_CPU0 VCCINFAON44 @S9S_MB_2U_LIB.S9S_MB_2U(SCH_1):PVCCINFAON_CPU0
CA15 PVCCINFAON_CPU0 VCCINFAON43 @S9S_MB_2U_LIB.S9S_MB_2U(SCH_1):PVCCINFAON_CPU0
BN15 PVCCINFAON_CPU0 VCCINFAON42 @S9S_MB_2U_LIB.S9S_MB_2U(SCH_1):PVCCINFAON_CPU0
BK61 PVCCINFAON_CPU0 VCCINFAON41 @S9S_MB_2U_LIB.S9S_MB_2U(SCH_1):PVCCINFAON_CPU0
BJ60 PVCCINFAON_CPU0 VCCINFAON40 @S9S_MB_2U_LIB.S9S_MB_2U(SCH_1):PVCCINFAON_CPU0
BJ15 PVCCINFAON_CPU0 VCCINFAON39 @S9S_MB_2U_LIB.S9S_MB_2U(SCH_1):PVCCINFAON_CPU0
BG60 PVCCINFAON_CPU0 VCCINFAON38 @S9S_MB_2U_LIB.S9S_MB_2U(SCH_1):PVCCINFAON_CPU0
BE60 PVCCINFAON_CPU0 VCCINFAON37 @S9S_MB_2U_LIB.S9S_MB_2U(SCH_1):PVCCINFAON_CPU0
BE15 PVCCINFAON_CPU0 VCCINFAON36 @S9S_MB_2U_LIB.S9S_MB_2U(SCH_1):PVCCINFAON_CPU0
BC60 PVCCINFAON_CPU0 VCCINFAON35 @S9S_MB_2U_LIB.S9S_MB_2U(SCH_1):PVCCINFAON_CPU0
BA15 PVCCINFAON_CPU0 VCCINFAON34 @S9S_MB_2U_LIB.S9S_MB_2U(SCH_1):PVCCINFAON_CPU0
AY18 PVCCINFAON_CPU0 VCCINFAON33 @S9S_MB_2U_LIB.S9S_MB_2U(SCH_1):PVCCINFAON_CPU0

SOCKET4677_AZIF0045P001C01CS-SA  I8  U2
BC21 P3V3_AUX VCC_3P3_AUX0 @S9S_MB_2U_LIB.S9S_MB_2U(SCH_1):P3V3_AUX
BA21 P3V3_AUX VCC_3P3_AUX1 @S9S_MB_2U_LIB.S9S_MB_2U(SCH_1):P3V3_AUX
CY53 PVCCD_HV_CPU0 VCCD_HV28 @S9S_MB_2U_LIB.S9S_MB_2U(SCH_1):PVCCD_HV_CPU0
CY36 PVCCD_HV_CPU0 VCCD_HV27 @S9S_MB_2U_LIB.S9S_MB_2U(SCH_1):PVCCD_HV_CPU0
CW54 PVCCD_HV_CPU0 VCCD_HV24 @S9S_MB_2U_LIB.S9S_MB_2U(SCH_1):PVCCD_HV_CPU0
CY34 PVCCD_HV_CPU0 VCCD_HV26 @S9S_MB_2U_LIB.S9S_MB_2U(SCH_1):PVCCD_HV_CPU0
CW56 PVCCD_HV_CPU0 VCCD_HV25 @S9S_MB_2U_LIB.S9S_MB_2U(SCH_1):PVCCD_HV_CPU0
CW52 PVCCD_HV_CPU0 VCCD_HV23 @S9S_MB_2U_LIB.S9S_MB_2U(SCH_1):PVCCD_HV_CPU0
CW37 PVCCD_HV_CPU0 VCCD_HV22 @S9S_MB_2U_LIB.S9S_MB_2U(SCH_1):PVCCD_HV_CPU0
CW35 PVCCD_HV_CPU0 VCCD_HV21 @S9S_MB_2U_LIB.S9S_MB_2U(SCH_1):PVCCD_HV_CPU0
 CE7 PVCCD_HV_CPU0 VCCD_HV20 @S9S_MB_2U_LIB.S9S_MB_2U(SCH_1):PVCCD_HV_CPU0
 CA7 PVCCD_HV_CPU0 VCCD_HV19 @S9S_MB_2U_LIB.S9S_MB_2U(SCH_1):PVCCD_HV_CPU0
 BN7 PVCCD_HV_CPU0 VCCD_HV18 @S9S_MB_2U_LIB.S9S_MB_2U(SCH_1):PVCCD_HV_CPU0
 BJ7 PVCCD_HV_CPU0 VCCD_HV17 @S9S_MB_2U_LIB.S9S_MB_2U(SCH_1):PVCCD_HV_CPU0
 BJ3 PVCCD_HV_CPU0 VCCD_HV16 @S9S_MB_2U_LIB.S9S_MB_2U(SCH_1):PVCCD_HV_CPU0
BJ11 PVCCD_HV_CPU0 VCCD_HV15 @S9S_MB_2U_LIB.S9S_MB_2U(SCH_1):PVCCD_HV_CPU0
 BE7 PVCCD_HV_CPU0 VCCD_HV14 @S9S_MB_2U_LIB.S9S_MB_2U(SCH_1):PVCCD_HV_CPU0
 BE3 PVCCD_HV_CPU0 VCCD_HV13 @S9S_MB_2U_LIB.S9S_MB_2U(SCH_1):PVCCD_HV_CPU0
BE11 PVCCD_HV_CPU0 VCCD_HV12 @S9S_MB_2U_LIB.S9S_MB_2U(SCH_1):PVCCD_HV_CPU0
 BA7 PVCCD_HV_CPU0 VCCD_HV11 @S9S_MB_2U_LIB.S9S_MB_2U(SCH_1):PVCCD_HV_CPU0
 BA3 PVCCD_HV_CPU0 VCCD_HV10 @S9S_MB_2U_LIB.S9S_MB_2U(SCH_1):PVCCD_HV_CPU0
AV55 PVCCD_HV_CPU0 VCCD_HV9 @S9S_MB_2U_LIB.S9S_MB_2U(SCH_1):PVCCD_HV_CPU0
AV53 PVCCD_HV_CPU0 VCCD_HV8 @S9S_MB_2U_LIB.S9S_MB_2U(SCH_1):PVCCD_HV_CPU0
AV36 PVCCD_HV_CPU0 VCCD_HV7 @S9S_MB_2U_LIB.S9S_MB_2U(SCH_1):PVCCD_HV_CPU0
AV34 PVCCD_HV_CPU0 VCCD_HV6 @S9S_MB_2U_LIB.S9S_MB_2U(SCH_1):PVCCD_HV_CPU0
 AU7 PVCCD_HV_CPU0 VCCD_HV5 @S9S_MB_2U_LIB.S9S_MB_2U(SCH_1):PVCCD_HV_CPU0
AU54 PVCCD_HV_CPU0 VCCD_HV4 @S9S_MB_2U_LIB.S9S_MB_2U(SCH_1):PVCCD_HV_CPU0
AU35 PVCCD_HV_CPU0 VCCD_HV3 @S9S_MB_2U_LIB.S9S_MB_2U(SCH_1):PVCCD_HV_CPU0
 AU3 PVCCD_HV_CPU0 VCCD_HV2 @S9S_MB_2U_LIB.S9S_MB_2U(SCH_1):PVCCD_HV_CPU0
AT55 PVCCD_HV_CPU0 VCCD_HV1 @S9S_MB_2U_LIB.S9S_MB_2U(SCH_1):PVCCD_HV_CPU0
AT36 PVCCD_HV_CPU0 VCCD_HV0 @S9S_MB_2U_LIB.S9S_MB_2U(SCH_1):PVCCD_HV_CPU0
  N3 PVCCFA_EHV_CPU0 VCCFA_EHV8 @S9S_MB_2U_LIB.S9S_MB_2U(SCH_1):PVCCFA_EHV_CPU0
  U3 PVCCFA_EHV_CPU0 VCCFA_EHV9 @S9S_MB_2U_LIB.S9S_MB_2U(SCH_1):PVCCFA_EHV_CPU0
AW60 PVCCFA_EHV_CPU0 VCCFA_EHV7 @S9S_MB_2U_LIB.S9S_MB_2U(SCH_1):PVCCFA_EHV_CPU0
AV61 PVCCFA_EHV_CPU0 VCCFA_EHV6 @S9S_MB_2U_LIB.S9S_MB_2U(SCH_1):PVCCFA_EHV_CPU0
AU60 PVCCFA_EHV_CPU0 VCCFA_EHV5 @S9S_MB_2U_LIB.S9S_MB_2U(SCH_1):PVCCFA_EHV_CPU0
AT61 PVCCFA_EHV_CPU0 VCCFA_EHV4 @S9S_MB_2U_LIB.S9S_MB_2U(SCH_1):PVCCFA_EHV_CPU0
 AN3 PVCCFA_EHV_CPU0 VCCFA_EHV3 @S9S_MB_2U_LIB.S9S_MB_2U(SCH_1):PVCCFA_EHV_CPU0
 AJ3 PVCCFA_EHV_CPU0 VCCFA_EHV2 @S9S_MB_2U_LIB.S9S_MB_2U(SCH_1):PVCCFA_EHV_CPU0
 AE3 PVCCFA_EHV_CPU0 VCCFA_EHV1 @S9S_MB_2U_LIB.S9S_MB_2U(SCH_1):PVCCFA_EHV_CPU0
 AA3 PVCCFA_EHV_CPU0 VCCFA_EHV0 @S9S_MB_2U_LIB.S9S_MB_2U(SCH_1):PVCCFA_EHV_CPU0
DJ11 PVCCINFAON_CPU0 VCCINFAON59 @S9S_MB_2U_LIB.S9S_MB_2U(SCH_1):PVCCINFAON_CPU0
 DE7 PVCCINFAON_CPU0 VCCINFAON58 @S9S_MB_2U_LIB.S9S_MB_2U(SCH_1):PVCCINFAON_CPU0
 DA7 PVCCINFAON_CPU0 VCCINFAON57 @S9S_MB_2U_LIB.S9S_MB_2U(SCH_1):PVCCINFAON_CPU0
 DA3 PVCCINFAON_CPU0 VCCINFAON56 @S9S_MB_2U_LIB.S9S_MB_2U(SCH_1):PVCCINFAON_CPU0
CW64 PVCCINFAON_CPU0 VCCINFAON55 @S9S_MB_2U_LIB.S9S_MB_2U(SCH_1):PVCCINFAON_CPU0
CR66 PVCCINFAON_CPU0 VCCINFAON54 @S9S_MB_2U_LIB.S9S_MB_2U(SCH_1):PVCCINFAON_CPU0
 DJ7 PVCCINFAON_CPU0 VCCINFAON32 @S9S_MB_2U_LIB.S9S_MB_2U(SCH_1):PVCCINFAON_CPU0
 DJ3 PVCCINFAON_CPU0 VCCINFAON31 @S9S_MB_2U_LIB.S9S_MB_2U(SCH_1):PVCCINFAON_CPU0
DJ15 PVCCINFAON_CPU0 VCCINFAON30 @S9S_MB_2U_LIB.S9S_MB_2U(SCH_1):PVCCINFAON_CPU0
 DE3 PVCCINFAON_CPU0 VCCINFAON29 @S9S_MB_2U_LIB.S9S_MB_2U(SCH_1):PVCCINFAON_CPU0
DE15 PVCCINFAON_CPU0 VCCINFAON28 @S9S_MB_2U_LIB.S9S_MB_2U(SCH_1):PVCCINFAON_CPU0
DE11 PVCCINFAON_CPU0 VCCINFAON27 @S9S_MB_2U_LIB.S9S_MB_2U(SCH_1):PVCCINFAON_CPU0
DA64 PVCCINFAON_CPU0 VCCINFAON26 @S9S_MB_2U_LIB.S9S_MB_2U(SCH_1):PVCCINFAON_CPU0
DA15 PVCCINFAON_CPU0 VCCINFAON25 @S9S_MB_2U_LIB.S9S_MB_2U(SCH_1):PVCCINFAON_CPU0
DA11 PVCCINFAON_CPU0 VCCINFAON24 @S9S_MB_2U_LIB.S9S_MB_2U(SCH_1):PVCCINFAON_CPU0
CY67 PVCCINFAON_CPU0 VCCINFAON23 @S9S_MB_2U_LIB.S9S_MB_2U(SCH_1):PVCCINFAON_CPU0
CY65 PVCCINFAON_CPU0 VCCINFAON22 @S9S_MB_2U_LIB.S9S_MB_2U(SCH_1):PVCCINFAON_CPU0
CW66 PVCCINFAON_CPU0 VCCINFAON21 @S9S_MB_2U_LIB.S9S_MB_2U(SCH_1):PVCCINFAON_CPU0
CV67 PVCCINFAON_CPU0 VCCINFAON20 @S9S_MB_2U_LIB.S9S_MB_2U(SCH_1):PVCCINFAON_CPU0
CV65 PVCCINFAON_CPU0 VCCINFAON19 @S9S_MB_2U_LIB.S9S_MB_2U(SCH_1):PVCCINFAON_CPU0
 CU7 PVCCINFAON_CPU0 VCCINFAON18 @S9S_MB_2U_LIB.S9S_MB_2U(SCH_1):PVCCINFAON_CPU0
CU64 PVCCINFAON_CPU0 VCCINFAON17 @S9S_MB_2U_LIB.S9S_MB_2U(SCH_1):PVCCINFAON_CPU0
 CU3 PVCCINFAON_CPU0 VCCINFAON16 @S9S_MB_2U_LIB.S9S_MB_2U(SCH_1):PVCCINFAON_CPU0
CU15 PVCCINFAON_CPU0 VCCINFAON15 @S9S_MB_2U_LIB.S9S_MB_2U(SCH_1):PVCCINFAON_CPU0
CU11 PVCCINFAON_CPU0 VCCINFAON14 @S9S_MB_2U_LIB.S9S_MB_2U(SCH_1):PVCCINFAON_CPU0
CT67 PVCCINFAON_CPU0 VCCINFAON13 @S9S_MB_2U_LIB.S9S_MB_2U(SCH_1):PVCCINFAON_CPU0
CT65 PVCCINFAON_CPU0 VCCINFAON12 @S9S_MB_2U_LIB.S9S_MB_2U(SCH_1):PVCCINFAON_CPU0
CP67 PVCCINFAON_CPU0 VCCINFAON11 @S9S_MB_2U_LIB.S9S_MB_2U(SCH_1):PVCCINFAON_CPU0
CP65 PVCCINFAON_CPU0 VCCINFAON10 @S9S_MB_2U_LIB.S9S_MB_2U(SCH_1):PVCCINFAON_CPU0
 CN7 PVCCINFAON_CPU0 VCCINFAON9 @S9S_MB_2U_LIB.S9S_MB_2U(SCH_1):PVCCINFAON_CPU0
CN66 PVCCINFAON_CPU0 VCCINFAON8 @S9S_MB_2U_LIB.S9S_MB_2U(SCH_1):PVCCINFAON_CPU0
CN64 PVCCINFAON_CPU0 VCCINFAON7 @S9S_MB_2U_LIB.S9S_MB_2U(SCH_1):PVCCINFAON_CPU0
 CN3 PVCCINFAON_CPU0 VCCINFAON6 @S9S_MB_2U_LIB.S9S_MB_2U(SCH_1):PVCCINFAON_CPU0
CN15 PVCCINFAON_CPU0 VCCINFAON5 @S9S_MB_2U_LIB.S9S_MB_2U(SCH_1):PVCCINFAON_CPU0
CN11 PVCCINFAON_CPU0 VCCINFAON4 @S9S_MB_2U_LIB.S9S_MB_2U(SCH_1):PVCCINFAON_CPU0
 CJ7 PVCCINFAON_CPU0 VCCINFAON3 @S9S_MB_2U_LIB.S9S_MB_2U(SCH_1):PVCCINFAON_CPU0
 CJ3 PVCCINFAON_CPU0 VCCINFAON2 @S9S_MB_2U_LIB.S9S_MB_2U(SCH_1):PVCCINFAON_CPU0
CJ15 PVCCINFAON_CPU0 VCCINFAON1 @S9S_MB_2U_LIB.S9S_MB_2U(SCH_1):PVCCINFAON_CPU0
CE15 PVCCINFAON_CPU0 VCCINFAON0 @S9S_MB_2U_LIB.S9S_MB_2U(SCH_1):PVCCINFAON_CPU0
BN19 PVNN_MAIN_CPU0 VCCVNN3 @S9S_MB_2U_LIB.S9S_MB_2U(SCH_1):PVNN_MAIN_CPU0
BJ19 PVNN_MAIN_CPU0 VCCVNN2 @S9S_MB_2U_LIB.S9S_MB_2U(SCH_1):PVNN_MAIN_CPU0
BE19 PVNN_MAIN_CPU0 VCCVNN1 @S9S_MB_2U_LIB.S9S_MB_2U(SCH_1):PVNN_MAIN_CPU0
BA19 PVNN_MAIN_CPU0 VCCVNN0 @S9S_MB_2U_LIB.S9S_MB_2U(SCH_1):PVNN_MAIN_CPU0
CG68 PVPP_HBM_CPU0 VPP_HBM @S9S_MB_2U_LIB.S9S_MB_2U(SCH_1):PVPP_HBM_CPU0
CF67 PVPP_HBM_CPU0 VPP_HBM1 @S9S_MB_2U_LIB.S9S_MB_2U(SCH_1):PVPP_HBM_CPU0
CE68 PVPP_HBM_CPU0 VPP_HBM2 @S9S_MB_2U_LIB.S9S_MB_2U(SCH_1):PVPP_HBM_CPU0
CD67 PVPP_HBM_CPU0 VPP_HBM3 @S9S_MB_2U_LIB.S9S_MB_2U(SCH_1):PVPP_HBM_CPU0
CC68 PVPP_HBM_CPU0 VPP_HBM4 @S9S_MB_2U_LIB.S9S_MB_2U(SCH_1):PVPP_HBM_CPU0

Q_CAP_C0402-10UF,6.3V,20%,X6S,A  I15  C1
   1 P3V3_AUX      A @S9S_MB_2U_LIB.S9S_MB_2U(SCH_1):P3V3_AUX
   2    GND      B @S9S_MB_2U_LIB.S9S_MB_2U(SCH_1):GND


DRAWING: @S9S_MB_2U_LIB.S9S_MB_2U(SCH_1):PAGE38 

SOCKET4677_AZIF0045P001C01CS-SA  I4  U2
 Y89 PVCCFA_EHV_FIVRA_CPU0 VCCFA_EHV_FIVRA104 @S9S_MB_2U_LIB.S9S_MB_2U(SCH_1):PVCCFA_EHV_FIVRA_CPU0
 Y85 PVCCFA_EHV_FIVRA_CPU0 VCCFA_EHV_FIVRA103 @S9S_MB_2U_LIB.S9S_MB_2U(SCH_1):PVCCFA_EHV_FIVRA_CPU0
 Y79 PVCCFA_EHV_FIVRA_CPU0 VCCFA_EHV_FIVRA102 @S9S_MB_2U_LIB.S9S_MB_2U(SCH_1):PVCCFA_EHV_FIVRA_CPU0
 W80 PVCCFA_EHV_FIVRA_CPU0 VCCFA_EHV_FIVRA101 @S9S_MB_2U_LIB.S9S_MB_2U(SCH_1):PVCCFA_EHV_FIVRA_CPU0
  U7 PVCCFA_EHV_FIVRA_CPU0 VCCFA_EHV_FIVRA100 @S9S_MB_2U_LIB.S9S_MB_2U(SCH_1):PVCCFA_EHV_FIVRA_CPU0
 U15 PVCCFA_EHV_FIVRA_CPU0 VCCFA_EHV_FIVRA99 @S9S_MB_2U_LIB.S9S_MB_2U(SCH_1):PVCCFA_EHV_FIVRA_CPU0
 U11 PVCCFA_EHV_FIVRA_CPU0 VCCFA_EHV_FIVRA98 @S9S_MB_2U_LIB.S9S_MB_2U(SCH_1):PVCCFA_EHV_FIVRA_CPU0
 T89 PVCCFA_EHV_FIVRA_CPU0 VCCFA_EHV_FIVRA97 @S9S_MB_2U_LIB.S9S_MB_2U(SCH_1):PVCCFA_EHV_FIVRA_CPU0
 T85 PVCCFA_EHV_FIVRA_CPU0 VCCFA_EHV_FIVRA96 @S9S_MB_2U_LIB.S9S_MB_2U(SCH_1):PVCCFA_EHV_FIVRA_CPU0
 R80 PVCCFA_EHV_FIVRA_CPU0 VCCFA_EHV_FIVRA95 @S9S_MB_2U_LIB.S9S_MB_2U(SCH_1):PVCCFA_EHV_FIVRA_CPU0
 P79 PVCCFA_EHV_FIVRA_CPU0 VCCFA_EHV_FIVRA94 @S9S_MB_2U_LIB.S9S_MB_2U(SCH_1):PVCCFA_EHV_FIVRA_CPU0
  N7 PVCCFA_EHV_FIVRA_CPU0 VCCFA_EHV_FIVRA93 @S9S_MB_2U_LIB.S9S_MB_2U(SCH_1):PVCCFA_EHV_FIVRA_CPU0
 N11 PVCCFA_EHV_FIVRA_CPU0 VCCFA_EHV_FIVRA92 @S9S_MB_2U_LIB.S9S_MB_2U(SCH_1):PVCCFA_EHV_FIVRA_CPU0
 M89 PVCCFA_EHV_FIVRA_CPU0 VCCFA_EHV_FIVRA91 @S9S_MB_2U_LIB.S9S_MB_2U(SCH_1):PVCCFA_EHV_FIVRA_CPU0
 M85 PVCCFA_EHV_FIVRA_CPU0 VCCFA_EHV_FIVRA90 @S9S_MB_2U_LIB.S9S_MB_2U(SCH_1):PVCCFA_EHV_FIVRA_CPU0
 L84 PVCCFA_EHV_FIVRA_CPU0 VCCFA_EHV_FIVRA89 @S9S_MB_2U_LIB.S9S_MB_2U(SCH_1):PVCCFA_EHV_FIVRA_CPU0
 K87 PVCCFA_EHV_FIVRA_CPU0 VCCFA_EHV_FIVRA88 @S9S_MB_2U_LIB.S9S_MB_2U(SCH_1):PVCCFA_EHV_FIVRA_CPU0
 J80 PVCCFA_EHV_FIVRA_CPU0 VCCFA_EHV_FIVRA87 @S9S_MB_2U_LIB.S9S_MB_2U(SCH_1):PVCCFA_EHV_FIVRA_CPU0
  J7 PVCCFA_EHV_FIVRA_CPU0 VCCFA_EHV_FIVRA86 @S9S_MB_2U_LIB.S9S_MB_2U(SCH_1):PVCCFA_EHV_FIVRA_CPU0
 J11 PVCCFA_EHV_FIVRA_CPU0 VCCFA_EHV_FIVRA85 @S9S_MB_2U_LIB.S9S_MB_2U(SCH_1):PVCCFA_EHV_FIVRA_CPU0
 H89 PVCCFA_EHV_FIVRA_CPU0 VCCFA_EHV_FIVRA84 @S9S_MB_2U_LIB.S9S_MB_2U(SCH_1):PVCCFA_EHV_FIVRA_CPU0
EN84 PVCCFA_EHV_FIVRA_CPU0 VCCFA_EHV_FIVRA83 @S9S_MB_2U_LIB.S9S_MB_2U(SCH_1):PVCCFA_EHV_FIVRA_CPU0
EJ84 PVCCFA_EHV_FIVRA_CPU0 VCCFA_EHV_FIVRA82 @S9S_MB_2U_LIB.S9S_MB_2U(SCH_1):PVCCFA_EHV_FIVRA_CPU0
EJ15 PVCCFA_EHV_FIVRA_CPU0 VCCFA_EHV_FIVRA81 @S9S_MB_2U_LIB.S9S_MB_2U(SCH_1):PVCCFA_EHV_FIVRA_CPU0
EG80 PVCCFA_EHV_FIVRA_CPU0 VCCFA_EHV_FIVRA80 @S9S_MB_2U_LIB.S9S_MB_2U(SCH_1):PVCCFA_EHV_FIVRA_CPU0
EF79 PVCCFA_EHV_FIVRA_CPU0 VCCFA_EHV_FIVRA79 @S9S_MB_2U_LIB.S9S_MB_2U(SCH_1):PVCCFA_EHV_FIVRA_CPU0
EE84 PVCCFA_EHV_FIVRA_CPU0 VCCFA_EHV_FIVRA78 @S9S_MB_2U_LIB.S9S_MB_2U(SCH_1):PVCCFA_EHV_FIVRA_CPU0
 EE7 PVCCFA_EHV_FIVRA_CPU0 VCCFA_EHV_FIVRA77 @S9S_MB_2U_LIB.S9S_MB_2U(SCH_1):PVCCFA_EHV_FIVRA_CPU0
EE15 PVCCFA_EHV_FIVRA_CPU0 VCCFA_EHV_FIVRA76 @S9S_MB_2U_LIB.S9S_MB_2U(SCH_1):PVCCFA_EHV_FIVRA_CPU0
EE11 PVCCFA_EHV_FIVRA_CPU0 VCCFA_EHV_FIVRA75 @S9S_MB_2U_LIB.S9S_MB_2U(SCH_1):PVCCFA_EHV_FIVRA_CPU0
ED89 PVCCFA_EHV_FIVRA_CPU0 VCCFA_EHV_FIVRA74 @S9S_MB_2U_LIB.S9S_MB_2U(SCH_1):PVCCFA_EHV_FIVRA_CPU0
ED85 PVCCFA_EHV_FIVRA_CPU0 VCCFA_EHV_FIVRA73 @S9S_MB_2U_LIB.S9S_MB_2U(SCH_1):PVCCFA_EHV_FIVRA_CPU0
ED79 PVCCFA_EHV_FIVRA_CPU0 VCCFA_EHV_FIVRA72 @S9S_MB_2U_LIB.S9S_MB_2U(SCH_1):PVCCFA_EHV_FIVRA_CPU0
EC78 PVCCFA_EHV_FIVRA_CPU0 VCCFA_EHV_FIVRA71 @S9S_MB_2U_LIB.S9S_MB_2U(SCH_1):PVCCFA_EHV_FIVRA_CPU0
 EA7 PVCCFA_EHV_FIVRA_CPU0 VCCFA_EHV_FIVRA70 @S9S_MB_2U_LIB.S9S_MB_2U(SCH_1):PVCCFA_EHV_FIVRA_CPU0
 EA3 PVCCFA_EHV_FIVRA_CPU0 VCCFA_EHV_FIVRA69 @S9S_MB_2U_LIB.S9S_MB_2U(SCH_1):PVCCFA_EHV_FIVRA_CPU0
EA15 PVCCFA_EHV_FIVRA_CPU0 VCCFA_EHV_FIVRA68 @S9S_MB_2U_LIB.S9S_MB_2U(SCH_1):PVCCFA_EHV_FIVRA_CPU0
EA11 PVCCFA_EHV_FIVRA_CPU0 VCCFA_EHV_FIVRA67 @S9S_MB_2U_LIB.S9S_MB_2U(SCH_1):PVCCFA_EHV_FIVRA_CPU0
DY89 PVCCFA_EHV_FIVRA_CPU0 VCCFA_EHV_FIVRA66 @S9S_MB_2U_LIB.S9S_MB_2U(SCH_1):PVCCFA_EHV_FIVRA_CPU0
DY85 PVCCFA_EHV_FIVRA_CPU0 VCCFA_EHV_FIVRA65 @S9S_MB_2U_LIB.S9S_MB_2U(SCH_1):PVCCFA_EHV_FIVRA_CPU0
 DU7 PVCCFA_EHV_FIVRA_CPU0 VCCFA_EHV_FIVRA64 @S9S_MB_2U_LIB.S9S_MB_2U(SCH_1):PVCCFA_EHV_FIVRA_CPU0
 DU3 PVCCFA_EHV_FIVRA_CPU0 VCCFA_EHV_FIVRA63 @S9S_MB_2U_LIB.S9S_MB_2U(SCH_1):PVCCFA_EHV_FIVRA_CPU0
DU15 PVCCFA_EHV_FIVRA_CPU0 VCCFA_EHV_FIVRA62 @S9S_MB_2U_LIB.S9S_MB_2U(SCH_1):PVCCFA_EHV_FIVRA_CPU0
DU11 PVCCFA_EHV_FIVRA_CPU0 VCCFA_EHV_FIVRA61 @S9S_MB_2U_LIB.S9S_MB_2U(SCH_1):PVCCFA_EHV_FIVRA_CPU0
DT89 PVCCFA_EHV_FIVRA_CPU0 VCCFA_EHV_FIVRA60 @S9S_MB_2U_LIB.S9S_MB_2U(SCH_1):PVCCFA_EHV_FIVRA_CPU0
DT85 PVCCFA_EHV_FIVRA_CPU0 VCCFA_EHV_FIVRA59 @S9S_MB_2U_LIB.S9S_MB_2U(SCH_1):PVCCFA_EHV_FIVRA_CPU0
DT79 PVCCFA_EHV_FIVRA_CPU0 VCCFA_EHV_FIVRA58 @S9S_MB_2U_LIB.S9S_MB_2U(SCH_1):PVCCFA_EHV_FIVRA_CPU0
 DN7 PVCCFA_EHV_FIVRA_CPU0 VCCFA_EHV_FIVRA57 @S9S_MB_2U_LIB.S9S_MB_2U(SCH_1):PVCCFA_EHV_FIVRA_CPU0
 DN3 PVCCFA_EHV_FIVRA_CPU0 VCCFA_EHV_FIVRA56 @S9S_MB_2U_LIB.S9S_MB_2U(SCH_1):PVCCFA_EHV_FIVRA_CPU0
DN15 PVCCFA_EHV_FIVRA_CPU0 VCCFA_EHV_FIVRA55 @S9S_MB_2U_LIB.S9S_MB_2U(SCH_1):PVCCFA_EHV_FIVRA_CPU0
DN11 PVCCFA_EHV_FIVRA_CPU0 VCCFA_EHV_FIVRA54 @S9S_MB_2U_LIB.S9S_MB_2U(SCH_1):PVCCFA_EHV_FIVRA_CPU0
DM89 PVCCFA_EHV_FIVRA_CPU0 VCCFA_EHV_FIVRA53 @S9S_MB_2U_LIB.S9S_MB_2U(SCH_1):PVCCFA_EHV_FIVRA_CPU0
DM85 PVCCFA_EHV_FIVRA_CPU0 VCCFA_EHV_FIVRA52 @S9S_MB_2U_LIB.S9S_MB_2U(SCH_1):PVCCFA_EHV_FIVRA_CPU0
DM83 PVCCFA_EHV_FIVRA_CPU0 VCCFA_EHV_FIVRA51 @S9S_MB_2U_LIB.S9S_MB_2U(SCH_1):PVCCFA_EHV_FIVRA_CPU0
DH89 PVCCFA_EHV_FIVRA_CPU0 VCCFA_EHV_FIVRA50 @S9S_MB_2U_LIB.S9S_MB_2U(SCH_1):PVCCFA_EHV_FIVRA_CPU0
DD89 PVCCFA_EHV_FIVRA_CPU0 VCCFA_EHV_FIVRA49 @S9S_MB_2U_LIB.S9S_MB_2U(SCH_1):PVCCFA_EHV_FIVRA_CPU0
DD85 PVCCFA_EHV_FIVRA_CPU0 VCCFA_EHV_FIVRA48 @S9S_MB_2U_LIB.S9S_MB_2U(SCH_1):PVCCFA_EHV_FIVRA_CPU0
DD83 PVCCFA_EHV_FIVRA_CPU0 VCCFA_EHV_FIVRA47 @S9S_MB_2U_LIB.S9S_MB_2U(SCH_1):PVCCFA_EHV_FIVRA_CPU0
DD77 PVCCFA_EHV_FIVRA_CPU0 VCCFA_EHV_FIVRA46 @S9S_MB_2U_LIB.S9S_MB_2U(SCH_1):PVCCFA_EHV_FIVRA_CPU0
CY89 PVCCFA_EHV_FIVRA_CPU0 VCCFA_EHV_FIVRA45 @S9S_MB_2U_LIB.S9S_MB_2U(SCH_1):PVCCFA_EHV_FIVRA_CPU0
CY85 PVCCFA_EHV_FIVRA_CPU0 VCCFA_EHV_FIVRA44 @S9S_MB_2U_LIB.S9S_MB_2U(SCH_1):PVCCFA_EHV_FIVRA_CPU0
CY79 PVCCFA_EHV_FIVRA_CPU0 VCCFA_EHV_FIVRA43 @S9S_MB_2U_LIB.S9S_MB_2U(SCH_1):PVCCFA_EHV_FIVRA_CPU0
CY75 PVCCFA_EHV_FIVRA_CPU0 VCCFA_EHV_FIVRA42 @S9S_MB_2U_LIB.S9S_MB_2U(SCH_1):PVCCFA_EHV_FIVRA_CPU0
CT85 PVCCFA_EHV_FIVRA_CPU0 VCCFA_EHV_FIVRA41 @S9S_MB_2U_LIB.S9S_MB_2U(SCH_1):PVCCFA_EHV_FIVRA_CPU0
CT77 PVCCFA_EHV_FIVRA_CPU0 VCCFA_EHV_FIVRA40 @S9S_MB_2U_LIB.S9S_MB_2U(SCH_1):PVCCFA_EHV_FIVRA_CPU0
CP73 PVCCFA_EHV_FIVRA_CPU0 VCCFA_EHV_FIVRA39 @S9S_MB_2U_LIB.S9S_MB_2U(SCH_1):PVCCFA_EHV_FIVRA_CPU0
CN78 PVCCFA_EHV_FIVRA_CPU0 VCCFA_EHV_FIVRA38 @S9S_MB_2U_LIB.S9S_MB_2U(SCH_1):PVCCFA_EHV_FIVRA_CPU0
CM73 PVCCFA_EHV_FIVRA_CPU0 VCCFA_EHV_FIVRA37 @S9S_MB_2U_LIB.S9S_MB_2U(SCH_1):PVCCFA_EHV_FIVRA_CPU0
CK79 PVCCFA_EHV_FIVRA_CPU0 VCCFA_EHV_FIVRA36 @S9S_MB_2U_LIB.S9S_MB_2U(SCH_1):PVCCFA_EHV_FIVRA_CPU0
CK73 PVCCFA_EHV_FIVRA_CPU0 VCCFA_EHV_FIVRA35 @S9S_MB_2U_LIB.S9S_MB_2U(SCH_1):PVCCFA_EHV_FIVRA_CPU0
CE74 PVCCFA_EHV_FIVRA_CPU0 VCCFA_EHV_FIVRA34 @S9S_MB_2U_LIB.S9S_MB_2U(SCH_1):PVCCFA_EHV_FIVRA_CPU0
 C88 PVCCFA_EHV_FIVRA_CPU0 VCCFA_EHV_FIVRA33 @S9S_MB_2U_LIB.S9S_MB_2U(SCH_1):PVCCFA_EHV_FIVRA_CPU0
 C84 PVCCFA_EHV_FIVRA_CPU0 VCCFA_EHV_FIVRA32 @S9S_MB_2U_LIB.S9S_MB_2U(SCH_1):PVCCFA_EHV_FIVRA_CPU0
BJ78 PVCCFA_EHV_FIVRA_CPU0 VCCFA_EHV_FIVRA31 @S9S_MB_2U_LIB.S9S_MB_2U(SCH_1):PVCCFA_EHV_FIVRA_CPU0
BJ72 PVCCFA_EHV_FIVRA_CPU0 VCCFA_EHV_FIVRA30 @S9S_MB_2U_LIB.S9S_MB_2U(SCH_1):PVCCFA_EHV_FIVRA_CPU0
BH79 PVCCFA_EHV_FIVRA_CPU0 VCCFA_EHV_FIVRA29 @S9S_MB_2U_LIB.S9S_MB_2U(SCH_1):PVCCFA_EHV_FIVRA_CPU0
BF77 PVCCFA_EHV_FIVRA_CPU0 VCCFA_EHV_FIVRA28 @S9S_MB_2U_LIB.S9S_MB_2U(SCH_1):PVCCFA_EHV_FIVRA_CPU0
BE72 PVCCFA_EHV_FIVRA_CPU0 VCCFA_EHV_FIVRA27 @S9S_MB_2U_LIB.S9S_MB_2U(SCH_1):PVCCFA_EHV_FIVRA_CPU0
AY89 PVCCFA_EHV_FIVRA_CPU0 VCCFA_EHV_FIVRA26 @S9S_MB_2U_LIB.S9S_MB_2U(SCH_1):PVCCFA_EHV_FIVRA_CPU0
AW76 PVCCFA_EHV_FIVRA_CPU0 VCCFA_EHV_FIVRA25 @S9S_MB_2U_LIB.S9S_MB_2U(SCH_1):PVCCFA_EHV_FIVRA_CPU0
AU15 PVCCFA_EHV_FIVRA_CPU0 VCCFA_EHV_FIVRA24 @S9S_MB_2U_LIB.S9S_MB_2U(SCH_1):PVCCFA_EHV_FIVRA_CPU0
AT89 PVCCFA_EHV_FIVRA_CPU0 VCCFA_EHV_FIVRA23 @S9S_MB_2U_LIB.S9S_MB_2U(SCH_1):PVCCFA_EHV_FIVRA_CPU0
AT73 PVCCFA_EHV_FIVRA_CPU0 VCCFA_EHV_FIVRA22 @S9S_MB_2U_LIB.S9S_MB_2U(SCH_1):PVCCFA_EHV_FIVRA_CPU0
AN80 PVCCFA_EHV_FIVRA_CPU0 VCCFA_EHV_FIVRA21 @S9S_MB_2U_LIB.S9S_MB_2U(SCH_1):PVCCFA_EHV_FIVRA_CPU0
 AN7 PVCCFA_EHV_FIVRA_CPU0 VCCFA_EHV_FIVRA20 @S9S_MB_2U_LIB.S9S_MB_2U(SCH_1):PVCCFA_EHV_FIVRA_CPU0
AN15 PVCCFA_EHV_FIVRA_CPU0 VCCFA_EHV_FIVRA19 @S9S_MB_2U_LIB.S9S_MB_2U(SCH_1):PVCCFA_EHV_FIVRA_CPU0
AN11 PVCCFA_EHV_FIVRA_CPU0 VCCFA_EHV_FIVRA18 @S9S_MB_2U_LIB.S9S_MB_2U(SCH_1):PVCCFA_EHV_FIVRA_CPU0
AM89 PVCCFA_EHV_FIVRA_CPU0 VCCFA_EHV_FIVRA17 @S9S_MB_2U_LIB.S9S_MB_2U(SCH_1):PVCCFA_EHV_FIVRA_CPU0
AM85 PVCCFA_EHV_FIVRA_CPU0 VCCFA_EHV_FIVRA16 @S9S_MB_2U_LIB.S9S_MB_2U(SCH_1):PVCCFA_EHV_FIVRA_CPU0
AM79 PVCCFA_EHV_FIVRA_CPU0 VCCFA_EHV_FIVRA15 @S9S_MB_2U_LIB.S9S_MB_2U(SCH_1):PVCCFA_EHV_FIVRA_CPU0
 AJ7 PVCCFA_EHV_FIVRA_CPU0 VCCFA_EHV_FIVRA14 @S9S_MB_2U_LIB.S9S_MB_2U(SCH_1):PVCCFA_EHV_FIVRA_CPU0
AJ15 PVCCFA_EHV_FIVRA_CPU0 VCCFA_EHV_FIVRA13 @S9S_MB_2U_LIB.S9S_MB_2U(SCH_1):PVCCFA_EHV_FIVRA_CPU0
AJ11 PVCCFA_EHV_FIVRA_CPU0 VCCFA_EHV_FIVRA12 @S9S_MB_2U_LIB.S9S_MB_2U(SCH_1):PVCCFA_EHV_FIVRA_CPU0
AH89 PVCCFA_EHV_FIVRA_CPU0 VCCFA_EHV_FIVRA11 @S9S_MB_2U_LIB.S9S_MB_2U(SCH_1):PVCCFA_EHV_FIVRA_CPU0
AH85 PVCCFA_EHV_FIVRA_CPU0 VCCFA_EHV_FIVRA10 @S9S_MB_2U_LIB.S9S_MB_2U(SCH_1):PVCCFA_EHV_FIVRA_CPU0
AG78 PVCCFA_EHV_FIVRA_CPU0 VCCFA_EHV_FIVRA9 @S9S_MB_2U_LIB.S9S_MB_2U(SCH_1):PVCCFA_EHV_FIVRA_CPU0
AF77 PVCCFA_EHV_FIVRA_CPU0 VCCFA_EHV_FIVRA8 @S9S_MB_2U_LIB.S9S_MB_2U(SCH_1):PVCCFA_EHV_FIVRA_CPU0
 AE7 PVCCFA_EHV_FIVRA_CPU0 VCCFA_EHV_FIVRA7 @S9S_MB_2U_LIB.S9S_MB_2U(SCH_1):PVCCFA_EHV_FIVRA_CPU0
AE15 PVCCFA_EHV_FIVRA_CPU0 VCCFA_EHV_FIVRA6 @S9S_MB_2U_LIB.S9S_MB_2U(SCH_1):PVCCFA_EHV_FIVRA_CPU0
AE11 PVCCFA_EHV_FIVRA_CPU0 VCCFA_EHV_FIVRA5 @S9S_MB_2U_LIB.S9S_MB_2U(SCH_1):PVCCFA_EHV_FIVRA_CPU0
AD89 PVCCFA_EHV_FIVRA_CPU0 VCCFA_EHV_FIVRA4 @S9S_MB_2U_LIB.S9S_MB_2U(SCH_1):PVCCFA_EHV_FIVRA_CPU0
AD85 PVCCFA_EHV_FIVRA_CPU0 VCCFA_EHV_FIVRA3 @S9S_MB_2U_LIB.S9S_MB_2U(SCH_1):PVCCFA_EHV_FIVRA_CPU0
 AA7 PVCCFA_EHV_FIVRA_CPU0 VCCFA_EHV_FIVRA2 @S9S_MB_2U_LIB.S9S_MB_2U(SCH_1):PVCCFA_EHV_FIVRA_CPU0
AA15 PVCCFA_EHV_FIVRA_CPU0 VCCFA_EHV_FIVRA1 @S9S_MB_2U_LIB.S9S_MB_2U(SCH_1):PVCCFA_EHV_FIVRA_CPU0
AA11 PVCCFA_EHV_FIVRA_CPU0 VCCFA_EHV_FIVRA0 @S9S_MB_2U_LIB.S9S_MB_2U(SCH_1):PVCCFA_EHV_FIVRA_CPU0


DRAWING: @S9S_MB_2U_LIB.S9S_MB_2U(SCH_1):PAGE39 

SOCKET4677_AZIF0045P001C01CS-SA  I1  U2
ER41    GND VSS1834 @S9S_MB_2U_LIB.S9S_MB_2U(SCH_1):GND
ER43    GND VSS1835 @S9S_MB_2U_LIB.S9S_MB_2U(SCH_1):GND
ER48    GND VSS1836 @S9S_MB_2U_LIB.S9S_MB_2U(SCH_1):GND
ER50    GND VSS1837 @S9S_MB_2U_LIB.S9S_MB_2U(SCH_1):GND
ET57    GND VSS1569 @S9S_MB_2U_LIB.S9S_MB_2U(SCH_1):GND
ET38    GND VSS1565 @S9S_MB_2U_LIB.S9S_MB_2U(SCH_1):GND
ET34    GND VSS1563 @S9S_MB_2U_LIB.S9S_MB_2U(SCH_1):GND
ET28    GND VSS1562 @S9S_MB_2U_LIB.S9S_MB_2U(SCH_1):GND
ET22    GND VSS1561 @S9S_MB_2U_LIB.S9S_MB_2U(SCH_1):GND
ET16    GND VSS1559 @S9S_MB_2U_LIB.S9S_MB_2U(SCH_1):GND
ET10    GND VSS1557 @S9S_MB_2U_LIB.S9S_MB_2U(SCH_1):GND
ER86    GND VSS1556 @S9S_MB_2U_LIB.S9S_MB_2U(SCH_1):GND
ER84    GND VSS1555 @S9S_MB_2U_LIB.S9S_MB_2U(SCH_1):GND
ER80    GND VSS1554 @S9S_MB_2U_LIB.S9S_MB_2U(SCH_1):GND
ER78    GND VSS1553 @S9S_MB_2U_LIB.S9S_MB_2U(SCH_1):GND
ER74    GND VSS1552 @S9S_MB_2U_LIB.S9S_MB_2U(SCH_1):GND
ER70    GND VSS1551 @S9S_MB_2U_LIB.S9S_MB_2U(SCH_1):GND
 ER7    GND VSS1550 @S9S_MB_2U_LIB.S9S_MB_2U(SCH_1):GND
 ER5    GND VSS1549 @S9S_MB_2U_LIB.S9S_MB_2U(SCH_1):GND
ER33    GND VSS1548 @S9S_MB_2U_LIB.S9S_MB_2U(SCH_1):GND
ER27    GND VSS1547 @S9S_MB_2U_LIB.S9S_MB_2U(SCH_1):GND
EP83    GND VSS1545 @S9S_MB_2U_LIB.S9S_MB_2U(SCH_1):GND
EP67    GND VSS1543 @S9S_MB_2U_LIB.S9S_MB_2U(SCH_1):GND
EN80    GND VSS1542 @S9S_MB_2U_LIB.S9S_MB_2U(SCH_1):GND
EN78    GND VSS1541 @S9S_MB_2U_LIB.S9S_MB_2U(SCH_1):GND
EN64    GND VSS1540 @S9S_MB_2U_LIB.S9S_MB_2U(SCH_1):GND
EN56    GND VSS1539 @S9S_MB_2U_LIB.S9S_MB_2U(SCH_1):GND
EN54    GND VSS1537 @S9S_MB_2U_LIB.S9S_MB_2U(SCH_1):GND
EN52    GND VSS1533 @S9S_MB_2U_LIB.S9S_MB_2U(SCH_1):GND
EN50    GND VSS1531 @S9S_MB_2U_LIB.S9S_MB_2U(SCH_1):GND
EN48    GND VSS1530 @S9S_MB_2U_LIB.S9S_MB_2U(SCH_1):GND
EN45    GND VSS1529 @S9S_MB_2U_LIB.S9S_MB_2U(SCH_1):GND
EN43    GND VSS1528 @S9S_MB_2U_LIB.S9S_MB_2U(SCH_1):GND
EN41    GND VSS1526 @S9S_MB_2U_LIB.S9S_MB_2U(SCH_1):GND
EN37    GND VSS1525 @S9S_MB_2U_LIB.S9S_MB_2U(SCH_1):GND
EN35    GND VSS1524 @S9S_MB_2U_LIB.S9S_MB_2U(SCH_1):GND
EN33    GND VSS1522 @S9S_MB_2U_LIB.S9S_MB_2U(SCH_1):GND
EN31    GND VSS1520 @S9S_MB_2U_LIB.S9S_MB_2U(SCH_1):GND
EN29    GND VSS1518 @S9S_MB_2U_LIB.S9S_MB_2U(SCH_1):GND
EN27    GND VSS1517 @S9S_MB_2U_LIB.S9S_MB_2U(SCH_1):GND
EN25    GND VSS1515 @S9S_MB_2U_LIB.S9S_MB_2U(SCH_1):GND
EN23    GND VSS1513 @S9S_MB_2U_LIB.S9S_MB_2U(SCH_1):GND
EN21    GND VSS1512 @S9S_MB_2U_LIB.S9S_MB_2U(SCH_1):GND
EN19    GND VSS1506 @S9S_MB_2U_LIB.S9S_MB_2U(SCH_1):GND
EN17    GND VSS1505 @S9S_MB_2U_LIB.S9S_MB_2U(SCH_1):GND
EN15    GND VSS1503 @S9S_MB_2U_LIB.S9S_MB_2U(SCH_1):GND
EN13    GND VSS1501 @S9S_MB_2U_LIB.S9S_MB_2U(SCH_1):GND
EN11    GND VSS1500 @S9S_MB_2U_LIB.S9S_MB_2U(SCH_1):GND
EM83    GND VSS1499 @S9S_MB_2U_LIB.S9S_MB_2U(SCH_1):GND
EM81    GND VSS1498 @S9S_MB_2U_LIB.S9S_MB_2U(SCH_1):GND
 EM8    GND VSS1497 @S9S_MB_2U_LIB.S9S_MB_2U(SCH_1):GND
EM73    GND VSS1496 @S9S_MB_2U_LIB.S9S_MB_2U(SCH_1):GND
ET59    GND VSS1493 @S9S_MB_2U_LIB.S9S_MB_2U(SCH_1):GND
EM42    GND VSS1492 @S9S_MB_2U_LIB.S9S_MB_2U(SCH_1):GND
ET53    GND VSS1491 @S9S_MB_2U_LIB.S9S_MB_2U(SCH_1):GND
EL76    GND VSS1489 @S9S_MB_2U_LIB.S9S_MB_2U(SCH_1):GND
EL64    GND VSS1488 @S9S_MB_2U_LIB.S9S_MB_2U(SCH_1):GND
 EL5    GND VSS1486 @S9S_MB_2U_LIB.S9S_MB_2U(SCH_1):GND
EL45    GND VSS1485 @S9S_MB_2U_LIB.S9S_MB_2U(SCH_1):GND
ET32    GND VSS1484 @S9S_MB_2U_LIB.S9S_MB_2U(SCH_1):GND
EL39    GND VSS1483 @S9S_MB_2U_LIB.S9S_MB_2U(SCH_1):GND
ET26    GND VSS1482 @S9S_MB_2U_LIB.S9S_MB_2U(SCH_1):GND
EL33    GND VSS1481 @S9S_MB_2U_LIB.S9S_MB_2U(SCH_1):GND
ET20    GND VSS1480 @S9S_MB_2U_LIB.S9S_MB_2U(SCH_1):GND
 EL3    GND VSS1479 @S9S_MB_2U_LIB.S9S_MB_2U(SCH_1):GND
ET14    GND VSS1478 @S9S_MB_2U_LIB.S9S_MB_2U(SCH_1):GND
EL27    GND VSS1477 @S9S_MB_2U_LIB.S9S_MB_2U(SCH_1):GND
 ER9    GND VSS1476 @S9S_MB_2U_LIB.S9S_MB_2U(SCH_1):GND
EL21    GND VSS1475 @S9S_MB_2U_LIB.S9S_MB_2U(SCH_1):GND
EK75    GND VSS1474 @S9S_MB_2U_LIB.S9S_MB_2U(SCH_1):GND
EK69    GND VSS1473 @S9S_MB_2U_LIB.S9S_MB_2U(SCH_1):GND
EK65    GND VSS1472 @S9S_MB_2U_LIB.S9S_MB_2U(SCH_1):GND
EK57    GND VSS1471 @S9S_MB_2U_LIB.S9S_MB_2U(SCH_1):GND
EK47    GND VSS1470 @S9S_MB_2U_LIB.S9S_MB_2U(SCH_1):GND
EK40    GND VSS1469 @S9S_MB_2U_LIB.S9S_MB_2U(SCH_1):GND
ER64    GND VSS1468 @S9S_MB_2U_LIB.S9S_MB_2U(SCH_1):GND
ER58    GND VSS1467 @S9S_MB_2U_LIB.S9S_MB_2U(SCH_1):GND
 EK4    GND VSS1466 @S9S_MB_2U_LIB.S9S_MB_2U(SCH_1):GND
EK38    GND VSS1465 @S9S_MB_2U_LIB.S9S_MB_2U(SCH_1):GND
ER52    GND VSS1464 @S9S_MB_2U_LIB.S9S_MB_2U(SCH_1):GND
EK34    GND VSS1463 @S9S_MB_2U_LIB.S9S_MB_2U(SCH_1):GND
ER39    GND VSS1462 @S9S_MB_2U_LIB.S9S_MB_2U(SCH_1):GND
EK32    GND VSS1461 @S9S_MB_2U_LIB.S9S_MB_2U(SCH_1):GND
EK28    GND VSS1460 @S9S_MB_2U_LIB.S9S_MB_2U(SCH_1):GND
EK22    GND VSS1459 @S9S_MB_2U_LIB.S9S_MB_2U(SCH_1):GND
 EK2    GND VSS1458 @S9S_MB_2U_LIB.S9S_MB_2U(SCH_1):GND
ER21    GND VSS1457 @S9S_MB_2U_LIB.S9S_MB_2U(SCH_1):GND
ER15    GND VSS1456 @S9S_MB_2U_LIB.S9S_MB_2U(SCH_1):GND
EK14    GND VSS1455 @S9S_MB_2U_LIB.S9S_MB_2U(SCH_1):GND
EP77    GND VSS1454 @S9S_MB_2U_LIB.S9S_MB_2U(SCH_1):GND
EP71    GND VSS1453 @S9S_MB_2U_LIB.S9S_MB_2U(SCH_1):GND
EP69    GND VSS1452 @S9S_MB_2U_LIB.S9S_MB_2U(SCH_1):GND
EK10    GND VSS1451 @S9S_MB_2U_LIB.S9S_MB_2U(SCH_1):GND
 EJ9    GND VSS1450 @S9S_MB_2U_LIB.S9S_MB_2U(SCH_1):GND
EJ88    GND VSS1449 @S9S_MB_2U_LIB.S9S_MB_2U(SCH_1):GND
EJ78    GND VSS1448 @S9S_MB_2U_LIB.S9S_MB_2U(SCH_1):GND
EJ74    GND VSS1447 @S9S_MB_2U_LIB.S9S_MB_2U(SCH_1):GND
 EN9    GND VSS1446 @S9S_MB_2U_LIB.S9S_MB_2U(SCH_1):GND
EN88    GND VSS1445 @S9S_MB_2U_LIB.S9S_MB_2U(SCH_1):GND
 EJ7    GND VSS1444 @S9S_MB_2U_LIB.S9S_MB_2U(SCH_1):GND
EJ66    GND VSS1443 @S9S_MB_2U_LIB.S9S_MB_2U(SCH_1):GND
EJ60    GND VSS1442 @S9S_MB_2U_LIB.S9S_MB_2U(SCH_1):GND
EN72    GND VSS1441 @S9S_MB_2U_LIB.S9S_MB_2U(SCH_1):GND
EN66    GND VSS1440 @S9S_MB_2U_LIB.S9S_MB_2U(SCH_1):GND
EJ56    GND VSS1439 @S9S_MB_2U_LIB.S9S_MB_2U(SCH_1):GND
EN62    GND VSS1438 @S9S_MB_2U_LIB.S9S_MB_2U(SCH_1):GND
EN60    GND VSS1437 @S9S_MB_2U_LIB.S9S_MB_2U(SCH_1):GND
EN58    GND VSS1436 @S9S_MB_2U_LIB.S9S_MB_2U(SCH_1):GND
EJ50    GND VSS1435 @S9S_MB_2U_LIB.S9S_MB_2U(SCH_1):GND
EJ48    GND VSS1434 @S9S_MB_2U_LIB.S9S_MB_2U(SCH_1):GND
EJ43    GND VSS1433 @S9S_MB_2U_LIB.S9S_MB_2U(SCH_1):GND
EJ41    GND VSS1432 @S9S_MB_2U_LIB.S9S_MB_2U(SCH_1):GND
EJ37    GND VSS1431 @S9S_MB_2U_LIB.S9S_MB_2U(SCH_1):GND
EJ31    GND VSS1430 @S9S_MB_2U_LIB.S9S_MB_2U(SCH_1):GND
EJ29    GND VSS1429 @S9S_MB_2U_LIB.S9S_MB_2U(SCH_1):GND
EJ23    GND VSS1428 @S9S_MB_2U_LIB.S9S_MB_2U(SCH_1):GND
EN39    GND VSS1427 @S9S_MB_2U_LIB.S9S_MB_2U(SCH_1):GND
EJ19    GND VSS1426 @S9S_MB_2U_LIB.S9S_MB_2U(SCH_1):GND
EJ13    GND VSS1425 @S9S_MB_2U_LIB.S9S_MB_2U(SCH_1):GND
EH83    GND VSS1424 @S9S_MB_2U_LIB.S9S_MB_2U(SCH_1):GND
EH81    GND VSS1423 @S9S_MB_2U_LIB.S9S_MB_2U(SCH_1):GND
EH73    GND VSS1422 @S9S_MB_2U_LIB.S9S_MB_2U(SCH_1):GND
EH49    GND VSS1421 @S9S_MB_2U_LIB.S9S_MB_2U(SCH_1):GND
EH36    GND VSS1419 @S9S_MB_2U_LIB.S9S_MB_2U(SCH_1):GND
EM79    GND VSS1409 @S9S_MB_2U_LIB.S9S_MB_2U(SCH_1):GND
EM49    GND VSS1405 @S9S_MB_2U_LIB.S9S_MB_2U(SCH_1):GND
 EL9    GND VSS1401 @S9S_MB_2U_LIB.S9S_MB_2U(SCH_1):GND
EL86    GND VSS1400 @S9S_MB_2U_LIB.S9S_MB_2U(SCH_1):GND
EL72    GND VSS1398 @S9S_MB_2U_LIB.S9S_MB_2U(SCH_1):GND
EL70    GND VSS1397 @S9S_MB_2U_LIB.S9S_MB_2U(SCH_1):GND
 EL7    GND VSS1396 @S9S_MB_2U_LIB.S9S_MB_2U(SCH_1):GND
EL58    GND VSS1394 @S9S_MB_2U_LIB.S9S_MB_2U(SCH_1):GND
EL52    GND VSS1391 @S9S_MB_2U_LIB.S9S_MB_2U(SCH_1):GND
EL15    GND VSS1381 @S9S_MB_2U_LIB.S9S_MB_2U(SCH_1):GND
EK89    GND VSS1380 @S9S_MB_2U_LIB.S9S_MB_2U(SCH_1):GND
EK83    GND VSS1379 @S9S_MB_2U_LIB.S9S_MB_2U(SCH_1):GND
EK79    GND VSS1378 @S9S_MB_2U_LIB.S9S_MB_2U(SCH_1):GND
EK77    GND VSS1377 @S9S_MB_2U_LIB.S9S_MB_2U(SCH_1):GND
EK71    GND VSS1375 @S9S_MB_2U_LIB.S9S_MB_2U(SCH_1):GND
EK63    GND VSS1372 @S9S_MB_2U_LIB.S9S_MB_2U(SCH_1):GND
EK59    GND VSS1371 @S9S_MB_2U_LIB.S9S_MB_2U(SCH_1):GND
EK53    GND VSS1369 @S9S_MB_2U_LIB.S9S_MB_2U(SCH_1):GND
EK51    GND VSS1368 @S9S_MB_2U_LIB.S9S_MB_2U(SCH_1):GND
EK44    GND VSS1366 @S9S_MB_2U_LIB.S9S_MB_2U(SCH_1):GND
EK26    GND VSS1359 @S9S_MB_2U_LIB.S9S_MB_2U(SCH_1):GND
EK20    GND VSS1357 @S9S_MB_2U_LIB.S9S_MB_2U(SCH_1):GND
EK16    GND VSS1355 @S9S_MB_2U_LIB.S9S_MB_2U(SCH_1):GND
EJ72    GND VSS1347 @S9S_MB_2U_LIB.S9S_MB_2U(SCH_1):GND
EJ68    GND VSS1345 @S9S_MB_2U_LIB.S9S_MB_2U(SCH_1):GND
EJ62    GND VSS1343 @S9S_MB_2U_LIB.S9S_MB_2U(SCH_1):GND
EJ54    GND VSS1340 @S9S_MB_2U_LIB.S9S_MB_2U(SCH_1):GND
EJ35    GND VSS1334 @S9S_MB_2U_LIB.S9S_MB_2U(SCH_1):GND
EJ25    GND VSS1331 @S9S_MB_2U_LIB.S9S_MB_2U(SCH_1):GND
EJ17    GND VSS1328 @S9S_MB_2U_LIB.S9S_MB_2U(SCH_1):GND
EJ11    GND VSS1325 @S9S_MB_2U_LIB.S9S_MB_2U(SCH_1):GND
EH79    GND VSS1322 @S9S_MB_2U_LIB.S9S_MB_2U(SCH_1):GND
EH67    GND VSS1320 @S9S_MB_2U_LIB.S9S_MB_2U(SCH_1):GND
EH61    GND VSS1319 @S9S_MB_2U_LIB.S9S_MB_2U(SCH_1):GND
EH55    GND VSS1315 @S9S_MB_2U_LIB.S9S_MB_2U(SCH_1):GND
EH42    GND VSS1312 @S9S_MB_2U_LIB.S9S_MB_2U(SCH_1):GND

SOCKET4677_AZIF0045P001C01CS-SA  I9  U2
 EH4    GND VSS1420 @S9S_MB_2U_LIB.S9S_MB_2U(SCH_1):GND
EH30    GND VSS1418 @S9S_MB_2U_LIB.S9S_MB_2U(SCH_1):GND
EH24    GND VSS1417 @S9S_MB_2U_LIB.S9S_MB_2U(SCH_1):GND
EH16    GND VSS1416 @S9S_MB_2U_LIB.S9S_MB_2U(SCH_1):GND
EG90    GND VSS1415 @S9S_MB_2U_LIB.S9S_MB_2U(SCH_1):GND
 EG9    GND VSS1414 @S9S_MB_2U_LIB.S9S_MB_2U(SCH_1):GND
EG88    GND VSS1413 @S9S_MB_2U_LIB.S9S_MB_2U(SCH_1):GND
EG86    GND VSS1412 @S9S_MB_2U_LIB.S9S_MB_2U(SCH_1):GND
EG84    GND VSS1411 @S9S_MB_2U_LIB.S9S_MB_2U(SCH_1):GND
EG82    GND VSS1410 @S9S_MB_2U_LIB.S9S_MB_2U(SCH_1):GND
EG39    GND VSS1408 @S9S_MB_2U_LIB.S9S_MB_2U(SCH_1):GND
EF87    GND VSS1407 @S9S_MB_2U_LIB.S9S_MB_2U(SCH_1):GND
EF85    GND VSS1406 @S9S_MB_2U_LIB.S9S_MB_2U(SCH_1):GND
 EF8    GND VSS1404 @S9S_MB_2U_LIB.S9S_MB_2U(SCH_1):GND
EF77    GND VSS1403 @S9S_MB_2U_LIB.S9S_MB_2U(SCH_1):GND
EF71    GND VSS1402 @S9S_MB_2U_LIB.S9S_MB_2U(SCH_1):GND
EF69    GND VSS1399 @S9S_MB_2U_LIB.S9S_MB_2U(SCH_1):GND
EF67    GND VSS1395 @S9S_MB_2U_LIB.S9S_MB_2U(SCH_1):GND
EF65    GND VSS1393 @S9S_MB_2U_LIB.S9S_MB_2U(SCH_1):GND
EF63    GND VSS1392 @S9S_MB_2U_LIB.S9S_MB_2U(SCH_1):GND
EF61    GND VSS1390 @S9S_MB_2U_LIB.S9S_MB_2U(SCH_1):GND
EF59    GND VSS1389 @S9S_MB_2U_LIB.S9S_MB_2U(SCH_1):GND
EF57    GND VSS1388 @S9S_MB_2U_LIB.S9S_MB_2U(SCH_1):GND
EF55    GND VSS1387 @S9S_MB_2U_LIB.S9S_MB_2U(SCH_1):GND
EF53    GND VSS1386 @S9S_MB_2U_LIB.S9S_MB_2U(SCH_1):GND
EF49    GND VSS1385 @S9S_MB_2U_LIB.S9S_MB_2U(SCH_1):GND
EF47    GND VSS1384 @S9S_MB_2U_LIB.S9S_MB_2U(SCH_1):GND
EF44    GND VSS1383 @S9S_MB_2U_LIB.S9S_MB_2U(SCH_1):GND
EF42    GND VSS1382 @S9S_MB_2U_LIB.S9S_MB_2U(SCH_1):GND
EF40    GND VSS1376 @S9S_MB_2U_LIB.S9S_MB_2U(SCH_1):GND
 EF4    GND VSS1374 @S9S_MB_2U_LIB.S9S_MB_2U(SCH_1):GND
EF38    GND VSS1373 @S9S_MB_2U_LIB.S9S_MB_2U(SCH_1):GND
EF36    GND VSS1370 @S9S_MB_2U_LIB.S9S_MB_2U(SCH_1):GND
EF34    GND VSS1367 @S9S_MB_2U_LIB.S9S_MB_2U(SCH_1):GND
EF32    GND VSS1365 @S9S_MB_2U_LIB.S9S_MB_2U(SCH_1):GND
EF30    GND VSS1364 @S9S_MB_2U_LIB.S9S_MB_2U(SCH_1):GND
EF28    GND VSS1363 @S9S_MB_2U_LIB.S9S_MB_2U(SCH_1):GND
EF26    GND VSS1362 @S9S_MB_2U_LIB.S9S_MB_2U(SCH_1):GND
EF24    GND VSS1361 @S9S_MB_2U_LIB.S9S_MB_2U(SCH_1):GND
EF22    GND VSS1360 @S9S_MB_2U_LIB.S9S_MB_2U(SCH_1):GND
EF20    GND VSS1358 @S9S_MB_2U_LIB.S9S_MB_2U(SCH_1):GND
 EF2    GND VSS1356 @S9S_MB_2U_LIB.S9S_MB_2U(SCH_1):GND
EF18    GND VSS1354 @S9S_MB_2U_LIB.S9S_MB_2U(SCH_1):GND
EF16    GND VSS1353 @S9S_MB_2U_LIB.S9S_MB_2U(SCH_1):GND
EF12    GND VSS1352 @S9S_MB_2U_LIB.S9S_MB_2U(SCH_1):GND
EE88    GND VSS1351 @S9S_MB_2U_LIB.S9S_MB_2U(SCH_1):GND
EE80    GND VSS1350 @S9S_MB_2U_LIB.S9S_MB_2U(SCH_1):GND
EE78    GND VSS1349 @S9S_MB_2U_LIB.S9S_MB_2U(SCH_1):GND
 ED8    GND VSS1348 @S9S_MB_2U_LIB.S9S_MB_2U(SCH_1):GND
ED49    GND VSS1346 @S9S_MB_2U_LIB.S9S_MB_2U(SCH_1):GND
 ED4    GND VSS1344 @S9S_MB_2U_LIB.S9S_MB_2U(SCH_1):GND
ED36    GND VSS1342 @S9S_MB_2U_LIB.S9S_MB_2U(SCH_1):GND
ED30    GND VSS1341 @S9S_MB_2U_LIB.S9S_MB_2U(SCH_1):GND
ED24    GND VSS1339 @S9S_MB_2U_LIB.S9S_MB_2U(SCH_1):GND
ED16    GND VSS1338 @S9S_MB_2U_LIB.S9S_MB_2U(SCH_1):GND
 EC9    GND VSS1337 @S9S_MB_2U_LIB.S9S_MB_2U(SCH_1):GND
EC88    GND VSS1336 @S9S_MB_2U_LIB.S9S_MB_2U(SCH_1):GND
EC84    GND VSS1335 @S9S_MB_2U_LIB.S9S_MB_2U(SCH_1):GND
EC82    GND VSS1333 @S9S_MB_2U_LIB.S9S_MB_2U(SCH_1):GND
EC74    GND VSS1332 @S9S_MB_2U_LIB.S9S_MB_2U(SCH_1):GND
EC72    GND VSS1330 @S9S_MB_2U_LIB.S9S_MB_2U(SCH_1):GND
EC66    GND VSS1329 @S9S_MB_2U_LIB.S9S_MB_2U(SCH_1):GND
EC56    GND VSS1327 @S9S_MB_2U_LIB.S9S_MB_2U(SCH_1):GND
EC50    GND VSS1326 @S9S_MB_2U_LIB.S9S_MB_2U(SCH_1):GND
EC48    GND VSS1324 @S9S_MB_2U_LIB.S9S_MB_2U(SCH_1):GND
EC43    GND VSS1323 @S9S_MB_2U_LIB.S9S_MB_2U(SCH_1):GND
EC41    GND VSS1321 @S9S_MB_2U_LIB.S9S_MB_2U(SCH_1):GND
 EH6    GND VSS1318 @S9S_MB_2U_LIB.S9S_MB_2U(SCH_1):GND
EC37    GND VSS1317 @S9S_MB_2U_LIB.S9S_MB_2U(SCH_1):GND
EC31    GND VSS1316 @S9S_MB_2U_LIB.S9S_MB_2U(SCH_1):GND
EC29    GND VSS1314 @S9S_MB_2U_LIB.S9S_MB_2U(SCH_1):GND
EC23    GND VSS1313 @S9S_MB_2U_LIB.S9S_MB_2U(SCH_1):GND
EC19    GND VSS1311 @S9S_MB_2U_LIB.S9S_MB_2U(SCH_1):GND
EC13    GND VSS1310 @S9S_MB_2U_LIB.S9S_MB_2U(SCH_1):GND
 EC1    GND VSS1309 @S9S_MB_2U_LIB.S9S_MB_2U(SCH_1):GND
EB87    GND VSS1308 @S9S_MB_2U_LIB.S9S_MB_2U(SCH_1):GND
EB83    GND VSS1307 @S9S_MB_2U_LIB.S9S_MB_2U(SCH_1):GND
 EB8    GND VSS1306 @S9S_MB_2U_LIB.S9S_MB_2U(SCH_1):GND
EH18    GND VSS1305 @S9S_MB_2U_LIB.S9S_MB_2U(SCH_1):GND
EB79    GND VSS1304 @S9S_MB_2U_LIB.S9S_MB_2U(SCH_1):GND
EH14    GND VSS1303 @S9S_MB_2U_LIB.S9S_MB_2U(SCH_1):GND
EH12    GND VSS1302 @S9S_MB_2U_LIB.S9S_MB_2U(SCH_1):GND
EB75    GND VSS1301 @S9S_MB_2U_LIB.S9S_MB_2U(SCH_1):GND
EB71    GND VSS1300 @S9S_MB_2U_LIB.S9S_MB_2U(SCH_1):GND
EB69    GND VSS1299 @S9S_MB_2U_LIB.S9S_MB_2U(SCH_1):GND
EB65    GND VSS1298 @S9S_MB_2U_LIB.S9S_MB_2U(SCH_1):GND
EB57    GND VSS1297 @S9S_MB_2U_LIB.S9S_MB_2U(SCH_1):GND
EB47    GND VSS1296 @S9S_MB_2U_LIB.S9S_MB_2U(SCH_1):GND
EB40    GND VSS1295 @S9S_MB_2U_LIB.S9S_MB_2U(SCH_1):GND
 EG7    GND VSS1294 @S9S_MB_2U_LIB.S9S_MB_2U(SCH_1):GND
EB38    GND VSS1293 @S9S_MB_2U_LIB.S9S_MB_2U(SCH_1):GND
EB32    GND VSS1292 @S9S_MB_2U_LIB.S9S_MB_2U(SCH_1):GND
EG52    GND VSS1291 @S9S_MB_2U_LIB.S9S_MB_2U(SCH_1):GND
 EG5    GND VSS1290 @S9S_MB_2U_LIB.S9S_MB_2U(SCH_1):GND
EB28    GND VSS1289 @S9S_MB_2U_LIB.S9S_MB_2U(SCH_1):GND
EB22    GND VSS1288 @S9S_MB_2U_LIB.S9S_MB_2U(SCH_1):GND
EB12    GND VSS1287 @S9S_MB_2U_LIB.S9S_MB_2U(SCH_1):GND
EA88    GND VSS1286 @S9S_MB_2U_LIB.S9S_MB_2U(SCH_1):GND
EA84    GND VSS1285 @S9S_MB_2U_LIB.S9S_MB_2U(SCH_1):GND
EG13    GND VSS1284 @S9S_MB_2U_LIB.S9S_MB_2U(SCH_1):GND
EF89    GND VSS1283 @S9S_MB_2U_LIB.S9S_MB_2U(SCH_1):GND
EA80    GND VSS1282 @S9S_MB_2U_LIB.S9S_MB_2U(SCH_1):GND
EA78    GND VSS1281 @S9S_MB_2U_LIB.S9S_MB_2U(SCH_1):GND
EA76    GND VSS1280 @S9S_MB_2U_LIB.S9S_MB_2U(SCH_1):GND
EA70    GND VSS1279 @S9S_MB_2U_LIB.S9S_MB_2U(SCH_1):GND
EA33    GND VSS1278 @S9S_MB_2U_LIB.S9S_MB_2U(SCH_1):GND
EF75    GND VSS1277 @S9S_MB_2U_LIB.S9S_MB_2U(SCH_1):GND
EF73    GND VSS1276 @S9S_MB_2U_LIB.S9S_MB_2U(SCH_1):GND
EA27    GND VSS1275 @S9S_MB_2U_LIB.S9S_MB_2U(SCH_1):GND
EA21    GND VSS1274 @S9S_MB_2U_LIB.S9S_MB_2U(SCH_1):GND
 DY8    GND VSS1270 @S9S_MB_2U_LIB.S9S_MB_2U(SCH_1):GND
DY77    GND VSS1269 @S9S_MB_2U_LIB.S9S_MB_2U(SCH_1):GND
DW88    GND VSS1267 @S9S_MB_2U_LIB.S9S_MB_2U(SCH_1):GND
DW84    GND VSS1266 @S9S_MB_2U_LIB.S9S_MB_2U(SCH_1):GND
EF51    GND VSS1265 @S9S_MB_2U_LIB.S9S_MB_2U(SCH_1):GND
DW82    GND VSS1264 @S9S_MB_2U_LIB.S9S_MB_2U(SCH_1):GND
DW80    GND VSS1263 @S9S_MB_2U_LIB.S9S_MB_2U(SCH_1):GND
DW76    GND VSS1262 @S9S_MB_2U_LIB.S9S_MB_2U(SCH_1):GND
DW74    GND VSS1261 @S9S_MB_2U_LIB.S9S_MB_2U(SCH_1):GND
DW72    GND VSS1260 @S9S_MB_2U_LIB.S9S_MB_2U(SCH_1):GND
DW70    GND VSS1259 @S9S_MB_2U_LIB.S9S_MB_2U(SCH_1):GND
DW68    GND VSS1258 @S9S_MB_2U_LIB.S9S_MB_2U(SCH_1):GND
DW66    GND VSS1257 @S9S_MB_2U_LIB.S9S_MB_2U(SCH_1):GND
EE52    GND VSS1237 @S9S_MB_2U_LIB.S9S_MB_2U(SCH_1):GND
EE39    GND VSS1235 @S9S_MB_2U_LIB.S9S_MB_2U(SCH_1):GND
EE17    GND VSS1232 @S9S_MB_2U_LIB.S9S_MB_2U(SCH_1):GND
ED73    GND VSS1225 @S9S_MB_2U_LIB.S9S_MB_2U(SCH_1):GND
ED67    GND VSS1224 @S9S_MB_2U_LIB.S9S_MB_2U(SCH_1):GND
ED61    GND VSS1223 @S9S_MB_2U_LIB.S9S_MB_2U(SCH_1):GND
ED55    GND VSS1220 @S9S_MB_2U_LIB.S9S_MB_2U(SCH_1):GND
ED42    GND VSS1217 @S9S_MB_2U_LIB.S9S_MB_2U(SCH_1):GND
ED18    GND VSS1210 @S9S_MB_2U_LIB.S9S_MB_2U(SCH_1):GND
ED12    GND VSS1208 @S9S_MB_2U_LIB.S9S_MB_2U(SCH_1):GND
EC68    GND VSS1200 @S9S_MB_2U_LIB.S9S_MB_2U(SCH_1):GND
EC62    GND VSS1198 @S9S_MB_2U_LIB.S9S_MB_2U(SCH_1):GND
EC60    GND VSS1197 @S9S_MB_2U_LIB.S9S_MB_2U(SCH_1):GND
EC54    GND VSS1195 @S9S_MB_2U_LIB.S9S_MB_2U(SCH_1):GND
 EC5    GND VSS1193 @S9S_MB_2U_LIB.S9S_MB_2U(SCH_1):GND
EC35    GND VSS1188 @S9S_MB_2U_LIB.S9S_MB_2U(SCH_1):GND
EC25    GND VSS1185 @S9S_MB_2U_LIB.S9S_MB_2U(SCH_1):GND
EB91    GND VSS1180 @S9S_MB_2U_LIB.S9S_MB_2U(SCH_1):GND
EB63    GND VSS1171 @S9S_MB_2U_LIB.S9S_MB_2U(SCH_1):GND
EB59    GND VSS1170 @S9S_MB_2U_LIB.S9S_MB_2U(SCH_1):GND
EB53    GND VSS1168 @S9S_MB_2U_LIB.S9S_MB_2U(SCH_1):GND
EB51    GND VSS1167 @S9S_MB_2U_LIB.S9S_MB_2U(SCH_1):GND
EB44    GND VSS1165 @S9S_MB_2U_LIB.S9S_MB_2U(SCH_1):GND
 EB4    GND VSS1163 @S9S_MB_2U_LIB.S9S_MB_2U(SCH_1):GND
EB34    GND VSS1161 @S9S_MB_2U_LIB.S9S_MB_2U(SCH_1):GND
EB26    GND VSS1158 @S9S_MB_2U_LIB.S9S_MB_2U(SCH_1):GND
EB20    GND VSS1156 @S9S_MB_2U_LIB.S9S_MB_2U(SCH_1):GND
EB16    GND VSS1155 @S9S_MB_2U_LIB.S9S_MB_2U(SCH_1):GND
EA64    GND VSS1146 @S9S_MB_2U_LIB.S9S_MB_2U(SCH_1):GND
EA58    GND VSS1145 @S9S_MB_2U_LIB.S9S_MB_2U(SCH_1):GND
EA52    GND VSS1144 @S9S_MB_2U_LIB.S9S_MB_2U(SCH_1):GND
EA45    GND VSS1142 @S9S_MB_2U_LIB.S9S_MB_2U(SCH_1):GND
EA39    GND VSS1141 @S9S_MB_2U_LIB.S9S_MB_2U(SCH_1):GND
DY42    GND VSS1116 @S9S_MB_2U_LIB.S9S_MB_2U(SCH_1):GND
 DY4    GND VSS1115 @S9S_MB_2U_LIB.S9S_MB_2U(SCH_1):GND
DY16    GND VSS1112 @S9S_MB_2U_LIB.S9S_MB_2U(SCH_1):GND
DY12    GND VSS1111 @S9S_MB_2U_LIB.S9S_MB_2U(SCH_1):GND

SOCKET4677_AZIF0045P001C01CS-SA  I10  U2
 DW9    GND VSS1268 @S9S_MB_2U_LIB.S9S_MB_2U(SCH_1):GND
DW64    GND VSS1256 @S9S_MB_2U_LIB.S9S_MB_2U(SCH_1):GND
DW62    GND VSS1255 @S9S_MB_2U_LIB.S9S_MB_2U(SCH_1):GND
DW58    GND VSS1254 @S9S_MB_2U_LIB.S9S_MB_2U(SCH_1):GND
DW56    GND VSS1253 @S9S_MB_2U_LIB.S9S_MB_2U(SCH_1):GND
DW54    GND VSS1252 @S9S_MB_2U_LIB.S9S_MB_2U(SCH_1):GND
DW52    GND VSS1251 @S9S_MB_2U_LIB.S9S_MB_2U(SCH_1):GND
DW50    GND VSS1250 @S9S_MB_2U_LIB.S9S_MB_2U(SCH_1):GND
 DW5    GND VSS1249 @S9S_MB_2U_LIB.S9S_MB_2U(SCH_1):GND
DW48    GND VSS1248 @S9S_MB_2U_LIB.S9S_MB_2U(SCH_1):GND
DW45    GND VSS1247 @S9S_MB_2U_LIB.S9S_MB_2U(SCH_1):GND
DW43    GND VSS1246 @S9S_MB_2U_LIB.S9S_MB_2U(SCH_1):GND
DW41    GND VSS1245 @S9S_MB_2U_LIB.S9S_MB_2U(SCH_1):GND
DW39    GND VSS1244 @S9S_MB_2U_LIB.S9S_MB_2U(SCH_1):GND
DW37    GND VSS1243 @S9S_MB_2U_LIB.S9S_MB_2U(SCH_1):GND
DW35    GND VSS1242 @S9S_MB_2U_LIB.S9S_MB_2U(SCH_1):GND
DW33    GND VSS1241 @S9S_MB_2U_LIB.S9S_MB_2U(SCH_1):GND
DW31    GND VSS1240 @S9S_MB_2U_LIB.S9S_MB_2U(SCH_1):GND
DW29    GND VSS1239 @S9S_MB_2U_LIB.S9S_MB_2U(SCH_1):GND
DW27    GND VSS1238 @S9S_MB_2U_LIB.S9S_MB_2U(SCH_1):GND
DW25    GND VSS1236 @S9S_MB_2U_LIB.S9S_MB_2U(SCH_1):GND
DW23    GND VSS1234 @S9S_MB_2U_LIB.S9S_MB_2U(SCH_1):GND
DW19    GND VSS1233 @S9S_MB_2U_LIB.S9S_MB_2U(SCH_1):GND
DW17    GND VSS1231 @S9S_MB_2U_LIB.S9S_MB_2U(SCH_1):GND
DW13    GND VSS1230 @S9S_MB_2U_LIB.S9S_MB_2U(SCH_1):GND
 DW1    GND VSS1229 @S9S_MB_2U_LIB.S9S_MB_2U(SCH_1):GND
DV91    GND VSS1228 @S9S_MB_2U_LIB.S9S_MB_2U(SCH_1):GND
DV87    GND VSS1227 @S9S_MB_2U_LIB.S9S_MB_2U(SCH_1):GND
DV83    GND VSS1226 @S9S_MB_2U_LIB.S9S_MB_2U(SCH_1):GND
DV81    GND VSS1222 @S9S_MB_2U_LIB.S9S_MB_2U(SCH_1):GND
 DV8    GND VSS1221 @S9S_MB_2U_LIB.S9S_MB_2U(SCH_1):GND
DV79    GND VSS1219 @S9S_MB_2U_LIB.S9S_MB_2U(SCH_1):GND
DV77    GND VSS1218 @S9S_MB_2U_LIB.S9S_MB_2U(SCH_1):GND
DU88    GND VSS1216 @S9S_MB_2U_LIB.S9S_MB_2U(SCH_1):GND
DU84    GND VSS1215 @S9S_MB_2U_LIB.S9S_MB_2U(SCH_1):GND
DU78    GND VSS1214 @S9S_MB_2U_LIB.S9S_MB_2U(SCH_1):GND
DU76    GND VSS1213 @S9S_MB_2U_LIB.S9S_MB_2U(SCH_1):GND
DU33    GND VSS1212 @S9S_MB_2U_LIB.S9S_MB_2U(SCH_1):GND
DU27    GND VSS1211 @S9S_MB_2U_LIB.S9S_MB_2U(SCH_1):GND
DU21    GND VSS1209 @S9S_MB_2U_LIB.S9S_MB_2U(SCH_1):GND
 DT8    GND VSS1207 @S9S_MB_2U_LIB.S9S_MB_2U(SCH_1):GND
DT75    GND VSS1206 @S9S_MB_2U_LIB.S9S_MB_2U(SCH_1):GND
DT71    GND VSS1205 @S9S_MB_2U_LIB.S9S_MB_2U(SCH_1):GND
DT69    GND VSS1204 @S9S_MB_2U_LIB.S9S_MB_2U(SCH_1):GND
DT65    GND VSS1203 @S9S_MB_2U_LIB.S9S_MB_2U(SCH_1):GND
DT57    GND VSS1202 @S9S_MB_2U_LIB.S9S_MB_2U(SCH_1):GND
DT47    GND VSS1201 @S9S_MB_2U_LIB.S9S_MB_2U(SCH_1):GND
DT40    GND VSS1199 @S9S_MB_2U_LIB.S9S_MB_2U(SCH_1):GND
DT38    GND VSS1196 @S9S_MB_2U_LIB.S9S_MB_2U(SCH_1):GND
DT34    GND VSS1194 @S9S_MB_2U_LIB.S9S_MB_2U(SCH_1):GND
DT32    GND VSS1192 @S9S_MB_2U_LIB.S9S_MB_2U(SCH_1):GND
DT28    GND VSS1191 @S9S_MB_2U_LIB.S9S_MB_2U(SCH_1):GND
DT22    GND VSS1190 @S9S_MB_2U_LIB.S9S_MB_2U(SCH_1):GND
DT12    GND VSS1189 @S9S_MB_2U_LIB.S9S_MB_2U(SCH_1):GND
 DR9    GND VSS1187 @S9S_MB_2U_LIB.S9S_MB_2U(SCH_1):GND
DR88    GND VSS1186 @S9S_MB_2U_LIB.S9S_MB_2U(SCH_1):GND
DR84    GND VSS1184 @S9S_MB_2U_LIB.S9S_MB_2U(SCH_1):GND
DR78    GND VSS1183 @S9S_MB_2U_LIB.S9S_MB_2U(SCH_1):GND
DR74    GND VSS1182 @S9S_MB_2U_LIB.S9S_MB_2U(SCH_1):GND
DR66    GND VSS1181 @S9S_MB_2U_LIB.S9S_MB_2U(SCH_1):GND
DR56    GND VSS1179 @S9S_MB_2U_LIB.S9S_MB_2U(SCH_1):GND
DR50    GND VSS1178 @S9S_MB_2U_LIB.S9S_MB_2U(SCH_1):GND
DR48    GND VSS1177 @S9S_MB_2U_LIB.S9S_MB_2U(SCH_1):GND
DR43    GND VSS1176 @S9S_MB_2U_LIB.S9S_MB_2U(SCH_1):GND
DR41    GND VSS1175 @S9S_MB_2U_LIB.S9S_MB_2U(SCH_1):GND
DR37    GND VSS1174 @S9S_MB_2U_LIB.S9S_MB_2U(SCH_1):GND
DR31    GND VSS1173 @S9S_MB_2U_LIB.S9S_MB_2U(SCH_1):GND
DR29    GND VSS1172 @S9S_MB_2U_LIB.S9S_MB_2U(SCH_1):GND
DR23    GND VSS1169 @S9S_MB_2U_LIB.S9S_MB_2U(SCH_1):GND
DR19    GND VSS1166 @S9S_MB_2U_LIB.S9S_MB_2U(SCH_1):GND
DR13    GND VSS1164 @S9S_MB_2U_LIB.S9S_MB_2U(SCH_1):GND
 DR1    GND VSS1162 @S9S_MB_2U_LIB.S9S_MB_2U(SCH_1):GND
DP87    GND VSS1160 @S9S_MB_2U_LIB.S9S_MB_2U(SCH_1):GND
DP81    GND VSS1159 @S9S_MB_2U_LIB.S9S_MB_2U(SCH_1):GND
 DP8    GND VSS1157 @S9S_MB_2U_LIB.S9S_MB_2U(SCH_1):GND
DP73    GND VSS1154 @S9S_MB_2U_LIB.S9S_MB_2U(SCH_1):GND
DP49    GND VSS1153 @S9S_MB_2U_LIB.S9S_MB_2U(SCH_1):GND
 DP4    GND VSS1152 @S9S_MB_2U_LIB.S9S_MB_2U(SCH_1):GND
DP36    GND VSS1151 @S9S_MB_2U_LIB.S9S_MB_2U(SCH_1):GND
DP30    GND VSS1150 @S9S_MB_2U_LIB.S9S_MB_2U(SCH_1):GND
DP16    GND VSS1149 @S9S_MB_2U_LIB.S9S_MB_2U(SCH_1):GND
DN88    GND VSS1148 @S9S_MB_2U_LIB.S9S_MB_2U(SCH_1):GND
DN84    GND VSS1147 @S9S_MB_2U_LIB.S9S_MB_2U(SCH_1):GND
DN78    GND VSS1143 @S9S_MB_2U_LIB.S9S_MB_2U(SCH_1):GND
 DM8    GND VSS1140 @S9S_MB_2U_LIB.S9S_MB_2U(SCH_1):GND
DM79    GND VSS1139 @S9S_MB_2U_LIB.S9S_MB_2U(SCH_1):GND
DM77    GND VSS1138 @S9S_MB_2U_LIB.S9S_MB_2U(SCH_1):GND
DM75    GND VSS1137 @S9S_MB_2U_LIB.S9S_MB_2U(SCH_1):GND
DM71    GND VSS1136 @S9S_MB_2U_LIB.S9S_MB_2U(SCH_1):GND
DM69    GND VSS1135 @S9S_MB_2U_LIB.S9S_MB_2U(SCH_1):GND
DM67    GND VSS1134 @S9S_MB_2U_LIB.S9S_MB_2U(SCH_1):GND
DM65    GND VSS1133 @S9S_MB_2U_LIB.S9S_MB_2U(SCH_1):GND
DM63    GND VSS1132 @S9S_MB_2U_LIB.S9S_MB_2U(SCH_1):GND
DM61    GND VSS1130 @S9S_MB_2U_LIB.S9S_MB_2U(SCH_1):GND
DM59    GND VSS1128 @S9S_MB_2U_LIB.S9S_MB_2U(SCH_1):GND
DM57    GND VSS1127 @S9S_MB_2U_LIB.S9S_MB_2U(SCH_1):GND
DM55    GND VSS1124 @S9S_MB_2U_LIB.S9S_MB_2U(SCH_1):GND
DM53    GND VSS1123 @S9S_MB_2U_LIB.S9S_MB_2U(SCH_1):GND
DM49    GND VSS1122 @S9S_MB_2U_LIB.S9S_MB_2U(SCH_1):GND
DM47    GND VSS1121 @S9S_MB_2U_LIB.S9S_MB_2U(SCH_1):GND
DM44    GND VSS1120 @S9S_MB_2U_LIB.S9S_MB_2U(SCH_1):GND
DM42    GND VSS1119 @S9S_MB_2U_LIB.S9S_MB_2U(SCH_1):GND
DM40    GND VSS1118 @S9S_MB_2U_LIB.S9S_MB_2U(SCH_1):GND
 DM4    GND VSS1117 @S9S_MB_2U_LIB.S9S_MB_2U(SCH_1):GND
DM38    GND VSS1114 @S9S_MB_2U_LIB.S9S_MB_2U(SCH_1):GND
DM36    GND VSS1113 @S9S_MB_2U_LIB.S9S_MB_2U(SCH_1):GND
DM34    GND VSS1110 @S9S_MB_2U_LIB.S9S_MB_2U(SCH_1):GND
DM32    GND VSS1109 @S9S_MB_2U_LIB.S9S_MB_2U(SCH_1):GND
DM30    GND VSS1108 @S9S_MB_2U_LIB.S9S_MB_2U(SCH_1):GND
DM28    GND VSS1107 @S9S_MB_2U_LIB.S9S_MB_2U(SCH_1):GND
DM26    GND VSS1106 @S9S_MB_2U_LIB.S9S_MB_2U(SCH_1):GND
DM24    GND VSS1105 @S9S_MB_2U_LIB.S9S_MB_2U(SCH_1):GND
DM22    GND VSS1104 @S9S_MB_2U_LIB.S9S_MB_2U(SCH_1):GND
DM20    GND VSS1103 @S9S_MB_2U_LIB.S9S_MB_2U(SCH_1):GND
DM18    GND VSS1102 @S9S_MB_2U_LIB.S9S_MB_2U(SCH_1):GND
DM16    GND VSS1101 @S9S_MB_2U_LIB.S9S_MB_2U(SCH_1):GND
DM12    GND VSS1100 @S9S_MB_2U_LIB.S9S_MB_2U(SCH_1):GND
DW60    GND VSS1097 @S9S_MB_2U_LIB.S9S_MB_2U(SCH_1):GND
DW21    GND VSS1077 @S9S_MB_2U_LIB.S9S_MB_2U(SCH_1):GND
DV42    GND VSS1064 @S9S_MB_2U_LIB.S9S_MB_2U(SCH_1):GND
 DV4    GND VSS1063 @S9S_MB_2U_LIB.S9S_MB_2U(SCH_1):GND
DV16    GND VSS1060 @S9S_MB_2U_LIB.S9S_MB_2U(SCH_1):GND
DV12    GND VSS1059 @S9S_MB_2U_LIB.S9S_MB_2U(SCH_1):GND
DU70    GND VSS1054 @S9S_MB_2U_LIB.S9S_MB_2U(SCH_1):GND
DU64    GND VSS1052 @S9S_MB_2U_LIB.S9S_MB_2U(SCH_1):GND
DU58    GND VSS1051 @S9S_MB_2U_LIB.S9S_MB_2U(SCH_1):GND
DU52    GND VSS1050 @S9S_MB_2U_LIB.S9S_MB_2U(SCH_1):GND
DU45    GND VSS1048 @S9S_MB_2U_LIB.S9S_MB_2U(SCH_1):GND
DU39    GND VSS1047 @S9S_MB_2U_LIB.S9S_MB_2U(SCH_1):GND
DT83    GND VSS1036 @S9S_MB_2U_LIB.S9S_MB_2U(SCH_1):GND
DT63    GND VSS1029 @S9S_MB_2U_LIB.S9S_MB_2U(SCH_1):GND
DT59    GND VSS1028 @S9S_MB_2U_LIB.S9S_MB_2U(SCH_1):GND
DT53    GND VSS1026 @S9S_MB_2U_LIB.S9S_MB_2U(SCH_1):GND
DT51    GND VSS1025 @S9S_MB_2U_LIB.S9S_MB_2U(SCH_1):GND
DT44    GND VSS1023 @S9S_MB_2U_LIB.S9S_MB_2U(SCH_1):GND
 DT4    GND VSS1021 @S9S_MB_2U_LIB.S9S_MB_2U(SCH_1):GND
DT26    GND VSS1016 @S9S_MB_2U_LIB.S9S_MB_2U(SCH_1):GND
DT20    GND VSS1014 @S9S_MB_2U_LIB.S9S_MB_2U(SCH_1):GND
DT16    GND VSS1013 @S9S_MB_2U_LIB.S9S_MB_2U(SCH_1):GND
DR72    GND VSS1006 @S9S_MB_2U_LIB.S9S_MB_2U(SCH_1):GND
DR68    GND VSS1005 @S9S_MB_2U_LIB.S9S_MB_2U(SCH_1):GND
DR62    GND VSS1003 @S9S_MB_2U_LIB.S9S_MB_2U(SCH_1):GND
DR60    GND VSS1002 @S9S_MB_2U_LIB.S9S_MB_2U(SCH_1):GND
DR54    GND VSS1000 @S9S_MB_2U_LIB.S9S_MB_2U(SCH_1):GND
 DR5    GND VSS998 @S9S_MB_2U_LIB.S9S_MB_2U(SCH_1):GND
DR35    GND VSS993 @S9S_MB_2U_LIB.S9S_MB_2U(SCH_1):GND
DR25    GND VSS990 @S9S_MB_2U_LIB.S9S_MB_2U(SCH_1):GND
DP91    GND VSS985 @S9S_MB_2U_LIB.S9S_MB_2U(SCH_1):GND
DP67    GND VSS980 @S9S_MB_2U_LIB.S9S_MB_2U(SCH_1):GND
DP61    GND VSS979 @S9S_MB_2U_LIB.S9S_MB_2U(SCH_1):GND
DP55    GND VSS976 @S9S_MB_2U_LIB.S9S_MB_2U(SCH_1):GND
DP42    GND VSS973 @S9S_MB_2U_LIB.S9S_MB_2U(SCH_1):GND
DP24    GND VSS969 @S9S_MB_2U_LIB.S9S_MB_2U(SCH_1):GND
DP18    GND VSS968 @S9S_MB_2U_LIB.S9S_MB_2U(SCH_1):GND
DP12    GND VSS966 @S9S_MB_2U_LIB.S9S_MB_2U(SCH_1):GND
DN52    GND VSS959 @S9S_MB_2U_LIB.S9S_MB_2U(SCH_1):GND
DN39    GND VSS957 @S9S_MB_2U_LIB.S9S_MB_2U(SCH_1):GND
DN17    GND VSS955 @S9S_MB_2U_LIB.S9S_MB_2U(SCH_1):GND
DM73    GND VSS945 @S9S_MB_2U_LIB.S9S_MB_2U(SCH_1):GND
DM51    GND VSS934 @S9S_MB_2U_LIB.S9S_MB_2U(SCH_1):GND


DRAWING: @S9S_MB_2U_LIB.S9S_MB_2U(SCH_1):PAGE40 

SOCKET4677_AZIF0045P001C01CS-SA  I10  U2
 DL9    GND VSS1099 @S9S_MB_2U_LIB.S9S_MB_2U(SCH_1):GND
DL88    GND VSS1098 @S9S_MB_2U_LIB.S9S_MB_2U(SCH_1):GND
DL84    GND VSS1096 @S9S_MB_2U_LIB.S9S_MB_2U(SCH_1):GND
DL39    GND VSS1095 @S9S_MB_2U_LIB.S9S_MB_2U(SCH_1):GND
DK91    GND VSS1094 @S9S_MB_2U_LIB.S9S_MB_2U(SCH_1):GND
DK87    GND VSS1093 @S9S_MB_2U_LIB.S9S_MB_2U(SCH_1):GND
DK83    GND VSS1092 @S9S_MB_2U_LIB.S9S_MB_2U(SCH_1):GND
DK81    GND VSS1091 @S9S_MB_2U_LIB.S9S_MB_2U(SCH_1):GND
 DK8    GND VSS1090 @S9S_MB_2U_LIB.S9S_MB_2U(SCH_1):GND
DK79    GND VSS1089 @S9S_MB_2U_LIB.S9S_MB_2U(SCH_1):GND
DK77    GND VSS1088 @S9S_MB_2U_LIB.S9S_MB_2U(SCH_1):GND
DK73    GND VSS1087 @S9S_MB_2U_LIB.S9S_MB_2U(SCH_1):GND
DK49    GND VSS1086 @S9S_MB_2U_LIB.S9S_MB_2U(SCH_1):GND
 DK4    GND VSS1085 @S9S_MB_2U_LIB.S9S_MB_2U(SCH_1):GND
DK36    GND VSS1084 @S9S_MB_2U_LIB.S9S_MB_2U(SCH_1):GND
DK30    GND VSS1083 @S9S_MB_2U_LIB.S9S_MB_2U(SCH_1):GND
DK16    GND VSS1082 @S9S_MB_2U_LIB.S9S_MB_2U(SCH_1):GND
DJ88    GND VSS1081 @S9S_MB_2U_LIB.S9S_MB_2U(SCH_1):GND
DJ84    GND VSS1080 @S9S_MB_2U_LIB.S9S_MB_2U(SCH_1):GND
DJ82    GND VSS1079 @S9S_MB_2U_LIB.S9S_MB_2U(SCH_1):GND
DJ80    GND VSS1078 @S9S_MB_2U_LIB.S9S_MB_2U(SCH_1):GND
DJ74    GND VSS1076 @S9S_MB_2U_LIB.S9S_MB_2U(SCH_1):GND
DJ72    GND VSS1075 @S9S_MB_2U_LIB.S9S_MB_2U(SCH_1):GND
DJ66    GND VSS1074 @S9S_MB_2U_LIB.S9S_MB_2U(SCH_1):GND
DJ60    GND VSS1073 @S9S_MB_2U_LIB.S9S_MB_2U(SCH_1):GND
DJ56    GND VSS1072 @S9S_MB_2U_LIB.S9S_MB_2U(SCH_1):GND
DJ50    GND VSS1071 @S9S_MB_2U_LIB.S9S_MB_2U(SCH_1):GND
DJ48    GND VSS1070 @S9S_MB_2U_LIB.S9S_MB_2U(SCH_1):GND
DJ43    GND VSS1069 @S9S_MB_2U_LIB.S9S_MB_2U(SCH_1):GND
DJ41    GND VSS1068 @S9S_MB_2U_LIB.S9S_MB_2U(SCH_1):GND
DJ37    GND VSS1067 @S9S_MB_2U_LIB.S9S_MB_2U(SCH_1):GND
DJ31    GND VSS1066 @S9S_MB_2U_LIB.S9S_MB_2U(SCH_1):GND
DJ29    GND VSS1065 @S9S_MB_2U_LIB.S9S_MB_2U(SCH_1):GND
DJ23    GND VSS1062 @S9S_MB_2U_LIB.S9S_MB_2U(SCH_1):GND
DJ19    GND VSS1061 @S9S_MB_2U_LIB.S9S_MB_2U(SCH_1):GND
DH85    GND VSS1058 @S9S_MB_2U_LIB.S9S_MB_2U(SCH_1):GND
 DH8    GND VSS1057 @S9S_MB_2U_LIB.S9S_MB_2U(SCH_1):GND
DH77    GND VSS1056 @S9S_MB_2U_LIB.S9S_MB_2U(SCH_1):GND
DH71    GND VSS1055 @S9S_MB_2U_LIB.S9S_MB_2U(SCH_1):GND
DH65    GND VSS1053 @S9S_MB_2U_LIB.S9S_MB_2U(SCH_1):GND
DH57    GND VSS1049 @S9S_MB_2U_LIB.S9S_MB_2U(SCH_1):GND
DH47    GND VSS1046 @S9S_MB_2U_LIB.S9S_MB_2U(SCH_1):GND
DH40    GND VSS1045 @S9S_MB_2U_LIB.S9S_MB_2U(SCH_1):GND
 DH4    GND VSS1044 @S9S_MB_2U_LIB.S9S_MB_2U(SCH_1):GND
DH38    GND VSS1043 @S9S_MB_2U_LIB.S9S_MB_2U(SCH_1):GND
DH32    GND VSS1042 @S9S_MB_2U_LIB.S9S_MB_2U(SCH_1):GND
DH28    GND VSS1041 @S9S_MB_2U_LIB.S9S_MB_2U(SCH_1):GND
DH22    GND VSS1040 @S9S_MB_2U_LIB.S9S_MB_2U(SCH_1):GND
DH12    GND VSS1039 @S9S_MB_2U_LIB.S9S_MB_2U(SCH_1):GND
 DG9    GND VSS1038 @S9S_MB_2U_LIB.S9S_MB_2U(SCH_1):GND
DG88    GND VSS1037 @S9S_MB_2U_LIB.S9S_MB_2U(SCH_1):GND
DG84    GND VSS1035 @S9S_MB_2U_LIB.S9S_MB_2U(SCH_1):GND
DG80    GND VSS1034 @S9S_MB_2U_LIB.S9S_MB_2U(SCH_1):GND
DG76    GND VSS1033 @S9S_MB_2U_LIB.S9S_MB_2U(SCH_1):GND
DG70    GND VSS1032 @S9S_MB_2U_LIB.S9S_MB_2U(SCH_1):GND
 DG5    GND VSS1031 @S9S_MB_2U_LIB.S9S_MB_2U(SCH_1):GND
DG45    GND VSS1030 @S9S_MB_2U_LIB.S9S_MB_2U(SCH_1):GND
DG39    GND VSS1027 @S9S_MB_2U_LIB.S9S_MB_2U(SCH_1):GND
DG33    GND VSS1024 @S9S_MB_2U_LIB.S9S_MB_2U(SCH_1):GND
DG27    GND VSS1022 @S9S_MB_2U_LIB.S9S_MB_2U(SCH_1):GND
DF87    GND VSS1020 @S9S_MB_2U_LIB.S9S_MB_2U(SCH_1):GND
 DF8    GND VSS1019 @S9S_MB_2U_LIB.S9S_MB_2U(SCH_1):GND
DF79    GND VSS1018 @S9S_MB_2U_LIB.S9S_MB_2U(SCH_1):GND
 DF4    GND VSS1017 @S9S_MB_2U_LIB.S9S_MB_2U(SCH_1):GND
DE88    GND VSS1015 @S9S_MB_2U_LIB.S9S_MB_2U(SCH_1):GND
DE84    GND VSS1012 @S9S_MB_2U_LIB.S9S_MB_2U(SCH_1):GND
DE82    GND VSS1011 @S9S_MB_2U_LIB.S9S_MB_2U(SCH_1):GND
DE76    GND VSS1010 @S9S_MB_2U_LIB.S9S_MB_2U(SCH_1):GND
DE74    GND VSS1009 @S9S_MB_2U_LIB.S9S_MB_2U(SCH_1):GND
DE72    GND VSS1008 @S9S_MB_2U_LIB.S9S_MB_2U(SCH_1):GND
DE68    GND VSS1007 @S9S_MB_2U_LIB.S9S_MB_2U(SCH_1):GND
DE66    GND VSS1004 @S9S_MB_2U_LIB.S9S_MB_2U(SCH_1):GND
DE64    GND VSS1001 @S9S_MB_2U_LIB.S9S_MB_2U(SCH_1):GND
DE62    GND VSS999 @S9S_MB_2U_LIB.S9S_MB_2U(SCH_1):GND
DE60    GND VSS997 @S9S_MB_2U_LIB.S9S_MB_2U(SCH_1):GND
DE58    GND VSS996 @S9S_MB_2U_LIB.S9S_MB_2U(SCH_1):GND
DE56    GND VSS995 @S9S_MB_2U_LIB.S9S_MB_2U(SCH_1):GND
DE54    GND VSS994 @S9S_MB_2U_LIB.S9S_MB_2U(SCH_1):GND
DE52    GND VSS992 @S9S_MB_2U_LIB.S9S_MB_2U(SCH_1):GND
DE50    GND VSS991 @S9S_MB_2U_LIB.S9S_MB_2U(SCH_1):GND
DE48    GND VSS989 @S9S_MB_2U_LIB.S9S_MB_2U(SCH_1):GND
DE45    GND VSS988 @S9S_MB_2U_LIB.S9S_MB_2U(SCH_1):GND
DE43    GND VSS987 @S9S_MB_2U_LIB.S9S_MB_2U(SCH_1):GND
DE41    GND VSS986 @S9S_MB_2U_LIB.S9S_MB_2U(SCH_1):GND
DE37    GND VSS984 @S9S_MB_2U_LIB.S9S_MB_2U(SCH_1):GND
DE35    GND VSS983 @S9S_MB_2U_LIB.S9S_MB_2U(SCH_1):GND
DE33    GND VSS982 @S9S_MB_2U_LIB.S9S_MB_2U(SCH_1):GND
DE31    GND VSS981 @S9S_MB_2U_LIB.S9S_MB_2U(SCH_1):GND
DE29    GND VSS978 @S9S_MB_2U_LIB.S9S_MB_2U(SCH_1):GND
DE27    GND VSS977 @S9S_MB_2U_LIB.S9S_MB_2U(SCH_1):GND
DE25    GND VSS975 @S9S_MB_2U_LIB.S9S_MB_2U(SCH_1):GND
DE23    GND VSS974 @S9S_MB_2U_LIB.S9S_MB_2U(SCH_1):GND
DE21    GND VSS972 @S9S_MB_2U_LIB.S9S_MB_2U(SCH_1):GND
DE19    GND VSS971 @S9S_MB_2U_LIB.S9S_MB_2U(SCH_1):GND
DE17    GND VSS970 @S9S_MB_2U_LIB.S9S_MB_2U(SCH_1):GND
 DD8    GND VSS967 @S9S_MB_2U_LIB.S9S_MB_2U(SCH_1):GND
DD79    GND VSS965 @S9S_MB_2U_LIB.S9S_MB_2U(SCH_1):GND
 DD4    GND VSS964 @S9S_MB_2U_LIB.S9S_MB_2U(SCH_1):GND
 DC9    GND VSS963 @S9S_MB_2U_LIB.S9S_MB_2U(SCH_1):GND
DC88    GND VSS962 @S9S_MB_2U_LIB.S9S_MB_2U(SCH_1):GND
DC84    GND VSS961 @S9S_MB_2U_LIB.S9S_MB_2U(SCH_1):GND
DC80    GND VSS960 @S9S_MB_2U_LIB.S9S_MB_2U(SCH_1):GND
DC78    GND VSS958 @S9S_MB_2U_LIB.S9S_MB_2U(SCH_1):GND
DC76    GND VSS956 @S9S_MB_2U_LIB.S9S_MB_2U(SCH_1):GND
DC70    GND VSS954 @S9S_MB_2U_LIB.S9S_MB_2U(SCH_1):GND
 DC5    GND VSS953 @S9S_MB_2U_LIB.S9S_MB_2U(SCH_1):GND
DC45    GND VSS952 @S9S_MB_2U_LIB.S9S_MB_2U(SCH_1):GND
DC39    GND VSS951 @S9S_MB_2U_LIB.S9S_MB_2U(SCH_1):GND
DC33    GND VSS950 @S9S_MB_2U_LIB.S9S_MB_2U(SCH_1):GND
DC27    GND VSS949 @S9S_MB_2U_LIB.S9S_MB_2U(SCH_1):GND
DL52    GND VSS909 @S9S_MB_2U_LIB.S9S_MB_2U(SCH_1):GND
 DL5    GND VSS908 @S9S_MB_2U_LIB.S9S_MB_2U(SCH_1):GND
DL17    GND VSS905 @S9S_MB_2U_LIB.S9S_MB_2U(SCH_1):GND
DL13    GND VSS904 @S9S_MB_2U_LIB.S9S_MB_2U(SCH_1):GND
 DL1    GND VSS903 @S9S_MB_2U_LIB.S9S_MB_2U(SCH_1):GND
DK67    GND VSS894 @S9S_MB_2U_LIB.S9S_MB_2U(SCH_1):GND
DK61    GND VSS893 @S9S_MB_2U_LIB.S9S_MB_2U(SCH_1):GND
DK55    GND VSS890 @S9S_MB_2U_LIB.S9S_MB_2U(SCH_1):GND
DK42    GND VSS887 @S9S_MB_2U_LIB.S9S_MB_2U(SCH_1):GND
DK24    GND VSS883 @S9S_MB_2U_LIB.S9S_MB_2U(SCH_1):GND
DK18    GND VSS882 @S9S_MB_2U_LIB.S9S_MB_2U(SCH_1):GND
DK12    GND VSS880 @S9S_MB_2U_LIB.S9S_MB_2U(SCH_1):GND
DJ68    GND VSS872 @S9S_MB_2U_LIB.S9S_MB_2U(SCH_1):GND
DJ62    GND VSS870 @S9S_MB_2U_LIB.S9S_MB_2U(SCH_1):GND
DJ54    GND VSS867 @S9S_MB_2U_LIB.S9S_MB_2U(SCH_1):GND
DJ35    GND VSS861 @S9S_MB_2U_LIB.S9S_MB_2U(SCH_1):GND
DJ25    GND VSS857 @S9S_MB_2U_LIB.S9S_MB_2U(SCH_1):GND
DH75    GND VSS849 @S9S_MB_2U_LIB.S9S_MB_2U(SCH_1):GND
DH69    GND VSS847 @S9S_MB_2U_LIB.S9S_MB_2U(SCH_1):GND
DH63    GND VSS845 @S9S_MB_2U_LIB.S9S_MB_2U(SCH_1):GND
DH59    GND VSS844 @S9S_MB_2U_LIB.S9S_MB_2U(SCH_1):GND
DH53    GND VSS842 @S9S_MB_2U_LIB.S9S_MB_2U(SCH_1):GND
DH51    GND VSS841 @S9S_MB_2U_LIB.S9S_MB_2U(SCH_1):GND
DH44    GND VSS839 @S9S_MB_2U_LIB.S9S_MB_2U(SCH_1):GND
DH34    GND VSS835 @S9S_MB_2U_LIB.S9S_MB_2U(SCH_1):GND
DH26    GND VSS832 @S9S_MB_2U_LIB.S9S_MB_2U(SCH_1):GND
DH20    GND VSS830 @S9S_MB_2U_LIB.S9S_MB_2U(SCH_1):GND
DH16    GND VSS829 @S9S_MB_2U_LIB.S9S_MB_2U(SCH_1):GND
DG64    GND VSS821 @S9S_MB_2U_LIB.S9S_MB_2U(SCH_1):GND
DG58    GND VSS820 @S9S_MB_2U_LIB.S9S_MB_2U(SCH_1):GND
DG52    GND VSS817 @S9S_MB_2U_LIB.S9S_MB_2U(SCH_1):GND
DG21    GND VSS809 @S9S_MB_2U_LIB.S9S_MB_2U(SCH_1):GND
DG13    GND VSS808 @S9S_MB_2U_LIB.S9S_MB_2U(SCH_1):GND
 DG1    GND VSS807 @S9S_MB_2U_LIB.S9S_MB_2U(SCH_1):GND
DF91    GND VSS806 @S9S_MB_2U_LIB.S9S_MB_2U(SCH_1):GND
DF49    GND VSS802 @S9S_MB_2U_LIB.S9S_MB_2U(SCH_1):GND
DF16    GND VSS799 @S9S_MB_2U_LIB.S9S_MB_2U(SCH_1):GND
DF12    GND VSS798 @S9S_MB_2U_LIB.S9S_MB_2U(SCH_1):GND
DE70    GND VSS791 @S9S_MB_2U_LIB.S9S_MB_2U(SCH_1):GND
DE39    GND VSS776 @S9S_MB_2U_LIB.S9S_MB_2U(SCH_1):GND
DD49    GND VSS753 @S9S_MB_2U_LIB.S9S_MB_2U(SCH_1):GND
DD16    GND VSS748 @S9S_MB_2U_LIB.S9S_MB_2U(SCH_1):GND
DD12    GND VSS747 @S9S_MB_2U_LIB.S9S_MB_2U(SCH_1):GND
DC64    GND VSS739 @S9S_MB_2U_LIB.S9S_MB_2U(SCH_1):GND
DC58    GND VSS738 @S9S_MB_2U_LIB.S9S_MB_2U(SCH_1):GND
DC52    GND VSS735 @S9S_MB_2U_LIB.S9S_MB_2U(SCH_1):GND
DC21    GND VSS726 @S9S_MB_2U_LIB.S9S_MB_2U(SCH_1):GND
DC13    GND VSS725 @S9S_MB_2U_LIB.S9S_MB_2U(SCH_1):GND
 DC1    GND VSS724 @S9S_MB_2U_LIB.S9S_MB_2U(SCH_1):GND
DB91    GND VSS723 @S9S_MB_2U_LIB.S9S_MB_2U(SCH_1):GND

SOCKET4677_AZIF0045P001C01CS-SA  I11  U2
DB87    GND VSS948 @S9S_MB_2U_LIB.S9S_MB_2U(SCH_1):GND
 DB8    GND VSS947 @S9S_MB_2U_LIB.S9S_MB_2U(SCH_1):GND
DB77    GND VSS946 @S9S_MB_2U_LIB.S9S_MB_2U(SCH_1):GND
DB71    GND VSS944 @S9S_MB_2U_LIB.S9S_MB_2U(SCH_1):GND
DB65    GND VSS943 @S9S_MB_2U_LIB.S9S_MB_2U(SCH_1):GND
DB57    GND VSS942 @S9S_MB_2U_LIB.S9S_MB_2U(SCH_1):GND
DB47    GND VSS941 @S9S_MB_2U_LIB.S9S_MB_2U(SCH_1):GND
DB40    GND VSS940 @S9S_MB_2U_LIB.S9S_MB_2U(SCH_1):GND
 DB4    GND VSS939 @S9S_MB_2U_LIB.S9S_MB_2U(SCH_1):GND
DB38    GND VSS938 @S9S_MB_2U_LIB.S9S_MB_2U(SCH_1):GND
DB32    GND VSS937 @S9S_MB_2U_LIB.S9S_MB_2U(SCH_1):GND
DB28    GND VSS936 @S9S_MB_2U_LIB.S9S_MB_2U(SCH_1):GND
DB22    GND VSS935 @S9S_MB_2U_LIB.S9S_MB_2U(SCH_1):GND
DB12    GND VSS933 @S9S_MB_2U_LIB.S9S_MB_2U(SCH_1):GND
DA88    GND VSS932 @S9S_MB_2U_LIB.S9S_MB_2U(SCH_1):GND
DA84    GND VSS931 @S9S_MB_2U_LIB.S9S_MB_2U(SCH_1):GND
DA82    GND VSS930 @S9S_MB_2U_LIB.S9S_MB_2U(SCH_1):GND
DA80    GND VSS929 @S9S_MB_2U_LIB.S9S_MB_2U(SCH_1):GND
DA74    GND VSS928 @S9S_MB_2U_LIB.S9S_MB_2U(SCH_1):GND
DA72    GND VSS927 @S9S_MB_2U_LIB.S9S_MB_2U(SCH_1):GND
DA66    GND VSS926 @S9S_MB_2U_LIB.S9S_MB_2U(SCH_1):GND
DA62    GND VSS925 @S9S_MB_2U_LIB.S9S_MB_2U(SCH_1):GND
DA60    GND VSS924 @S9S_MB_2U_LIB.S9S_MB_2U(SCH_1):GND
DA58    GND VSS923 @S9S_MB_2U_LIB.S9S_MB_2U(SCH_1):GND
DA56    GND VSS922 @S9S_MB_2U_LIB.S9S_MB_2U(SCH_1):GND
DA54    GND VSS921 @S9S_MB_2U_LIB.S9S_MB_2U(SCH_1):GND
DA50    GND VSS920 @S9S_MB_2U_LIB.S9S_MB_2U(SCH_1):GND
DA48    GND VSS919 @S9S_MB_2U_LIB.S9S_MB_2U(SCH_1):GND
DA41    GND VSS918 @S9S_MB_2U_LIB.S9S_MB_2U(SCH_1):GND
DA37    GND VSS917 @S9S_MB_2U_LIB.S9S_MB_2U(SCH_1):GND
DA35    GND VSS916 @S9S_MB_2U_LIB.S9S_MB_2U(SCH_1):GND
DA33    GND VSS915 @S9S_MB_2U_LIB.S9S_MB_2U(SCH_1):GND
DA31    GND VSS914 @S9S_MB_2U_LIB.S9S_MB_2U(SCH_1):GND
DA29    GND VSS913 @S9S_MB_2U_LIB.S9S_MB_2U(SCH_1):GND
DA25    GND VSS912 @S9S_MB_2U_LIB.S9S_MB_2U(SCH_1):GND
DA23    GND VSS911 @S9S_MB_2U_LIB.S9S_MB_2U(SCH_1):GND
DA19    GND VSS910 @S9S_MB_2U_LIB.S9S_MB_2U(SCH_1):GND
CY83    GND VSS863 @S9S_MB_2U_LIB.S9S_MB_2U(SCH_1):GND
CY81    GND VSS862 @S9S_MB_2U_LIB.S9S_MB_2U(SCH_1):GND
 CY8    GND VSS860 @S9S_MB_2U_LIB.S9S_MB_2U(SCH_1):GND
CY77    GND VSS859 @S9S_MB_2U_LIB.S9S_MB_2U(SCH_1):GND
CY73    GND VSS858 @S9S_MB_2U_LIB.S9S_MB_2U(SCH_1):GND
CY63    GND VSS856 @S9S_MB_2U_LIB.S9S_MB_2U(SCH_1):GND
CY30    GND VSS855 @S9S_MB_2U_LIB.S9S_MB_2U(SCH_1):GND
CY26    GND VSS854 @S9S_MB_2U_LIB.S9S_MB_2U(SCH_1):GND
CY18    GND VSS853 @S9S_MB_2U_LIB.S9S_MB_2U(SCH_1):GND
CY16    GND VSS852 @S9S_MB_2U_LIB.S9S_MB_2U(SCH_1):GND
CY12    GND VSS851 @S9S_MB_2U_LIB.S9S_MB_2U(SCH_1):GND
 CW9    GND VSS850 @S9S_MB_2U_LIB.S9S_MB_2U(SCH_1):GND
CW88    GND VSS848 @S9S_MB_2U_LIB.S9S_MB_2U(SCH_1):GND
CW84    GND VSS846 @S9S_MB_2U_LIB.S9S_MB_2U(SCH_1):GND
CW78    GND VSS843 @S9S_MB_2U_LIB.S9S_MB_2U(SCH_1):GND
CW72    GND VSS840 @S9S_MB_2U_LIB.S9S_MB_2U(SCH_1):GND
 CW5    GND VSS838 @S9S_MB_2U_LIB.S9S_MB_2U(SCH_1):GND
CW17    GND VSS837 @S9S_MB_2U_LIB.S9S_MB_2U(SCH_1):GND
CW13    GND VSS836 @S9S_MB_2U_LIB.S9S_MB_2U(SCH_1):GND
 CW1    GND VSS834 @S9S_MB_2U_LIB.S9S_MB_2U(SCH_1):GND
CV91    GND VSS833 @S9S_MB_2U_LIB.S9S_MB_2U(SCH_1):GND
CV87    GND VSS831 @S9S_MB_2U_LIB.S9S_MB_2U(SCH_1):GND
CV83    GND VSS828 @S9S_MB_2U_LIB.S9S_MB_2U(SCH_1):GND
 CV8    GND VSS827 @S9S_MB_2U_LIB.S9S_MB_2U(SCH_1):GND
CV75    GND VSS826 @S9S_MB_2U_LIB.S9S_MB_2U(SCH_1):GND
 CV4    GND VSS825 @S9S_MB_2U_LIB.S9S_MB_2U(SCH_1):GND
CV12    GND VSS824 @S9S_MB_2U_LIB.S9S_MB_2U(SCH_1):GND
CU88    GND VSS823 @S9S_MB_2U_LIB.S9S_MB_2U(SCH_1):GND
CU84    GND VSS822 @S9S_MB_2U_LIB.S9S_MB_2U(SCH_1):GND
CU68    GND VSS819 @S9S_MB_2U_LIB.S9S_MB_2U(SCH_1):GND
CU66    GND VSS818 @S9S_MB_2U_LIB.S9S_MB_2U(SCH_1):GND
CU60    GND VSS816 @S9S_MB_2U_LIB.S9S_MB_2U(SCH_1):GND
CU23    GND VSS815 @S9S_MB_2U_LIB.S9S_MB_2U(SCH_1):GND
CU21    GND VSS814 @S9S_MB_2U_LIB.S9S_MB_2U(SCH_1):GND
CU19    GND VSS813 @S9S_MB_2U_LIB.S9S_MB_2U(SCH_1):GND
CT81    GND VSS812 @S9S_MB_2U_LIB.S9S_MB_2U(SCH_1):GND
CT73    GND VSS811 @S9S_MB_2U_LIB.S9S_MB_2U(SCH_1):GND
CT69    GND VSS810 @S9S_MB_2U_LIB.S9S_MB_2U(SCH_1):GND
CT12    GND VSS805 @S9S_MB_2U_LIB.S9S_MB_2U(SCH_1):GND
CT10    GND VSS804 @S9S_MB_2U_LIB.S9S_MB_2U(SCH_1):GND
CR90    GND VSS803 @S9S_MB_2U_LIB.S9S_MB_2U(SCH_1):GND
 CR9    GND VSS801 @S9S_MB_2U_LIB.S9S_MB_2U(SCH_1):GND
CR88    GND VSS800 @S9S_MB_2U_LIB.S9S_MB_2U(SCH_1):GND
CR84    GND VSS797 @S9S_MB_2U_LIB.S9S_MB_2U(SCH_1):GND
CR64    GND VSS796 @S9S_MB_2U_LIB.S9S_MB_2U(SCH_1):GND
CR62    GND VSS795 @S9S_MB_2U_LIB.S9S_MB_2U(SCH_1):GND
 CR5    GND VSS794 @S9S_MB_2U_LIB.S9S_MB_2U(SCH_1):GND
CR17    GND VSS793 @S9S_MB_2U_LIB.S9S_MB_2U(SCH_1):GND
CR13    GND VSS792 @S9S_MB_2U_LIB.S9S_MB_2U(SCH_1):GND
CR11    GND VSS790 @S9S_MB_2U_LIB.S9S_MB_2U(SCH_1):GND
 CR1    GND VSS789 @S9S_MB_2U_LIB.S9S_MB_2U(SCH_1):GND
CP91    GND VSS788 @S9S_MB_2U_LIB.S9S_MB_2U(SCH_1):GND
CP87    GND VSS787 @S9S_MB_2U_LIB.S9S_MB_2U(SCH_1):GND
CP83    GND VSS786 @S9S_MB_2U_LIB.S9S_MB_2U(SCH_1):GND
 CP8    GND VSS785 @S9S_MB_2U_LIB.S9S_MB_2U(SCH_1):GND
CP77    GND VSS784 @S9S_MB_2U_LIB.S9S_MB_2U(SCH_1):GND
CP75    GND VSS783 @S9S_MB_2U_LIB.S9S_MB_2U(SCH_1):GND
 CP4    GND VSS782 @S9S_MB_2U_LIB.S9S_MB_2U(SCH_1):GND
CP18    GND VSS781 @S9S_MB_2U_LIB.S9S_MB_2U(SCH_1):GND
CP12    GND VSS780 @S9S_MB_2U_LIB.S9S_MB_2U(SCH_1):GND
CN86    GND VSS779 @S9S_MB_2U_LIB.S9S_MB_2U(SCH_1):GND
CN84    GND VSS778 @S9S_MB_2U_LIB.S9S_MB_2U(SCH_1):GND
CN74    GND VSS777 @S9S_MB_2U_LIB.S9S_MB_2U(SCH_1):GND
CN72    GND VSS775 @S9S_MB_2U_LIB.S9S_MB_2U(SCH_1):GND
CN70    GND VSS774 @S9S_MB_2U_LIB.S9S_MB_2U(SCH_1):GND
CN68    GND VSS773 @S9S_MB_2U_LIB.S9S_MB_2U(SCH_1):GND
CM85    GND VSS772 @S9S_MB_2U_LIB.S9S_MB_2U(SCH_1):GND
CM83    GND VSS771 @S9S_MB_2U_LIB.S9S_MB_2U(SCH_1):GND
CM81    GND VSS770 @S9S_MB_2U_LIB.S9S_MB_2U(SCH_1):GND
 CM8    GND VSS769 @S9S_MB_2U_LIB.S9S_MB_2U(SCH_1):GND
CM79    GND VSS768 @S9S_MB_2U_LIB.S9S_MB_2U(SCH_1):GND
CM67    GND VSS767 @S9S_MB_2U_LIB.S9S_MB_2U(SCH_1):GND
CM65    GND VSS766 @S9S_MB_2U_LIB.S9S_MB_2U(SCH_1):GND
CM61    GND VSS765 @S9S_MB_2U_LIB.S9S_MB_2U(SCH_1):GND
 CM4    GND VSS764 @S9S_MB_2U_LIB.S9S_MB_2U(SCH_1):GND
CM24    GND VSS763 @S9S_MB_2U_LIB.S9S_MB_2U(SCH_1):GND
CM20    GND VSS762 @S9S_MB_2U_LIB.S9S_MB_2U(SCH_1):GND
CM12    GND VSS761 @S9S_MB_2U_LIB.S9S_MB_2U(SCH_1):GND
 CL9    GND VSS760 @S9S_MB_2U_LIB.S9S_MB_2U(SCH_1):GND
CL82    GND VSS759 @S9S_MB_2U_LIB.S9S_MB_2U(SCH_1):GND
CL80    GND VSS758 @S9S_MB_2U_LIB.S9S_MB_2U(SCH_1):GND
CL78    GND VSS757 @S9S_MB_2U_LIB.S9S_MB_2U(SCH_1):GND
CL74    GND VSS756 @S9S_MB_2U_LIB.S9S_MB_2U(SCH_1):GND
CL62    GND VSS755 @S9S_MB_2U_LIB.S9S_MB_2U(SCH_1):GND
 CL5    GND VSS754 @S9S_MB_2U_LIB.S9S_MB_2U(SCH_1):GND
CL17    GND VSS752 @S9S_MB_2U_LIB.S9S_MB_2U(SCH_1):GND
CL13    GND VSS751 @S9S_MB_2U_LIB.S9S_MB_2U(SCH_1):GND
 CL1    GND VSS750 @S9S_MB_2U_LIB.S9S_MB_2U(SCH_1):GND
CK81    GND VSS749 @S9S_MB_2U_LIB.S9S_MB_2U(SCH_1):GND
CK69    GND VSS745 @S9S_MB_2U_LIB.S9S_MB_2U(SCH_1):GND
CK63    GND VSS744 @S9S_MB_2U_LIB.S9S_MB_2U(SCH_1):GND
DB75    GND VSS719 @S9S_MB_2U_LIB.S9S_MB_2U(SCH_1):GND
DB69    GND VSS717 @S9S_MB_2U_LIB.S9S_MB_2U(SCH_1):GND
DB63    GND VSS715 @S9S_MB_2U_LIB.S9S_MB_2U(SCH_1):GND
DB59    GND VSS714 @S9S_MB_2U_LIB.S9S_MB_2U(SCH_1):GND
DB53    GND VSS712 @S9S_MB_2U_LIB.S9S_MB_2U(SCH_1):GND
DB51    GND VSS711 @S9S_MB_2U_LIB.S9S_MB_2U(SCH_1):GND
DB44    GND VSS709 @S9S_MB_2U_LIB.S9S_MB_2U(SCH_1):GND
DB34    GND VSS705 @S9S_MB_2U_LIB.S9S_MB_2U(SCH_1):GND
DB26    GND VSS702 @S9S_MB_2U_LIB.S9S_MB_2U(SCH_1):GND
DB20    GND VSS700 @S9S_MB_2U_LIB.S9S_MB_2U(SCH_1):GND
DB16    GND VSS699 @S9S_MB_2U_LIB.S9S_MB_2U(SCH_1):GND
DA68    GND VSS690 @S9S_MB_2U_LIB.S9S_MB_2U(SCH_1):GND
DA43    GND VSS679 @S9S_MB_2U_LIB.S9S_MB_2U(SCH_1):GND
 CY4    GND VSS611 @S9S_MB_2U_LIB.S9S_MB_2U(SCH_1):GND
CW70    GND VSS595 @S9S_MB_2U_LIB.S9S_MB_2U(SCH_1):GND
CW33    GND VSS583 @S9S_MB_2U_LIB.S9S_MB_2U(SCH_1):GND
CV79    GND VSS571 @S9S_MB_2U_LIB.S9S_MB_2U(SCH_1):GND
CV26    GND VSS562 @S9S_MB_2U_LIB.S9S_MB_2U(SCH_1):GND
CV16    GND VSS558 @S9S_MB_2U_LIB.S9S_MB_2U(SCH_1):GND
CU78    GND VSS554 @S9S_MB_2U_LIB.S9S_MB_2U(SCH_1):GND
CU72    GND VSS553 @S9S_MB_2U_LIB.S9S_MB_2U(SCH_1):GND
CU25    GND VSS544 @S9S_MB_2U_LIB.S9S_MB_2U(SCH_1):GND
CT89    GND VSS537 @S9S_MB_2U_LIB.S9S_MB_2U(SCH_1):GND
 CT8    GND VSS534 @S9S_MB_2U_LIB.S9S_MB_2U(SCH_1):GND
 CT4    GND VSS526 @S9S_MB_2U_LIB.S9S_MB_2U(SCH_1):GND
CT16    GND VSS521 @S9S_MB_2U_LIB.S9S_MB_2U(SCH_1):GND
CR78    GND VSS514 @S9S_MB_2U_LIB.S9S_MB_2U(SCH_1):GND
CP79    GND VSS493 @S9S_MB_2U_LIB.S9S_MB_2U(SCH_1):GND
CP16    GND VSS478 @S9S_MB_2U_LIB.S9S_MB_2U(SCH_1):GND
CN76    GND VSS471 @S9S_MB_2U_LIB.S9S_MB_2U(SCH_1):GND
CM22    GND VSS438 @S9S_MB_2U_LIB.S9S_MB_2U(SCH_1):GND
CM16    GND VSS436 @S9S_MB_2U_LIB.S9S_MB_2U(SCH_1):GND

SOCKET4677_AZIF0045P001C01CS-SA  I12  U2
 CK8    GND VSS746 @S9S_MB_2U_LIB.S9S_MB_2U(SCH_1):GND
CK26    GND VSS743 @S9S_MB_2U_LIB.S9S_MB_2U(SCH_1):GND
CK20    GND VSS742 @S9S_MB_2U_LIB.S9S_MB_2U(SCH_1):GND
CK16    GND VSS741 @S9S_MB_2U_LIB.S9S_MB_2U(SCH_1):GND
CK12    GND VSS740 @S9S_MB_2U_LIB.S9S_MB_2U(SCH_1):GND
CJ80    GND VSS737 @S9S_MB_2U_LIB.S9S_MB_2U(SCH_1):GND
CJ60    GND VSS736 @S9S_MB_2U_LIB.S9S_MB_2U(SCH_1):GND
CH89    GND VSS734 @S9S_MB_2U_LIB.S9S_MB_2U(SCH_1):GND
CH87    GND VSS733 @S9S_MB_2U_LIB.S9S_MB_2U(SCH_1):GND
CH85    GND VSS732 @S9S_MB_2U_LIB.S9S_MB_2U(SCH_1):GND
CH83    GND VSS731 @S9S_MB_2U_LIB.S9S_MB_2U(SCH_1):GND
 CH8    GND VSS730 @S9S_MB_2U_LIB.S9S_MB_2U(SCH_1):GND
CH79    GND VSS729 @S9S_MB_2U_LIB.S9S_MB_2U(SCH_1):GND
CH73    GND VSS728 @S9S_MB_2U_LIB.S9S_MB_2U(SCH_1):GND
CH67    GND VSS727 @S9S_MB_2U_LIB.S9S_MB_2U(SCH_1):GND
 CH4    GND VSS722 @S9S_MB_2U_LIB.S9S_MB_2U(SCH_1):GND
CH20    GND VSS721 @S9S_MB_2U_LIB.S9S_MB_2U(SCH_1):GND
CH16    GND VSS720 @S9S_MB_2U_LIB.S9S_MB_2U(SCH_1):GND
CH12    GND VSS718 @S9S_MB_2U_LIB.S9S_MB_2U(SCH_1):GND
 CG9    GND VSS716 @S9S_MB_2U_LIB.S9S_MB_2U(SCH_1):GND
CG78    GND VSS713 @S9S_MB_2U_LIB.S9S_MB_2U(SCH_1):GND
CG74    GND VSS710 @S9S_MB_2U_LIB.S9S_MB_2U(SCH_1):GND
CG72    GND VSS708 @S9S_MB_2U_LIB.S9S_MB_2U(SCH_1):GND
CG70    GND VSS707 @S9S_MB_2U_LIB.S9S_MB_2U(SCH_1):GND
CG64    GND VSS706 @S9S_MB_2U_LIB.S9S_MB_2U(SCH_1):GND
CG62    GND VSS704 @S9S_MB_2U_LIB.S9S_MB_2U(SCH_1):GND
 CG5    GND VSS703 @S9S_MB_2U_LIB.S9S_MB_2U(SCH_1):GND
CG25    GND VSS701 @S9S_MB_2U_LIB.S9S_MB_2U(SCH_1):GND
CG23    GND VSS698 @S9S_MB_2U_LIB.S9S_MB_2U(SCH_1):GND
CG21    GND VSS697 @S9S_MB_2U_LIB.S9S_MB_2U(SCH_1):GND
CG17    GND VSS696 @S9S_MB_2U_LIB.S9S_MB_2U(SCH_1):GND
CG13    GND VSS695 @S9S_MB_2U_LIB.S9S_MB_2U(SCH_1):GND
 CG1    GND VSS694 @S9S_MB_2U_LIB.S9S_MB_2U(SCH_1):GND
 CF8    GND VSS693 @S9S_MB_2U_LIB.S9S_MB_2U(SCH_1):GND
CF71    GND VSS692 @S9S_MB_2U_LIB.S9S_MB_2U(SCH_1):GND
CF69    GND VSS691 @S9S_MB_2U_LIB.S9S_MB_2U(SCH_1):GND
 CF4    GND VSS689 @S9S_MB_2U_LIB.S9S_MB_2U(SCH_1):GND
CF20    GND VSS688 @S9S_MB_2U_LIB.S9S_MB_2U(SCH_1):GND
CF16    GND VSS687 @S9S_MB_2U_LIB.S9S_MB_2U(SCH_1):GND
CF12    GND VSS686 @S9S_MB_2U_LIB.S9S_MB_2U(SCH_1):GND
CE78    GND VSS685 @S9S_MB_2U_LIB.S9S_MB_2U(SCH_1):GND
CE76    GND VSS684 @S9S_MB_2U_LIB.S9S_MB_2U(SCH_1):GND
CE72    GND VSS683 @S9S_MB_2U_LIB.S9S_MB_2U(SCH_1):GND
CE66    GND VSS682 @S9S_MB_2U_LIB.S9S_MB_2U(SCH_1):GND
CE60    GND VSS681 @S9S_MB_2U_LIB.S9S_MB_2U(SCH_1):GND
 CE3    GND VSS680 @S9S_MB_2U_LIB.S9S_MB_2U(SCH_1):GND
 CD8    GND VSS678 @S9S_MB_2U_LIB.S9S_MB_2U(SCH_1):GND
CD77    GND VSS677 @S9S_MB_2U_LIB.S9S_MB_2U(SCH_1):GND
CD75    GND VSS676 @S9S_MB_2U_LIB.S9S_MB_2U(SCH_1):GND
CD61    GND VSS675 @S9S_MB_2U_LIB.S9S_MB_2U(SCH_1):GND
 CD4    GND VSS674 @S9S_MB_2U_LIB.S9S_MB_2U(SCH_1):GND
CD20    GND VSS673 @S9S_MB_2U_LIB.S9S_MB_2U(SCH_1):GND
CD16    GND VSS672 @S9S_MB_2U_LIB.S9S_MB_2U(SCH_1):GND
CD12    GND VSS671 @S9S_MB_2U_LIB.S9S_MB_2U(SCH_1):GND
 CC9    GND VSS670 @S9S_MB_2U_LIB.S9S_MB_2U(SCH_1):GND
CC74    GND VSS669 @S9S_MB_2U_LIB.S9S_MB_2U(SCH_1):GND
CC72    GND VSS668 @S9S_MB_2U_LIB.S9S_MB_2U(SCH_1):GND
CC70    GND VSS667 @S9S_MB_2U_LIB.S9S_MB_2U(SCH_1):GND
CC62    GND VSS666 @S9S_MB_2U_LIB.S9S_MB_2U(SCH_1):GND
 CC5    GND VSS665 @S9S_MB_2U_LIB.S9S_MB_2U(SCH_1):GND
CC31    GND VSS664 @S9S_MB_2U_LIB.S9S_MB_2U(SCH_1):GND
CC17    GND VSS661 @S9S_MB_2U_LIB.S9S_MB_2U(SCH_1):GND
CC13    GND VSS660 @S9S_MB_2U_LIB.S9S_MB_2U(SCH_1):GND
CB89    GND VSS656 @S9S_MB_2U_LIB.S9S_MB_2U(SCH_1):GND
CB87    GND VSS655 @S9S_MB_2U_LIB.S9S_MB_2U(SCH_1):GND
CB85    GND VSS654 @S9S_MB_2U_LIB.S9S_MB_2U(SCH_1):GND
CB83    GND VSS653 @S9S_MB_2U_LIB.S9S_MB_2U(SCH_1):GND
CB81    GND VSS652 @S9S_MB_2U_LIB.S9S_MB_2U(SCH_1):GND
 CB8    GND VSS651 @S9S_MB_2U_LIB.S9S_MB_2U(SCH_1):GND
CB79    GND VSS650 @S9S_MB_2U_LIB.S9S_MB_2U(SCH_1):GND
CB73    GND VSS649 @S9S_MB_2U_LIB.S9S_MB_2U(SCH_1):GND
CB71    GND VSS648 @S9S_MB_2U_LIB.S9S_MB_2U(SCH_1):GND
CB69    GND VSS647 @S9S_MB_2U_LIB.S9S_MB_2U(SCH_1):GND
CB67    GND VSS646 @S9S_MB_2U_LIB.S9S_MB_2U(SCH_1):GND
CB65    GND VSS645 @S9S_MB_2U_LIB.S9S_MB_2U(SCH_1):GND
CB63    GND VSS644 @S9S_MB_2U_LIB.S9S_MB_2U(SCH_1):GND
CB59    GND VSS643 @S9S_MB_2U_LIB.S9S_MB_2U(SCH_1):GND
CB57    GND VSS642 @S9S_MB_2U_LIB.S9S_MB_2U(SCH_1):GND
CB55    GND VSS641 @S9S_MB_2U_LIB.S9S_MB_2U(SCH_1):GND
CB53    GND VSS640 @S9S_MB_2U_LIB.S9S_MB_2U(SCH_1):GND
CB51    GND VSS639 @S9S_MB_2U_LIB.S9S_MB_2U(SCH_1):GND
CB49    GND VSS638 @S9S_MB_2U_LIB.S9S_MB_2U(SCH_1):GND
CB47    GND VSS637 @S9S_MB_2U_LIB.S9S_MB_2U(SCH_1):GND
CB44    GND VSS636 @S9S_MB_2U_LIB.S9S_MB_2U(SCH_1):GND
CB42    GND VSS635 @S9S_MB_2U_LIB.S9S_MB_2U(SCH_1):GND
CB40    GND VSS634 @S9S_MB_2U_LIB.S9S_MB_2U(SCH_1):GND
 CB4    GND VSS633 @S9S_MB_2U_LIB.S9S_MB_2U(SCH_1):GND
CB38    GND VSS632 @S9S_MB_2U_LIB.S9S_MB_2U(SCH_1):GND
CB36    GND VSS631 @S9S_MB_2U_LIB.S9S_MB_2U(SCH_1):GND
CB34    GND VSS630 @S9S_MB_2U_LIB.S9S_MB_2U(SCH_1):GND
CB32    GND VSS629 @S9S_MB_2U_LIB.S9S_MB_2U(SCH_1):GND
CB28    GND VSS628 @S9S_MB_2U_LIB.S9S_MB_2U(SCH_1):GND
CB26    GND VSS627 @S9S_MB_2U_LIB.S9S_MB_2U(SCH_1):GND
CB24    GND VSS626 @S9S_MB_2U_LIB.S9S_MB_2U(SCH_1):GND
CB22    GND VSS625 @S9S_MB_2U_LIB.S9S_MB_2U(SCH_1):GND
CB20    GND VSS624 @S9S_MB_2U_LIB.S9S_MB_2U(SCH_1):GND
CB16    GND VSS623 @S9S_MB_2U_LIB.S9S_MB_2U(SCH_1):GND
CB12    GND VSS622 @S9S_MB_2U_LIB.S9S_MB_2U(SCH_1):GND
CA31    GND VSS621 @S9S_MB_2U_LIB.S9S_MB_2U(SCH_1):GND
 CA3    GND VSS620 @S9S_MB_2U_LIB.S9S_MB_2U(SCH_1):GND
 BY8    GND VSS608 @S9S_MB_2U_LIB.S9S_MB_2U(SCH_1):GND
 BY4    GND VSS607 @S9S_MB_2U_LIB.S9S_MB_2U(SCH_1):GND
BY20    GND VSS606 @S9S_MB_2U_LIB.S9S_MB_2U(SCH_1):GND
BY16    GND VSS605 @S9S_MB_2U_LIB.S9S_MB_2U(SCH_1):GND
BY12    GND VSS604 @S9S_MB_2U_LIB.S9S_MB_2U(SCH_1):GND
 BW9    GND VSS603 @S9S_MB_2U_LIB.S9S_MB_2U(SCH_1):GND
 BW5    GND VSS602 @S9S_MB_2U_LIB.S9S_MB_2U(SCH_1):GND
BW31    GND VSS601 @S9S_MB_2U_LIB.S9S_MB_2U(SCH_1):GND
 BW3    GND VSS600 @S9S_MB_2U_LIB.S9S_MB_2U(SCH_1):GND
BW29    GND VSS599 @S9S_MB_2U_LIB.S9S_MB_2U(SCH_1):GND
BW27    GND VSS598 @S9S_MB_2U_LIB.S9S_MB_2U(SCH_1):GND
BW17    GND VSS597 @S9S_MB_2U_LIB.S9S_MB_2U(SCH_1):GND
BW13    GND VSS596 @S9S_MB_2U_LIB.S9S_MB_2U(SCH_1):GND
 BV8    GND VSS594 @S9S_MB_2U_LIB.S9S_MB_2U(SCH_1):GND
 BV6    GND VSS593 @S9S_MB_2U_LIB.S9S_MB_2U(SCH_1):GND
 BV4    GND VSS592 @S9S_MB_2U_LIB.S9S_MB_2U(SCH_1):GND
BV20    GND VSS591 @S9S_MB_2U_LIB.S9S_MB_2U(SCH_1):GND
 BV2    GND VSS590 @S9S_MB_2U_LIB.S9S_MB_2U(SCH_1):GND
BV18    GND VSS589 @S9S_MB_2U_LIB.S9S_MB_2U(SCH_1):GND
BV16    GND VSS588 @S9S_MB_2U_LIB.S9S_MB_2U(SCH_1):GND
BV12    GND VSS587 @S9S_MB_2U_LIB.S9S_MB_2U(SCH_1):GND
 BU7    GND VSS586 @S9S_MB_2U_LIB.S9S_MB_2U(SCH_1):GND
BU31    GND VSS585 @S9S_MB_2U_LIB.S9S_MB_2U(SCH_1):GND
BU25    GND VSS584 @S9S_MB_2U_LIB.S9S_MB_2U(SCH_1):GND
BU23    GND VSS582 @S9S_MB_2U_LIB.S9S_MB_2U(SCH_1):GND
BU21    GND VSS581 @S9S_MB_2U_LIB.S9S_MB_2U(SCH_1):GND
BU19    GND VSS580 @S9S_MB_2U_LIB.S9S_MB_2U(SCH_1):GND
BU15    GND VSS579 @S9S_MB_2U_LIB.S9S_MB_2U(SCH_1):GND
 BT8    GND VSS578 @S9S_MB_2U_LIB.S9S_MB_2U(SCH_1):GND
 BT4    GND VSS577 @S9S_MB_2U_LIB.S9S_MB_2U(SCH_1):GND
BT20    GND VSS576 @S9S_MB_2U_LIB.S9S_MB_2U(SCH_1):GND
BT16    GND VSS575 @S9S_MB_2U_LIB.S9S_MB_2U(SCH_1):GND
BT12    GND VSS574 @S9S_MB_2U_LIB.S9S_MB_2U(SCH_1):GND
BR90    GND VSS573 @S9S_MB_2U_LIB.S9S_MB_2U(SCH_1):GND
BR88    GND VSS570 @S9S_MB_2U_LIB.S9S_MB_2U(SCH_1):GND
BR86    GND VSS569 @S9S_MB_2U_LIB.S9S_MB_2U(SCH_1):GND
BR84    GND VSS568 @S9S_MB_2U_LIB.S9S_MB_2U(SCH_1):GND
BR82    GND VSS567 @S9S_MB_2U_LIB.S9S_MB_2U(SCH_1):GND
BR80    GND VSS566 @S9S_MB_2U_LIB.S9S_MB_2U(SCH_1):GND
BR76    GND VSS565 @S9S_MB_2U_LIB.S9S_MB_2U(SCH_1):GND
BR74    GND VSS564 @S9S_MB_2U_LIB.S9S_MB_2U(SCH_1):GND
BR72    GND VSS563 @S9S_MB_2U_LIB.S9S_MB_2U(SCH_1):GND
BR70    GND VSS561 @S9S_MB_2U_LIB.S9S_MB_2U(SCH_1):GND
BR68    GND VSS560 @S9S_MB_2U_LIB.S9S_MB_2U(SCH_1):GND
BR66    GND VSS559 @S9S_MB_2U_LIB.S9S_MB_2U(SCH_1):GND
BR64    GND VSS557 @S9S_MB_2U_LIB.S9S_MB_2U(SCH_1):GND
BR58    GND VSS556 @S9S_MB_2U_LIB.S9S_MB_2U(SCH_1):GND
BR56    GND VSS555 @S9S_MB_2U_LIB.S9S_MB_2U(SCH_1):GND
BR54    GND VSS552 @S9S_MB_2U_LIB.S9S_MB_2U(SCH_1):GND
BR52    GND VSS551 @S9S_MB_2U_LIB.S9S_MB_2U(SCH_1):GND
BR50    GND VSS550 @S9S_MB_2U_LIB.S9S_MB_2U(SCH_1):GND
BR48    GND VSS549 @S9S_MB_2U_LIB.S9S_MB_2U(SCH_1):GND
BR45    GND VSS548 @S9S_MB_2U_LIB.S9S_MB_2U(SCH_1):GND
BR43    GND VSS547 @S9S_MB_2U_LIB.S9S_MB_2U(SCH_1):GND
BR41    GND VSS546 @S9S_MB_2U_LIB.S9S_MB_2U(SCH_1):GND
BR39    GND VSS545 @S9S_MB_2U_LIB.S9S_MB_2U(SCH_1):GND
BR37    GND VSS543 @S9S_MB_2U_LIB.S9S_MB_2U(SCH_1):GND
BR35    GND VSS542 @S9S_MB_2U_LIB.S9S_MB_2U(SCH_1):GND
 CK4    GND VSS396 @S9S_MB_2U_LIB.S9S_MB_2U(SCH_1):GND
CJ76    GND VSS383 @S9S_MB_2U_LIB.S9S_MB_2U(SCH_1):GND


DRAWING: @S9S_MB_2U_LIB.S9S_MB_2U(SCH_1):PAGE41 

SOCKET4677_AZIF0045P001C01CS-SA  I9  U2
 BR9    GND VSS572 @S9S_MB_2U_LIB.S9S_MB_2U(SCH_1):GND
BR33    GND VSS541 @S9S_MB_2U_LIB.S9S_MB_2U(SCH_1):GND
BR31    GND VSS540 @S9S_MB_2U_LIB.S9S_MB_2U(SCH_1):GND
BR29    GND VSS539 @S9S_MB_2U_LIB.S9S_MB_2U(SCH_1):GND
BR27    GND VSS538 @S9S_MB_2U_LIB.S9S_MB_2U(SCH_1):GND
BR17    GND VSS536 @S9S_MB_2U_LIB.S9S_MB_2U(SCH_1):GND
BR13    GND VSS535 @S9S_MB_2U_LIB.S9S_MB_2U(SCH_1):GND
 BP8    GND VSS533 @S9S_MB_2U_LIB.S9S_MB_2U(SCH_1):GND
BP77    GND VSS532 @S9S_MB_2U_LIB.S9S_MB_2U(SCH_1):GND
BP75    GND VSS531 @S9S_MB_2U_LIB.S9S_MB_2U(SCH_1):GND
BP73    GND VSS530 @S9S_MB_2U_LIB.S9S_MB_2U(SCH_1):GND
BP71    GND VSS529 @S9S_MB_2U_LIB.S9S_MB_2U(SCH_1):GND
BP63    GND VSS528 @S9S_MB_2U_LIB.S9S_MB_2U(SCH_1):GND
 BP4    GND VSS527 @S9S_MB_2U_LIB.S9S_MB_2U(SCH_1):GND
BP20    GND VSS525 @S9S_MB_2U_LIB.S9S_MB_2U(SCH_1):GND
 BP2    GND VSS524 @S9S_MB_2U_LIB.S9S_MB_2U(SCH_1):GND
BP16    GND VSS523 @S9S_MB_2U_LIB.S9S_MB_2U(SCH_1):GND
BP12    GND VSS522 @S9S_MB_2U_LIB.S9S_MB_2U(SCH_1):GND
BN70    GND VSS520 @S9S_MB_2U_LIB.S9S_MB_2U(SCH_1):GND
BN62    GND VSS519 @S9S_MB_2U_LIB.S9S_MB_2U(SCH_1):GND
BN31    GND VSS518 @S9S_MB_2U_LIB.S9S_MB_2U(SCH_1):GND
 BM8    GND VSS517 @S9S_MB_2U_LIB.S9S_MB_2U(SCH_1):GND
BM77    GND VSS516 @S9S_MB_2U_LIB.S9S_MB_2U(SCH_1):GND
BM73    GND VSS515 @S9S_MB_2U_LIB.S9S_MB_2U(SCH_1):GND
BM61    GND VSS513 @S9S_MB_2U_LIB.S9S_MB_2U(SCH_1):GND
 BM4    GND VSS512 @S9S_MB_2U_LIB.S9S_MB_2U(SCH_1):GND
BM26    GND VSS511 @S9S_MB_2U_LIB.S9S_MB_2U(SCH_1):GND
BM24    GND VSS510 @S9S_MB_2U_LIB.S9S_MB_2U(SCH_1):GND
BM22    GND VSS509 @S9S_MB_2U_LIB.S9S_MB_2U(SCH_1):GND
BM20    GND VSS508 @S9S_MB_2U_LIB.S9S_MB_2U(SCH_1):GND
BM16    GND VSS507 @S9S_MB_2U_LIB.S9S_MB_2U(SCH_1):GND
BM12    GND VSS506 @S9S_MB_2U_LIB.S9S_MB_2U(SCH_1):GND
 BL9    GND VSS505 @S9S_MB_2U_LIB.S9S_MB_2U(SCH_1):GND
BL78    GND VSS504 @S9S_MB_2U_LIB.S9S_MB_2U(SCH_1):GND
BL72    GND VSS503 @S9S_MB_2U_LIB.S9S_MB_2U(SCH_1):GND
BL70    GND VSS502 @S9S_MB_2U_LIB.S9S_MB_2U(SCH_1):GND
BL68    GND VSS501 @S9S_MB_2U_LIB.S9S_MB_2U(SCH_1):GND
 BL5    GND VSS500 @S9S_MB_2U_LIB.S9S_MB_2U(SCH_1):GND
BL17    GND VSS499 @S9S_MB_2U_LIB.S9S_MB_2U(SCH_1):GND
BL13    GND VSS498 @S9S_MB_2U_LIB.S9S_MB_2U(SCH_1):GND
 BL1    GND VSS497 @S9S_MB_2U_LIB.S9S_MB_2U(SCH_1):GND
 BK8    GND VSS496 @S9S_MB_2U_LIB.S9S_MB_2U(SCH_1):GND
BK79    GND VSS495 @S9S_MB_2U_LIB.S9S_MB_2U(SCH_1):GND
BK75    GND VSS494 @S9S_MB_2U_LIB.S9S_MB_2U(SCH_1):GND
BK71    GND VSS492 @S9S_MB_2U_LIB.S9S_MB_2U(SCH_1):GND
BK65    GND VSS491 @S9S_MB_2U_LIB.S9S_MB_2U(SCH_1):GND
 BK4    GND VSS490 @S9S_MB_2U_LIB.S9S_MB_2U(SCH_1):GND
BK20    GND VSS489 @S9S_MB_2U_LIB.S9S_MB_2U(SCH_1):GND
BK16    GND VSS488 @S9S_MB_2U_LIB.S9S_MB_2U(SCH_1):GND
BK12    GND VSS487 @S9S_MB_2U_LIB.S9S_MB_2U(SCH_1):GND
BJ90    GND VSS486 @S9S_MB_2U_LIB.S9S_MB_2U(SCH_1):GND
BJ88    GND VSS485 @S9S_MB_2U_LIB.S9S_MB_2U(SCH_1):GND
BJ86    GND VSS484 @S9S_MB_2U_LIB.S9S_MB_2U(SCH_1):GND
BJ84    GND VSS483 @S9S_MB_2U_LIB.S9S_MB_2U(SCH_1):GND
BJ82    GND VSS482 @S9S_MB_2U_LIB.S9S_MB_2U(SCH_1):GND
BJ80    GND VSS481 @S9S_MB_2U_LIB.S9S_MB_2U(SCH_1):GND
BJ68    GND VSS480 @S9S_MB_2U_LIB.S9S_MB_2U(SCH_1):GND
BJ62    GND VSS479 @S9S_MB_2U_LIB.S9S_MB_2U(SCH_1):GND
BH83    GND VSS477 @S9S_MB_2U_LIB.S9S_MB_2U(SCH_1):GND
BH81    GND VSS476 @S9S_MB_2U_LIB.S9S_MB_2U(SCH_1):GND
 BH8    GND VSS475 @S9S_MB_2U_LIB.S9S_MB_2U(SCH_1):GND
BH77    GND VSS474 @S9S_MB_2U_LIB.S9S_MB_2U(SCH_1):GND
BH73    GND VSS473 @S9S_MB_2U_LIB.S9S_MB_2U(SCH_1):GND
BH67    GND VSS472 @S9S_MB_2U_LIB.S9S_MB_2U(SCH_1):GND
 BH4    GND VSS470 @S9S_MB_2U_LIB.S9S_MB_2U(SCH_1):GND
BH20    GND VSS469 @S9S_MB_2U_LIB.S9S_MB_2U(SCH_1):GND
BH16    GND VSS468 @S9S_MB_2U_LIB.S9S_MB_2U(SCH_1):GND
BH12    GND VSS467 @S9S_MB_2U_LIB.S9S_MB_2U(SCH_1):GND
 BG9    GND VSS466 @S9S_MB_2U_LIB.S9S_MB_2U(SCH_1):GND
BG70    GND VSS465 @S9S_MB_2U_LIB.S9S_MB_2U(SCH_1):GND
 BG5    GND VSS464 @S9S_MB_2U_LIB.S9S_MB_2U(SCH_1):GND
BG25    GND VSS463 @S9S_MB_2U_LIB.S9S_MB_2U(SCH_1):GND
BG23    GND VSS462 @S9S_MB_2U_LIB.S9S_MB_2U(SCH_1):GND
BG21    GND VSS461 @S9S_MB_2U_LIB.S9S_MB_2U(SCH_1):GND
BG17    GND VSS460 @S9S_MB_2U_LIB.S9S_MB_2U(SCH_1):GND
BG13    GND VSS459 @S9S_MB_2U_LIB.S9S_MB_2U(SCH_1):GND
 BG1    GND VSS458 @S9S_MB_2U_LIB.S9S_MB_2U(SCH_1):GND
BF83    GND VSS457 @S9S_MB_2U_LIB.S9S_MB_2U(SCH_1):GND
 BF8    GND VSS456 @S9S_MB_2U_LIB.S9S_MB_2U(SCH_1):GND
BF79    GND VSS455 @S9S_MB_2U_LIB.S9S_MB_2U(SCH_1):GND
BF75    GND VSS454 @S9S_MB_2U_LIB.S9S_MB_2U(SCH_1):GND
BF73    GND VSS453 @S9S_MB_2U_LIB.S9S_MB_2U(SCH_1):GND
BF63    GND VSS452 @S9S_MB_2U_LIB.S9S_MB_2U(SCH_1):GND
BF61    GND VSS451 @S9S_MB_2U_LIB.S9S_MB_2U(SCH_1):GND
 BF4    GND VSS450 @S9S_MB_2U_LIB.S9S_MB_2U(SCH_1):GND
BF20    GND VSS449 @S9S_MB_2U_LIB.S9S_MB_2U(SCH_1):GND
BF16    GND VSS448 @S9S_MB_2U_LIB.S9S_MB_2U(SCH_1):GND
BF12    GND VSS447 @S9S_MB_2U_LIB.S9S_MB_2U(SCH_1):GND
BE84    GND VSS446 @S9S_MB_2U_LIB.S9S_MB_2U(SCH_1):GND
BE78    GND VSS445 @S9S_MB_2U_LIB.S9S_MB_2U(SCH_1):GND
BE76    GND VSS444 @S9S_MB_2U_LIB.S9S_MB_2U(SCH_1):GND
BE74    GND VSS443 @S9S_MB_2U_LIB.S9S_MB_2U(SCH_1):GND
BE68    GND VSS442 @S9S_MB_2U_LIB.S9S_MB_2U(SCH_1):GND
BE66    GND VSS441 @S9S_MB_2U_LIB.S9S_MB_2U(SCH_1):GND
BE64    GND VSS440 @S9S_MB_2U_LIB.S9S_MB_2U(SCH_1):GND
BD89    GND VSS439 @S9S_MB_2U_LIB.S9S_MB_2U(SCH_1):GND
BD85    GND VSS437 @S9S_MB_2U_LIB.S9S_MB_2U(SCH_1):GND
BD81    GND VSS435 @S9S_MB_2U_LIB.S9S_MB_2U(SCH_1):GND
 BD8    GND VSS434 @S9S_MB_2U_LIB.S9S_MB_2U(SCH_1):GND
 BD4    GND VSS433 @S9S_MB_2U_LIB.S9S_MB_2U(SCH_1):GND
BD20    GND VSS432 @S9S_MB_2U_LIB.S9S_MB_2U(SCH_1):GND
BD16    GND VSS431 @S9S_MB_2U_LIB.S9S_MB_2U(SCH_1):GND
BD12    GND VSS430 @S9S_MB_2U_LIB.S9S_MB_2U(SCH_1):GND
 BC9    GND VSS429 @S9S_MB_2U_LIB.S9S_MB_2U(SCH_1):GND
BC88    GND VSS428 @S9S_MB_2U_LIB.S9S_MB_2U(SCH_1):GND
BC86    GND VSS427 @S9S_MB_2U_LIB.S9S_MB_2U(SCH_1):GND
BC84    GND VSS426 @S9S_MB_2U_LIB.S9S_MB_2U(SCH_1):GND
BC78    GND VSS425 @S9S_MB_2U_LIB.S9S_MB_2U(SCH_1):GND
BC76    GND VSS424 @S9S_MB_2U_LIB.S9S_MB_2U(SCH_1):GND
BC72    GND VSS423 @S9S_MB_2U_LIB.S9S_MB_2U(SCH_1):GND
BC66    GND VSS422 @S9S_MB_2U_LIB.S9S_MB_2U(SCH_1):GND
BC62    GND VSS421 @S9S_MB_2U_LIB.S9S_MB_2U(SCH_1):GND
 BC5    GND VSS420 @S9S_MB_2U_LIB.S9S_MB_2U(SCH_1):GND
BC17    GND VSS419 @S9S_MB_2U_LIB.S9S_MB_2U(SCH_1):GND
BC13    GND VSS418 @S9S_MB_2U_LIB.S9S_MB_2U(SCH_1):GND
 BC1    GND VSS417 @S9S_MB_2U_LIB.S9S_MB_2U(SCH_1):GND
BB91    GND VSS416 @S9S_MB_2U_LIB.S9S_MB_2U(SCH_1):GND
BB87    GND VSS415 @S9S_MB_2U_LIB.S9S_MB_2U(SCH_1):GND
BB83    GND VSS414 @S9S_MB_2U_LIB.S9S_MB_2U(SCH_1):GND
 BB8    GND VSS413 @S9S_MB_2U_LIB.S9S_MB_2U(SCH_1):GND
BB79    GND VSS412 @S9S_MB_2U_LIB.S9S_MB_2U(SCH_1):GND
BB77    GND VSS411 @S9S_MB_2U_LIB.S9S_MB_2U(SCH_1):GND
BB71    GND VSS410 @S9S_MB_2U_LIB.S9S_MB_2U(SCH_1):GND
BB69    GND VSS409 @S9S_MB_2U_LIB.S9S_MB_2U(SCH_1):GND
BB63    GND VSS408 @S9S_MB_2U_LIB.S9S_MB_2U(SCH_1):GND
 BB4    GND VSS407 @S9S_MB_2U_LIB.S9S_MB_2U(SCH_1):GND
BB26    GND VSS406 @S9S_MB_2U_LIB.S9S_MB_2U(SCH_1):GND
BB24    GND VSS405 @S9S_MB_2U_LIB.S9S_MB_2U(SCH_1):GND
BB22    GND VSS404 @S9S_MB_2U_LIB.S9S_MB_2U(SCH_1):GND
BB20    GND VSS403 @S9S_MB_2U_LIB.S9S_MB_2U(SCH_1):GND
BB16    GND VSS402 @S9S_MB_2U_LIB.S9S_MB_2U(SCH_1):GND
BB12    GND VSS401 @S9S_MB_2U_LIB.S9S_MB_2U(SCH_1):GND
BB10    GND VSS400 @S9S_MB_2U_LIB.S9S_MB_2U(SCH_1):GND
BA88    GND VSS399 @S9S_MB_2U_LIB.S9S_MB_2U(SCH_1):GND
BA84    GND VSS398 @S9S_MB_2U_LIB.S9S_MB_2U(SCH_1):GND
BA74    GND VSS397 @S9S_MB_2U_LIB.S9S_MB_2U(SCH_1):GND
BA64    GND VSS395 @S9S_MB_2U_LIB.S9S_MB_2U(SCH_1):GND
BA60    GND VSS394 @S9S_MB_2U_LIB.S9S_MB_2U(SCH_1):GND
BA17    GND VSS393 @S9S_MB_2U_LIB.S9S_MB_2U(SCH_1):GND
AY83    GND VSS377 @S9S_MB_2U_LIB.S9S_MB_2U(SCH_1):GND
AY81    GND VSS376 @S9S_MB_2U_LIB.S9S_MB_2U(SCH_1):GND
 AY8    GND VSS375 @S9S_MB_2U_LIB.S9S_MB_2U(SCH_1):GND
AY79    GND VSS374 @S9S_MB_2U_LIB.S9S_MB_2U(SCH_1):GND
AY77    GND VSS373 @S9S_MB_2U_LIB.S9S_MB_2U(SCH_1):GND
AY71    GND VSS372 @S9S_MB_2U_LIB.S9S_MB_2U(SCH_1):GND
 AY4    GND VSS371 @S9S_MB_2U_LIB.S9S_MB_2U(SCH_1):GND
AY16    GND VSS370 @S9S_MB_2U_LIB.S9S_MB_2U(SCH_1):GND
AY12    GND VSS369 @S9S_MB_2U_LIB.S9S_MB_2U(SCH_1):GND
AW88    GND VSS367 @S9S_MB_2U_LIB.S9S_MB_2U(SCH_1):GND
AW84    GND VSS366 @S9S_MB_2U_LIB.S9S_MB_2U(SCH_1):GND
AW82    GND VSS365 @S9S_MB_2U_LIB.S9S_MB_2U(SCH_1):GND
AW80    GND VSS364 @S9S_MB_2U_LIB.S9S_MB_2U(SCH_1):GND
AW72    GND VSS363 @S9S_MB_2U_LIB.S9S_MB_2U(SCH_1):GND
AW68    GND VSS362 @S9S_MB_2U_LIB.S9S_MB_2U(SCH_1):GND
AW66    GND VSS361 @S9S_MB_2U_LIB.S9S_MB_2U(SCH_1):GND
AW62    GND VSS360 @S9S_MB_2U_LIB.S9S_MB_2U(SCH_1):GND
AW25    GND VSS358 @S9S_MB_2U_LIB.S9S_MB_2U(SCH_1):GND
AW23    GND VSS357 @S9S_MB_2U_LIB.S9S_MB_2U(SCH_1):GND
AW21    GND VSS356 @S9S_MB_2U_LIB.S9S_MB_2U(SCH_1):GND
 BR5    GND   VSS0 @S9S_MB_2U_LIB.S9S_MB_2U(SCH_1):GND

SOCKET4677_AZIF0045P001C01CS-SA  I10  U2
 AW9    GND VSS368 @S9S_MB_2U_LIB.S9S_MB_2U(SCH_1):GND
 AW5    GND VSS359 @S9S_MB_2U_LIB.S9S_MB_2U(SCH_1):GND
AW13    GND VSS355 @S9S_MB_2U_LIB.S9S_MB_2U(SCH_1):GND
 AW1    GND VSS354 @S9S_MB_2U_LIB.S9S_MB_2U(SCH_1):GND
AV91    GND VSS353 @S9S_MB_2U_LIB.S9S_MB_2U(SCH_1):GND
AV87    GND VSS352 @S9S_MB_2U_LIB.S9S_MB_2U(SCH_1):GND
 AV8    GND VSS351 @S9S_MB_2U_LIB.S9S_MB_2U(SCH_1):GND
AV77    GND VSS350 @S9S_MB_2U_LIB.S9S_MB_2U(SCH_1):GND
 AV4    GND VSS349 @S9S_MB_2U_LIB.S9S_MB_2U(SCH_1):GND
AV16    GND VSS348 @S9S_MB_2U_LIB.S9S_MB_2U(SCH_1):GND
AV12    GND VSS347 @S9S_MB_2U_LIB.S9S_MB_2U(SCH_1):GND
AU88    GND VSS346 @S9S_MB_2U_LIB.S9S_MB_2U(SCH_1):GND
AU84    GND VSS345 @S9S_MB_2U_LIB.S9S_MB_2U(SCH_1):GND
AU80    GND VSS344 @S9S_MB_2U_LIB.S9S_MB_2U(SCH_1):GND
AU76    GND VSS343 @S9S_MB_2U_LIB.S9S_MB_2U(SCH_1):GND
AU74    GND VSS342 @S9S_MB_2U_LIB.S9S_MB_2U(SCH_1):GND
AU72    GND VSS341 @S9S_MB_2U_LIB.S9S_MB_2U(SCH_1):GND
AU70    GND VSS340 @S9S_MB_2U_LIB.S9S_MB_2U(SCH_1):GND
AU48    GND VSS339 @S9S_MB_2U_LIB.S9S_MB_2U(SCH_1):GND
AU45    GND VSS338 @S9S_MB_2U_LIB.S9S_MB_2U(SCH_1):GND
AU41    GND VSS337 @S9S_MB_2U_LIB.S9S_MB_2U(SCH_1):GND
AU39    GND VSS336 @S9S_MB_2U_LIB.S9S_MB_2U(SCH_1):GND
AU37    GND VSS335 @S9S_MB_2U_LIB.S9S_MB_2U(SCH_1):GND
AU31    GND VSS334 @S9S_MB_2U_LIB.S9S_MB_2U(SCH_1):GND
AU27    GND VSS333 @S9S_MB_2U_LIB.S9S_MB_2U(SCH_1):GND
 AT8    GND VSS332 @S9S_MB_2U_LIB.S9S_MB_2U(SCH_1):GND
AT79    GND VSS331 @S9S_MB_2U_LIB.S9S_MB_2U(SCH_1):GND
AT77    GND VSS330 @S9S_MB_2U_LIB.S9S_MB_2U(SCH_1):GND
AT75    GND VSS329 @S9S_MB_2U_LIB.S9S_MB_2U(SCH_1):GND
AT71    GND VSS328 @S9S_MB_2U_LIB.S9S_MB_2U(SCH_1):GND
AT69    GND VSS327 @S9S_MB_2U_LIB.S9S_MB_2U(SCH_1):GND
AT65    GND VSS326 @S9S_MB_2U_LIB.S9S_MB_2U(SCH_1):GND
AT63    GND VSS325 @S9S_MB_2U_LIB.S9S_MB_2U(SCH_1):GND
AT59    GND VSS324 @S9S_MB_2U_LIB.S9S_MB_2U(SCH_1):GND
AT57    GND VSS323 @S9S_MB_2U_LIB.S9S_MB_2U(SCH_1):GND
AT53    GND VSS322 @S9S_MB_2U_LIB.S9S_MB_2U(SCH_1):GND
AT51    GND VSS321 @S9S_MB_2U_LIB.S9S_MB_2U(SCH_1):GND
AT44    GND VSS320 @S9S_MB_2U_LIB.S9S_MB_2U(SCH_1):GND
AT40    GND VSS319 @S9S_MB_2U_LIB.S9S_MB_2U(SCH_1):GND
 AT4    GND VSS318 @S9S_MB_2U_LIB.S9S_MB_2U(SCH_1):GND
AT38    GND VSS317 @S9S_MB_2U_LIB.S9S_MB_2U(SCH_1):GND
AT34    GND VSS316 @S9S_MB_2U_LIB.S9S_MB_2U(SCH_1):GND
AT32    GND VSS315 @S9S_MB_2U_LIB.S9S_MB_2U(SCH_1):GND
AT28    GND VSS314 @S9S_MB_2U_LIB.S9S_MB_2U(SCH_1):GND
AT26    GND VSS313 @S9S_MB_2U_LIB.S9S_MB_2U(SCH_1):GND
AT22    GND VSS312 @S9S_MB_2U_LIB.S9S_MB_2U(SCH_1):GND
AT20    GND VSS311 @S9S_MB_2U_LIB.S9S_MB_2U(SCH_1):GND
AT16    GND VSS310 @S9S_MB_2U_LIB.S9S_MB_2U(SCH_1):GND
AT12    GND VSS309 @S9S_MB_2U_LIB.S9S_MB_2U(SCH_1):GND
 AR9    GND VSS308 @S9S_MB_2U_LIB.S9S_MB_2U(SCH_1):GND
AR88    GND VSS307 @S9S_MB_2U_LIB.S9S_MB_2U(SCH_1):GND
AR84    GND VSS306 @S9S_MB_2U_LIB.S9S_MB_2U(SCH_1):GND
AR82    GND VSS305 @S9S_MB_2U_LIB.S9S_MB_2U(SCH_1):GND
AR78    GND VSS304 @S9S_MB_2U_LIB.S9S_MB_2U(SCH_1):GND
AR74    GND VSS303 @S9S_MB_2U_LIB.S9S_MB_2U(SCH_1):GND
AR72    GND VSS302 @S9S_MB_2U_LIB.S9S_MB_2U(SCH_1):GND
AR68    GND VSS301 @S9S_MB_2U_LIB.S9S_MB_2U(SCH_1):GND
AR66    GND VSS300 @S9S_MB_2U_LIB.S9S_MB_2U(SCH_1):GND
AR62    GND VSS299 @S9S_MB_2U_LIB.S9S_MB_2U(SCH_1):GND
AR60    GND VSS298 @S9S_MB_2U_LIB.S9S_MB_2U(SCH_1):GND
AR56    GND VSS297 @S9S_MB_2U_LIB.S9S_MB_2U(SCH_1):GND
AR54    GND VSS296 @S9S_MB_2U_LIB.S9S_MB_2U(SCH_1):GND
AR50    GND VSS295 @S9S_MB_2U_LIB.S9S_MB_2U(SCH_1):GND
 AR5    GND VSS294 @S9S_MB_2U_LIB.S9S_MB_2U(SCH_1):GND
AR48    GND VSS293 @S9S_MB_2U_LIB.S9S_MB_2U(SCH_1):GND
AR43    GND VSS292 @S9S_MB_2U_LIB.S9S_MB_2U(SCH_1):GND
AR41    GND VSS291 @S9S_MB_2U_LIB.S9S_MB_2U(SCH_1):GND
AR37    GND VSS290 @S9S_MB_2U_LIB.S9S_MB_2U(SCH_1):GND
AR35    GND VSS289 @S9S_MB_2U_LIB.S9S_MB_2U(SCH_1):GND
AR31    GND VSS288 @S9S_MB_2U_LIB.S9S_MB_2U(SCH_1):GND
AR29    GND VSS287 @S9S_MB_2U_LIB.S9S_MB_2U(SCH_1):GND
AR25    GND VSS286 @S9S_MB_2U_LIB.S9S_MB_2U(SCH_1):GND
AR23    GND VSS285 @S9S_MB_2U_LIB.S9S_MB_2U(SCH_1):GND
AR19    GND VSS284 @S9S_MB_2U_LIB.S9S_MB_2U(SCH_1):GND
AR13    GND VSS283 @S9S_MB_2U_LIB.S9S_MB_2U(SCH_1):GND
 AR1    GND VSS282 @S9S_MB_2U_LIB.S9S_MB_2U(SCH_1):GND
AP91    GND VSS281 @S9S_MB_2U_LIB.S9S_MB_2U(SCH_1):GND
AP87    GND VSS280 @S9S_MB_2U_LIB.S9S_MB_2U(SCH_1):GND
AP83    GND VSS279 @S9S_MB_2U_LIB.S9S_MB_2U(SCH_1):GND
 AP8    GND VSS278 @S9S_MB_2U_LIB.S9S_MB_2U(SCH_1):GND
AP79    GND VSS277 @S9S_MB_2U_LIB.S9S_MB_2U(SCH_1):GND
AP73    GND VSS276 @S9S_MB_2U_LIB.S9S_MB_2U(SCH_1):GND
AP67    GND VSS275 @S9S_MB_2U_LIB.S9S_MB_2U(SCH_1):GND
AP61    GND VSS274 @S9S_MB_2U_LIB.S9S_MB_2U(SCH_1):GND
AP55    GND VSS273 @S9S_MB_2U_LIB.S9S_MB_2U(SCH_1):GND
AP49    GND VSS272 @S9S_MB_2U_LIB.S9S_MB_2U(SCH_1):GND
AP42    GND VSS271 @S9S_MB_2U_LIB.S9S_MB_2U(SCH_1):GND
 AP4    GND VSS270 @S9S_MB_2U_LIB.S9S_MB_2U(SCH_1):GND
AP36    GND VSS269 @S9S_MB_2U_LIB.S9S_MB_2U(SCH_1):GND
AP30    GND VSS268 @S9S_MB_2U_LIB.S9S_MB_2U(SCH_1):GND
AP24    GND VSS267 @S9S_MB_2U_LIB.S9S_MB_2U(SCH_1):GND
AP18    GND VSS266 @S9S_MB_2U_LIB.S9S_MB_2U(SCH_1):GND
AP16    GND VSS265 @S9S_MB_2U_LIB.S9S_MB_2U(SCH_1):GND
AP12    GND VSS264 @S9S_MB_2U_LIB.S9S_MB_2U(SCH_1):GND
AN88    GND VSS263 @S9S_MB_2U_LIB.S9S_MB_2U(SCH_1):GND
AN84    GND VSS262 @S9S_MB_2U_LIB.S9S_MB_2U(SCH_1):GND
AN52    GND VSS261 @S9S_MB_2U_LIB.S9S_MB_2U(SCH_1):GND
 AM8    GND VSS260 @S9S_MB_2U_LIB.S9S_MB_2U(SCH_1):GND
AM77    GND VSS259 @S9S_MB_2U_LIB.S9S_MB_2U(SCH_1):GND
AM75    GND VSS258 @S9S_MB_2U_LIB.S9S_MB_2U(SCH_1):GND
AM73    GND VSS257 @S9S_MB_2U_LIB.S9S_MB_2U(SCH_1):GND
AM71    GND VSS256 @S9S_MB_2U_LIB.S9S_MB_2U(SCH_1):GND
AM69    GND VSS255 @S9S_MB_2U_LIB.S9S_MB_2U(SCH_1):GND
AM67    GND VSS254 @S9S_MB_2U_LIB.S9S_MB_2U(SCH_1):GND
AM65    GND VSS253 @S9S_MB_2U_LIB.S9S_MB_2U(SCH_1):GND
AM63    GND VSS252 @S9S_MB_2U_LIB.S9S_MB_2U(SCH_1):GND
AM61    GND VSS251 @S9S_MB_2U_LIB.S9S_MB_2U(SCH_1):GND
AM59    GND VSS250 @S9S_MB_2U_LIB.S9S_MB_2U(SCH_1):GND
AM57    GND VSS249 @S9S_MB_2U_LIB.S9S_MB_2U(SCH_1):GND
AM55    GND VSS248 @S9S_MB_2U_LIB.S9S_MB_2U(SCH_1):GND
AM53    GND VSS247 @S9S_MB_2U_LIB.S9S_MB_2U(SCH_1):GND
AM51    GND VSS246 @S9S_MB_2U_LIB.S9S_MB_2U(SCH_1):GND
AM49    GND VSS245 @S9S_MB_2U_LIB.S9S_MB_2U(SCH_1):GND
AM47    GND VSS244 @S9S_MB_2U_LIB.S9S_MB_2U(SCH_1):GND
AM44    GND VSS243 @S9S_MB_2U_LIB.S9S_MB_2U(SCH_1):GND
AM42    GND VSS242 @S9S_MB_2U_LIB.S9S_MB_2U(SCH_1):GND
AM40    GND VSS241 @S9S_MB_2U_LIB.S9S_MB_2U(SCH_1):GND
 AM4    GND VSS240 @S9S_MB_2U_LIB.S9S_MB_2U(SCH_1):GND
AM38    GND VSS239 @S9S_MB_2U_LIB.S9S_MB_2U(SCH_1):GND
AM36    GND VSS238 @S9S_MB_2U_LIB.S9S_MB_2U(SCH_1):GND
AM34    GND VSS237 @S9S_MB_2U_LIB.S9S_MB_2U(SCH_1):GND
AM32    GND VSS236 @S9S_MB_2U_LIB.S9S_MB_2U(SCH_1):GND
AM30    GND VSS235 @S9S_MB_2U_LIB.S9S_MB_2U(SCH_1):GND
AM28    GND VSS234 @S9S_MB_2U_LIB.S9S_MB_2U(SCH_1):GND
AM26    GND VSS233 @S9S_MB_2U_LIB.S9S_MB_2U(SCH_1):GND
AM24    GND VSS232 @S9S_MB_2U_LIB.S9S_MB_2U(SCH_1):GND
AM22    GND VSS231 @S9S_MB_2U_LIB.S9S_MB_2U(SCH_1):GND
AM20    GND VSS230 @S9S_MB_2U_LIB.S9S_MB_2U(SCH_1):GND
AM18    GND VSS229 @S9S_MB_2U_LIB.S9S_MB_2U(SCH_1):GND
AM16    GND VSS228 @S9S_MB_2U_LIB.S9S_MB_2U(SCH_1):GND
AM12    GND VSS227 @S9S_MB_2U_LIB.S9S_MB_2U(SCH_1):GND
 AL9    GND VSS226 @S9S_MB_2U_LIB.S9S_MB_2U(SCH_1):GND
AL88    GND VSS225 @S9S_MB_2U_LIB.S9S_MB_2U(SCH_1):GND
AL84    GND VSS224 @S9S_MB_2U_LIB.S9S_MB_2U(SCH_1):GND
AL82    GND VSS223 @S9S_MB_2U_LIB.S9S_MB_2U(SCH_1):GND
AL80    GND VSS222 @S9S_MB_2U_LIB.S9S_MB_2U(SCH_1):GND
AL52    GND VSS221 @S9S_MB_2U_LIB.S9S_MB_2U(SCH_1):GND
 AL5    GND VSS220 @S9S_MB_2U_LIB.S9S_MB_2U(SCH_1):GND
AL17    GND VSS219 @S9S_MB_2U_LIB.S9S_MB_2U(SCH_1):GND
AL13    GND VSS218 @S9S_MB_2U_LIB.S9S_MB_2U(SCH_1):GND
 AL1    GND VSS217 @S9S_MB_2U_LIB.S9S_MB_2U(SCH_1):GND
AK91    GND VSS216 @S9S_MB_2U_LIB.S9S_MB_2U(SCH_1):GND
AK87    GND VSS215 @S9S_MB_2U_LIB.S9S_MB_2U(SCH_1):GND
AK83    GND VSS214 @S9S_MB_2U_LIB.S9S_MB_2U(SCH_1):GND
AK81    GND VSS213 @S9S_MB_2U_LIB.S9S_MB_2U(SCH_1):GND
 AK8    GND VSS212 @S9S_MB_2U_LIB.S9S_MB_2U(SCH_1):GND
AK79    GND VSS211 @S9S_MB_2U_LIB.S9S_MB_2U(SCH_1):GND
AK73    GND VSS210 @S9S_MB_2U_LIB.S9S_MB_2U(SCH_1):GND
AK67    GND VSS209 @S9S_MB_2U_LIB.S9S_MB_2U(SCH_1):GND
AK61    GND VSS208 @S9S_MB_2U_LIB.S9S_MB_2U(SCH_1):GND
AK55    GND VSS207 @S9S_MB_2U_LIB.S9S_MB_2U(SCH_1):GND
AK49    GND VSS206 @S9S_MB_2U_LIB.S9S_MB_2U(SCH_1):GND
AK42    GND VSS205 @S9S_MB_2U_LIB.S9S_MB_2U(SCH_1):GND
 AK4    GND VSS204 @S9S_MB_2U_LIB.S9S_MB_2U(SCH_1):GND
AK36    GND VSS203 @S9S_MB_2U_LIB.S9S_MB_2U(SCH_1):GND
AK30    GND VSS202 @S9S_MB_2U_LIB.S9S_MB_2U(SCH_1):GND
AK24    GND VSS201 @S9S_MB_2U_LIB.S9S_MB_2U(SCH_1):GND
AK18    GND VSS200 @S9S_MB_2U_LIB.S9S_MB_2U(SCH_1):GND
AK16    GND VSS199 @S9S_MB_2U_LIB.S9S_MB_2U(SCH_1):GND
AK12    GND VSS198 @S9S_MB_2U_LIB.S9S_MB_2U(SCH_1):GND

SOCKET4677_AZIF0045P001C01CS-SA  I11  U2
AJ88    GND VSS197 @S9S_MB_2U_LIB.S9S_MB_2U(SCH_1):GND
AJ84    GND VSS196 @S9S_MB_2U_LIB.S9S_MB_2U(SCH_1):GND
AJ78    GND VSS195 @S9S_MB_2U_LIB.S9S_MB_2U(SCH_1):GND
AJ74    GND VSS194 @S9S_MB_2U_LIB.S9S_MB_2U(SCH_1):GND
AJ72    GND VSS193 @S9S_MB_2U_LIB.S9S_MB_2U(SCH_1):GND
AJ68    GND VSS192 @S9S_MB_2U_LIB.S9S_MB_2U(SCH_1):GND
AJ66    GND VSS191 @S9S_MB_2U_LIB.S9S_MB_2U(SCH_1):GND
AJ62    GND VSS190 @S9S_MB_2U_LIB.S9S_MB_2U(SCH_1):GND
AJ60    GND VSS189 @S9S_MB_2U_LIB.S9S_MB_2U(SCH_1):GND
AJ56    GND VSS188 @S9S_MB_2U_LIB.S9S_MB_2U(SCH_1):GND
AJ54    GND VSS187 @S9S_MB_2U_LIB.S9S_MB_2U(SCH_1):GND
AJ50    GND VSS186 @S9S_MB_2U_LIB.S9S_MB_2U(SCH_1):GND
AJ48    GND VSS185 @S9S_MB_2U_LIB.S9S_MB_2U(SCH_1):GND
AJ43    GND VSS184 @S9S_MB_2U_LIB.S9S_MB_2U(SCH_1):GND
AJ41    GND VSS183 @S9S_MB_2U_LIB.S9S_MB_2U(SCH_1):GND
AJ37    GND VSS182 @S9S_MB_2U_LIB.S9S_MB_2U(SCH_1):GND
AJ35    GND VSS181 @S9S_MB_2U_LIB.S9S_MB_2U(SCH_1):GND
AJ31    GND VSS180 @S9S_MB_2U_LIB.S9S_MB_2U(SCH_1):GND
AJ29    GND VSS179 @S9S_MB_2U_LIB.S9S_MB_2U(SCH_1):GND
AJ25    GND VSS178 @S9S_MB_2U_LIB.S9S_MB_2U(SCH_1):GND
AJ23    GND VSS177 @S9S_MB_2U_LIB.S9S_MB_2U(SCH_1):GND
AJ19    GND VSS176 @S9S_MB_2U_LIB.S9S_MB_2U(SCH_1):GND
AH83    GND VSS175 @S9S_MB_2U_LIB.S9S_MB_2U(SCH_1):GND
 AH8    GND VSS174 @S9S_MB_2U_LIB.S9S_MB_2U(SCH_1):GND
AH79    GND VSS173 @S9S_MB_2U_LIB.S9S_MB_2U(SCH_1):GND
AH77    GND VSS172 @S9S_MB_2U_LIB.S9S_MB_2U(SCH_1):GND
AH75    GND VSS171 @S9S_MB_2U_LIB.S9S_MB_2U(SCH_1):GND
AH71    GND VSS170 @S9S_MB_2U_LIB.S9S_MB_2U(SCH_1):GND
AH69    GND VSS169 @S9S_MB_2U_LIB.S9S_MB_2U(SCH_1):GND
AH65    GND VSS168 @S9S_MB_2U_LIB.S9S_MB_2U(SCH_1):GND
AH63    GND VSS167 @S9S_MB_2U_LIB.S9S_MB_2U(SCH_1):GND
AH59    GND VSS166 @S9S_MB_2U_LIB.S9S_MB_2U(SCH_1):GND
AH57    GND VSS165 @S9S_MB_2U_LIB.S9S_MB_2U(SCH_1):GND
AH53    GND VSS164 @S9S_MB_2U_LIB.S9S_MB_2U(SCH_1):GND
AH51    GND VSS163 @S9S_MB_2U_LIB.S9S_MB_2U(SCH_1):GND
AH47    GND VSS162 @S9S_MB_2U_LIB.S9S_MB_2U(SCH_1):GND
AH44    GND VSS161 @S9S_MB_2U_LIB.S9S_MB_2U(SCH_1):GND
AH40    GND VSS160 @S9S_MB_2U_LIB.S9S_MB_2U(SCH_1):GND
 AH4    GND VSS159 @S9S_MB_2U_LIB.S9S_MB_2U(SCH_1):GND
AH38    GND VSS158 @S9S_MB_2U_LIB.S9S_MB_2U(SCH_1):GND
AH34    GND VSS157 @S9S_MB_2U_LIB.S9S_MB_2U(SCH_1):GND
AH32    GND VSS156 @S9S_MB_2U_LIB.S9S_MB_2U(SCH_1):GND
AH28    GND VSS155 @S9S_MB_2U_LIB.S9S_MB_2U(SCH_1):GND
AH26    GND VSS154 @S9S_MB_2U_LIB.S9S_MB_2U(SCH_1):GND
AH22    GND VSS153 @S9S_MB_2U_LIB.S9S_MB_2U(SCH_1):GND
AH20    GND VSS152 @S9S_MB_2U_LIB.S9S_MB_2U(SCH_1):GND
AH16    GND VSS151 @S9S_MB_2U_LIB.S9S_MB_2U(SCH_1):GND
AH12    GND VSS150 @S9S_MB_2U_LIB.S9S_MB_2U(SCH_1):GND
 AG9    GND VSS149 @S9S_MB_2U_LIB.S9S_MB_2U(SCH_1):GND
AG88    GND VSS148 @S9S_MB_2U_LIB.S9S_MB_2U(SCH_1):GND
AG84    GND VSS147 @S9S_MB_2U_LIB.S9S_MB_2U(SCH_1):GND
AG76    GND VSS146 @S9S_MB_2U_LIB.S9S_MB_2U(SCH_1):GND
AG70    GND VSS145 @S9S_MB_2U_LIB.S9S_MB_2U(SCH_1):GND
AG64    GND VSS144 @S9S_MB_2U_LIB.S9S_MB_2U(SCH_1):GND
AG58    GND VSS143 @S9S_MB_2U_LIB.S9S_MB_2U(SCH_1):GND
AG52    GND VSS142 @S9S_MB_2U_LIB.S9S_MB_2U(SCH_1):GND
 AG5    GND VSS141 @S9S_MB_2U_LIB.S9S_MB_2U(SCH_1):GND
AG45    GND VSS140 @S9S_MB_2U_LIB.S9S_MB_2U(SCH_1):GND
AG39    GND VSS139 @S9S_MB_2U_LIB.S9S_MB_2U(SCH_1):GND
AG33    GND VSS138 @S9S_MB_2U_LIB.S9S_MB_2U(SCH_1):GND
AG27    GND VSS137 @S9S_MB_2U_LIB.S9S_MB_2U(SCH_1):GND
AG21    GND VSS136 @S9S_MB_2U_LIB.S9S_MB_2U(SCH_1):GND
AG13    GND VSS135 @S9S_MB_2U_LIB.S9S_MB_2U(SCH_1):GND
 AG1    GND VSS134 @S9S_MB_2U_LIB.S9S_MB_2U(SCH_1):GND
AF91    GND VSS133 @S9S_MB_2U_LIB.S9S_MB_2U(SCH_1):GND
AF87    GND VSS132 @S9S_MB_2U_LIB.S9S_MB_2U(SCH_1):GND
AF81    GND VSS131 @S9S_MB_2U_LIB.S9S_MB_2U(SCH_1):GND
 AF8    GND VSS130 @S9S_MB_2U_LIB.S9S_MB_2U(SCH_1):GND
AF42    GND VSS129 @S9S_MB_2U_LIB.S9S_MB_2U(SCH_1):GND
 AF4    GND VSS128 @S9S_MB_2U_LIB.S9S_MB_2U(SCH_1):GND
AF16    GND VSS127 @S9S_MB_2U_LIB.S9S_MB_2U(SCH_1):GND
AF12    GND VSS126 @S9S_MB_2U_LIB.S9S_MB_2U(SCH_1):GND
AE88    GND VSS125 @S9S_MB_2U_LIB.S9S_MB_2U(SCH_1):GND
AE84    GND VSS124 @S9S_MB_2U_LIB.S9S_MB_2U(SCH_1):GND
AE78    GND VSS123 @S9S_MB_2U_LIB.S9S_MB_2U(SCH_1):GND
AE76    GND VSS122 @S9S_MB_2U_LIB.S9S_MB_2U(SCH_1):GND
AE74    GND VSS121 @S9S_MB_2U_LIB.S9S_MB_2U(SCH_1):GND
AE72    GND VSS120 @S9S_MB_2U_LIB.S9S_MB_2U(SCH_1):GND
AE70    GND VSS119 @S9S_MB_2U_LIB.S9S_MB_2U(SCH_1):GND
AE68    GND VSS118 @S9S_MB_2U_LIB.S9S_MB_2U(SCH_1):GND
AE66    GND VSS117 @S9S_MB_2U_LIB.S9S_MB_2U(SCH_1):GND
AE64    GND VSS116 @S9S_MB_2U_LIB.S9S_MB_2U(SCH_1):GND
AE62    GND VSS115 @S9S_MB_2U_LIB.S9S_MB_2U(SCH_1):GND
AE60    GND VSS114 @S9S_MB_2U_LIB.S9S_MB_2U(SCH_1):GND
AE58    GND VSS113 @S9S_MB_2U_LIB.S9S_MB_2U(SCH_1):GND
AE56    GND VSS112 @S9S_MB_2U_LIB.S9S_MB_2U(SCH_1):GND
AE54    GND VSS111 @S9S_MB_2U_LIB.S9S_MB_2U(SCH_1):GND
AE52    GND VSS110 @S9S_MB_2U_LIB.S9S_MB_2U(SCH_1):GND
AE50    GND VSS109 @S9S_MB_2U_LIB.S9S_MB_2U(SCH_1):GND
AE48    GND VSS108 @S9S_MB_2U_LIB.S9S_MB_2U(SCH_1):GND
AE45    GND VSS107 @S9S_MB_2U_LIB.S9S_MB_2U(SCH_1):GND
AE43    GND VSS106 @S9S_MB_2U_LIB.S9S_MB_2U(SCH_1):GND
AE41    GND VSS105 @S9S_MB_2U_LIB.S9S_MB_2U(SCH_1):GND
AE39    GND VSS104 @S9S_MB_2U_LIB.S9S_MB_2U(SCH_1):GND
AE37    GND VSS103 @S9S_MB_2U_LIB.S9S_MB_2U(SCH_1):GND
AE35    GND VSS102 @S9S_MB_2U_LIB.S9S_MB_2U(SCH_1):GND
AE33    GND VSS101 @S9S_MB_2U_LIB.S9S_MB_2U(SCH_1):GND
AE31    GND VSS100 @S9S_MB_2U_LIB.S9S_MB_2U(SCH_1):GND
AE29    GND  VSS99 @S9S_MB_2U_LIB.S9S_MB_2U(SCH_1):GND
AE27    GND  VSS98 @S9S_MB_2U_LIB.S9S_MB_2U(SCH_1):GND
AE25    GND  VSS97 @S9S_MB_2U_LIB.S9S_MB_2U(SCH_1):GND
AE23    GND  VSS96 @S9S_MB_2U_LIB.S9S_MB_2U(SCH_1):GND
AE21    GND  VSS95 @S9S_MB_2U_LIB.S9S_MB_2U(SCH_1):GND
AE19    GND  VSS94 @S9S_MB_2U_LIB.S9S_MB_2U(SCH_1):GND
AE17    GND  VSS93 @S9S_MB_2U_LIB.S9S_MB_2U(SCH_1):GND
AD83    GND  VSS92 @S9S_MB_2U_LIB.S9S_MB_2U(SCH_1):GND
 AD8    GND  VSS91 @S9S_MB_2U_LIB.S9S_MB_2U(SCH_1):GND
AD79    GND  VSS90 @S9S_MB_2U_LIB.S9S_MB_2U(SCH_1):GND
AD42    GND  VSS89 @S9S_MB_2U_LIB.S9S_MB_2U(SCH_1):GND
 AD4    GND  VSS88 @S9S_MB_2U_LIB.S9S_MB_2U(SCH_1):GND
AD16    GND  VSS87 @S9S_MB_2U_LIB.S9S_MB_2U(SCH_1):GND
AD12    GND  VSS86 @S9S_MB_2U_LIB.S9S_MB_2U(SCH_1):GND
 AC9    GND  VSS85 @S9S_MB_2U_LIB.S9S_MB_2U(SCH_1):GND
AC88    GND  VSS84 @S9S_MB_2U_LIB.S9S_MB_2U(SCH_1):GND
AC84    GND  VSS83 @S9S_MB_2U_LIB.S9S_MB_2U(SCH_1):GND
AC76    GND  VSS82 @S9S_MB_2U_LIB.S9S_MB_2U(SCH_1):GND
AC70    GND  VSS81 @S9S_MB_2U_LIB.S9S_MB_2U(SCH_1):GND
AC64    GND  VSS80 @S9S_MB_2U_LIB.S9S_MB_2U(SCH_1):GND
AC58    GND  VSS79 @S9S_MB_2U_LIB.S9S_MB_2U(SCH_1):GND
AC52    GND  VSS78 @S9S_MB_2U_LIB.S9S_MB_2U(SCH_1):GND
 AC5    GND  VSS77 @S9S_MB_2U_LIB.S9S_MB_2U(SCH_1):GND
AC45    GND  VSS76 @S9S_MB_2U_LIB.S9S_MB_2U(SCH_1):GND
AC39    GND  VSS75 @S9S_MB_2U_LIB.S9S_MB_2U(SCH_1):GND
AC33    GND  VSS74 @S9S_MB_2U_LIB.S9S_MB_2U(SCH_1):GND
AC27    GND  VSS73 @S9S_MB_2U_LIB.S9S_MB_2U(SCH_1):GND
AC21    GND  VSS72 @S9S_MB_2U_LIB.S9S_MB_2U(SCH_1):GND
AC13    GND  VSS71 @S9S_MB_2U_LIB.S9S_MB_2U(SCH_1):GND
 AC1    GND  VSS70 @S9S_MB_2U_LIB.S9S_MB_2U(SCH_1):GND
AB91    GND  VSS69 @S9S_MB_2U_LIB.S9S_MB_2U(SCH_1):GND
AB87    GND  VSS68 @S9S_MB_2U_LIB.S9S_MB_2U(SCH_1):GND
AB83    GND  VSS67 @S9S_MB_2U_LIB.S9S_MB_2U(SCH_1):GND
AB81    GND  VSS66 @S9S_MB_2U_LIB.S9S_MB_2U(SCH_1):GND
 AB8    GND  VSS65 @S9S_MB_2U_LIB.S9S_MB_2U(SCH_1):GND
AB79    GND  VSS64 @S9S_MB_2U_LIB.S9S_MB_2U(SCH_1):GND
AB77    GND  VSS63 @S9S_MB_2U_LIB.S9S_MB_2U(SCH_1):GND
AB75    GND  VSS62 @S9S_MB_2U_LIB.S9S_MB_2U(SCH_1):GND
AB71    GND  VSS61 @S9S_MB_2U_LIB.S9S_MB_2U(SCH_1):GND
AB69    GND  VSS60 @S9S_MB_2U_LIB.S9S_MB_2U(SCH_1):GND
AB65    GND  VSS59 @S9S_MB_2U_LIB.S9S_MB_2U(SCH_1):GND
AB63    GND  VSS58 @S9S_MB_2U_LIB.S9S_MB_2U(SCH_1):GND
AB59    GND  VSS57 @S9S_MB_2U_LIB.S9S_MB_2U(SCH_1):GND
AB57    GND  VSS56 @S9S_MB_2U_LIB.S9S_MB_2U(SCH_1):GND
AB53    GND  VSS55 @S9S_MB_2U_LIB.S9S_MB_2U(SCH_1):GND
AB51    GND  VSS54 @S9S_MB_2U_LIB.S9S_MB_2U(SCH_1):GND
AB47    GND  VSS53 @S9S_MB_2U_LIB.S9S_MB_2U(SCH_1):GND
AB44    GND  VSS52 @S9S_MB_2U_LIB.S9S_MB_2U(SCH_1):GND
AB40    GND  VSS51 @S9S_MB_2U_LIB.S9S_MB_2U(SCH_1):GND
 AB4    GND  VSS50 @S9S_MB_2U_LIB.S9S_MB_2U(SCH_1):GND
AB38    GND  VSS49 @S9S_MB_2U_LIB.S9S_MB_2U(SCH_1):GND
AB34    GND  VSS48 @S9S_MB_2U_LIB.S9S_MB_2U(SCH_1):GND
AB32    GND  VSS47 @S9S_MB_2U_LIB.S9S_MB_2U(SCH_1):GND
AB28    GND  VSS46 @S9S_MB_2U_LIB.S9S_MB_2U(SCH_1):GND
AB26    GND  VSS45 @S9S_MB_2U_LIB.S9S_MB_2U(SCH_1):GND
AB22    GND  VSS44 @S9S_MB_2U_LIB.S9S_MB_2U(SCH_1):GND
AB20    GND  VSS43 @S9S_MB_2U_LIB.S9S_MB_2U(SCH_1):GND
AB16    GND  VSS42 @S9S_MB_2U_LIB.S9S_MB_2U(SCH_1):GND
AB12    GND  VSS41 @S9S_MB_2U_LIB.S9S_MB_2U(SCH_1):GND
AA88    GND  VSS40 @S9S_MB_2U_LIB.S9S_MB_2U(SCH_1):GND
AA84    GND  VSS39 @S9S_MB_2U_LIB.S9S_MB_2U(SCH_1):GND
AA82    GND  VSS38 @S9S_MB_2U_LIB.S9S_MB_2U(SCH_1):GND


DRAWING: @S9S_MB_2U_LIB.S9S_MB_2U(SCH_1):PAGE42 

SOCKET4677_AZIF0045P001C01CS-SA  I10  U2
 Y73    GND VSS1833 @S9S_MB_2U_LIB.S9S_MB_2U(SCH_1):GND
  Y8    GND VSS1832 @S9S_MB_2U_LIB.S9S_MB_2U(SCH_1):GND
 Y55    GND VSS1831 @S9S_MB_2U_LIB.S9S_MB_2U(SCH_1):GND
 Y49    GND VSS1830 @S9S_MB_2U_LIB.S9S_MB_2U(SCH_1):GND
 Y67    GND VSS1829 @S9S_MB_2U_LIB.S9S_MB_2U(SCH_1):GND
 Y61    GND VSS1828 @S9S_MB_2U_LIB.S9S_MB_2U(SCH_1):GND
 Y42    GND VSS1827 @S9S_MB_2U_LIB.S9S_MB_2U(SCH_1):GND
  Y4    GND VSS1826 @S9S_MB_2U_LIB.S9S_MB_2U(SCH_1):GND
 Y36    GND VSS1825 @S9S_MB_2U_LIB.S9S_MB_2U(SCH_1):GND
 Y30    GND VSS1824 @S9S_MB_2U_LIB.S9S_MB_2U(SCH_1):GND
 Y24    GND VSS1823 @S9S_MB_2U_LIB.S9S_MB_2U(SCH_1):GND
 Y18    GND VSS1822 @S9S_MB_2U_LIB.S9S_MB_2U(SCH_1):GND
 Y16    GND VSS1821 @S9S_MB_2U_LIB.S9S_MB_2U(SCH_1):GND
 Y12    GND VSS1820 @S9S_MB_2U_LIB.S9S_MB_2U(SCH_1):GND
  W9    GND VSS1819 @S9S_MB_2U_LIB.S9S_MB_2U(SCH_1):GND
 W88    GND VSS1818 @S9S_MB_2U_LIB.S9S_MB_2U(SCH_1):GND
 W84    GND VSS1817 @S9S_MB_2U_LIB.S9S_MB_2U(SCH_1):GND
 W39    GND VSS1816 @S9S_MB_2U_LIB.S9S_MB_2U(SCH_1):GND
 W52    GND VSS1815 @S9S_MB_2U_LIB.S9S_MB_2U(SCH_1):GND
  W5    GND VSS1814 @S9S_MB_2U_LIB.S9S_MB_2U(SCH_1):GND
 V87    GND VSS1813 @S9S_MB_2U_LIB.S9S_MB_2U(SCH_1):GND
  V8    GND VSS1812 @S9S_MB_2U_LIB.S9S_MB_2U(SCH_1):GND
 V79    GND VSS1811 @S9S_MB_2U_LIB.S9S_MB_2U(SCH_1):GND
 V77    GND VSS1810 @S9S_MB_2U_LIB.S9S_MB_2U(SCH_1):GND
 W13    GND VSS1809 @S9S_MB_2U_LIB.S9S_MB_2U(SCH_1):GND
  W1    GND VSS1808 @S9S_MB_2U_LIB.S9S_MB_2U(SCH_1):GND
 V91    GND VSS1807 @S9S_MB_2U_LIB.S9S_MB_2U(SCH_1):GND
 V75    GND VSS1806 @S9S_MB_2U_LIB.S9S_MB_2U(SCH_1):GND
 V69    GND VSS1805 @S9S_MB_2U_LIB.S9S_MB_2U(SCH_1):GND
 V67    GND VSS1804 @S9S_MB_2U_LIB.S9S_MB_2U(SCH_1):GND
 V65    GND VSS1803 @S9S_MB_2U_LIB.S9S_MB_2U(SCH_1):GND
 V63    GND VSS1802 @S9S_MB_2U_LIB.S9S_MB_2U(SCH_1):GND
 V73    GND VSS1801 @S9S_MB_2U_LIB.S9S_MB_2U(SCH_1):GND
 V71    GND VSS1800 @S9S_MB_2U_LIB.S9S_MB_2U(SCH_1):GND
 V61    GND VSS1799 @S9S_MB_2U_LIB.S9S_MB_2U(SCH_1):GND
 V59    GND VSS1798 @S9S_MB_2U_LIB.S9S_MB_2U(SCH_1):GND
 V57    GND VSS1797 @S9S_MB_2U_LIB.S9S_MB_2U(SCH_1):GND
 V55    GND VSS1796 @S9S_MB_2U_LIB.S9S_MB_2U(SCH_1):GND
 V53    GND VSS1795 @S9S_MB_2U_LIB.S9S_MB_2U(SCH_1):GND
 V51    GND VSS1794 @S9S_MB_2U_LIB.S9S_MB_2U(SCH_1):GND
 V47    GND VSS1793 @S9S_MB_2U_LIB.S9S_MB_2U(SCH_1):GND
 V44    GND VSS1792 @S9S_MB_2U_LIB.S9S_MB_2U(SCH_1):GND
 V42    GND VSS1791 @S9S_MB_2U_LIB.S9S_MB_2U(SCH_1):GND
 V40    GND VSS1790 @S9S_MB_2U_LIB.S9S_MB_2U(SCH_1):GND
 V49    GND VSS1789 @S9S_MB_2U_LIB.S9S_MB_2U(SCH_1):GND
  V4    GND VSS1788 @S9S_MB_2U_LIB.S9S_MB_2U(SCH_1):GND
 V38    GND VSS1787 @S9S_MB_2U_LIB.S9S_MB_2U(SCH_1):GND
 V36    GND VSS1786 @S9S_MB_2U_LIB.S9S_MB_2U(SCH_1):GND
 V34    GND VSS1785 @S9S_MB_2U_LIB.S9S_MB_2U(SCH_1):GND
 V32    GND VSS1784 @S9S_MB_2U_LIB.S9S_MB_2U(SCH_1):GND
 V30    GND VSS1783 @S9S_MB_2U_LIB.S9S_MB_2U(SCH_1):GND
 V28    GND VSS1782 @S9S_MB_2U_LIB.S9S_MB_2U(SCH_1):GND
 V26    GND VSS1781 @S9S_MB_2U_LIB.S9S_MB_2U(SCH_1):GND
 V24    GND VSS1780 @S9S_MB_2U_LIB.S9S_MB_2U(SCH_1):GND
 V22    GND VSS1779 @S9S_MB_2U_LIB.S9S_MB_2U(SCH_1):GND
 V20    GND VSS1778 @S9S_MB_2U_LIB.S9S_MB_2U(SCH_1):GND
 V18    GND VSS1777 @S9S_MB_2U_LIB.S9S_MB_2U(SCH_1):GND
 V16    GND VSS1776 @S9S_MB_2U_LIB.S9S_MB_2U(SCH_1):GND
 V12    GND VSS1775 @S9S_MB_2U_LIB.S9S_MB_2U(SCH_1):GND
 U88    GND VSS1774 @S9S_MB_2U_LIB.S9S_MB_2U(SCH_1):GND
 U84    GND VSS1773 @S9S_MB_2U_LIB.S9S_MB_2U(SCH_1):GND
 U82    GND VSS1772 @S9S_MB_2U_LIB.S9S_MB_2U(SCH_1):GND
 U39    GND VSS1771 @S9S_MB_2U_LIB.S9S_MB_2U(SCH_1):GND
 T83    GND VSS1770 @S9S_MB_2U_LIB.S9S_MB_2U(SCH_1):GND
  T8    GND VSS1769 @S9S_MB_2U_LIB.S9S_MB_2U(SCH_1):GND
 T79    GND VSS1768 @S9S_MB_2U_LIB.S9S_MB_2U(SCH_1):GND
 T73    GND VSS1767 @S9S_MB_2U_LIB.S9S_MB_2U(SCH_1):GND
 U52    GND VSS1766 @S9S_MB_2U_LIB.S9S_MB_2U(SCH_1):GND
 T67    GND VSS1765 @S9S_MB_2U_LIB.S9S_MB_2U(SCH_1):GND
 T61    GND VSS1764 @S9S_MB_2U_LIB.S9S_MB_2U(SCH_1):GND
 T42    GND VSS1763 @S9S_MB_2U_LIB.S9S_MB_2U(SCH_1):GND
  T4    GND VSS1762 @S9S_MB_2U_LIB.S9S_MB_2U(SCH_1):GND
 T30    GND VSS1761 @S9S_MB_2U_LIB.S9S_MB_2U(SCH_1):GND
 T24    GND VSS1760 @S9S_MB_2U_LIB.S9S_MB_2U(SCH_1):GND
  R9    GND VSS1759 @S9S_MB_2U_LIB.S9S_MB_2U(SCH_1):GND
 R88    GND VSS1758 @S9S_MB_2U_LIB.S9S_MB_2U(SCH_1):GND
 R84    GND VSS1757 @S9S_MB_2U_LIB.S9S_MB_2U(SCH_1):GND
 R78    GND VSS1756 @S9S_MB_2U_LIB.S9S_MB_2U(SCH_1):GND
 R74    GND VSS1755 @S9S_MB_2U_LIB.S9S_MB_2U(SCH_1):GND
 R72    GND VSS1754 @S9S_MB_2U_LIB.S9S_MB_2U(SCH_1):GND
 R68    GND VSS1753 @S9S_MB_2U_LIB.S9S_MB_2U(SCH_1):GND
 R62    GND VSS1752 @S9S_MB_2U_LIB.S9S_MB_2U(SCH_1):GND
 R56    GND VSS1751 @S9S_MB_2U_LIB.S9S_MB_2U(SCH_1):GND
 T55    GND VSS1750 @S9S_MB_2U_LIB.S9S_MB_2U(SCH_1):GND
 T49    GND VSS1749 @S9S_MB_2U_LIB.S9S_MB_2U(SCH_1):GND
 R54    GND VSS1748 @S9S_MB_2U_LIB.S9S_MB_2U(SCH_1):GND
 R50    GND VSS1747 @S9S_MB_2U_LIB.S9S_MB_2U(SCH_1):GND
 T36    GND VSS1746 @S9S_MB_2U_LIB.S9S_MB_2U(SCH_1):GND
  R5    GND VSS1745 @S9S_MB_2U_LIB.S9S_MB_2U(SCH_1):GND
 R43    GND VSS1744 @S9S_MB_2U_LIB.S9S_MB_2U(SCH_1):GND
 R41    GND VSS1743 @S9S_MB_2U_LIB.S9S_MB_2U(SCH_1):GND
 R37    GND VSS1742 @S9S_MB_2U_LIB.S9S_MB_2U(SCH_1):GND
 T18    GND VSS1741 @S9S_MB_2U_LIB.S9S_MB_2U(SCH_1):GND
 T16    GND VSS1740 @S9S_MB_2U_LIB.S9S_MB_2U(SCH_1):GND
 T12    GND VSS1739 @S9S_MB_2U_LIB.S9S_MB_2U(SCH_1):GND
 R35    GND VSS1738 @S9S_MB_2U_LIB.S9S_MB_2U(SCH_1):GND
 R31    GND VSS1737 @S9S_MB_2U_LIB.S9S_MB_2U(SCH_1):GND
 R29    GND VSS1736 @S9S_MB_2U_LIB.S9S_MB_2U(SCH_1):GND
 R25    GND VSS1735 @S9S_MB_2U_LIB.S9S_MB_2U(SCH_1):GND
 R17    GND VSS1734 @S9S_MB_2U_LIB.S9S_MB_2U(SCH_1):GND
 R13    GND VSS1733 @S9S_MB_2U_LIB.S9S_MB_2U(SCH_1):GND
 P91    GND VSS1732 @S9S_MB_2U_LIB.S9S_MB_2U(SCH_1):GND
 P87    GND VSS1731 @S9S_MB_2U_LIB.S9S_MB_2U(SCH_1):GND
 R66    GND VSS1730 @S9S_MB_2U_LIB.S9S_MB_2U(SCH_1):GND
  P8    GND VSS1729 @S9S_MB_2U_LIB.S9S_MB_2U(SCH_1):GND
 R60    GND VSS1728 @S9S_MB_2U_LIB.S9S_MB_2U(SCH_1):GND
 P77    GND VSS1727 @S9S_MB_2U_LIB.S9S_MB_2U(SCH_1):GND
 P75    GND VSS1726 @S9S_MB_2U_LIB.S9S_MB_2U(SCH_1):GND
 P69    GND VSS1725 @S9S_MB_2U_LIB.S9S_MB_2U(SCH_1):GND
 P65    GND VSS1724 @S9S_MB_2U_LIB.S9S_MB_2U(SCH_1):GND
 R48    GND VSS1723 @S9S_MB_2U_LIB.S9S_MB_2U(SCH_1):GND
 P63    GND VSS1722 @S9S_MB_2U_LIB.S9S_MB_2U(SCH_1):GND
 P59    GND VSS1721 @S9S_MB_2U_LIB.S9S_MB_2U(SCH_1):GND
 P53    GND VSS1720 @S9S_MB_2U_LIB.S9S_MB_2U(SCH_1):GND
 P47    GND VSS1719 @S9S_MB_2U_LIB.S9S_MB_2U(SCH_1):GND
 P44    GND VSS1718 @S9S_MB_2U_LIB.S9S_MB_2U(SCH_1):GND
 P40    GND VSS1717 @S9S_MB_2U_LIB.S9S_MB_2U(SCH_1):GND
  P4    GND VSS1716 @S9S_MB_2U_LIB.S9S_MB_2U(SCH_1):GND
 R23    GND VSS1715 @S9S_MB_2U_LIB.S9S_MB_2U(SCH_1):GND
 R19    GND VSS1714 @S9S_MB_2U_LIB.S9S_MB_2U(SCH_1):GND
 P38    GND VSS1713 @S9S_MB_2U_LIB.S9S_MB_2U(SCH_1):GND
 P34    GND VSS1712 @S9S_MB_2U_LIB.S9S_MB_2U(SCH_1):GND
  R1    GND VSS1711 @S9S_MB_2U_LIB.S9S_MB_2U(SCH_1):GND
 P28    GND VSS1710 @S9S_MB_2U_LIB.S9S_MB_2U(SCH_1):GND
 P26    GND VSS1709 @S9S_MB_2U_LIB.S9S_MB_2U(SCH_1):GND
 P22    GND VSS1708 @S9S_MB_2U_LIB.S9S_MB_2U(SCH_1):GND
 P20    GND VSS1707 @S9S_MB_2U_LIB.S9S_MB_2U(SCH_1):GND
 P16    GND VSS1706 @S9S_MB_2U_LIB.S9S_MB_2U(SCH_1):GND
 P12    GND VSS1705 @S9S_MB_2U_LIB.S9S_MB_2U(SCH_1):GND
 P71    GND VSS1704 @S9S_MB_2U_LIB.S9S_MB_2U(SCH_1):GND
 N88    GND VSS1703 @S9S_MB_2U_LIB.S9S_MB_2U(SCH_1):GND
 N84    GND VSS1702 @S9S_MB_2U_LIB.S9S_MB_2U(SCH_1):GND
 N82    GND VSS1701 @S9S_MB_2U_LIB.S9S_MB_2U(SCH_1):GND
 N80    GND VSS1700 @S9S_MB_2U_LIB.S9S_MB_2U(SCH_1):GND
 P57    GND VSS1699 @S9S_MB_2U_LIB.S9S_MB_2U(SCH_1):GND
 N78    GND VSS1698 @S9S_MB_2U_LIB.S9S_MB_2U(SCH_1):GND
 P51    GND VSS1697 @S9S_MB_2U_LIB.S9S_MB_2U(SCH_1):GND
 N76    GND VSS1696 @S9S_MB_2U_LIB.S9S_MB_2U(SCH_1):GND
 P32    GND VSS1690 @S9S_MB_2U_LIB.S9S_MB_2U(SCH_1):GND
AA80    GND  VSS37 @S9S_MB_2U_LIB.S9S_MB_2U(SCH_1):GND
AA78    GND  VSS36 @S9S_MB_2U_LIB.S9S_MB_2U(SCH_1):GND
AA74    GND  VSS35 @S9S_MB_2U_LIB.S9S_MB_2U(SCH_1):GND
AA72    GND  VSS34 @S9S_MB_2U_LIB.S9S_MB_2U(SCH_1):GND
AA68    GND  VSS33 @S9S_MB_2U_LIB.S9S_MB_2U(SCH_1):GND
AA66    GND  VSS32 @S9S_MB_2U_LIB.S9S_MB_2U(SCH_1):GND
AA62    GND  VSS31 @S9S_MB_2U_LIB.S9S_MB_2U(SCH_1):GND
AA60    GND  VSS30 @S9S_MB_2U_LIB.S9S_MB_2U(SCH_1):GND
AA56    GND  VSS29 @S9S_MB_2U_LIB.S9S_MB_2U(SCH_1):GND
AA54    GND  VSS28 @S9S_MB_2U_LIB.S9S_MB_2U(SCH_1):GND
AA50    GND  VSS27 @S9S_MB_2U_LIB.S9S_MB_2U(SCH_1):GND
AA48    GND  VSS26 @S9S_MB_2U_LIB.S9S_MB_2U(SCH_1):GND
AA43    GND  VSS25 @S9S_MB_2U_LIB.S9S_MB_2U(SCH_1):GND
AA41    GND  VSS24 @S9S_MB_2U_LIB.S9S_MB_2U(SCH_1):GND
AA37    GND  VSS23 @S9S_MB_2U_LIB.S9S_MB_2U(SCH_1):GND
AA35    GND  VSS22 @S9S_MB_2U_LIB.S9S_MB_2U(SCH_1):GND
AA31    GND  VSS21 @S9S_MB_2U_LIB.S9S_MB_2U(SCH_1):GND
AA29    GND  VSS20 @S9S_MB_2U_LIB.S9S_MB_2U(SCH_1):GND
AA25    GND  VSS19 @S9S_MB_2U_LIB.S9S_MB_2U(SCH_1):GND
AA23    GND  VSS18 @S9S_MB_2U_LIB.S9S_MB_2U(SCH_1):GND
AA19    GND  VSS17 @S9S_MB_2U_LIB.S9S_MB_2U(SCH_1):GND

SOCKET4677_AZIF0045P001C01CS-SA  I11  U2
 N70    GND VSS1695 @S9S_MB_2U_LIB.S9S_MB_2U(SCH_1):GND
 N58    GND VSS1694 @S9S_MB_2U_LIB.S9S_MB_2U(SCH_1):GND
 N52    GND VSS1693 @S9S_MB_2U_LIB.S9S_MB_2U(SCH_1):GND
 N45    GND VSS1692 @S9S_MB_2U_LIB.S9S_MB_2U(SCH_1):GND
 N33    GND VSS1691 @S9S_MB_2U_LIB.S9S_MB_2U(SCH_1):GND
 N27    GND VSS1689 @S9S_MB_2U_LIB.S9S_MB_2U(SCH_1):GND
 N15    GND VSS1688 @S9S_MB_2U_LIB.S9S_MB_2U(SCH_1):GND
 M83    GND VSS1687 @S9S_MB_2U_LIB.S9S_MB_2U(SCH_1):GND
 M81    GND VSS1686 @S9S_MB_2U_LIB.S9S_MB_2U(SCH_1):GND
 L78    GND VSS1685 @S9S_MB_2U_LIB.S9S_MB_2U(SCH_1):GND
 L76    GND VSS1684 @S9S_MB_2U_LIB.S9S_MB_2U(SCH_1):GND
 L74    GND VSS1683 @S9S_MB_2U_LIB.S9S_MB_2U(SCH_1):GND
 L72    GND VSS1682 @S9S_MB_2U_LIB.S9S_MB_2U(SCH_1):GND
 L68    GND VSS1681 @S9S_MB_2U_LIB.S9S_MB_2U(SCH_1):GND
 L66    GND VSS1680 @S9S_MB_2U_LIB.S9S_MB_2U(SCH_1):GND
 L64    GND VSS1679 @S9S_MB_2U_LIB.S9S_MB_2U(SCH_1):GND
 L62    GND VSS1678 @S9S_MB_2U_LIB.S9S_MB_2U(SCH_1):GND
 L60    GND VSS1677 @S9S_MB_2U_LIB.S9S_MB_2U(SCH_1):GND
 L56    GND VSS1676 @S9S_MB_2U_LIB.S9S_MB_2U(SCH_1):GND
 N64    GND VSS1675 @S9S_MB_2U_LIB.S9S_MB_2U(SCH_1):GND
 L54    GND VSS1674 @S9S_MB_2U_LIB.S9S_MB_2U(SCH_1):GND
 L52    GND VSS1673 @S9S_MB_2U_LIB.S9S_MB_2U(SCH_1):GND
 L50    GND VSS1672 @S9S_MB_2U_LIB.S9S_MB_2U(SCH_1):GND
  L5    GND VSS1671 @S9S_MB_2U_LIB.S9S_MB_2U(SCH_1):GND
 L48    GND VSS1670 @S9S_MB_2U_LIB.S9S_MB_2U(SCH_1):GND
 N39    GND VSS1669 @S9S_MB_2U_LIB.S9S_MB_2U(SCH_1):GND
 L45    GND VSS1668 @S9S_MB_2U_LIB.S9S_MB_2U(SCH_1):GND
 L43    GND VSS1667 @S9S_MB_2U_LIB.S9S_MB_2U(SCH_1):GND
 L41    GND VSS1666 @S9S_MB_2U_LIB.S9S_MB_2U(SCH_1):GND
 L39    GND VSS1665 @S9S_MB_2U_LIB.S9S_MB_2U(SCH_1):GND
 N21    GND VSS1664 @S9S_MB_2U_LIB.S9S_MB_2U(SCH_1):GND
 L37    GND VSS1663 @S9S_MB_2U_LIB.S9S_MB_2U(SCH_1):GND
 L35    GND VSS1662 @S9S_MB_2U_LIB.S9S_MB_2U(SCH_1):GND
 L33    GND VSS1661 @S9S_MB_2U_LIB.S9S_MB_2U(SCH_1):GND
 L31    GND VSS1660 @S9S_MB_2U_LIB.S9S_MB_2U(SCH_1):GND
 L29    GND VSS1659 @S9S_MB_2U_LIB.S9S_MB_2U(SCH_1):GND
 L27    GND VSS1658 @S9S_MB_2U_LIB.S9S_MB_2U(SCH_1):GND
  M8    GND VSS1657 @S9S_MB_2U_LIB.S9S_MB_2U(SCH_1):GND
 L25    GND VSS1656 @S9S_MB_2U_LIB.S9S_MB_2U(SCH_1):GND
 L23    GND VSS1655 @S9S_MB_2U_LIB.S9S_MB_2U(SCH_1):GND
 M49    GND VSS1654 @S9S_MB_2U_LIB.S9S_MB_2U(SCH_1):GND
 M42    GND VSS1653 @S9S_MB_2U_LIB.S9S_MB_2U(SCH_1):GND
  M4    GND VSS1652 @S9S_MB_2U_LIB.S9S_MB_2U(SCH_1):GND
 L21    GND VSS1651 @S9S_MB_2U_LIB.S9S_MB_2U(SCH_1):GND
 L17    GND VSS1650 @S9S_MB_2U_LIB.S9S_MB_2U(SCH_1):GND
 M12    GND VSS1649 @S9S_MB_2U_LIB.S9S_MB_2U(SCH_1):GND
 L90    GND VSS1648 @S9S_MB_2U_LIB.S9S_MB_2U(SCH_1):GND
  L9    GND VSS1647 @S9S_MB_2U_LIB.S9S_MB_2U(SCH_1):GND
 L88    GND VSS1646 @S9S_MB_2U_LIB.S9S_MB_2U(SCH_1):GND
 L15    GND VSS1645 @S9S_MB_2U_LIB.S9S_MB_2U(SCH_1):GND
 L13    GND VSS1644 @S9S_MB_2U_LIB.S9S_MB_2U(SCH_1):GND
 K85    GND VSS1643 @S9S_MB_2U_LIB.S9S_MB_2U(SCH_1):GND
 K83    GND VSS1642 @S9S_MB_2U_LIB.S9S_MB_2U(SCH_1):GND
  K8    GND VSS1641 @S9S_MB_2U_LIB.S9S_MB_2U(SCH_1):GND
 L70    GND VSS1640 @S9S_MB_2U_LIB.S9S_MB_2U(SCH_1):GND
 K77    GND VSS1639 @S9S_MB_2U_LIB.S9S_MB_2U(SCH_1):GND
 J86    GND VSS1638 @S9S_MB_2U_LIB.S9S_MB_2U(SCH_1):GND
 J84    GND VSS1637 @S9S_MB_2U_LIB.S9S_MB_2U(SCH_1):GND
 J78    GND VSS1636 @S9S_MB_2U_LIB.S9S_MB_2U(SCH_1):GND
 J76    GND VSS1635 @S9S_MB_2U_LIB.S9S_MB_2U(SCH_1):GND
 L58    GND VSS1634 @S9S_MB_2U_LIB.S9S_MB_2U(SCH_1):GND
 J58    GND VSS1633 @S9S_MB_2U_LIB.S9S_MB_2U(SCH_1):GND
 J52    GND VSS1632 @S9S_MB_2U_LIB.S9S_MB_2U(SCH_1):GND
 J45    GND VSS1631 @S9S_MB_2U_LIB.S9S_MB_2U(SCH_1):GND
 J33    GND VSS1630 @S9S_MB_2U_LIB.S9S_MB_2U(SCH_1):GND
 J27    GND VSS1629 @S9S_MB_2U_LIB.S9S_MB_2U(SCH_1):GND
 J15    GND VSS1628 @S9S_MB_2U_LIB.S9S_MB_2U(SCH_1):GND
 H81    GND VSS1627 @S9S_MB_2U_LIB.S9S_MB_2U(SCH_1):GND
  H8    GND VSS1626 @S9S_MB_2U_LIB.S9S_MB_2U(SCH_1):GND
 H79    GND VSS1625 @S9S_MB_2U_LIB.S9S_MB_2U(SCH_1):GND
 H71    GND VSS1624 @S9S_MB_2U_LIB.S9S_MB_2U(SCH_1):GND
 H69    GND VSS1623 @S9S_MB_2U_LIB.S9S_MB_2U(SCH_1):GND
 H63    GND VSS1622 @S9S_MB_2U_LIB.S9S_MB_2U(SCH_1):GND
  H6    GND VSS1621 @S9S_MB_2U_LIB.S9S_MB_2U(SCH_1):GND
 H59    GND VSS1620 @S9S_MB_2U_LIB.S9S_MB_2U(SCH_1):GND
 H53    GND VSS1619 @S9S_MB_2U_LIB.S9S_MB_2U(SCH_1):GND
 H47    GND VSS1618 @S9S_MB_2U_LIB.S9S_MB_2U(SCH_1):GND
 H44    GND VSS1617 @S9S_MB_2U_LIB.S9S_MB_2U(SCH_1):GND
 H40    GND VSS1616 @S9S_MB_2U_LIB.S9S_MB_2U(SCH_1):GND
  H4    GND VSS1615 @S9S_MB_2U_LIB.S9S_MB_2U(SCH_1):GND
 L19    GND VSS1614 @S9S_MB_2U_LIB.S9S_MB_2U(SCH_1):GND
 H38    GND VSS1613 @S9S_MB_2U_LIB.S9S_MB_2U(SCH_1):GND
 H34    GND VSS1612 @S9S_MB_2U_LIB.S9S_MB_2U(SCH_1):GND
 H32    GND VSS1611 @S9S_MB_2U_LIB.S9S_MB_2U(SCH_1):GND
 H28    GND VSS1610 @S9S_MB_2U_LIB.S9S_MB_2U(SCH_1):GND
 H26    GND VSS1609 @S9S_MB_2U_LIB.S9S_MB_2U(SCH_1):GND
 H22    GND VSS1608 @S9S_MB_2U_LIB.S9S_MB_2U(SCH_1):GND
 H20    GND VSS1607 @S9S_MB_2U_LIB.S9S_MB_2U(SCH_1):GND
 H16    GND VSS1606 @S9S_MB_2U_LIB.S9S_MB_2U(SCH_1):GND
 H10    GND VSS1605 @S9S_MB_2U_LIB.S9S_MB_2U(SCH_1):GND
 G90    GND VSS1604 @S9S_MB_2U_LIB.S9S_MB_2U(SCH_1):GND
 K49    GND VSS1603 @S9S_MB_2U_LIB.S9S_MB_2U(SCH_1):GND
 K42    GND VSS1602 @S9S_MB_2U_LIB.S9S_MB_2U(SCH_1):GND
 G88    GND VSS1601 @S9S_MB_2U_LIB.S9S_MB_2U(SCH_1):GND
 G84    GND VSS1600 @S9S_MB_2U_LIB.S9S_MB_2U(SCH_1):GND
  K2    GND VSS1599 @S9S_MB_2U_LIB.S9S_MB_2U(SCH_1):GND
 K14    GND VSS1598 @S9S_MB_2U_LIB.S9S_MB_2U(SCH_1):GND
 K12    GND VSS1597 @S9S_MB_2U_LIB.S9S_MB_2U(SCH_1):GND
  J9    GND VSS1596 @S9S_MB_2U_LIB.S9S_MB_2U(SCH_1):GND
 J88    GND VSS1595 @S9S_MB_2U_LIB.S9S_MB_2U(SCH_1):GND
 G72    GND VSS1594 @S9S_MB_2U_LIB.S9S_MB_2U(SCH_1):GND
 G62    GND VSS1593 @S9S_MB_2U_LIB.S9S_MB_2U(SCH_1):GND
 G56    GND VSS1592 @S9S_MB_2U_LIB.S9S_MB_2U(SCH_1):GND
 G54    GND VSS1591 @S9S_MB_2U_LIB.S9S_MB_2U(SCH_1):GND
 G50    GND VSS1590 @S9S_MB_2U_LIB.S9S_MB_2U(SCH_1):GND
 J70    GND VSS1589 @S9S_MB_2U_LIB.S9S_MB_2U(SCH_1):GND
 G43    GND VSS1588 @S9S_MB_2U_LIB.S9S_MB_2U(SCH_1):GND
 J64    GND VSS1587 @S9S_MB_2U_LIB.S9S_MB_2U(SCH_1):GND
 G41    GND VSS1586 @S9S_MB_2U_LIB.S9S_MB_2U(SCH_1):GND
 G37    GND VSS1585 @S9S_MB_2U_LIB.S9S_MB_2U(SCH_1):GND
 G31    GND VSS1584 @S9S_MB_2U_LIB.S9S_MB_2U(SCH_1):GND
 G29    GND VSS1583 @S9S_MB_2U_LIB.S9S_MB_2U(SCH_1):GND
  J5    GND VSS1582 @S9S_MB_2U_LIB.S9S_MB_2U(SCH_1):GND
 G23    GND VSS1581 @S9S_MB_2U_LIB.S9S_MB_2U(SCH_1):GND
 J39    GND VSS1580 @S9S_MB_2U_LIB.S9S_MB_2U(SCH_1):GND
 G19    GND VSS1579 @S9S_MB_2U_LIB.S9S_MB_2U(SCH_1):GND
 G13    GND VSS1578 @S9S_MB_2U_LIB.S9S_MB_2U(SCH_1):GND
 F89    GND VSS1577 @S9S_MB_2U_LIB.S9S_MB_2U(SCH_1):GND
 F83    GND VSS1576 @S9S_MB_2U_LIB.S9S_MB_2U(SCH_1):GND
 J21    GND VSS1575 @S9S_MB_2U_LIB.S9S_MB_2U(SCH_1):GND
 F49    GND VSS1574 @S9S_MB_2U_LIB.S9S_MB_2U(SCH_1):GND
  F4    GND VSS1573 @S9S_MB_2U_LIB.S9S_MB_2U(SCH_1):GND
 F36    GND VSS1572 @S9S_MB_2U_LIB.S9S_MB_2U(SCH_1):GND
 F30    GND VSS1571 @S9S_MB_2U_LIB.S9S_MB_2U(SCH_1):GND
 F24    GND VSS1570 @S9S_MB_2U_LIB.S9S_MB_2U(SCH_1):GND
 H75    GND VSS1567 @S9S_MB_2U_LIB.S9S_MB_2U(SCH_1):GND
 H65    GND VSS1564 @S9S_MB_2U_LIB.S9S_MB_2U(SCH_1):GND
 H57    GND VSS1560 @S9S_MB_2U_LIB.S9S_MB_2U(SCH_1):GND
 H51    GND VSS1558 @S9S_MB_2U_LIB.S9S_MB_2U(SCH_1):GND
  H2    GND VSS1546 @S9S_MB_2U_LIB.S9S_MB_2U(SCH_1):GND
 H14    GND VSS1544 @S9S_MB_2U_LIB.S9S_MB_2U(SCH_1):GND
 G74    GND VSS1538 @S9S_MB_2U_LIB.S9S_MB_2U(SCH_1):GND
  G7    GND VSS1536 @S9S_MB_2U_LIB.S9S_MB_2U(SCH_1):GND
 G68    GND VSS1535 @S9S_MB_2U_LIB.S9S_MB_2U(SCH_1):GND
 G66    GND VSS1534 @S9S_MB_2U_LIB.S9S_MB_2U(SCH_1):GND
 G60    GND VSS1532 @S9S_MB_2U_LIB.S9S_MB_2U(SCH_1):GND
 G48    GND VSS1527 @S9S_MB_2U_LIB.S9S_MB_2U(SCH_1):GND
 G35    GND VSS1523 @S9S_MB_2U_LIB.S9S_MB_2U(SCH_1):GND
  G3    GND VSS1521 @S9S_MB_2U_LIB.S9S_MB_2U(SCH_1):GND
 G25    GND VSS1519 @S9S_MB_2U_LIB.S9S_MB_2U(SCH_1):GND
 G17    GND VSS1516 @S9S_MB_2U_LIB.S9S_MB_2U(SCH_1):GND
 G11    GND VSS1514 @S9S_MB_2U_LIB.S9S_MB_2U(SCH_1):GND
 F79    GND VSS1511 @S9S_MB_2U_LIB.S9S_MB_2U(SCH_1):GND
 F73    GND VSS1510 @S9S_MB_2U_LIB.S9S_MB_2U(SCH_1):GND
 F67    GND VSS1509 @S9S_MB_2U_LIB.S9S_MB_2U(SCH_1):GND
 F61    GND VSS1508 @S9S_MB_2U_LIB.S9S_MB_2U(SCH_1):GND
  F6    GND VSS1507 @S9S_MB_2U_LIB.S9S_MB_2U(SCH_1):GND
 F55    GND VSS1504 @S9S_MB_2U_LIB.S9S_MB_2U(SCH_1):GND
 F42    GND VSS1502 @S9S_MB_2U_LIB.S9S_MB_2U(SCH_1):GND
 F18    GND VSS1495 @S9S_MB_2U_LIB.S9S_MB_2U(SCH_1):GND
 F12    GND VSS1494 @S9S_MB_2U_LIB.S9S_MB_2U(SCH_1):GND
 E86    GND VSS1273 @S9S_MB_2U_LIB.S9S_MB_2U(SCH_1):GND
 E76    GND VSS1272 @S9S_MB_2U_LIB.S9S_MB_2U(SCH_1):GND
 E78    GND VSS1131 @S9S_MB_2U_LIB.S9S_MB_2U(SCH_1):GND
 E74    GND VSS1129 @S9S_MB_2U_LIB.S9S_MB_2U(SCH_1):GND
 E52    GND VSS1126 @S9S_MB_2U_LIB.S9S_MB_2U(SCH_1):GND

SOCKET4677_AZIF0045P001C01CS-SA  I12  U2
 E39    GND VSS1271 @S9S_MB_2U_LIB.S9S_MB_2U(SCH_1):GND
  E5    GND VSS1125 @S9S_MB_2U_LIB.S9S_MB_2U(SCH_1):GND
 D83    GND VSS907 @S9S_MB_2U_LIB.S9S_MB_2U(SCH_1):GND
 D81    GND VSS906 @S9S_MB_2U_LIB.S9S_MB_2U(SCH_1):GND
 D71    GND VSS902 @S9S_MB_2U_LIB.S9S_MB_2U(SCH_1):GND
 D69    GND VSS901 @S9S_MB_2U_LIB.S9S_MB_2U(SCH_1):GND
 D61    GND VSS900 @S9S_MB_2U_LIB.S9S_MB_2U(SCH_1):GND
  D6    GND VSS899 @S9S_MB_2U_LIB.S9S_MB_2U(SCH_1):GND
 D59    GND VSS898 @S9S_MB_2U_LIB.S9S_MB_2U(SCH_1):GND
 D57    GND VSS897 @S9S_MB_2U_LIB.S9S_MB_2U(SCH_1):GND
 D55    GND VSS896 @S9S_MB_2U_LIB.S9S_MB_2U(SCH_1):GND
 D53    GND VSS895 @S9S_MB_2U_LIB.S9S_MB_2U(SCH_1):GND
 D51    GND VSS892 @S9S_MB_2U_LIB.S9S_MB_2U(SCH_1):GND
 D49    GND VSS891 @S9S_MB_2U_LIB.S9S_MB_2U(SCH_1):GND
 D47    GND VSS889 @S9S_MB_2U_LIB.S9S_MB_2U(SCH_1):GND
 D44    GND VSS888 @S9S_MB_2U_LIB.S9S_MB_2U(SCH_1):GND
 D42    GND VSS886 @S9S_MB_2U_LIB.S9S_MB_2U(SCH_1):GND
 D40    GND VSS885 @S9S_MB_2U_LIB.S9S_MB_2U(SCH_1):GND
 D38    GND VSS884 @S9S_MB_2U_LIB.S9S_MB_2U(SCH_1):GND
 D36    GND VSS881 @S9S_MB_2U_LIB.S9S_MB_2U(SCH_1):GND
 D34    GND VSS879 @S9S_MB_2U_LIB.S9S_MB_2U(SCH_1):GND
 D32    GND VSS878 @S9S_MB_2U_LIB.S9S_MB_2U(SCH_1):GND
 D30    GND VSS877 @S9S_MB_2U_LIB.S9S_MB_2U(SCH_1):GND
 D28    GND VSS876 @S9S_MB_2U_LIB.S9S_MB_2U(SCH_1):GND
 D26    GND VSS875 @S9S_MB_2U_LIB.S9S_MB_2U(SCH_1):GND
 D24    GND VSS874 @S9S_MB_2U_LIB.S9S_MB_2U(SCH_1):GND
 D22    GND VSS873 @S9S_MB_2U_LIB.S9S_MB_2U(SCH_1):GND
 D20    GND VSS871 @S9S_MB_2U_LIB.S9S_MB_2U(SCH_1):GND
 D18    GND VSS869 @S9S_MB_2U_LIB.S9S_MB_2U(SCH_1):GND
 D16    GND VSS868 @S9S_MB_2U_LIB.S9S_MB_2U(SCH_1):GND
 D14    GND VSS866 @S9S_MB_2U_LIB.S9S_MB_2U(SCH_1):GND
 D12    GND VSS865 @S9S_MB_2U_LIB.S9S_MB_2U(SCH_1):GND
 D10    GND VSS864 @S9S_MB_2U_LIB.S9S_MB_2U(SCH_1):GND
  D8    GND VSS663 @S9S_MB_2U_LIB.S9S_MB_2U(SCH_1):GND
 D79    GND VSS662 @S9S_MB_2U_LIB.S9S_MB_2U(SCH_1):GND
 D67    GND VSS659 @S9S_MB_2U_LIB.S9S_MB_2U(SCH_1):GND
 D65    GND VSS658 @S9S_MB_2U_LIB.S9S_MB_2U(SCH_1):GND
 D63    GND VSS657 @S9S_MB_2U_LIB.S9S_MB_2U(SCH_1):GND
 C86    GND VSS619 @S9S_MB_2U_LIB.S9S_MB_2U(SCH_1):GND
 C82    GND VSS618 @S9S_MB_2U_LIB.S9S_MB_2U(SCH_1):GND
 C80    GND VSS617 @S9S_MB_2U_LIB.S9S_MB_2U(SCH_1):GND
 C78    GND VSS616 @S9S_MB_2U_LIB.S9S_MB_2U(SCH_1):GND
 C74    GND VSS615 @S9S_MB_2U_LIB.S9S_MB_2U(SCH_1):GND
 C72    GND VSS614 @S9S_MB_2U_LIB.S9S_MB_2U(SCH_1):GND
 C52    GND VSS613 @S9S_MB_2U_LIB.S9S_MB_2U(SCH_1):GND
  C5    GND VSS612 @S9S_MB_2U_LIB.S9S_MB_2U(SCH_1):GND
 C45    GND VSS610 @S9S_MB_2U_LIB.S9S_MB_2U(SCH_1):GND
 C39    GND VSS609 @S9S_MB_2U_LIB.S9S_MB_2U(SCH_1):GND
 B87    GND VSS392 @S9S_MB_2U_LIB.S9S_MB_2U(SCH_1):GND
 B83    GND VSS391 @S9S_MB_2U_LIB.S9S_MB_2U(SCH_1):GND
 B75    GND VSS390 @S9S_MB_2U_LIB.S9S_MB_2U(SCH_1):GND
 B67    GND VSS389 @S9S_MB_2U_LIB.S9S_MB_2U(SCH_1):GND
 B61    GND VSS388 @S9S_MB_2U_LIB.S9S_MB_2U(SCH_1):GND
  B6    GND VSS387 @S9S_MB_2U_LIB.S9S_MB_2U(SCH_1):GND
 B55    GND VSS386 @S9S_MB_2U_LIB.S9S_MB_2U(SCH_1):GND
 B49    GND VSS385 @S9S_MB_2U_LIB.S9S_MB_2U(SCH_1):GND
 B42    GND VSS384 @S9S_MB_2U_LIB.S9S_MB_2U(SCH_1):GND
 B36    GND VSS382 @S9S_MB_2U_LIB.S9S_MB_2U(SCH_1):GND
 B30    GND VSS381 @S9S_MB_2U_LIB.S9S_MB_2U(SCH_1):GND
 B24    GND VSS380 @S9S_MB_2U_LIB.S9S_MB_2U(SCH_1):GND
 B18    GND VSS379 @S9S_MB_2U_LIB.S9S_MB_2U(SCH_1):GND
 B12    GND VSS378 @S9S_MB_2U_LIB.S9S_MB_2U(SCH_1):GND
 A62    GND  VSS16 @S9S_MB_2U_LIB.S9S_MB_2U(SCH_1):GND
 A60    GND  VSS15 @S9S_MB_2U_LIB.S9S_MB_2U(SCH_1):GND
 A56    GND  VSS14 @S9S_MB_2U_LIB.S9S_MB_2U(SCH_1):GND
 A54    GND  VSS13 @S9S_MB_2U_LIB.S9S_MB_2U(SCH_1):GND
 A50    GND  VSS12 @S9S_MB_2U_LIB.S9S_MB_2U(SCH_1):GND
 A41    GND  VSS11 @S9S_MB_2U_LIB.S9S_MB_2U(SCH_1):GND
 A37    GND  VSS10 @S9S_MB_2U_LIB.S9S_MB_2U(SCH_1):GND
 A35    GND   VSS9 @S9S_MB_2U_LIB.S9S_MB_2U(SCH_1):GND
 A31    GND   VSS8 @S9S_MB_2U_LIB.S9S_MB_2U(SCH_1):GND
 A29    GND   VSS7 @S9S_MB_2U_LIB.S9S_MB_2U(SCH_1):GND
 A25    GND   VSS6 @S9S_MB_2U_LIB.S9S_MB_2U(SCH_1):GND
 A23    GND   VSS5 @S9S_MB_2U_LIB.S9S_MB_2U(SCH_1):GND
 A19    GND   VSS4 @S9S_MB_2U_LIB.S9S_MB_2U(SCH_1):GND
 A17    GND   VSS3 @S9S_MB_2U_LIB.S9S_MB_2U(SCH_1):GND
 A13    GND   VSS2 @S9S_MB_2U_LIB.S9S_MB_2U(SCH_1):GND
 A11    GND   VSS1 @S9S_MB_2U_LIB.S9S_MB_2U(SCH_1):GND


DRAWING: @S9S_MB_2U_LIB.S9S_MB_2U(SCH_1):PAGE43 

Q_RES_0402LF-33.2,1%,1/16W,CHIA  I12  R67
   1 PWRGD_PLT_AUX_CPU0_LVT3_R      A @S9S_MB_2U_LIB.S9S_MB_2U(SCH_1):PWRGD_PLT_AUX_CPU0_LVT3_R
   2 PWRGD_PLT_AUX_CPU0_LVT3      B @S9S_MB_2U_LIB.S9S_MB_2U(SCH_1):PWRGD_PLT_AUX_CPU0_LVT3

Q_RES_0402LF-33.2,1%,1/16W,CHIA  I13  R68
   1 PWRGD_PLT_AUX_CPU1_LVT3_R      A @S9S_MB_2U_LIB.S9S_MB_2U(SCH_1):PWRGD_PLT_AUX_CPU1_LVT3_R
   2 PWRGD_PLT_AUX_CPU1_LVT3      B @S9S_MB_2U_LIB.S9S_MB_2U(SCH_1):PWRGD_PLT_AUX_CPU1_LVT3

Q_RES_0402LF-10K,1%,1/16W,CHIPA  I16  R69
   1 PWRGD_PLT_AUX_CPU0_LVT3      A @S9S_MB_2U_LIB.S9S_MB_2U(SCH_1):PWRGD_PLT_AUX_CPU0_LVT3
   2    GND      B @S9S_MB_2U_LIB.S9S_MB_2U(SCH_1):GND

Q_RES_0402LF-10K,1%,1/16W,CHIPA  I17  R70
   1 PWRGD_PLT_AUX_CPU1_LVT3      A @S9S_MB_2U_LIB.S9S_MB_2U(SCH_1):PWRGD_PLT_AUX_CPU1_LVT3
   2    GND      B @S9S_MB_2U_LIB.S9S_MB_2U(SCH_1):GND

Q_RES_0402LF-10K,1%,1/16W,CHIPA  I52  R1226
   1 PD_JTAG_CPU0_PLD_TCK      A @S9S_MB_2U_LIB.S9S_MB_2U(SCH_1):PD_JTAG_CPU0_PLD_TCK
   2    GND      B @S9S_MB_2U_LIB.S9S_MB_2U(SCH_1):GND

Q_RES_0402LF-10K,1%,1/16W,CHIPA  I56  R1227
   1 PD_JTAG_CPU1_PLD_TCK      A @S9S_MB_2U_LIB.S9S_MB_2U(SCH_1):PD_JTAG_CPU1_PLD_TCK
   2    GND      B @S9S_MB_2U_LIB.S9S_MB_2U(SCH_1):GND


DRAWING: @S9S_MB_2U_LIB.S9S_MB_2U(SCH_1):PAGE44 

Q_RES_0402LF-100,1%,1/16W,CHIPA  I7  R66
   1 JTAG_DBP_CPU_QS_GTL_TMS      A @S9S_MB_2U_LIB.S9S_MB_2U(SCH_1):JTAG_DBP_CPU_QS_GTL_TMS
   2 JTAG_DBP_CPU1_QS_GTL_R_TMS      B @S9S_MB_2U_LIB.S9S_MB_2U(SCH_1):JTAG_DBP_CPU1_QS_GTL_R_TMS

Q_RES_0402LF-100,1%,1/16W,CHIPA  I8  R65
   1 JTAG_DBP_CPU_GTL_TCK      A @S9S_MB_2U_LIB.S9S_MB_2U(SCH_1):JTAG_DBP_CPU_GTL_TCK
   2 JTAG_DBP_CPU1_GTL_R_TCK      B @S9S_MB_2U_LIB.S9S_MB_2U(SCH_1):JTAG_DBP_CPU1_GTL_R_TCK

Q_RES_0402LF-200,1%,1/16W,CHIPA  I9  R64
   1 JTAG_MUX_CPU1_GTL_TDI      A @S9S_MB_2U_LIB.S9S_MB_2U(SCH_1):JTAG_MUX_CPU1_GTL_TDI
   2 JTAG_DBP_CPU1_GTL_R_TDI      B @S9S_MB_2U_LIB.S9S_MB_2U(SCH_1):JTAG_DBP_CPU1_GTL_R_TDI

Q_RES_0402LF-33.2,1%,1/16W,CHIA  I10  R63
   1 PECI_CPU_GTL      A @S9S_MB_2U_LIB.S9S_MB_2U(SCH_1):PECI_CPU_GTL
   2 PECI_CPU1_GTL_R      B @S9S_MB_2U_LIB.S9S_MB_2U(SCH_1):PECI_CPU1_GTL_R

Q_RES_0402LF-100,1%,1/16W,CHIPA  I11  R62
   1 H_CPU_PREQ_QS_GTL_N      A @S9S_MB_2U_LIB.S9S_MB_2U(SCH_1):H_CPU_PREQ_QS_GTL_N
   2 H_CPU1_PREQ_QS_GTL_R_N      B @S9S_MB_2U_LIB.S9S_MB_2U(SCH_1):H_CPU1_PREQ_QS_GTL_R_N

Q_RES_0402LF-10,1%,1/16W,CHIP,A  I16  R61
   1 H_CPU_PRDY_QS_GTL_N      A @S9S_MB_2U_LIB.S9S_MB_2U(SCH_1):H_CPU_PRDY_QS_GTL_N
   2 H_CPU1_PRDY_QS_GTL_R_N      B @S9S_MB_2U_LIB.S9S_MB_2U(SCH_1):H_CPU1_PRDY_QS_GTL_R_N

SOCKET4677_AZIF0045P001C01CS-SA  I51  U1
CY32 CLK_25M_NSSC_CPU1_DP XTAL_CLK_DP @S9S_MB_2U_LIB.S9S_MB_2U(SCH_1):CLK_25M_NSSC_CPU1_DP
CT20 PD_CPU1_TXT_PLTEN TXT_PLTEN @S9S_MB_2U_LIB.S9S_MB_2U(SCH_1):PD_CPU1_TXT_PLTEN
BT26 PU_CPU1_TXT_AGENT TXT_AGENT @S9S_MB_2U_LIB.S9S_MB_2U(SCH_1):PU_CPU1_TXT_AGENT
BR25 JTAG_DBP_CPU1_QS_GTL_R_TMS    TMS @S9S_MB_2U_LIB.S9S_MB_2U(SCH_1):JTAG_DBP_CPU1_QS_GTL_R_TMS
BW25 JTAG_CPU1_MUX_GTL_TDO    TDO @S9S_MB_2U_LIB.S9S_MB_2U(SCH_1):JTAG_CPU1_MUX_GTL_TDO
BV24 JTAG_DBP_CPU1_GTL_R_TDI    TDI @S9S_MB_2U_LIB.S9S_MB_2U(SCH_1):JTAG_DBP_CPU1_GTL_R_TDI
BT24 JTAG_DBP_CPU1_GTL_R_TCK    TCK @S9S_MB_2U_LIB.S9S_MB_2U(SCH_1):JTAG_DBP_CPU1_GTL_R_TCK
CW60 PU_CPU1_SOCKET_ID0 SOCKET_ID0 @S9S_MB_2U_LIB.S9S_MB_2U(SCH_1):PU_CPU1_SOCKET_ID0
CY61 PU_CPU1_SOCKET_ID1 SOCKET_ID1 @S9S_MB_2U_LIB.S9S_MB_2U(SCH_1):PU_CPU1_SOCKET_ID1
CT61 PU_CPU1_SOCKET_ID2 SOCKET_ID2 @S9S_MB_2U_LIB.S9S_MB_2U(SCH_1):PU_CPU1_SOCKET_ID2
AU23 PU_CPU1_SAFE_MODE_BOOT SAFE_MODE_BOOT @S9S_MB_2U_LIB.S9S_MB_2U(SCH_1):PU_CPU1_SAFE_MODE_BOOT
CE70 CPU1_RSVD<85> RSVD91 @S9S_MB_2U_LIB.S9S_MB_2U(SCH_1):CPU1_RSVD(85)
CD71 CPU1_RSVD<82> RSVD88 @S9S_MB_2U_LIB.S9S_MB_2U(SCH_1):CPU1_RSVD(82)
BY24 PD_EXT_CLK_SEL_CPU1 RSVD76 @S9S_MB_2U_LIB.S9S_MB_2U(SCH_1):PD_EXT_CLK_SEL_CPU1
  G5 CPU1_RSVD<157> RSVD161 @S9S_MB_2U_LIB.S9S_MB_2U(SCH_1):CPU1_RSVD(157)
CJ72 PUD_XTAL_CPU1_MODE1 RSVD108 @S9S_MB_2U_LIB.S9S_MB_2U(SCH_1):PUD_XTAL_CPU1_MODE1
BG72 FM_CPU1_PROC_ID0 PROC_ID0 @S9S_MB_2U_LIB.S9S_MB_2U(SCH_1):FM_CPU1_PROC_ID0
BH71 FM_CPU1_PROC_ID1 PROC_ID1 @S9S_MB_2U_LIB.S9S_MB_2U(SCH_1):FM_CPU1_PROC_ID1
DA52 PD_CPU1_PROCDIS_COD_GTL_N PROCDIS_N @S9S_MB_2U_LIB.S9S_MB_2U(SCH_1):PD_CPU1_PROCDIS_COD_GTL_N
AV22 H_CPU1_PREQ_QS_GTL_R_N PREQ_N @S9S_MB_2U_LIB.S9S_MB_2U(SCH_1):H_CPU1_PREQ_QS_GTL_R_N
BP26 H_CPU1_PRDY_QS_GTL_R_N PRDY_N @S9S_MB_2U_LIB.S9S_MB_2U(SCH_1):H_CPU1_PRDY_QS_GTL_R_N
BL64 FM_CPU1_PKGID0 PKG_ID0 @S9S_MB_2U_LIB.S9S_MB_2U(SCH_1):FM_CPU1_PKGID0
AY63 FM_CPU1_PKGID1 PKG_ID1 @S9S_MB_2U_LIB.S9S_MB_2U(SCH_1):FM_CPU1_PKGID1
BN64 FM_CPU1_PKGID2 PKG_ID2 @S9S_MB_2U_LIB.S9S_MB_2U(SCH_1):FM_CPU1_PKGID2
BH24 PECI_CPU1_GTL_R   PECI @S9S_MB_2U_LIB.S9S_MB_2U(SCH_1):PECI_CPU1_GTL_R
BR23 TP_CPU1_BR23 RSVD72 @S9S_MB_2U_LIB.S9S_MB_2U(SCH_1):TP_CPU1_BR23
CY59 PU_CPU1_LEGACY_SKT LEGACY_SKT @S9S_MB_2U_LIB.S9S_MB_2U(SCH_1):PU_CPU1_LEGACY_SKT
AU17 PU_CPU1_FRMAGENT FRMAGENT @S9S_MB_2U_LIB.S9S_MB_2U(SCH_1):PU_CPU1_FRMAGENT
AW17 PD_CPU1_DMIMODE_OVERRIDE DMIMODE_OVERRIDE @S9S_MB_2U_LIB.S9S_MB_2U(SCH_1):PD_CPU1_DMIMODE_OVERRIDE
CY55 RST_CPU1_DRAM_GH_N DDR67_RESET_N @S9S_MB_2U_LIB.S9S_MB_2U(SCH_1):RST_CPU1_DRAM_GH_N
CY42 RST_CPU1_DRAM_EF_N DDR45_RESET_N @S9S_MB_2U_LIB.S9S_MB_2U(SCH_1):RST_CPU1_DRAM_EF_N
CT18 I3C_SPD_DDREFGH_CPU1_SDA DDR4567_SPDSDA @S9S_MB_2U_LIB.S9S_MB_2U(SCH_1):I3C_SPD_DDREFGH_CPU1_SDA
CU17 I3C_SPD_DDREFGH_CPU1_SCL DDR4567_SPDSCL @S9S_MB_2U_LIB.S9S_MB_2U(SCH_1):I3C_SPD_DDREFGH_CPU1_SCL
AV51 RST_CPU1_DRAM_CD_N DDR23_RESET_N @S9S_MB_2U_LIB.S9S_MB_2U(SCH_1):RST_CPU1_DRAM_CD_N
AU50 RST_CPU1_DRAM_AB_N DDR01_RESET_N @S9S_MB_2U_LIB.S9S_MB_2U(SCH_1):RST_CPU1_DRAM_AB_N
BY22 I3C_SPD_DDRABCD_CPU1_SDA DDR0123_SPDSDA @S9S_MB_2U_LIB.S9S_MB_2U(SCH_1):I3C_SPD_DDRABCD_CPU1_SDA
BT22 I3C_SPD_DDRABCD_CPU1_SCL DDR0123_SPDSCL @S9S_MB_2U_LIB.S9S_MB_2U(SCH_1):I3C_SPD_DDRABCD_CPU1_SCL
BN23 H_CPU1_BMCINIT_LVC1 BMCINIT @S9S_MB_2U_LIB.S9S_MB_2U(SCH_1):H_CPU1_BMCINIT_LVC1
AT18 PD_CPU1_BIST_ENABLE BIST_ENABLE @S9S_MB_2U_LIB.S9S_MB_2U(SCH_1):PD_CPU1_BIST_ENABLE
DA27 CLK_100M_DB2000_CPU1_BCLK3_DP BCLK3_DP @S9S_MB_2U_LIB.S9S_MB_2U(SCH_1):CLK_100M_DB2000_CPU1_BCLK3_DP
CW27 CLK_100M_DB2000_CPU1_BCLK3_DN BCLK3_DN @S9S_MB_2U_LIB.S9S_MB_2U(SCH_1):CLK_100M_DB2000_CPU1_BCLK3_DN
AV28 CLK_100M_DB2000_CPU1_BCLK2_DP BCLK2_DP @S9S_MB_2U_LIB.S9S_MB_2U(SCH_1):CLK_100M_DB2000_CPU1_BCLK2_DP
AU29 CLK_100M_DB2000_CPU1_BCLK2_DN BCLK2_DN @S9S_MB_2U_LIB.S9S_MB_2U(SCH_1):CLK_100M_DB2000_CPU1_BCLK2_DN
AV30 CLK_100M_DB2000_CPU1_BCLK0_DP BCLK0_DP @S9S_MB_2U_LIB.S9S_MB_2U(SCH_1):CLK_100M_DB2000_CPU1_BCLK0_DP
CY28 CLK_100M_DB2000_CPU1_BCLK1_DN BCLK1_DN @S9S_MB_2U_LIB.S9S_MB_2U(SCH_1):CLK_100M_DB2000_CPU1_BCLK1_DN
CW29 CLK_100M_DB2000_CPU1_BCLK1_DP BCLK1_DP @S9S_MB_2U_LIB.S9S_MB_2U(SCH_1):CLK_100M_DB2000_CPU1_BCLK1_DP
AT30 CLK_100M_DB2000_CPU1_BCLK0_DN BCLK0_DN @S9S_MB_2U_LIB.S9S_MB_2U(SCH_1):CLK_100M_DB2000_CPU1_BCLK0_DN
CL72 PUD_XTAL_CPU1_MODE0 RSVD120 @S9S_MB_2U_LIB.S9S_MB_2U(SCH_1):PUD_XTAL_CPU1_MODE0
  D4 CPU1_RSVD<153> RSVD157 @S9S_MB_2U_LIB.S9S_MB_2U(SCH_1):CPU1_RSVD(153)
CW31 CLK_25M_NSSC_CPU1_DN XTAL_CLK_DN @S9S_MB_2U_LIB.S9S_MB_2U(SCH_1):CLK_25M_NSSC_CPU1_DN

Q_RES_0402LF-240,1%,1/16W,EMPTA  I55  R1270
   1 PD_CPU1_PROCDIS_COD_GTL_N      A @S9S_MB_2U_LIB.S9S_MB_2U(SCH_1):PD_CPU1_PROCDIS_COD_GTL_N
   2    GND      B @S9S_MB_2U_LIB.S9S_MB_2U(SCH_1):GND


DRAWING: @S9S_MB_2U_LIB.S9S_MB_2U(SCH_1):PAGE45 

SOCKET4677_AZIF0045P001C01CS-SA  I29  U1
BP24 H_CPU1_CATERR_LVC1_R_N CATERR_N @S9S_MB_2U_LIB.S9S_MB_2U(SCH_1):H_CPU1_CATERR_LVC1_R_N
CA25 SMB_PEHPCPU1_GTL_SCL CXPSMBUSSCL @S9S_MB_2U_LIB.S9S_MB_2U(SCH_1):SMB_PEHPCPU1_GTL_SCL
BY26 SMB_PEHPCPU1_GTL_SDA CXPSMBUSSDA @S9S_MB_2U_LIB.S9S_MB_2U(SCH_1):SMB_PEHPCPU1_GTL_SDA
BV26 FM_PEHPCPU1_ALERT_N CXPSMBUS_ALERT_N @S9S_MB_2U_LIB.S9S_MB_2U(SCH_1):FM_PEHPCPU1_ALERT_N
 A43 PWRGD_DRAMPWRGD_CPU1_AB_LVC1_R DDR01_DRAM_PWR_OK @S9S_MB_2U_LIB.S9S_MB_2U(SCH_1):PWRGD_DRAMPWRGD_CPU1_AB_LVC1_R
 F47 PWRGD_DRAMPWRGD_CPU1_CD_LVC1_R DDR23_DRAM_PWR_OK @S9S_MB_2U_LIB.S9S_MB_2U(SCH_1):PWRGD_DRAMPWRGD_CPU1_CD_LVC1_R
CY44 PWRGD_DRAMPWRGD_CPU1_EF_LVC1_R DDR45_DRAM_PWR_OK @S9S_MB_2U_LIB.S9S_MB_2U(SCH_1):PWRGD_DRAMPWRGD_CPU1_EF_LVC1_R
CW45 PWRGD_DRAMPWRGD_CPU1_GH_LVC1_R DDR67_DRAM_PWR_OK @S9S_MB_2U_LIB.S9S_MB_2U(SCH_1):PWRGD_DRAMPWRGD_CPU1_GH_LVC1_R
CH22 PD_CPU1_ENH_MCECC_DIS RSVD96 @S9S_MB_2U_LIB.S9S_MB_2U(SCH_1):PD_CPU1_ENH_MCECC_DIS
BD22 H_CPU1_ERR2_LVC1_R_N ERROR_N2 @S9S_MB_2U_LIB.S9S_MB_2U(SCH_1):H_CPU1_ERR2_LVC1_R_N
AY22 H_CPU1_ERR1_LVC1_R_N ERROR_N1 @S9S_MB_2U_LIB.S9S_MB_2U(SCH_1):H_CPU1_ERR1_LVC1_R_N
BF22 H_CPU1_ERR0_LVC1_R_N ERROR_N0 @S9S_MB_2U_LIB.S9S_MB_2U(SCH_1):H_CPU1_ERR0_LVC1_R_N
AV57 FM_CPU_FBRK_DEBUG_R_N FBRK_N @S9S_MB_2U_LIB.S9S_MB_2U(SCH_1):FM_CPU_FBRK_DEBUG_R_N
AU21 H_CPU1_MEMHOT_IN_LVC1_N MEMHOT_IN_N @S9S_MB_2U_LIB.S9S_MB_2U(SCH_1):H_CPU1_MEMHOT_IN_LVC1_N
CF26 H_CPU1_MEMHOT_OUT_LVC1_R_N MEMHOT_OUT_N @S9S_MB_2U_LIB.S9S_MB_2U(SCH_1):H_CPU1_MEMHOT_OUT_LVC1_R_N
AV24 H_CPU1_MEMTRIP_LVC1_R_N MEMTRIP_N @S9S_MB_2U_LIB.S9S_MB_2U(SCH_1):H_CPU1_MEMTRIP_LVC1_R_N
AV18 H_CPU1_NMI_LVC1_N    NMI @S9S_MB_2U_LIB.S9S_MB_2U(SCH_1):H_CPU1_NMI_LVC1_N
CP71 PD_PIROM_CPU1_ADDR2 PIROM_AD2 @S9S_MB_2U_LIB.S9S_MB_2U(SCH_1):PD_PIROM_CPU1_ADDR2
CT71 PD_PIROM_CPU1_ADDR1 PIROM_AD1 @S9S_MB_2U_LIB.S9S_MB_2U(SCH_1):PD_PIROM_CPU1_ADDR1
CR70 PU_PIROM_CPU1_ADDR0 PIROM_AD0 @S9S_MB_2U_LIB.S9S_MB_2U(SCH_1):PU_PIROM_CPU1_ADDR0
CU70 SMB_S3M_CPU1_PIROM_3V3AUX_SCL_1 PIROM_SCL @S9S_MB_2U_LIB.S9S_MB_2U(SCH_1):SMB_S3M_CPU1_PIROM_3V3AUX_SCL_R1
CM71 SMB_S3M_CPU1_PIROM_3V3AUX_SDA_1 PIROM_SDA @S9S_MB_2U_LIB.S9S_MB_2U(SCH_1):SMB_S3M_CPU1_PIROM_3V3AUX_SDA_R1
CR72 PU_PIROM_CPU1_SM_WP PIROM_SM_WP @S9S_MB_2U_LIB.S9S_MB_2U(SCH_1):PU_PIROM_CPU1_SM_WP
CC25 TP_H_SBLINK7_CPU1_PMDOWN PMDOWN6 @S9S_MB_2U_LIB.S9S_MB_2U(SCH_1):TP_H_SBLINK7_CPU1_PMDOWN
CE23 TP_H_SBLINK6_CPU1_PMDOWN PMDOWN5 @S9S_MB_2U_LIB.S9S_MB_2U(SCH_1):TP_H_SBLINK6_CPU1_PMDOWN
CV18 TP_H_SBLINK5_CPU1_PMDOWN PMDOWN4 @S9S_MB_2U_LIB.S9S_MB_2U(SCH_1):TP_H_SBLINK5_CPU1_PMDOWN
CD24 TP_H_SBLINK4_CPU1_PMDOWN PMDOWN3 @S9S_MB_2U_LIB.S9S_MB_2U(SCH_1):TP_H_SBLINK4_CPU1_PMDOWN
CM26 TP_H_SBLINK3_CPU1_PMDOWN PMDOWN2 @S9S_MB_2U_LIB.S9S_MB_2U(SCH_1):TP_H_SBLINK3_CPU1_PMDOWN
CP26 TP_H_SBLINK2_CPU1_PMDOWN PMDOWN1 @S9S_MB_2U_LIB.S9S_MB_2U(SCH_1):TP_H_SBLINK2_CPU1_PMDOWN
CW39 H_CPU0_PMSYNC_CPU1 PMDOWN0 @S9S_MB_2U_LIB.S9S_MB_2U(SCH_1):H_CPU0_PMSYNC_CPU1
CY40 TP_H_CPU1_PMDOWN_PCH_R PMDOWN_PCH @S9S_MB_2U_LIB.S9S_MB_2U(SCH_1):TP_H_CPU1_PMDOWN_PCH_R
CP20 H_CPU1_PM_FAST_WAKE_N PMFAST_WAKE_N @S9S_MB_2U_LIB.S9S_MB_2U(SCH_1):H_CPU1_PM_FAST_WAKE_N
CF24 TP_H_SBLINK7_CPU1_PMSYNC PMSYNC6 @S9S_MB_2U_LIB.S9S_MB_2U(SCH_1):TP_H_SBLINK7_CPU1_PMSYNC
CH24 TP_H_SBLINK6_CPU1_PMSYNC PMSYNC5 @S9S_MB_2U_LIB.S9S_MB_2U(SCH_1):TP_H_SBLINK6_CPU1_PMSYNC
CR19 TP_H_SBLINK5_CPU1_PMSYNC PMSYNC4 @S9S_MB_2U_LIB.S9S_MB_2U(SCH_1):TP_H_SBLINK5_CPU1_PMSYNC
CE25 TP_H_SBLINK4_CPU1_PMSYNC PMSYNC3 @S9S_MB_2U_LIB.S9S_MB_2U(SCH_1):TP_H_SBLINK4_CPU1_PMSYNC
CH26 TP_H_SBLINK3_CPU1_PMSYNC PMSYNC2 @S9S_MB_2U_LIB.S9S_MB_2U(SCH_1):TP_H_SBLINK3_CPU1_PMSYNC
CL25 TP_H_SBLINK2_CPU1_PMSYNC PMSYNC1 @S9S_MB_2U_LIB.S9S_MB_2U(SCH_1):TP_H_SBLINK2_CPU1_PMSYNC
CN25 H_CPU0_PMDOWN_CPU1 PMSYNC0 @S9S_MB_2U_LIB.S9S_MB_2U(SCH_1):H_CPU0_PMDOWN_CPU1
DA39 TP_H_CPU1_PMSYNC_PCH_INTRP_R PMSYNC_PCH @S9S_MB_2U_LIB.S9S_MB_2U(SCH_1):TP_H_CPU1_PMSYNC_PCH_INTRP_R
AU19 H_CPU1_PROCHOT_LVC1_N PROCHOT_N @S9S_MB_2U_LIB.S9S_MB_2U(SCH_1):H_CPU1_PROCHOT_LVC1_N
AV20 PWRGD_CPU1_LVC1 PWRGOOD @S9S_MB_2U_LIB.S9S_MB_2U(SCH_1):PWRGD_CPU1_LVC1
BH61 RST_CPU1_LVC1_N RESET_N @S9S_MB_2U_LIB.S9S_MB_2U(SCH_1):RST_CPU1_LVC1_N
CL21 CPU1_RSVD<107> RSVD113 @S9S_MB_2U_LIB.S9S_MB_2U(SCH_1):CPU1_RSVD(107)
CL64 CPU1_RSVD<110> RSVD116 @S9S_MB_2U_LIB.S9S_MB_2U(SCH_1):CPU1_RSVD(110)
CM63 CPU1_RSVD<115> RSVD121 @S9S_MB_2U_LIB.S9S_MB_2U(SCH_1):CPU1_RSVD(115)
CN62 CPU1_RSVD<120> RSVD126 @S9S_MB_2U_LIB.S9S_MB_2U(SCH_1):CPU1_RSVD(120)
CR23 CPU1_RSVD<126> RSVD132 @S9S_MB_2U_LIB.S9S_MB_2U(SCH_1):CPU1_RSVD(126)
CV24 CPU1_RSVD<135> RSVD141 @S9S_MB_2U_LIB.S9S_MB_2U(SCH_1):CPU1_RSVD(135)
CW23 CPU1_RSVD<139> RSVD145 @S9S_MB_2U_LIB.S9S_MB_2U(SCH_1):CPU1_RSVD(139)
CW25 CPU1_RSVD<140> RSVD146 @S9S_MB_2U_LIB.S9S_MB_2U(SCH_1):CPU1_RSVD(140)
CW68 CPU1_RSVD<144> RSVD150 @S9S_MB_2U_LIB.S9S_MB_2U(SCH_1):CPU1_RSVD(144)
AV26 CPU1_RSVD<15> RSVD15 @S9S_MB_2U_LIB.S9S_MB_2U(SCH_1):CPU1_RSVD(15)
AY26 CPU1_RSVD<25> RSVD27 @S9S_MB_2U_LIB.S9S_MB_2U(SCH_1):CPU1_RSVD(25)
AY65 CPU1_RSVD<27> RSVD29 @S9S_MB_2U_LIB.S9S_MB_2U(SCH_1):CPU1_RSVD(27)
AT24 CPU1_RSVD<4>  RSVD4 @S9S_MB_2U_LIB.S9S_MB_2U(SCH_1):CPU1_RSVD(4)
BJ70 CPU1_RSVD<54> RSVD59 @S9S_MB_2U_LIB.S9S_MB_2U(SCH_1):CPU1_RSVD(54)
AU25 CPU1_RSVD<6>  RSVD6 @S9S_MB_2U_LIB.S9S_MB_2U(SCH_1):CPU1_RSVD(6)
BP67 CPU1_RSVD<64> RSVD69 @S9S_MB_2U_LIB.S9S_MB_2U(SCH_1):CPU1_RSVD(64)
BP69 CPU1_RSVD<65> RSVD70 @S9S_MB_2U_LIB.S9S_MB_2U(SCH_1):CPU1_RSVD(65)
CJ62 CPU1_RSVD<98> RSVD104 @S9S_MB_2U_LIB.S9S_MB_2U(SCH_1):CPU1_RSVD(98)
CG66 FM_CPU1_SKTOCC_LVT3_N SKTOCC_N @S9S_MB_2U_LIB.S9S_MB_2U(SCH_1):FM_CPU1_SKTOCC_LVT3_N
BK26 SVID_ALERT0_CPU1_N SVIDALERT0_N @S9S_MB_2U_LIB.S9S_MB_2U(SCH_1):SVID_ALERT0_CPU1_N
BJ25 SVID_ALERT1_CPU1_N SVIDALERT1_N @S9S_MB_2U_LIB.S9S_MB_2U(SCH_1):SVID_ALERT1_CPU1_N
BH26 SVID_CLK0_CPU1 SVIDCLK0 @S9S_MB_2U_LIB.S9S_MB_2U(SCH_1):SVID_CLK0_CPU1
BF26 SVID_CLK1_CPU1 SVIDCLK1 @S9S_MB_2U_LIB.S9S_MB_2U(SCH_1):SVID_CLK1_CPU1
BD26 SVID_DIO0_CPU1 SVIDDATA0 @S9S_MB_2U_LIB.S9S_MB_2U(SCH_1):SVID_DIO0_CPU1
BL25 SVID_DIO1_CPU1 SVIDDATA1 @S9S_MB_2U_LIB.S9S_MB_2U(SCH_1):SVID_DIO1_CPU1
AY20 PU_TAP_ODT_CPU1_EN TAP_ODT_EN @S9S_MB_2U_LIB.S9S_MB_2U(SCH_1):PU_TAP_ODT_CPU1_EN
AV59 TP_EV_CPU1_EXT_BGREF RSVD19 @S9S_MB_2U_LIB.S9S_MB_2U(SCH_1):TP_EV_CPU1_EXT_BGREF
BL62 H_CPU1_THERMTRIP_LVC1_R_N THERMTRIP_N @S9S_MB_2U_LIB.S9S_MB_2U(SCH_1):H_CPU1_THERMTRIP_LVC1_R_N

Q_RES_0402LF-0,5%,1/16W,CHIP,CA  I51  R58
   1 SVID_DIO1_CPU1      A @S9S_MB_2U_LIB.S9S_MB_2U(SCH_1):SVID_DIO1_CPU1
   2 SVID_DIO1_CPU1_R      B @S9S_MB_2U_LIB.S9S_MB_2U(SCH_1):SVID_DIO1_CPU1_R

Q_RES_0402LF-0,5%,1/16W,CHIP,CA  I52  R59
   1 SVID_CLK1_CPU1      A @S9S_MB_2U_LIB.S9S_MB_2U(SCH_1):SVID_CLK1_CPU1
   2 SVID_CLK1_CPU1_R      B @S9S_MB_2U_LIB.S9S_MB_2U(SCH_1):SVID_CLK1_CPU1_R

Q_RES_0402LF-200,1%,1/16W,CHIPA  I53  R60
   1 SVID_ALERT1_CPU1_N      A @S9S_MB_2U_LIB.S9S_MB_2U(SCH_1):SVID_ALERT1_CPU1_N
   2 SVID_ALERT1_CPU1_R_N      B @S9S_MB_2U_LIB.S9S_MB_2U(SCH_1):SVID_ALERT1_CPU1_R_N

Q_RES_0402LF-0,5%,1/16W,CHIP,CA  I54  R55
   1 SVID_DIO0_CPU1      A @S9S_MB_2U_LIB.S9S_MB_2U(SCH_1):SVID_DIO0_CPU1
   2 SVID_DIO0_CPU1_R      B @S9S_MB_2U_LIB.S9S_MB_2U(SCH_1):SVID_DIO0_CPU1_R

Q_RES_0402LF-0,5%,1/16W,CHIP,CA  I55  R56
   1 SVID_CLK0_CPU1      A @S9S_MB_2U_LIB.S9S_MB_2U(SCH_1):SVID_CLK0_CPU1
   2 SVID_CLK0_CPU1_R      B @S9S_MB_2U_LIB.S9S_MB_2U(SCH_1):SVID_CLK0_CPU1_R

Q_RES_0402LF-200,1%,1/16W,CHIPA  I56  R57
   1 SVID_ALERT0_CPU1_N      A @S9S_MB_2U_LIB.S9S_MB_2U(SCH_1):SVID_ALERT0_CPU1_N
   2 SVID_ALERT0_CPU1_R_N      B @S9S_MB_2U_LIB.S9S_MB_2U(SCH_1):SVID_ALERT0_CPU1_R_N

Q_RES_0402LF-100,1%,1/16W,CHIPA  I69  R559
   1 SVID_DIO1_CPU1_R      A @S9S_MB_2U_LIB.S9S_MB_2U(SCH_1):SVID_DIO1_CPU1_R
   2 PVNN_TERM_CPU1      B @S9S_MB_2U_LIB.S9S_MB_2U(SCH_1):PVNN_TERM_CPU1

Q_RES_0402LF-49.9,1%,1/16W,CHIA  I70  R560
   1 SVID_ALERT1_CPU1_R_N      A @S9S_MB_2U_LIB.S9S_MB_2U(SCH_1):SVID_ALERT1_CPU1_R_N
   2 PVNN_TERM_CPU1      B @S9S_MB_2U_LIB.S9S_MB_2U(SCH_1):PVNN_TERM_CPU1

Q_RES_0402LF-49.9,1%,1/16W,CHIA  I73  R558
   1 SVID_ALERT0_CPU1_R_N      A @S9S_MB_2U_LIB.S9S_MB_2U(SCH_1):SVID_ALERT0_CPU1_R_N
   2 PVNN_TERM_CPU1      B @S9S_MB_2U_LIB.S9S_MB_2U(SCH_1):PVNN_TERM_CPU1

Q_RES_0402LF-100,1%,1/16W,CHIPA  I74  R557
   1 SVID_DIO0_CPU1_R      A @S9S_MB_2U_LIB.S9S_MB_2U(SCH_1):SVID_DIO0_CPU1_R
   2 PVNN_TERM_CPU1      B @S9S_MB_2U_LIB.S9S_MB_2U(SCH_1):PVNN_TERM_CPU1

Q_RES_0402LF-33.2,1%,1/16W,CHIA  I81  R1934
   1 SMB_S3M_CPU1_PIROM_3V3AUX_SCL      A @S9S_MB_2U_LIB.S9S_MB_2U(SCH_1):SMB_S3M_CPU1_PIROM_3V3AUX_SCL
   2 SMB_S3M_CPU1_PIROM_3V3AUX_SCL_1      B @S9S_MB_2U_LIB.S9S_MB_2U(SCH_1):SMB_S3M_CPU1_PIROM_3V3AUX_SCL_R1

Q_RES_0402LF-33.2,1%,1/16W,CHIA  I82  R1935
   1 SMB_S3M_CPU1_PIROM_3V3AUX_SDA      A @S9S_MB_2U_LIB.S9S_MB_2U(SCH_1):SMB_S3M_CPU1_PIROM_3V3AUX_SDA
   2 SMB_S3M_CPU1_PIROM_3V3AUX_SDA_1      B @S9S_MB_2U_LIB.S9S_MB_2U(SCH_1):SMB_S3M_CPU1_PIROM_3V3AUX_SDA_R1


DRAWING: @S9S_MB_2U_LIB.S9S_MB_2U(SCH_1):PAGE46 

SOCKET4677_AZIF0045P001C01CS-SA  I5  U1
CV20 PWRGD_PLT_AUX_CPU1_LVT3 PLT_AUX_PWRGOOD @S9S_MB_2U_LIB.S9S_MB_2U(SCH_1):PWRGD_PLT_AUX_CPU1_LVT3
CK22 TP_FM_SYS_RST_CPU1_N RSVD109 @S9S_MB_2U_LIB.S9S_MB_2U(SCH_1):TP_FM_SYS_RST_CPU1_N
CK24 TP_FM_IBL_PWRBTN_CPU1_N RSVD110 @S9S_MB_2U_LIB.S9S_MB_2U(SCH_1):TP_FM_IBL_PWRBTN_CPU1_N
CL23 TP_I2C_S3M_RTC_CPU1_SCL RSVD114 @S9S_MB_2U_LIB.S9S_MB_2U(SCH_1):TP_I2C_S3M_RTC_CPU1_SCL
AU62 NC_SPI_CPU1_NCM_CLK RSVD11 @S9S_MB_2U_LIB.S9S_MB_2U(SCH_1):NC_SPI_CPU1_NCM_CLK
CL66 TP_CPU1_SSC_SYNC RSVD117 @S9S_MB_2U_LIB.S9S_MB_2U(SCH_1):TP_CPU1_SSC_SYNC
CN21 TP_FM_IBL_SLPS4_CPU1_R_N RSVD123 @S9S_MB_2U_LIB.S9S_MB_2U(SCH_1):TP_FM_IBL_SLPS4_CPU1_R_N
CN23 NC_FM_IBL_ADR_ACK_CPU1 RSVD124 @S9S_MB_2U_LIB.S9S_MB_2U(SCH_1):NC_FM_IBL_ADR_ACK_CPU1
AU64 NC_ESPI_IBL_CPU1_IO2 RSVD12 @S9S_MB_2U_LIB.S9S_MB_2U(SCH_1):NC_ESPI_IBL_CPU1_IO2
CP22 TP_JTAG_CPU1_PLD_TDO_R RSVD127 @S9S_MB_2U_LIB.S9S_MB_2U(SCH_1):TP_JTAG_CPU1_PLD_TDO_R
CP24 NC_FM_IBL_ADR_COMPLETE_CPU1_R RSVD128 @S9S_MB_2U_LIB.S9S_MB_2U(SCH_1):NC_FM_IBL_ADR_COMPLETE_CPU1_R
CR21 TP_FM_IBL_SLPS3_CPU1_R_N RSVD131 @S9S_MB_2U_LIB.S9S_MB_2U(SCH_1):TP_FM_IBL_SLPS3_CPU1_R_N
CT22 TP_JTAG_CPU1_PLD_TDI RSVD136 @S9S_MB_2U_LIB.S9S_MB_2U(SCH_1):TP_JTAG_CPU1_PLD_TDI
CT24 NC_FM_IBL_ADR_TRIGGER_CPU1_R RSVD137 @S9S_MB_2U_LIB.S9S_MB_2U(SCH_1):NC_FM_IBL_ADR_TRIGGER_CPU1_R
CV22 TP_JTAG_CPU1_PLD_TMS RSVD140 @S9S_MB_2U_LIB.S9S_MB_2U(SCH_1):TP_JTAG_CPU1_PLD_TMS
CV69 NC_UART_IBL_CPU1_TXD RSVD142 @S9S_MB_2U_LIB.S9S_MB_2U(SCH_1):NC_UART_IBL_CPU1_TXD
CV71 NC_UART_IBL_CPU1_CTS RSVD143 @S9S_MB_2U_LIB.S9S_MB_2U(SCH_1):NC_UART_IBL_CPU1_CTS
CW21 TP_FM_IBL_SLPS5_CPU1_R_N RSVD144 @S9S_MB_2U_LIB.S9S_MB_2U(SCH_1):TP_FM_IBL_SLPS5_CPU1_R_N
CY20 FM_S3M_CPU1_CPLD_CRC_ERROR CD_INIT_ERROR @S9S_MB_2U_LIB.S9S_MB_2U(SCH_1):FM_S3M_CPU1_CPLD_CRC_ERROR
CY22 PD_JTAG_CPU1_PLD_TCK TEST_5 @S9S_MB_2U_LIB.S9S_MB_2U(SCH_1):PD_JTAG_CPU1_PLD_TCK
CY69 NC_UART_IBL_CPU1_RXD RSVD155 @S9S_MB_2U_LIB.S9S_MB_2U(SCH_1):NC_UART_IBL_CPU1_RXD
CY71 NC_UART_IBL_CPU1_RTS RSVD156 @S9S_MB_2U_LIB.S9S_MB_2U(SCH_1):NC_UART_IBL_CPU1_RTS
AV63 NC_SPI_S3M_CPU1_CS1_LVC1_R_N RSVD20 @S9S_MB_2U_LIB.S9S_MB_2U(SCH_1):NC_SPI_S3M_CPU1_CS1_LVC1_R_N
AW19 TP_FM_WAKE_CPU1_N RSVD23 @S9S_MB_2U_LIB.S9S_MB_2U(SCH_1):TP_FM_WAKE_CPU1_N
AW64 NC_SPI_S3M_CPU1_IO1_LVC1_R RSVD24 @S9S_MB_2U_LIB.S9S_MB_2U(SCH_1):NC_SPI_S3M_CPU1_IO1_LVC1_R
AY61 NC_SPI_CPU1_NCM_IO1 RSVD28 @S9S_MB_2U_LIB.S9S_MB_2U(SCH_1):NC_SPI_CPU1_NCM_IO1
AY67 NC_SPI_CPU1_NCM_CS0_N RSVD30 @S9S_MB_2U_LIB.S9S_MB_2U(SCH_1):NC_SPI_CPU1_NCM_CS0_N
BA62 NC_SPI_S3M_CPU1_IO0_LVC1_R RSVD32 @S9S_MB_2U_LIB.S9S_MB_2U(SCH_1):NC_SPI_S3M_CPU1_IO0_LVC1_R
BA66 NC_SPI_CPU1_NCM_IO0 RSVD33 @S9S_MB_2U_LIB.S9S_MB_2U(SCH_1):NC_SPI_CPU1_NCM_IO0
BA68 NC_SPI_S3M_CPU1_OE_LVC1_R_N RSVD34 @S9S_MB_2U_LIB.S9S_MB_2U(SCH_1):NC_SPI_S3M_CPU1_OE_LVC1_R_N
BB61 NC_SPI_S3M_CPU1_CS0_LVC1_R_N RSVD35 @S9S_MB_2U_LIB.S9S_MB_2U(SCH_1):NC_SPI_S3M_CPU1_CS0_LVC1_R_N
BB67 NC_SPI_CPU1_NCM_OE_N RSVD36 @S9S_MB_2U_LIB.S9S_MB_2U(SCH_1):NC_SPI_CPU1_NCM_OE_N
BC25 TP_I3C_MNG3_BMC_SW_SDA RSVD38 @S9S_MB_2U_LIB.S9S_MB_2U(SCH_1):TP_I3C_MNG3_BMC_SW_SDA
BC64 NC_SPI_S3M_CPU1_CLK_LVC1_R RSVD39 @S9S_MB_2U_LIB.S9S_MB_2U(SCH_1):NC_SPI_S3M_CPU1_CLK_LVC1_R
BD61 NC_SPI_S3M_CPU1_IO3_LVC1_R RSVD40 @S9S_MB_2U_LIB.S9S_MB_2U(SCH_1):NC_SPI_S3M_CPU1_IO3_LVC1_R
BD63 NC_ESPI_IBL_CPU1_ALERT1_N RSVD41 @S9S_MB_2U_LIB.S9S_MB_2U(SCH_1):NC_ESPI_IBL_CPU1_ALERT1_N
BD65 NC_SPI_S3M_CPU1_IO2_LVC1_R RSVD42 @S9S_MB_2U_LIB.S9S_MB_2U(SCH_1):NC_SPI_S3M_CPU1_IO2_LVC1_R
BE25 TP_I3C_MNG3_BMC_SW_SCL RSVD47 @S9S_MB_2U_LIB.S9S_MB_2U(SCH_1):TP_I3C_MNG3_BMC_SW_SCL
BE62 NC_ESPI_IBL_CPU1_ALERT0_N RSVD48 @S9S_MB_2U_LIB.S9S_MB_2U(SCH_1):NC_ESPI_IBL_CPU1_ALERT0_N
BF65 NC_ESPI_IBL_CPU1_CS0_N RSVD50 @S9S_MB_2U_LIB.S9S_MB_2U(SCH_1):NC_ESPI_IBL_CPU1_CS0_N
BG62 NC_ESPI_IBL_CPU1_CLK RSVD52 @S9S_MB_2U_LIB.S9S_MB_2U(SCH_1):NC_ESPI_IBL_CPU1_CLK
BG64 NC_ESPI_IBL_CPU1_RESET_N RSVD53 @S9S_MB_2U_LIB.S9S_MB_2U(SCH_1):NC_ESPI_IBL_CPU1_RESET_N
BH63 NC_ESPI_IBL_CPU1_OE_N RSVD55 @S9S_MB_2U_LIB.S9S_MB_2U(SCH_1):NC_ESPI_IBL_CPU1_OE_N
BH65 NC_ESPI_IBL_CPU1_CS1_N RSVD56 @S9S_MB_2U_LIB.S9S_MB_2U(SCH_1):NC_ESPI_IBL_CPU1_CS1_N
BJ64 NC_ESPI_IBL_CPU1_IO1 RSVD58 @S9S_MB_2U_LIB.S9S_MB_2U(SCH_1):NC_ESPI_IBL_CPU1_IO1
BK63 NC_ESPI_IBL_CPU1_IO0 RSVD61 @S9S_MB_2U_LIB.S9S_MB_2U(SCH_1):NC_ESPI_IBL_CPU1_IO0
BM63 NC_ESPI_IBL_CPU1_IO3 RSVD64 @S9S_MB_2U_LIB.S9S_MB_2U(SCH_1):NC_ESPI_IBL_CPU1_IO3
CD65 TP_SGPIO_S3M_CPU1_GSXRST_N RSVD86 @S9S_MB_2U_LIB.S9S_MB_2U(SCH_1):TP_SGPIO_S3M_CPU1_GSXRST_N
CF61 PUD_PCH_BOOT_MODE_CPU1 TEST_6 @S9S_MB_2U_LIB.S9S_MB_2U(SCH_1):PUD_PCH_BOOT_MODE_CPU1
CF63 TP_SGPIO_S3M_CPU1_GSXCLK RSVD93 @S9S_MB_2U_LIB.S9S_MB_2U(SCH_1):TP_SGPIO_S3M_CPU1_GSXCLK
CF65 TP_SGPIO_S3M_CPU1_GSXDOUT RSVD94 @S9S_MB_2U_LIB.S9S_MB_2U(SCH_1):TP_SGPIO_S3M_CPU1_GSXDOUT
CH63 TP_SGPIO_S3M_CPU1_GSXDIN RSVD98 @S9S_MB_2U_LIB.S9S_MB_2U(SCH_1):TP_SGPIO_S3M_CPU1_GSXDIN
CH71 TP_PWRGD_S0_PWROK_CPU1_LVC1 RSVD100 @S9S_MB_2U_LIB.S9S_MB_2U(SCH_1):TP_PWRGD_S0_PWROK_CPU1_LVC1
CJ21 TP_CPU1_IBL_GRST_WARN_CPU1_N RSVD101 @S9S_MB_2U_LIB.S9S_MB_2U(SCH_1):TP_CPU1_IBL_GRST_WARN_CPU1_N
CJ23 TP_I2C_S3M_RTC_CPU1_SDA RSVD102 @S9S_MB_2U_LIB.S9S_MB_2U(SCH_1):TP_I2C_S3M_RTC_CPU1_SDA
CJ25 TP_I2C_S3M_RTC_CPU1_RST_N RSVD103 @S9S_MB_2U_LIB.S9S_MB_2U(SCH_1):TP_I2C_S3M_RTC_CPU1_RST_N
CJ66 TP_SGPIO_S3M_CPU1_GSXDLOAD RSVD105 @S9S_MB_2U_LIB.S9S_MB_2U(SCH_1):TP_SGPIO_S3M_CPU1_GSXDLOAD
AW70 FM_S3M_CPU1_LVC1_GPIO_4 RSVD25 @S9S_MB_2U_LIB.S9S_MB_2U(SCH_1):FM_S3M_CPU1_LVC1_GPIO_4
AY69 FM_S3M_CPU1_LVC1_GPIO_3 TEST_8 @S9S_MB_2U_LIB.S9S_MB_2U(SCH_1):FM_S3M_CPU1_LVC1_GPIO_3
AV69 FM_S3M_CPU1_LVC1_GPIO_2 TEST_7 @S9S_MB_2U_LIB.S9S_MB_2U(SCH_1):FM_S3M_CPU1_LVC1_GPIO_2
AV71 FM_S3M_CPU1_LVC1_GPIO_1 PARTITION_ID1 @S9S_MB_2U_LIB.S9S_MB_2U(SCH_1):FM_S3M_CPU1_LVC1_GPIO_1
BA70 FM_S3M_CPU1_LVC1_GPIO_0 PARTITION_ID0 @S9S_MB_2U_LIB.S9S_MB_2U(SCH_1):FM_S3M_CPU1_LVC1_GPIO_0
CE64 SMB_S3M_CPU1_SCL SMB_CLK @S9S_MB_2U_LIB.S9S_MB_2U(SCH_1):SMB_S3M_CPU1_SCL
CD63 SMB_S3M_CPU1_SDA SMB_DATA @S9S_MB_2U_LIB.S9S_MB_2U(SCH_1):SMB_S3M_CPU1_SDA
CJ64 PU_S3M_CPU1_CPLD_CONFD TEST_1 @S9S_MB_2U_LIB.S9S_MB_2U(SCH_1):PU_S3M_CPU1_CPLD_CONFD
CK65 FM_S3M_CPU1_CPLD_CONFIG_N TEST_2 @S9S_MB_2U_LIB.S9S_MB_2U(SCH_1):FM_S3M_CPU1_CPLD_CONFIG_N
CH65 PU_S3M_CPU1_CPLD_STATUS TEST_3 @S9S_MB_2U_LIB.S9S_MB_2U(SCH_1):PU_S3M_CPU1_CPLD_STATUS


DRAWING: @S9S_MB_2U_LIB.S9S_MB_2U(SCH_1):PAGE47 

SOCKET4677_AZIF0045P001C01CS-SA  I16  U1
BC23 TP_CPU1_IFST_DONE_LVC1_R RSVD37 @S9S_MB_2U_LIB.S9S_MB_2U(SCH_1):TP_CPU1_IFST_DONE_LVC1_R
BE23 TP_CPU1_IFST_KOT_LVC1_R RSVD46 @S9S_MB_2U_LIB.S9S_MB_2U(SCH_1):TP_CPU1_IFST_KOT_LVC1_R
BF24 TP_CPU1_IFST_TRIG_LVC1_R RSVD49 @S9S_MB_2U_LIB.S9S_MB_2U(SCH_1):TP_CPU1_IFST_TRIG_LVC1_R
BL23 DBP_CPU1_MBP0_GTL_R_N MBP0_N @S9S_MB_2U_LIB.S9S_MB_2U(SCH_1):DBP_CPU1_MBP0_GTL_R_N
BN25 DBP_CPU1_MBP1_GTL_R_N MBP1_N @S9S_MB_2U_LIB.S9S_MB_2U(SCH_1):DBP_CPU1_MBP1_GTL_R_N
BJ23 DBP_CPU1_HOOK8_MBP2_GTL_QS_R_N MBP2_N @S9S_MB_2U_LIB.S9S_MB_2U(SCH_1):DBP_CPU1_HOOK8_MBP2_GTL_QS_R_N
BK24 DBP_CPU1_HOOK9_MBP3_GTL_QS_R_N MBP3_N @S9S_MB_2U_LIB.S9S_MB_2U(SCH_1):DBP_CPU1_HOOK9_MBP3_GTL_QS_R_N
BD24 H_PMAX_TRIGGER_IO_CPU1 PMAX_TRIGGER_IO @S9S_MB_2U_LIB.S9S_MB_2U(SCH_1):H_PMAX_TRIGGER_IO_CPU1
BH22 H_CPU1_RMCA_LVC1_R_N RMCA_N @S9S_MB_2U_LIB.S9S_MB_2U(SCH_1):H_CPU1_RMCA_LVC1_R_N
AU58 NC_CPU1_DDR01_VIEWDIG0 RSVD10 @S9S_MB_2U_LIB.S9S_MB_2U(SCH_1):NC_CPU1_DDR01_VIEWDIG0
CE62 NC_CPU1_LGSSPARE3 RSVD90 @S9S_MB_2U_LIB.S9S_MB_2U(SCH_1):NC_CPU1_LGSSPARE3
CU62 NC_CPU1_LGSSPARE2 RSVD139 @S9S_MB_2U_LIB.S9S_MB_2U(SCH_1):NC_CPU1_LGSSPARE2
CN60 NC_CPU1_LGSSPARE1 RSVD125 @S9S_MB_2U_LIB.S9S_MB_2U(SCH_1):NC_CPU1_LGSSPARE1
CP61 NC_CPU1_LGSSPARE5 RSVD129 @S9S_MB_2U_LIB.S9S_MB_2U(SCH_1):NC_CPU1_LGSSPARE5
CR60 NC_CPU1_LGSSPARE0 RSVD134 @S9S_MB_2U_LIB.S9S_MB_2U(SCH_1):NC_CPU1_LGSSPARE0
CY24 NC_CPU1_DDR45_VIEWDIG0 RSVD151 @S9S_MB_2U_LIB.S9S_MB_2U(SCH_1):NC_CPU1_DDR45_VIEWDIG0
CY38 NC_CPU1_DDR45_VIEWDIG1 RSVD152 @S9S_MB_2U_LIB.S9S_MB_2U(SCH_1):NC_CPU1_DDR45_VIEWDIG1
CY49 NC_CPU1_DDR67_VIEWDIG1 RSVD153 @S9S_MB_2U_LIB.S9S_MB_2U(SCH_1):NC_CPU1_DDR67_VIEWDIG1
DA45 NC_CPU1_DDR67_VIEWDIG0 RSVD158 @S9S_MB_2U_LIB.S9S_MB_2U(SCH_1):NC_CPU1_DDR67_VIEWDIG0
 H12 TP_CPU1_A0_DEBUG_EN RSVD162 @S9S_MB_2U_LIB.S9S_MB_2U(SCH_1):TP_CPU1_A0_DEBUG_EN
AV32 NC_CPU1_DDR23_VIEWDIG0 RSVD16 @S9S_MB_2U_LIB.S9S_MB_2U(SCH_1):NC_CPU1_DDR23_VIEWDIG0
AV38 NC_CPU1_THERMADC RSVD17 @S9S_MB_2U_LIB.S9S_MB_2U(SCH_1):NC_CPU1_THERMADC
AV40 NC_CPU1_THERMADA RSVD18 @S9S_MB_2U_LIB.S9S_MB_2U(SCH_1):NC_CPU1_THERMADA
AU33 NC_CPU1_DDR23_VIEWDIG1  RSVD7 @S9S_MB_2U_LIB.S9S_MB_2U(SCH_1):NC_CPU1_DDR23_VIEWDIG1
AU56 NC_CPU1_DDR01_VIEWDIG1  RSVD9 @S9S_MB_2U_LIB.S9S_MB_2U(SCH_1):NC_CPU1_DDR01_VIEWDIG1
CC64 NC_CPU1_LGSSPARE4 RSVD81 @S9S_MB_2U_LIB.S9S_MB_2U(SCH_1):NC_CPU1_LGSSPARE4
BU11 VSENSE_PVCCD_HV_CPU1_DP VCCD_HV_SENSE @S9S_MB_2U_LIB.S9S_MB_2U(SCH_1):VSENSE_PVCCD_HV_CPU1_DP
AY85 VSENSE_PVCCFA_EHV_FIVRA_CPU1_DP VCCFA_EHV_FIVRA_SENSE @S9S_MB_2U_LIB.S9S_MB_2U(SCH_1):VSENSE_PVCCFA_EHV_FIVRA_CPU1_DP
AU11 VSENSE_PVCCFA_EHV_CPU1_DP VCCFA_EHV_SENSE @S9S_MB_2U_LIB.S9S_MB_2U(SCH_1):VSENSE_PVCCFA_EHV_CPU1_DP
CA11 VSENSE_PVCCINFAON_CPU1_DP VCCINFAON_SENSE @S9S_MB_2U_LIB.S9S_MB_2U(SCH_1):VSENSE_PVCCINFAON_CPU1_DP
BD87 VSENSE_PVCCIN_CPU1_DP VCCIN_SENSE @S9S_MB_2U_LIB.S9S_MB_2U(SCH_1):VSENSE_PVCCIN_CPU1_DP
BN11 VSENSE_PVCCD_HV_CPU1_DN VSS_VCCD_HV_SENSE @S9S_MB_2U_LIB.S9S_MB_2U(SCH_1):VSENSE_PVCCD_HV_CPU1_DN
AT85 VSENSE_PVCCFA_EHV_FIVRA_CPU1_DN VSS_VCCFA_EHV_FIVRA_SENSE @S9S_MB_2U_LIB.S9S_MB_2U(SCH_1):VSENSE_PVCCFA_EHV_FIVRA_CPU1_DN
BA11 VSENSE_PVCCFA_EHV_CPU1_DN VSS_VCCFA_EHV_SENSE @S9S_MB_2U_LIB.S9S_MB_2U(SCH_1):VSENSE_PVCCFA_EHV_CPU1_DN
CE11 VSENSE_PVCCINFAON_CPU1_DN VSS_VCCINFAON_SENSE @S9S_MB_2U_LIB.S9S_MB_2U(SCH_1):VSENSE_PVCCINFAON_CPU1_DN
BC90 VSENSE_PVCCIN_CPU1_DN VSS_VCCIN_SENSE @S9S_MB_2U_LIB.S9S_MB_2U(SCH_1):VSENSE_PVCCIN_CPU1_DN

Q_RES_0402LF-10,1%,1/16W,CHIP,A  I22  R54
   1 DBP_CPU1_HOOK9_MBP3_GTL_QS_R_N      A @S9S_MB_2U_LIB.S9S_MB_2U(SCH_1):DBP_CPU1_HOOK9_MBP3_GTL_QS_R_N
   2 DBP_CPU_HOOK9_MBP3_GTL_QS_N      B @S9S_MB_2U_LIB.S9S_MB_2U(SCH_1):DBP_CPU_HOOK9_MBP3_GTL_QS_N

Q_RES_0402LF-10,1%,1/16W,CHIP,A  I23  R53
   1 DBP_CPU1_HOOK8_MBP2_GTL_QS_R_N      A @S9S_MB_2U_LIB.S9S_MB_2U(SCH_1):DBP_CPU1_HOOK8_MBP2_GTL_QS_R_N
   2 DBP_CPU_HOOK8_MBP2_GTL_QS_N      B @S9S_MB_2U_LIB.S9S_MB_2U(SCH_1):DBP_CPU_HOOK8_MBP2_GTL_QS_N

Q_RES_0402LF-100,1%,1/16W,CHIPA  I24  R51
   1 DBP_CPU1_MBP0_GTL_R_N      A @S9S_MB_2U_LIB.S9S_MB_2U(SCH_1):DBP_CPU1_MBP0_GTL_R_N
   2 DBP_CPU_MBP0_GTL_N      B @S9S_MB_2U_LIB.S9S_MB_2U(SCH_1):DBP_CPU_MBP0_GTL_N

Q_RES_0402LF-100,1%,1/16W,CHIPA  I25  R52
   1 DBP_CPU1_MBP1_GTL_R_N      A @S9S_MB_2U_LIB.S9S_MB_2U(SCH_1):DBP_CPU1_MBP1_GTL_R_N
   2 DBP_CPU_MBP1_GTL_N      B @S9S_MB_2U_LIB.S9S_MB_2U(SCH_1):DBP_CPU_MBP1_GTL_N

Q_RES_0402LF-499,1%,1/16W,CHIPA  I34  R49
   1 PVNN_TERM_CPU1      A @S9S_MB_2U_LIB.S9S_MB_2U(SCH_1):PVNN_TERM_CPU1
   2 DBP_CPU_MBP0_GTL_N      B @S9S_MB_2U_LIB.S9S_MB_2U(SCH_1):DBP_CPU_MBP0_GTL_N

Q_RES_0402LF-499,1%,1/16W,CHIPA  I35  R50
   1 PVNN_TERM_CPU1      A @S9S_MB_2U_LIB.S9S_MB_2U(SCH_1):PVNN_TERM_CPU1
   2 DBP_CPU_MBP1_GTL_N      B @S9S_MB_2U_LIB.S9S_MB_2U(SCH_1):DBP_CPU_MBP1_GTL_N


DRAWING: @S9S_MB_2U_LIB.S9S_MB_2U(SCH_1):PAGE48 

SOCKET4677_AZIF0045P001C01CS-SA  I1  U1
AC78 NC_CPU1_HBM2_VIEWDIG0  RSVD0 @S9S_MB_2U_LIB.S9S_MB_2U(SCH_1):NC_CPU1_HBM2_VIEWDIG0
AD77 NC_CPU1_HBM2_VIEWDIG1  RSVD1 @S9S_MB_2U_LIB.S9S_MB_2U(SCH_1):NC_CPU1_HBM2_VIEWDIG1
CJ68 NC_CPU1_MDFI_DIE11_NS0 RSVD106 @S9S_MB_2U_LIB.S9S_MB_2U(SCH_1):NC_CPU1_MDFI_DIE11_NS0
CJ70 NC_CPU1_MDFI_DIE11_EW0 RSVD107 @S9S_MB_2U_LIB.S9S_MB_2U(SCH_1):NC_CPU1_MDFI_DIE11_EW0
CK67 NC_CPU1_MDFI_DIE11_NS1 RSVD112 @S9S_MB_2U_LIB.S9S_MB_2U(SCH_1):NC_CPU1_MDFI_DIE11_NS1
CR25 NC_CPU1_VIEWPIN_GNR2 RSVD133 @S9S_MB_2U_LIB.S9S_MB_2U(SCH_1):NC_CPU1_VIEWPIN_GNR2
CT26 NC_CPU1_VIEWPIN_GNR0 RSVD138 @S9S_MB_2U_LIB.S9S_MB_2U(SCH_1):NC_CPU1_VIEWPIN_GNR0
CW41 NC_CPU1_HBM1_VIEWDIG1 RSVD147 @S9S_MB_2U_LIB.S9S_MB_2U(SCH_1):NC_CPU1_HBM1_VIEWDIG1
CW58 NC_CPU1_VIEWPIN_GNR1 RSVD149 @S9S_MB_2U_LIB.S9S_MB_2U(SCH_1):NC_CPU1_VIEWPIN_GNR1
CY57 NC_CPU1_VIEWPIN_GNR3 RSVD154 @S9S_MB_2U_LIB.S9S_MB_2U(SCH_1):NC_CPU1_VIEWPIN_GNR3
EG17 NC_CPU1_HBM0_VIEWDIG1 RSVD160 @S9S_MB_2U_LIB.S9S_MB_2U(SCH_1):NC_CPU1_HBM0_VIEWDIG1
 U17 NC_CPU1_HBM0_VIEWDIG0 RSVD164 @S9S_MB_2U_LIB.S9S_MB_2U(SCH_1):NC_CPU1_HBM0_VIEWDIG0
 W17 NC_CPU1_HBM1_VIEWDIG0 RSVD165 @S9S_MB_2U_LIB.S9S_MB_2U(SCH_1):NC_CPU1_HBM1_VIEWDIG0
AV65 NC_CPU1_MDFI_DIE01_EW0 RSVD21 @S9S_MB_2U_LIB.S9S_MB_2U(SCH_1):NC_CPU1_MDFI_DIE01_EW0
AY24 NC_CPU1_SOC_SPARE0 RSVD26 @S9S_MB_2U_LIB.S9S_MB_2U(SCH_1):NC_CPU1_SOC_SPARE0
BA25 NC_CPU1_SOC_SPARE4 RSVD31 @S9S_MB_2U_LIB.S9S_MB_2U(SCH_1):NC_CPU1_SOC_SPARE4
BD71 NC_CPU1_MDFI_DIE01_NS1 RSVD43 @S9S_MB_2U_LIB.S9S_MB_2U(SCH_1):NC_CPU1_MDFI_DIE01_NS1
BE21 TP_CPU1_DIE_HVM_EN_LVC1 RSVD45 @S9S_MB_2U_LIB.S9S_MB_2U(SCH_1):TP_CPU1_DIE_HVM_EN_LVC1
BF71 NC_CPU1_MDFI_DIE01_NS0 RSVD51 @S9S_MB_2U_LIB.S9S_MB_2U(SCH_1):NC_CPU1_MDFI_DIE01_NS0
BG78 NC_CPU1_HBM3_VIEWDIG0 RSVD54 @S9S_MB_2U_LIB.S9S_MB_2U(SCH_1):NC_CPU1_HBM3_VIEWDIG0
BJ21 NC_CPU1_MDFI_DIE00_NS1 RSVD57 @S9S_MB_2U_LIB.S9S_MB_2U(SCH_1):NC_CPU1_MDFI_DIE00_NS1
BK22 NC_CPU1_MDFI_DIE00_NS0 RSVD60 @S9S_MB_2U_LIB.S9S_MB_2U(SCH_1):NC_CPU1_MDFI_DIE00_NS0
BL60 NC_CPU1_HBM3_VIEWDIG1 RSVD63 @S9S_MB_2U_LIB.S9S_MB_2U(SCH_1):NC_CPU1_HBM3_VIEWDIG1
BM65 NC_CPU1_SOC_SPARE1 RSVD65 @S9S_MB_2U_LIB.S9S_MB_2U(SCH_1):NC_CPU1_SOC_SPARE1
BP22 NC_CPU1_MDFI_DIE00_EW0 RSVD67 @S9S_MB_2U_LIB.S9S_MB_2U(SCH_1):NC_CPU1_MDFI_DIE00_EW0
BP65 NC_CPU1_SOC_SPARE5 RSVD68 @S9S_MB_2U_LIB.S9S_MB_2U(SCH_1):NC_CPU1_SOC_SPARE5
BR21 NC_CPU1_MDFI_DIE00_EW1 RSVD71 @S9S_MB_2U_LIB.S9S_MB_2U(SCH_1):NC_CPU1_MDFI_DIE00_EW1
CC66 NC_CPU1_MDFI_DIE01_EW1 RSVD82 @S9S_MB_2U_LIB.S9S_MB_2U(SCH_1):NC_CPU1_MDFI_DIE01_EW1
CD22 NC_CPU1_MDFI_DIE10_NS1 RSVD83 @S9S_MB_2U_LIB.S9S_MB_2U(SCH_1):NC_CPU1_MDFI_DIE10_NS1
CD26 NC_CPU1_MDFI_DIE10_EW0 RSVD84 @S9S_MB_2U_LIB.S9S_MB_2U(SCH_1):NC_CPU1_MDFI_DIE10_EW0
CD30 NC_CPU1_MDFI_DIE10_EW1 RSVD85 @S9S_MB_2U_LIB.S9S_MB_2U(SCH_1):NC_CPU1_MDFI_DIE10_EW1
CF22 NC_CPU1_MDFI_DIE10_NS0 RSVD92 @S9S_MB_2U_LIB.S9S_MB_2U(SCH_1):NC_CPU1_MDFI_DIE10_NS0
CH69 NC_CPU1_MDFI_DIE11_EW1 RSVD99 @S9S_MB_2U_LIB.S9S_MB_2U(SCH_1):NC_CPU1_MDFI_DIE11_EW1


DRAWING: @S9S_MB_2U_LIB.S9S_MB_2U(SCH_1):PAGE49 

SOCKET4677_AZIF0045P001C01CS-SA  I2  U1
CL70 TP_CPU1_SPARE12 RSVD119 @S9S_MB_2U_LIB.S9S_MB_2U(SCH_1):TP_CPU1_SPARE12
CL60 TP_CPU1_SPARE7 RSVD115 @S9S_MB_2U_LIB.S9S_MB_2U(SCH_1):TP_CPU1_SPARE7
CW43 TP_CPU1_SPARE6 RSVD148 @S9S_MB_2U_LIB.S9S_MB_2U(SCH_1):TP_CPU1_SPARE6
DA70 TP_CPU1_SPARE4 RSVD159 @S9S_MB_2U_LIB.S9S_MB_2U(SCH_1):TP_CPU1_SPARE4
BD77 TP_CPU1_SPARE13 RSVD44 @S9S_MB_2U_LIB.S9S_MB_2U(SCH_1):TP_CPU1_SPARE13
CH61 TP_CPU1_SPARE9 RSVD97 @S9S_MB_2U_LIB.S9S_MB_2U(SCH_1):TP_CPU1_SPARE9
AU52 TP_CPU1_SPARE5  RSVD8 @S9S_MB_2U_LIB.S9S_MB_2U(SCH_1):TP_CPU1_SPARE5
CD69 TP_CPU1_SPARE11 RSVD87 @S9S_MB_2U_LIB.S9S_MB_2U(SCH_1):TP_CPU1_SPARE11
CK61 TP_CPU1_SPARE8 RSVD111 @S9S_MB_2U_LIB.S9S_MB_2U(SCH_1):TP_CPU1_SPARE8
CG60 TP_CPU1_SPARE10 RSVD95 @S9S_MB_2U_LIB.S9S_MB_2U(SCH_1):TP_CPU1_SPARE10
 J13 TP_CPU1_PPD RSVD163 @S9S_MB_2U_LIB.S9S_MB_2U(SCH_1):TP_CPU1_PPD


DRAWING: @S9S_MB_2U_LIB.S9S_MB_2U(SCH_1):PAGE50 

SOCKET4677_AZIF0045P001C01CS-SA  I23  U1
BP30 TP_TRC_CPU1_PTI<15> PTI_DIE0015 @S9S_MB_2U_LIB.S9S_MB_2U(SCH_1):TP_TRC_CPU1_PTI(15)
BN29 TP_TRC_CPU1_PTI<14> PTI_DIE0014 @S9S_MB_2U_LIB.S9S_MB_2U(SCH_1):TP_TRC_CPU1_PTI(14)
BP28 TP_TRC_CPU1_PTI<13> PTI_DIE0013 @S9S_MB_2U_LIB.S9S_MB_2U(SCH_1):TP_TRC_CPU1_PTI(13)
BN27 TP_TRC_CPU1_PTI<12> PTI_DIE0012 @S9S_MB_2U_LIB.S9S_MB_2U(SCH_1):TP_TRC_CPU1_PTI(12)
BT30 TP_TRC_CPU1_PTI<11> PTI_DIE0011 @S9S_MB_2U_LIB.S9S_MB_2U(SCH_1):TP_TRC_CPU1_PTI(11)
BU29 TP_TRC_CPU1_PTI<10> PTI_DIE0010 @S9S_MB_2U_LIB.S9S_MB_2U(SCH_1):TP_TRC_CPU1_PTI(10)
BT28 TP_TRC_CPU1_PTI<9> PTI_DIE009 @S9S_MB_2U_LIB.S9S_MB_2U(SCH_1):TP_TRC_CPU1_PTI(9)
BU27 TP_TRC_CPU1_PTI<8> PTI_DIE008 @S9S_MB_2U_LIB.S9S_MB_2U(SCH_1):TP_TRC_CPU1_PTI(8)
BV28 TP_TRC_CPU1_PTI<7> PTI_DIE007 @S9S_MB_2U_LIB.S9S_MB_2U(SCH_1):TP_TRC_CPU1_PTI(7)
CA27 TP_TRC_CPU1_PTI<6> PTI_DIE006 @S9S_MB_2U_LIB.S9S_MB_2U(SCH_1):TP_TRC_CPU1_PTI(6)
BV30 TP_TRC_CPU1_PTI<5> PTI_DIE005 @S9S_MB_2U_LIB.S9S_MB_2U(SCH_1):TP_TRC_CPU1_PTI(5)
CA29 TP_TRC_CPU1_PTI<4> PTI_DIE004 @S9S_MB_2U_LIB.S9S_MB_2U(SCH_1):TP_TRC_CPU1_PTI(4)
BY30 TP_TRC_CPU1_PTI<3> PTI_DIE003 @S9S_MB_2U_LIB.S9S_MB_2U(SCH_1):TP_TRC_CPU1_PTI(3)
CC27 TP_TRC_CPU1_PTI<2> PTI_DIE002 @S9S_MB_2U_LIB.S9S_MB_2U(SCH_1):TP_TRC_CPU1_PTI(2)
CD28 TP_TRC_CPU1_PTI<1> PTI_DIE001 @S9S_MB_2U_LIB.S9S_MB_2U(SCH_1):TP_TRC_CPU1_PTI(1)
CC29 TP_TRC_CPU1_PTI<0> PTI_DIE000 @S9S_MB_2U_LIB.S9S_MB_2U(SCH_1):TP_TRC_CPU1_PTI(0)
CB30 TP_TRC_CPU1_PTI0_CLK PTI_DIE00_STB_0 @S9S_MB_2U_LIB.S9S_MB_2U(SCH_1):TP_TRC_CPU1_PTI0_CLK
BY28 TP_TRC_CPU1_PTI1_CLK PTI_DIE00_STB_1 @S9S_MB_2U_LIB.S9S_MB_2U(SCH_1):TP_TRC_CPU1_PTI1_CLK
BN66 TP_TRC_CPU1_PTI<31> PTI_DIE0115 @S9S_MB_2U_LIB.S9S_MB_2U(SCH_1):TP_TRC_CPU1_PTI(31)
BM67 TP_TRC_CPU1_PTI<30> PTI_DIE0114 @S9S_MB_2U_LIB.S9S_MB_2U(SCH_1):TP_TRC_CPU1_PTI(30)
BL66 TP_TRC_CPU1_PTI<29> PTI_DIE0113 @S9S_MB_2U_LIB.S9S_MB_2U(SCH_1):TP_TRC_CPU1_PTI(29)
BJ66 TP_TRC_CPU1_PTI<28> PTI_DIE0112 @S9S_MB_2U_LIB.S9S_MB_2U(SCH_1):TP_TRC_CPU1_PTI(28)
BG66 TP_TRC_CPU1_PTI<27> PTI_DIE0111 @S9S_MB_2U_LIB.S9S_MB_2U(SCH_1):TP_TRC_CPU1_PTI(27)
BN68 TP_TRC_CPU1_PTI<26> PTI_DIE0110 @S9S_MB_2U_LIB.S9S_MB_2U(SCH_1):TP_TRC_CPU1_PTI(26)
BM69 TP_TRC_CPU1_PTI<25> PTI_DIE019 @S9S_MB_2U_LIB.S9S_MB_2U(SCH_1):TP_TRC_CPU1_PTI(25)
BK69 TP_TRC_CPU1_PTI<24> PTI_DIE018 @S9S_MB_2U_LIB.S9S_MB_2U(SCH_1):TP_TRC_CPU1_PTI(24)
BD67 TP_TRC_CPU1_PTI<23> PTI_DIE017 @S9S_MB_2U_LIB.S9S_MB_2U(SCH_1):TP_TRC_CPU1_PTI(23)
BG68 TP_TRC_CPU1_PTI<22> PTI_DIE016 @S9S_MB_2U_LIB.S9S_MB_2U(SCH_1):TP_TRC_CPU1_PTI(22)
BC68 TP_TRC_CPU1_PTI<21> PTI_DIE015 @S9S_MB_2U_LIB.S9S_MB_2U(SCH_1):TP_TRC_CPU1_PTI(21)
BH69 TP_TRC_CPU1_PTI<20> PTI_DIE014 @S9S_MB_2U_LIB.S9S_MB_2U(SCH_1):TP_TRC_CPU1_PTI(20)
BF69 TP_TRC_CPU1_PTI<19> PTI_DIE013 @S9S_MB_2U_LIB.S9S_MB_2U(SCH_1):TP_TRC_CPU1_PTI(19)
BD69 TP_TRC_CPU1_PTI<18> PTI_DIE012 @S9S_MB_2U_LIB.S9S_MB_2U(SCH_1):TP_TRC_CPU1_PTI(18)
BE70 TP_TRC_CPU1_PTI<17> PTI_DIE011 @S9S_MB_2U_LIB.S9S_MB_2U(SCH_1):TP_TRC_CPU1_PTI(17)
BC70 TP_TRC_CPU1_PTI<16> PTI_DIE010 @S9S_MB_2U_LIB.S9S_MB_2U(SCH_1):TP_TRC_CPU1_PTI(16)
BF67 TP_TRC_CPU1_PTI2_CLK PTI_DIE01_STB_0 @S9S_MB_2U_LIB.S9S_MB_2U(SCH_1):TP_TRC_CPU1_PTI2_CLK
BK67 TP_TRC_CPU1_PTI3_CLK PTI_DIE01_STB_1 @S9S_MB_2U_LIB.S9S_MB_2U(SCH_1):TP_TRC_CPU1_PTI3_CLK
CL68 NC_CPU1_PE3_APROBE<0> RSVD118 @S9S_MB_2U_LIB.S9S_MB_2U(SCH_1):NC_CPU1_PE3_APROBE(0)
CM69 NC_CPU1_PE3_APROBE<1> RSVD122 @S9S_MB_2U_LIB.S9S_MB_2U(SCH_1):NC_CPU1_PE3_APROBE(1)
CP69 NC_CPU1_UPI3_APROBE<0> RSVD130 @S9S_MB_2U_LIB.S9S_MB_2U(SCH_1):NC_CPU1_UPI3_APROBE(0)
CR68 NC_CPU1_UPI3_APROBE<1> RSVD135 @S9S_MB_2U_LIB.S9S_MB_2U(SCH_1):NC_CPU1_UPI3_APROBE(1)
AU66 NC_CPU1_PE4_APROBE<1> RSVD13 @S9S_MB_2U_LIB.S9S_MB_2U(SCH_1):NC_CPU1_PE4_APROBE(1)
AU68 NC_CPU1_UPI2_APROBE<0> RSVD14 @S9S_MB_2U_LIB.S9S_MB_2U(SCH_1):NC_CPU1_UPI2_APROBE(0)
AN17 NC_CPU1_UPI0_APROBE<0>  RSVD2 @S9S_MB_2U_LIB.S9S_MB_2U(SCH_1):NC_CPU1_UPI0_APROBE(0)
AV67 NC_CPU1_PE4_APROBE<0> RSVD22 @S9S_MB_2U_LIB.S9S_MB_2U(SCH_1):NC_CPU1_PE4_APROBE(0)
AR17 NC_CPU1_UPI0_APROBE<1>  RSVD3 @S9S_MB_2U_LIB.S9S_MB_2U(SCH_1):NC_CPU1_UPI0_APROBE(1)
AT67 NC_CPU1_UPI2_APROBE<1>  RSVD5 @S9S_MB_2U_LIB.S9S_MB_2U(SCH_1):NC_CPU1_UPI2_APROBE(1)
BL21 NC_CPU1_PE0_APROBE<1> RSVD62 @S9S_MB_2U_LIB.S9S_MB_2U(SCH_1):NC_CPU1_PE0_APROBE(1)
BN21 NC_CPU1_PE0_APROBE<0> RSVD66 @S9S_MB_2U_LIB.S9S_MB_2U(SCH_1):NC_CPU1_PE0_APROBE(0)
BV22 NC_CPU1_UPI1_APROBE<0> RSVD73 @S9S_MB_2U_LIB.S9S_MB_2U(SCH_1):NC_CPU1_UPI1_APROBE(0)
BW21 NC_CPU1_DMI_APROBE<1> RSVD74 @S9S_MB_2U_LIB.S9S_MB_2U(SCH_1):NC_CPU1_DMI_APROBE(1)
BW23 NC_CPU1_PE2_APROBE<1> RSVD75 @S9S_MB_2U_LIB.S9S_MB_2U(SCH_1):NC_CPU1_PE2_APROBE(1)
CA21 NC_CPU1_DMI_APROBE<0> RSVD77 @S9S_MB_2U_LIB.S9S_MB_2U(SCH_1):NC_CPU1_DMI_APROBE(0)
CA23 NC_CPU1_UPI1_APROBE<1> RSVD78 @S9S_MB_2U_LIB.S9S_MB_2U(SCH_1):NC_CPU1_UPI1_APROBE(1)
CC21 NC_CPU1_PE1_APROBE<1> RSVD79 @S9S_MB_2U_LIB.S9S_MB_2U(SCH_1):NC_CPU1_PE1_APROBE(1)
CC23 NC_CPU1_PE2_APROBE<0> RSVD80 @S9S_MB_2U_LIB.S9S_MB_2U(SCH_1):NC_CPU1_PE2_APROBE(0)
CE21 NC_CPU1_PE1_APROBE<0> RSVD89 @S9S_MB_2U_LIB.S9S_MB_2U(SCH_1):NC_CPU1_PE1_APROBE(0)
BA23 PU_CPU1_UPI0_AC_COUPLING UPI0_AC_COUPLING @S9S_MB_2U_LIB.S9S_MB_2U(SCH_1):PU_CPU1_UPI0_AC_COUPLING
CW19 PU_CPU1_UPI1_AC_COUPLING UPI1_AC_COUPLING @S9S_MB_2U_LIB.S9S_MB_2U(SCH_1):PU_CPU1_UPI1_AC_COUPLING
BB65 PU_CPU1_UPI2_AC_COUPLING UPI2_AC_COUPLING @S9S_MB_2U_LIB.S9S_MB_2U(SCH_1):PU_CPU1_UPI2_AC_COUPLING
CK71 PU_CPU1_UPI3_AC_COUPLING UPI3_AC_COUPLING @S9S_MB_2U_LIB.S9S_MB_2U(SCH_1):PU_CPU1_UPI3_AC_COUPLING


DRAWING: @S9S_MB_2U_LIB.S9S_MB_2U(SCH_1):PAGE51 

SOCKET4677_AZIF0045P001C01CS-SA  I2  U1
AT49 M_A_CPU1_ALERT_N DDR0_ALERT_N @S9S_MB_2U_LIB.S9S_MB_2U(SCH_1):M_A_CPU1_ALERT_N
AU43 M_A_CPU1_SA_RSP<1> DDR0_A_RSP1 @S9S_MB_2U_LIB.S9S_MB_2U(SCH_1):M_A_CPU1_SA_RSP(1)
AT42 M_A_CPU1_SA_RSP<0> DDR0_A_RSP0 @S9S_MB_2U_LIB.S9S_MB_2U(SCH_1):M_A_CPU1_SA_RSP(0)
AV42 M_A_CPU1_SB_RSP<1> DDR0_B_RSP1 @S9S_MB_2U_LIB.S9S_MB_2U(SCH_1):M_A_CPU1_SB_RSP(1)
AV44 M_A_CPU1_SB_RSP<0> DDR0_B_RSP0 @S9S_MB_2U_LIB.S9S_MB_2U(SCH_1):M_A_CPU1_SB_RSP(0)
 G45 M_A_CPU1_CLK_DN<1> DDR0_CLK_DN1 @S9S_MB_2U_LIB.S9S_MB_2U(SCH_1):M_A_CPU1_CLK_DN(1)
 B44 M_A_CPU1_CLK_DN<0> DDR0_CLK_DN0 @S9S_MB_2U_LIB.S9S_MB_2U(SCH_1):M_A_CPU1_CLK_DN(0)
 E45 M_A_CPU1_CLK_DP<1> DDR0_CLK_DP1 @S9S_MB_2U_LIB.S9S_MB_2U(SCH_1):M_A_CPU1_CLK_DP(1)
 C43 M_A_CPU1_CLK_DP<0> DDR0_CLK_DP0 @S9S_MB_2U_LIB.S9S_MB_2U(SCH_1):M_A_CPU1_CLK_DP(0)
 C48 M_A_CPU1_SA_CA<6> DDR0_SA_CA6 @S9S_MB_2U_LIB.S9S_MB_2U(SCH_1):M_A_CPU1_SA_CA(6)
 E50 M_A_CPU1_SA_CA<5> DDR0_SA_CA5 @S9S_MB_2U_LIB.S9S_MB_2U(SCH_1):M_A_CPU1_SA_CA(5)
 C50 M_A_CPU1_SA_CA<4> DDR0_SA_CA4 @S9S_MB_2U_LIB.S9S_MB_2U(SCH_1):M_A_CPU1_SA_CA(4)
 F51 M_A_CPU1_SA_CA<3> DDR0_SA_CA3 @S9S_MB_2U_LIB.S9S_MB_2U(SCH_1):M_A_CPU1_SA_CA(3)
 B51 M_A_CPU1_SA_CA<2> DDR0_SA_CA2 @S9S_MB_2U_LIB.S9S_MB_2U(SCH_1):M_A_CPU1_SA_CA(2)
 G52 M_A_CPU1_SA_CA<1> DDR0_SA_CA1 @S9S_MB_2U_LIB.S9S_MB_2U(SCH_1):M_A_CPU1_SA_CA(1)
 A52 M_A_CPU1_SA_CA<0> DDR0_SA_CA0 @S9S_MB_2U_LIB.S9S_MB_2U(SCH_1):M_A_CPU1_SA_CA(0)
 F53 M_A_CPU1_SA_CS_N<3> DDR0_SA_CS_N3 @S9S_MB_2U_LIB.S9S_MB_2U(SCH_1):M_A_CPU1_SA_CS_N(3)
 E54 M_A_CPU1_SA_CS_N<2> DDR0_SA_CS_N2 @S9S_MB_2U_LIB.S9S_MB_2U(SCH_1):M_A_CPU1_SA_CS_N(2)
 B53 M_A_CPU1_SA_CS_N<1> DDR0_SA_CS_N1 @S9S_MB_2U_LIB.S9S_MB_2U(SCH_1):M_A_CPU1_SA_CS_N(1)
 C54 M_A_CPU1_SA_CS_N<0> DDR0_SA_CS_N0 @S9S_MB_2U_LIB.S9S_MB_2U(SCH_1):M_A_CPU1_SA_CS_N(0)
 E62 M_A_CPU1_SA_DQ<31> DDR0_SA_DQ31 @S9S_MB_2U_LIB.S9S_MB_2U(SCH_1):M_A_CPU1_SA_DQ(31)
 F63 M_A_CPU1_SA_DQ<30> DDR0_SA_DQ30 @S9S_MB_2U_LIB.S9S_MB_2U(SCH_1):M_A_CPU1_SA_DQ(30)
 C62 M_A_CPU1_SA_DQ<29> DDR0_SA_DQ29 @S9S_MB_2U_LIB.S9S_MB_2U(SCH_1):M_A_CPU1_SA_DQ(29)
 B63 M_A_CPU1_SA_DQ<28> DDR0_SA_DQ28 @S9S_MB_2U_LIB.S9S_MB_2U(SCH_1):M_A_CPU1_SA_DQ(28)
 F65 M_A_CPU1_SA_DQ<27> DDR0_SA_DQ27 @S9S_MB_2U_LIB.S9S_MB_2U(SCH_1):M_A_CPU1_SA_DQ(27)
 E66 M_A_CPU1_SA_DQ<26> DDR0_SA_DQ26 @S9S_MB_2U_LIB.S9S_MB_2U(SCH_1):M_A_CPU1_SA_DQ(26)
 B65 M_A_CPU1_SA_DQ<25> DDR0_SA_DQ25 @S9S_MB_2U_LIB.S9S_MB_2U(SCH_1):M_A_CPU1_SA_DQ(25)
 C66 M_A_CPU1_SA_DQ<24> DDR0_SA_DQ24 @S9S_MB_2U_LIB.S9S_MB_2U(SCH_1):M_A_CPU1_SA_DQ(24)
 E68 M_A_CPU1_SA_DQ<23> DDR0_SA_DQ23 @S9S_MB_2U_LIB.S9S_MB_2U(SCH_1):M_A_CPU1_SA_DQ(23)
 F69 M_A_CPU1_SA_DQ<22> DDR0_SA_DQ22 @S9S_MB_2U_LIB.S9S_MB_2U(SCH_1):M_A_CPU1_SA_DQ(22)
 C68 M_A_CPU1_SA_DQ<21> DDR0_SA_DQ21 @S9S_MB_2U_LIB.S9S_MB_2U(SCH_1):M_A_CPU1_SA_DQ(21)
 B69 M_A_CPU1_SA_DQ<20> DDR0_SA_DQ20 @S9S_MB_2U_LIB.S9S_MB_2U(SCH_1):M_A_CPU1_SA_DQ(20)
 F71 M_A_CPU1_SA_DQ<19> DDR0_SA_DQ19 @S9S_MB_2U_LIB.S9S_MB_2U(SCH_1):M_A_CPU1_SA_DQ(19)
 D73 M_A_CPU1_SA_DQ<18> DDR0_SA_DQ18 @S9S_MB_2U_LIB.S9S_MB_2U(SCH_1):M_A_CPU1_SA_DQ(18)
 E72 M_A_CPU1_SA_DQ<17> DDR0_SA_DQ17 @S9S_MB_2U_LIB.S9S_MB_2U(SCH_1):M_A_CPU1_SA_DQ(17)
 B73 M_A_CPU1_SA_DQ<16> DDR0_SA_DQ16 @S9S_MB_2U_LIB.S9S_MB_2U(SCH_1):M_A_CPU1_SA_DQ(16)
 M65 M_A_CPU1_SA_DQ<15> DDR0_SA_DQ15 @S9S_MB_2U_LIB.S9S_MB_2U(SCH_1):M_A_CPU1_SA_DQ(15)
 N66 M_A_CPU1_SA_DQ<14> DDR0_SA_DQ14 @S9S_MB_2U_LIB.S9S_MB_2U(SCH_1):M_A_CPU1_SA_DQ(14)
 K65 M_A_CPU1_SA_DQ<13> DDR0_SA_DQ13 @S9S_MB_2U_LIB.S9S_MB_2U(SCH_1):M_A_CPU1_SA_DQ(13)
 J66 M_A_CPU1_SA_DQ<12> DDR0_SA_DQ12 @S9S_MB_2U_LIB.S9S_MB_2U(SCH_1):M_A_CPU1_SA_DQ(12)
 N68 M_A_CPU1_SA_DQ<11> DDR0_SA_DQ11 @S9S_MB_2U_LIB.S9S_MB_2U(SCH_1):M_A_CPU1_SA_DQ(11)
 M69 M_A_CPU1_SA_DQ<10> DDR0_SA_DQ10 @S9S_MB_2U_LIB.S9S_MB_2U(SCH_1):M_A_CPU1_SA_DQ(10)
 J68 M_A_CPU1_SA_DQ<9> DDR0_SA_DQ9 @S9S_MB_2U_LIB.S9S_MB_2U(SCH_1):M_A_CPU1_SA_DQ(9)
 K69 M_A_CPU1_SA_DQ<8> DDR0_SA_DQ8 @S9S_MB_2U_LIB.S9S_MB_2U(SCH_1):M_A_CPU1_SA_DQ(8)
 F75 M_A_CPU1_SA_DQ<7> DDR0_SA_DQ7 @S9S_MB_2U_LIB.S9S_MB_2U(SCH_1):M_A_CPU1_SA_DQ(7)
 G76 M_A_CPU1_SA_DQ<6> DDR0_SA_DQ6 @S9S_MB_2U_LIB.S9S_MB_2U(SCH_1):M_A_CPU1_SA_DQ(6)
 D75 M_A_CPU1_SA_DQ<5> DDR0_SA_DQ5 @S9S_MB_2U_LIB.S9S_MB_2U(SCH_1):M_A_CPU1_SA_DQ(5)
 C76 M_A_CPU1_SA_DQ<4> DDR0_SA_DQ4 @S9S_MB_2U_LIB.S9S_MB_2U(SCH_1):M_A_CPU1_SA_DQ(4)
 G78 M_A_CPU1_SA_DQ<3> DDR0_SA_DQ3 @S9S_MB_2U_LIB.S9S_MB_2U(SCH_1):M_A_CPU1_SA_DQ(3)
 M77 M_A_CPU1_SA_DQ<2> DDR0_SA_DQ2 @S9S_MB_2U_LIB.S9S_MB_2U(SCH_1):M_A_CPU1_SA_DQ(2)
 B79 M_A_CPU1_SA_DQ<1> DDR0_SA_DQ1 @S9S_MB_2U_LIB.S9S_MB_2U(SCH_1):M_A_CPU1_SA_DQ(1)
 B81 M_A_CPU1_SA_DQ<0> DDR0_SA_DQ0 @S9S_MB_2U_LIB.S9S_MB_2U(SCH_1):M_A_CPU1_SA_DQ(0)
 G58 M_A_CPU1_SA_DQS_DN<9> DDR0_SA_DQS_DN9 @S9S_MB_2U_LIB.S9S_MB_2U(SCH_1):M_A_CPU1_SA_DQS_DN(9)
 G64 M_A_CPU1_SA_DQS_DN<8> DDR0_SA_DQS_DN8 @S9S_MB_2U_LIB.S9S_MB_2U(SCH_1):M_A_CPU1_SA_DQS_DN(8)
 G70 M_A_CPU1_SA_DQS_DN<7> DDR0_SA_DQS_DN7 @S9S_MB_2U_LIB.S9S_MB_2U(SCH_1):M_A_CPU1_SA_DQS_DN(7)
 P67 M_A_CPU1_SA_DQS_DN<6> DDR0_SA_DQS_DN6 @S9S_MB_2U_LIB.S9S_MB_2U(SCH_1):M_A_CPU1_SA_DQS_DN(6)
 H77 M_A_CPU1_SA_DQS_DN<5> DDR0_SA_DQS_DN5 @S9S_MB_2U_LIB.S9S_MB_2U(SCH_1):M_A_CPU1_SA_DQS_DN(5)
 A58 M_A_CPU1_SA_DQS_DN<4> DDR0_SA_DQS_DN4 @S9S_MB_2U_LIB.S9S_MB_2U(SCH_1):M_A_CPU1_SA_DQS_DN(4)
 A64 M_A_CPU1_SA_DQS_DN<3> DDR0_SA_DQS_DN3 @S9S_MB_2U_LIB.S9S_MB_2U(SCH_1):M_A_CPU1_SA_DQS_DN(3)
 B71 M_A_CPU1_SA_DQS_DN<2> DDR0_SA_DQS_DN2 @S9S_MB_2U_LIB.S9S_MB_2U(SCH_1):M_A_CPU1_SA_DQS_DN(2)
 H67 M_A_CPU1_SA_DQS_DN<1> DDR0_SA_DQS_DN1 @S9S_MB_2U_LIB.S9S_MB_2U(SCH_1):M_A_CPU1_SA_DQS_DN(1)
 B77 M_A_CPU1_SA_DQS_DN<0> DDR0_SA_DQS_DN0 @S9S_MB_2U_LIB.S9S_MB_2U(SCH_1):M_A_CPU1_SA_DQS_DN(0)
 E58 M_A_CPU1_SA_DQS_DP<9> DDR0_SA_DQS_DP9 @S9S_MB_2U_LIB.S9S_MB_2U(SCH_1):M_A_CPU1_SA_DQS_DP(9)
 E64 M_A_CPU1_SA_DQS_DP<8> DDR0_SA_DQS_DP8 @S9S_MB_2U_LIB.S9S_MB_2U(SCH_1):M_A_CPU1_SA_DQS_DP(8)
 E70 M_A_CPU1_SA_DQS_DP<7> DDR0_SA_DQS_DP7 @S9S_MB_2U_LIB.S9S_MB_2U(SCH_1):M_A_CPU1_SA_DQS_DP(7)
 M67 M_A_CPU1_SA_DQS_DP<6> DDR0_SA_DQS_DP6 @S9S_MB_2U_LIB.S9S_MB_2U(SCH_1):M_A_CPU1_SA_DQS_DP(6)
 F77 M_A_CPU1_SA_DQS_DP<5> DDR0_SA_DQS_DP5 @S9S_MB_2U_LIB.S9S_MB_2U(SCH_1):M_A_CPU1_SA_DQS_DP(5)
 C58 M_A_CPU1_SA_DQS_DP<4> DDR0_SA_DQS_DP4 @S9S_MB_2U_LIB.S9S_MB_2U(SCH_1):M_A_CPU1_SA_DQS_DP(4)
 C64 M_A_CPU1_SA_DQS_DP<3> DDR0_SA_DQS_DP3 @S9S_MB_2U_LIB.S9S_MB_2U(SCH_1):M_A_CPU1_SA_DQS_DP(3)
 C70 M_A_CPU1_SA_DQS_DP<2> DDR0_SA_DQS_DP2 @S9S_MB_2U_LIB.S9S_MB_2U(SCH_1):M_A_CPU1_SA_DQS_DP(2)
 K67 M_A_CPU1_SA_DQS_DP<1> DDR0_SA_DQS_DP1 @S9S_MB_2U_LIB.S9S_MB_2U(SCH_1):M_A_CPU1_SA_DQS_DP(1)
 D77 M_A_CPU1_SA_DQS_DP<0> DDR0_SA_DQS_DP0 @S9S_MB_2U_LIB.S9S_MB_2U(SCH_1):M_A_CPU1_SA_DQS_DP(0)
 E56 M_A_CPU1_SA_CB<7> DDR0_SA_ECC7 @S9S_MB_2U_LIB.S9S_MB_2U(SCH_1):M_A_CPU1_SA_CB(7)
 F57 M_A_CPU1_SA_CB<6> DDR0_SA_ECC6 @S9S_MB_2U_LIB.S9S_MB_2U(SCH_1):M_A_CPU1_SA_CB(6)
 C56 M_A_CPU1_SA_CB<5> DDR0_SA_ECC5 @S9S_MB_2U_LIB.S9S_MB_2U(SCH_1):M_A_CPU1_SA_CB(5)
 B57 M_A_CPU1_SA_CB<4> DDR0_SA_ECC4 @S9S_MB_2U_LIB.S9S_MB_2U(SCH_1):M_A_CPU1_SA_CB(4)
 F59 M_A_CPU1_SA_CB<3> DDR0_SA_ECC3 @S9S_MB_2U_LIB.S9S_MB_2U(SCH_1):M_A_CPU1_SA_CB(3)
 E60 M_A_CPU1_SA_CB<2> DDR0_SA_ECC2 @S9S_MB_2U_LIB.S9S_MB_2U(SCH_1):M_A_CPU1_SA_CB(2)
 B59 M_A_CPU1_SA_CB<1> DDR0_SA_ECC1 @S9S_MB_2U_LIB.S9S_MB_2U(SCH_1):M_A_CPU1_SA_CB(1)
 C60 M_A_CPU1_SA_CB<0> DDR0_SA_ECC0 @S9S_MB_2U_LIB.S9S_MB_2U(SCH_1):M_A_CPU1_SA_CB(0)
 E48 M_A_CPU1_SA_PAR DDR0_SA_PAR @S9S_MB_2U_LIB.S9S_MB_2U(SCH_1):M_A_CPU1_SA_PAR
 A39 M_A_CPU1_SB_CA<6> DDR0_SB_CA6 @S9S_MB_2U_LIB.S9S_MB_2U(SCH_1):M_A_CPU1_SB_CA(6)
 F40 M_A_CPU1_SB_CA<5> DDR0_SB_CA5 @S9S_MB_2U_LIB.S9S_MB_2U(SCH_1):M_A_CPU1_SB_CA(5)
 B40 M_A_CPU1_SB_CA<4> DDR0_SB_CA4 @S9S_MB_2U_LIB.S9S_MB_2U(SCH_1):M_A_CPU1_SB_CA(4)
 E41 M_A_CPU1_SB_CA<3> DDR0_SB_CA3 @S9S_MB_2U_LIB.S9S_MB_2U(SCH_1):M_A_CPU1_SB_CA(3)
 C41 M_A_CPU1_SB_CA<2> DDR0_SB_CA2 @S9S_MB_2U_LIB.S9S_MB_2U(SCH_1):M_A_CPU1_SB_CA(2)
 F44 M_A_CPU1_SB_CA<1> DDR0_SB_CA1 @S9S_MB_2U_LIB.S9S_MB_2U(SCH_1):M_A_CPU1_SB_CA(1)
 E43 M_A_CPU1_SB_CA<0> DDR0_SB_CA0 @S9S_MB_2U_LIB.S9S_MB_2U(SCH_1):M_A_CPU1_SB_CA(0)
 E37 M_A_CPU1_SB_CS_N<3> DDR0_SB_CS_N3 @S9S_MB_2U_LIB.S9S_MB_2U(SCH_1):M_A_CPU1_SB_CS_N(3)
 F38 M_A_CPU1_SB_CS_N<2> DDR0_SB_CS_N2 @S9S_MB_2U_LIB.S9S_MB_2U(SCH_1):M_A_CPU1_SB_CS_N(2)
 C37 M_A_CPU1_SB_CS_N<1> DDR0_SB_CS_N1 @S9S_MB_2U_LIB.S9S_MB_2U(SCH_1):M_A_CPU1_SB_CS_N(1)
 B38 M_A_CPU1_SB_CS_N<0> DDR0_SB_CS_N0 @S9S_MB_2U_LIB.S9S_MB_2U(SCH_1):M_A_CPU1_SB_CS_N(0)
  E7 M_A_CPU1_SB_DQ<31> DDR0_SB_DQ31 @S9S_MB_2U_LIB.S9S_MB_2U(SCH_1):M_A_CPU1_SB_DQ(31)
  F8 M_A_CPU1_SB_DQ<30> DDR0_SB_DQ30 @S9S_MB_2U_LIB.S9S_MB_2U(SCH_1):M_A_CPU1_SB_DQ(30)
  C7 M_A_CPU1_SB_DQ<29> DDR0_SB_DQ29 @S9S_MB_2U_LIB.S9S_MB_2U(SCH_1):M_A_CPU1_SB_DQ(29)
  B8 M_A_CPU1_SB_DQ<28> DDR0_SB_DQ28 @S9S_MB_2U_LIB.S9S_MB_2U(SCH_1):M_A_CPU1_SB_DQ(28)
 F10 M_A_CPU1_SB_DQ<27> DDR0_SB_DQ27 @S9S_MB_2U_LIB.S9S_MB_2U(SCH_1):M_A_CPU1_SB_DQ(27)
 E11 M_A_CPU1_SB_DQ<26> DDR0_SB_DQ26 @S9S_MB_2U_LIB.S9S_MB_2U(SCH_1):M_A_CPU1_SB_DQ(26)
 B10 M_A_CPU1_SB_DQ<25> DDR0_SB_DQ25 @S9S_MB_2U_LIB.S9S_MB_2U(SCH_1):M_A_CPU1_SB_DQ(25)
 C11 M_A_CPU1_SB_DQ<24> DDR0_SB_DQ24 @S9S_MB_2U_LIB.S9S_MB_2U(SCH_1):M_A_CPU1_SB_DQ(24)
 E19 M_A_CPU1_SB_DQ<23> DDR0_SB_DQ23 @S9S_MB_2U_LIB.S9S_MB_2U(SCH_1):M_A_CPU1_SB_DQ(23)
 F20 M_A_CPU1_SB_DQ<22> DDR0_SB_DQ22 @S9S_MB_2U_LIB.S9S_MB_2U(SCH_1):M_A_CPU1_SB_DQ(22)
 C19 M_A_CPU1_SB_DQ<21> DDR0_SB_DQ21 @S9S_MB_2U_LIB.S9S_MB_2U(SCH_1):M_A_CPU1_SB_DQ(21)
 B20 M_A_CPU1_SB_DQ<20> DDR0_SB_DQ20 @S9S_MB_2U_LIB.S9S_MB_2U(SCH_1):M_A_CPU1_SB_DQ(20)
 F22 M_A_CPU1_SB_DQ<19> DDR0_SB_DQ19 @S9S_MB_2U_LIB.S9S_MB_2U(SCH_1):M_A_CPU1_SB_DQ(19)
 E23 M_A_CPU1_SB_DQ<18> DDR0_SB_DQ18 @S9S_MB_2U_LIB.S9S_MB_2U(SCH_1):M_A_CPU1_SB_DQ(18)
 B22 M_A_CPU1_SB_DQ<17> DDR0_SB_DQ17 @S9S_MB_2U_LIB.S9S_MB_2U(SCH_1):M_A_CPU1_SB_DQ(17)
 C23 M_A_CPU1_SB_DQ<16> DDR0_SB_DQ16 @S9S_MB_2U_LIB.S9S_MB_2U(SCH_1):M_A_CPU1_SB_DQ(16)
 E25 M_A_CPU1_SB_DQ<15> DDR0_SB_DQ15 @S9S_MB_2U_LIB.S9S_MB_2U(SCH_1):M_A_CPU1_SB_DQ(15)
 F26 M_A_CPU1_SB_DQ<14> DDR0_SB_DQ14 @S9S_MB_2U_LIB.S9S_MB_2U(SCH_1):M_A_CPU1_SB_DQ(14)
 C25 M_A_CPU1_SB_DQ<13> DDR0_SB_DQ13 @S9S_MB_2U_LIB.S9S_MB_2U(SCH_1):M_A_CPU1_SB_DQ(13)
 B26 M_A_CPU1_SB_DQ<12> DDR0_SB_DQ12 @S9S_MB_2U_LIB.S9S_MB_2U(SCH_1):M_A_CPU1_SB_DQ(12)
 F28 M_A_CPU1_SB_DQ<11> DDR0_SB_DQ11 @S9S_MB_2U_LIB.S9S_MB_2U(SCH_1):M_A_CPU1_SB_DQ(11)
 E29 M_A_CPU1_SB_DQ<10> DDR0_SB_DQ10 @S9S_MB_2U_LIB.S9S_MB_2U(SCH_1):M_A_CPU1_SB_DQ(10)
 B28 M_A_CPU1_SB_DQ<9> DDR0_SB_DQ9 @S9S_MB_2U_LIB.S9S_MB_2U(SCH_1):M_A_CPU1_SB_DQ(9)
 C29 M_A_CPU1_SB_DQ<8> DDR0_SB_DQ8 @S9S_MB_2U_LIB.S9S_MB_2U(SCH_1):M_A_CPU1_SB_DQ(8)
 M28 M_A_CPU1_SB_DQ<7> DDR0_SB_DQ7 @S9S_MB_2U_LIB.S9S_MB_2U(SCH_1):M_A_CPU1_SB_DQ(7)
 N29 M_A_CPU1_SB_DQ<6> DDR0_SB_DQ6 @S9S_MB_2U_LIB.S9S_MB_2U(SCH_1):M_A_CPU1_SB_DQ(6)
 K28 M_A_CPU1_SB_DQ<5> DDR0_SB_DQ5 @S9S_MB_2U_LIB.S9S_MB_2U(SCH_1):M_A_CPU1_SB_DQ(5)
 J29 M_A_CPU1_SB_DQ<4> DDR0_SB_DQ4 @S9S_MB_2U_LIB.S9S_MB_2U(SCH_1):M_A_CPU1_SB_DQ(4)
 N31 M_A_CPU1_SB_DQ<3> DDR0_SB_DQ3 @S9S_MB_2U_LIB.S9S_MB_2U(SCH_1):M_A_CPU1_SB_DQ(3)
 M32 M_A_CPU1_SB_DQ<2> DDR0_SB_DQ2 @S9S_MB_2U_LIB.S9S_MB_2U(SCH_1):M_A_CPU1_SB_DQ(2)
 J31 M_A_CPU1_SB_DQ<1> DDR0_SB_DQ1 @S9S_MB_2U_LIB.S9S_MB_2U(SCH_1):M_A_CPU1_SB_DQ(1)
 K32 M_A_CPU1_SB_DQ<0> DDR0_SB_DQ0 @S9S_MB_2U_LIB.S9S_MB_2U(SCH_1):M_A_CPU1_SB_DQ(0)
 A33 M_A_CPU1_SB_DQS_DN<9> DDR0_SB_DQS_DN9 @S9S_MB_2U_LIB.S9S_MB_2U(SCH_1):M_A_CPU1_SB_DQS_DN(9)
  G9 M_A_CPU1_SB_DQS_DN<8> DDR0_SB_DQS_DN8 @S9S_MB_2U_LIB.S9S_MB_2U(SCH_1):M_A_CPU1_SB_DQS_DN(8)
 G21 M_A_CPU1_SB_DQS_DN<7> DDR0_SB_DQS_DN7 @S9S_MB_2U_LIB.S9S_MB_2U(SCH_1):M_A_CPU1_SB_DQS_DN(7)
 G27 M_A_CPU1_SB_DQS_DN<6> DDR0_SB_DQS_DN6 @S9S_MB_2U_LIB.S9S_MB_2U(SCH_1):M_A_CPU1_SB_DQS_DN(6)
 M30 M_A_CPU1_SB_DQS_DN<5> DDR0_SB_DQS_DN5 @S9S_MB_2U_LIB.S9S_MB_2U(SCH_1):M_A_CPU1_SB_DQS_DN(5)
 G33 M_A_CPU1_SB_DQS_DN<4> DDR0_SB_DQS_DN4 @S9S_MB_2U_LIB.S9S_MB_2U(SCH_1):M_A_CPU1_SB_DQS_DN(4)
  A9 M_A_CPU1_SB_DQS_DN<3> DDR0_SB_DQS_DN3 @S9S_MB_2U_LIB.S9S_MB_2U(SCH_1):M_A_CPU1_SB_DQS_DN(3)
 A21 M_A_CPU1_SB_DQS_DN<2> DDR0_SB_DQS_DN2 @S9S_MB_2U_LIB.S9S_MB_2U(SCH_1):M_A_CPU1_SB_DQS_DN(2)
 A27 M_A_CPU1_SB_DQS_DN<1> DDR0_SB_DQS_DN1 @S9S_MB_2U_LIB.S9S_MB_2U(SCH_1):M_A_CPU1_SB_DQS_DN(1)
 H30 M_A_CPU1_SB_DQS_DN<0> DDR0_SB_DQS_DN0 @S9S_MB_2U_LIB.S9S_MB_2U(SCH_1):M_A_CPU1_SB_DQS_DN(0)
 C33 M_A_CPU1_SB_DQS_DP<9> DDR0_SB_DQS_DP9 @S9S_MB_2U_LIB.S9S_MB_2U(SCH_1):M_A_CPU1_SB_DQS_DP(9)
  E9 M_A_CPU1_SB_DQS_DP<8> DDR0_SB_DQS_DP8 @S9S_MB_2U_LIB.S9S_MB_2U(SCH_1):M_A_CPU1_SB_DQS_DP(8)
 E21 M_A_CPU1_SB_DQS_DP<7> DDR0_SB_DQS_DP7 @S9S_MB_2U_LIB.S9S_MB_2U(SCH_1):M_A_CPU1_SB_DQS_DP(7)
 E27 M_A_CPU1_SB_DQS_DP<6> DDR0_SB_DQS_DP6 @S9S_MB_2U_LIB.S9S_MB_2U(SCH_1):M_A_CPU1_SB_DQS_DP(6)
 P30 M_A_CPU1_SB_DQS_DP<5> DDR0_SB_DQS_DP5 @S9S_MB_2U_LIB.S9S_MB_2U(SCH_1):M_A_CPU1_SB_DQS_DP(5)
 E33 M_A_CPU1_SB_DQS_DP<4> DDR0_SB_DQS_DP4 @S9S_MB_2U_LIB.S9S_MB_2U(SCH_1):M_A_CPU1_SB_DQS_DP(4)
  C9 M_A_CPU1_SB_DQS_DP<3> DDR0_SB_DQS_DP3 @S9S_MB_2U_LIB.S9S_MB_2U(SCH_1):M_A_CPU1_SB_DQS_DP(3)
 C21 M_A_CPU1_SB_DQS_DP<2> DDR0_SB_DQS_DP2 @S9S_MB_2U_LIB.S9S_MB_2U(SCH_1):M_A_CPU1_SB_DQS_DP(2)
 C27 M_A_CPU1_SB_DQS_DP<1> DDR0_SB_DQS_DP1 @S9S_MB_2U_LIB.S9S_MB_2U(SCH_1):M_A_CPU1_SB_DQS_DP(1)
 K30 M_A_CPU1_SB_DQS_DP<0> DDR0_SB_DQS_DP0 @S9S_MB_2U_LIB.S9S_MB_2U(SCH_1):M_A_CPU1_SB_DQS_DP(0)
 F34 M_A_CPU1_SB_CB<7> DDR0_SB_ECC7 @S9S_MB_2U_LIB.S9S_MB_2U(SCH_1):M_A_CPU1_SB_CB(7)
 E35 M_A_CPU1_SB_CB<6> DDR0_SB_ECC6 @S9S_MB_2U_LIB.S9S_MB_2U(SCH_1):M_A_CPU1_SB_CB(6)
 B34 M_A_CPU1_SB_CB<5> DDR0_SB_ECC5 @S9S_MB_2U_LIB.S9S_MB_2U(SCH_1):M_A_CPU1_SB_CB(5)
 C35 M_A_CPU1_SB_CB<4> DDR0_SB_ECC4 @S9S_MB_2U_LIB.S9S_MB_2U(SCH_1):M_A_CPU1_SB_CB(4)
 E31 M_A_CPU1_SB_CB<3> DDR0_SB_ECC3 @S9S_MB_2U_LIB.S9S_MB_2U(SCH_1):M_A_CPU1_SB_CB(3)
 F32 M_A_CPU1_SB_CB<2> DDR0_SB_ECC2 @S9S_MB_2U_LIB.S9S_MB_2U(SCH_1):M_A_CPU1_SB_CB(2)
 C31 M_A_CPU1_SB_CB<1> DDR0_SB_ECC1 @S9S_MB_2U_LIB.S9S_MB_2U(SCH_1):M_A_CPU1_SB_CB(1)
 B32 M_A_CPU1_SB_CB<0> DDR0_SB_ECC0 @S9S_MB_2U_LIB.S9S_MB_2U(SCH_1):M_A_CPU1_SB_CB(0)
 G39 M_A_CPU1_SB_PAR DDR0_SB_PAR @S9S_MB_2U_LIB.S9S_MB_2U(SCH_1):M_A_CPU1_SB_PAR


DRAWING: @S9S_MB_2U_LIB.S9S_MB_2U(SCH_1):PAGE52 

SOCKET4677_AZIF0045P001C01CS-SA  I91  U1
AV49 M_B_CPU1_ALERT_N DDR1_ALERT_N @S9S_MB_2U_LIB.S9S_MB_2U(SCH_1):M_B_CPU1_ALERT_N
AK47 M_B_CPU1_SA_RSP<1> DDR1_A_RSP1 @S9S_MB_2U_LIB.S9S_MB_2U(SCH_1):M_B_CPU1_SA_RSP(1)
AL48 M_B_CPU1_SA_RSP<0> DDR1_A_RSP0 @S9S_MB_2U_LIB.S9S_MB_2U(SCH_1):M_B_CPU1_SA_RSP(0)
AP47 M_B_CPU1_SB_RSP<1> DDR1_B_RSP1 @S9S_MB_2U_LIB.S9S_MB_2U(SCH_1):M_B_CPU1_SB_RSP(1)
AN48 M_B_CPU1_SB_RSP<0> DDR1_B_RSP0 @S9S_MB_2U_LIB.S9S_MB_2U(SCH_1):M_B_CPU1_SB_RSP(0)
 W45 M_B_CPU1_CLK_DN<1> DDR1_CLK_DN1 @S9S_MB_2U_LIB.S9S_MB_2U(SCH_1):M_B_CPU1_CLK_DN(1)
 R45 M_B_CPU1_CLK_DN<0> DDR1_CLK_DN0 @S9S_MB_2U_LIB.S9S_MB_2U(SCH_1):M_B_CPU1_CLK_DN(0)
AA45 M_B_CPU1_CLK_DP<1> DDR1_CLK_DP1 @S9S_MB_2U_LIB.S9S_MB_2U(SCH_1):M_B_CPU1_CLK_DP(1)
 U45 M_B_CPU1_CLK_DP<0> DDR1_CLK_DP0 @S9S_MB_2U_LIB.S9S_MB_2U(SCH_1):M_B_CPU1_CLK_DP(0)
 Y44 M_B_CPU1_SA_CA<6> DDR1_SA_CA6 @S9S_MB_2U_LIB.S9S_MB_2U(SCH_1):M_B_CPU1_SA_CA(6)
 M47 M_B_CPU1_SA_CA<5> DDR1_SA_CA5 @S9S_MB_2U_LIB.S9S_MB_2U(SCH_1):M_B_CPU1_SA_CA(5)
 K47 M_B_CPU1_SA_CA<4> DDR1_SA_CA4 @S9S_MB_2U_LIB.S9S_MB_2U(SCH_1):M_B_CPU1_SA_CA(4)
 N48 M_B_CPU1_SA_CA<3> DDR1_SA_CA3 @S9S_MB_2U_LIB.S9S_MB_2U(SCH_1):M_B_CPU1_SA_CA(3)
 J48 M_B_CPU1_SA_CA<2> DDR1_SA_CA2 @S9S_MB_2U_LIB.S9S_MB_2U(SCH_1):M_B_CPU1_SA_CA(2)
 P49 M_B_CPU1_SA_CA<1> DDR1_SA_CA1 @S9S_MB_2U_LIB.S9S_MB_2U(SCH_1):M_B_CPU1_SA_CA(1)
 H49 M_B_CPU1_SA_CA<0> DDR1_SA_CA0 @S9S_MB_2U_LIB.S9S_MB_2U(SCH_1):M_B_CPU1_SA_CA(0)
 N50 M_B_CPU1_SA_CS_N<3> DDR1_SA_CS_N3 @S9S_MB_2U_LIB.S9S_MB_2U(SCH_1):M_B_CPU1_SA_CS_N(3)
 M51 M_B_CPU1_SA_CS_N<2> DDR1_SA_CS_N2 @S9S_MB_2U_LIB.S9S_MB_2U(SCH_1):M_B_CPU1_SA_CS_N(2)
 J50 M_B_CPU1_SA_CS_N<1> DDR1_SA_CS_N1 @S9S_MB_2U_LIB.S9S_MB_2U(SCH_1):M_B_CPU1_SA_CS_N(1)
 K51 M_B_CPU1_SA_CS_N<0> DDR1_SA_CS_N0 @S9S_MB_2U_LIB.S9S_MB_2U(SCH_1):M_B_CPU1_SA_CS_N(0)
 W56 M_B_CPU1_SA_DQ<31> DDR1_SA_DQ31 @S9S_MB_2U_LIB.S9S_MB_2U(SCH_1):M_B_CPU1_SA_DQ(31)
 Y57 M_B_CPU1_SA_DQ<30> DDR1_SA_DQ30 @S9S_MB_2U_LIB.S9S_MB_2U(SCH_1):M_B_CPU1_SA_DQ(30)
 U56 M_B_CPU1_SA_DQ<29> DDR1_SA_DQ29 @S9S_MB_2U_LIB.S9S_MB_2U(SCH_1):M_B_CPU1_SA_DQ(29)
 T57 M_B_CPU1_SA_DQ<28> DDR1_SA_DQ28 @S9S_MB_2U_LIB.S9S_MB_2U(SCH_1):M_B_CPU1_SA_DQ(28)
 Y59 M_B_CPU1_SA_DQ<27> DDR1_SA_DQ27 @S9S_MB_2U_LIB.S9S_MB_2U(SCH_1):M_B_CPU1_SA_DQ(27)
 W60 M_B_CPU1_SA_DQ<26> DDR1_SA_DQ26 @S9S_MB_2U_LIB.S9S_MB_2U(SCH_1):M_B_CPU1_SA_DQ(26)
 T59 M_B_CPU1_SA_DQ<25> DDR1_SA_DQ25 @S9S_MB_2U_LIB.S9S_MB_2U(SCH_1):M_B_CPU1_SA_DQ(25)
 U60 M_B_CPU1_SA_DQ<24> DDR1_SA_DQ24 @S9S_MB_2U_LIB.S9S_MB_2U(SCH_1):M_B_CPU1_SA_DQ(24)
 M59 M_B_CPU1_SA_DQ<23> DDR1_SA_DQ23 @S9S_MB_2U_LIB.S9S_MB_2U(SCH_1):M_B_CPU1_SA_DQ(23)
 N60 M_B_CPU1_SA_DQ<22> DDR1_SA_DQ22 @S9S_MB_2U_LIB.S9S_MB_2U(SCH_1):M_B_CPU1_SA_DQ(22)
 K59 M_B_CPU1_SA_DQ<21> DDR1_SA_DQ21 @S9S_MB_2U_LIB.S9S_MB_2U(SCH_1):M_B_CPU1_SA_DQ(21)
 J60 M_B_CPU1_SA_DQ<20> DDR1_SA_DQ20 @S9S_MB_2U_LIB.S9S_MB_2U(SCH_1):M_B_CPU1_SA_DQ(20)
 N62 M_B_CPU1_SA_DQ<19> DDR1_SA_DQ19 @S9S_MB_2U_LIB.S9S_MB_2U(SCH_1):M_B_CPU1_SA_DQ(19)
 M63 M_B_CPU1_SA_DQ<18> DDR1_SA_DQ18 @S9S_MB_2U_LIB.S9S_MB_2U(SCH_1):M_B_CPU1_SA_DQ(18)
 J62 M_B_CPU1_SA_DQ<17> DDR1_SA_DQ17 @S9S_MB_2U_LIB.S9S_MB_2U(SCH_1):M_B_CPU1_SA_DQ(17)
 K63 M_B_CPU1_SA_DQ<16> DDR1_SA_DQ16 @S9S_MB_2U_LIB.S9S_MB_2U(SCH_1):M_B_CPU1_SA_DQ(16)
 W68 M_B_CPU1_SA_DQ<15> DDR1_SA_DQ15 @S9S_MB_2U_LIB.S9S_MB_2U(SCH_1):M_B_CPU1_SA_DQ(15)
 Y69 M_B_CPU1_SA_DQ<14> DDR1_SA_DQ14 @S9S_MB_2U_LIB.S9S_MB_2U(SCH_1):M_B_CPU1_SA_DQ(14)
 U68 M_B_CPU1_SA_DQ<13> DDR1_SA_DQ13 @S9S_MB_2U_LIB.S9S_MB_2U(SCH_1):M_B_CPU1_SA_DQ(13)
 T69 M_B_CPU1_SA_DQ<12> DDR1_SA_DQ12 @S9S_MB_2U_LIB.S9S_MB_2U(SCH_1):M_B_CPU1_SA_DQ(12)
 Y71 M_B_CPU1_SA_DQ<11> DDR1_SA_DQ11 @S9S_MB_2U_LIB.S9S_MB_2U(SCH_1):M_B_CPU1_SA_DQ(11)
 W72 M_B_CPU1_SA_DQ<10> DDR1_SA_DQ10 @S9S_MB_2U_LIB.S9S_MB_2U(SCH_1):M_B_CPU1_SA_DQ(10)
 T71 M_B_CPU1_SA_DQ<9> DDR1_SA_DQ9 @S9S_MB_2U_LIB.S9S_MB_2U(SCH_1):M_B_CPU1_SA_DQ(9)
 U72 M_B_CPU1_SA_DQ<8> DDR1_SA_DQ8 @S9S_MB_2U_LIB.S9S_MB_2U(SCH_1):M_B_CPU1_SA_DQ(8)
 M71 M_B_CPU1_SA_DQ<7> DDR1_SA_DQ7 @S9S_MB_2U_LIB.S9S_MB_2U(SCH_1):M_B_CPU1_SA_DQ(7)
 N72 M_B_CPU1_SA_DQ<6> DDR1_SA_DQ6 @S9S_MB_2U_LIB.S9S_MB_2U(SCH_1):M_B_CPU1_SA_DQ(6)
 K71 M_B_CPU1_SA_DQ<5> DDR1_SA_DQ5 @S9S_MB_2U_LIB.S9S_MB_2U(SCH_1):M_B_CPU1_SA_DQ(5)
 J72 M_B_CPU1_SA_DQ<4> DDR1_SA_DQ4 @S9S_MB_2U_LIB.S9S_MB_2U(SCH_1):M_B_CPU1_SA_DQ(4)
 N74 M_B_CPU1_SA_DQ<3> DDR1_SA_DQ3 @S9S_MB_2U_LIB.S9S_MB_2U(SCH_1):M_B_CPU1_SA_DQ(3)
 M75 M_B_CPU1_SA_DQ<2> DDR1_SA_DQ2 @S9S_MB_2U_LIB.S9S_MB_2U(SCH_1):M_B_CPU1_SA_DQ(2)
 J74 M_B_CPU1_SA_DQ<1> DDR1_SA_DQ1 @S9S_MB_2U_LIB.S9S_MB_2U(SCH_1):M_B_CPU1_SA_DQ(1)
 K75 M_B_CPU1_SA_DQ<0> DDR1_SA_DQ0 @S9S_MB_2U_LIB.S9S_MB_2U(SCH_1):M_B_CPU1_SA_DQ(0)
 M55 M_B_CPU1_SA_DQS_DN<9> DDR1_SA_DQS_DN9 @S9S_MB_2U_LIB.S9S_MB_2U(SCH_1):M_B_CPU1_SA_DQS_DN(9)
AA58 M_B_CPU1_SA_DQS_DN<8> DDR1_SA_DQS_DN8 @S9S_MB_2U_LIB.S9S_MB_2U(SCH_1):M_B_CPU1_SA_DQS_DN(8)
 M61 M_B_CPU1_SA_DQS_DN<7> DDR1_SA_DQS_DN7 @S9S_MB_2U_LIB.S9S_MB_2U(SCH_1):M_B_CPU1_SA_DQS_DN(7)
AA70 M_B_CPU1_SA_DQS_DN<6> DDR1_SA_DQS_DN6 @S9S_MB_2U_LIB.S9S_MB_2U(SCH_1):M_B_CPU1_SA_DQS_DN(6)
 M73 M_B_CPU1_SA_DQS_DN<5> DDR1_SA_DQS_DN5 @S9S_MB_2U_LIB.S9S_MB_2U(SCH_1):M_B_CPU1_SA_DQS_DN(5)
 H55 M_B_CPU1_SA_DQS_DN<4> DDR1_SA_DQS_DN4 @S9S_MB_2U_LIB.S9S_MB_2U(SCH_1):M_B_CPU1_SA_DQS_DN(4)
 R58 M_B_CPU1_SA_DQS_DN<3> DDR1_SA_DQS_DN3 @S9S_MB_2U_LIB.S9S_MB_2U(SCH_1):M_B_CPU1_SA_DQS_DN(3)
 H61 M_B_CPU1_SA_DQS_DN<2> DDR1_SA_DQS_DN2 @S9S_MB_2U_LIB.S9S_MB_2U(SCH_1):M_B_CPU1_SA_DQS_DN(2)
 R70 M_B_CPU1_SA_DQS_DN<1> DDR1_SA_DQS_DN1 @S9S_MB_2U_LIB.S9S_MB_2U(SCH_1):M_B_CPU1_SA_DQS_DN(1)
 H73 M_B_CPU1_SA_DQS_DN<0> DDR1_SA_DQS_DN0 @S9S_MB_2U_LIB.S9S_MB_2U(SCH_1):M_B_CPU1_SA_DQS_DN(0)
 P55 M_B_CPU1_SA_DQS_DP<9> DDR1_SA_DQS_DP9 @S9S_MB_2U_LIB.S9S_MB_2U(SCH_1):M_B_CPU1_SA_DQS_DP(9)
 W58 M_B_CPU1_SA_DQS_DP<8> DDR1_SA_DQS_DP8 @S9S_MB_2U_LIB.S9S_MB_2U(SCH_1):M_B_CPU1_SA_DQS_DP(8)
 P61 M_B_CPU1_SA_DQS_DP<7> DDR1_SA_DQS_DP7 @S9S_MB_2U_LIB.S9S_MB_2U(SCH_1):M_B_CPU1_SA_DQS_DP(7)
 W70 M_B_CPU1_SA_DQS_DP<6> DDR1_SA_DQS_DP6 @S9S_MB_2U_LIB.S9S_MB_2U(SCH_1):M_B_CPU1_SA_DQS_DP(6)
 P73 M_B_CPU1_SA_DQS_DP<5> DDR1_SA_DQS_DP5 @S9S_MB_2U_LIB.S9S_MB_2U(SCH_1):M_B_CPU1_SA_DQS_DP(5)
 K55 M_B_CPU1_SA_DQS_DP<4> DDR1_SA_DQS_DP4 @S9S_MB_2U_LIB.S9S_MB_2U(SCH_1):M_B_CPU1_SA_DQS_DP(4)
 U58 M_B_CPU1_SA_DQS_DP<3> DDR1_SA_DQS_DP3 @S9S_MB_2U_LIB.S9S_MB_2U(SCH_1):M_B_CPU1_SA_DQS_DP(3)
 K61 M_B_CPU1_SA_DQS_DP<2> DDR1_SA_DQS_DP2 @S9S_MB_2U_LIB.S9S_MB_2U(SCH_1):M_B_CPU1_SA_DQS_DP(2)
 U70 M_B_CPU1_SA_DQS_DP<1> DDR1_SA_DQS_DP1 @S9S_MB_2U_LIB.S9S_MB_2U(SCH_1):M_B_CPU1_SA_DQS_DP(1)
 K73 M_B_CPU1_SA_DQS_DP<0> DDR1_SA_DQS_DP0 @S9S_MB_2U_LIB.S9S_MB_2U(SCH_1):M_B_CPU1_SA_DQS_DP(0)
 M53 M_B_CPU1_SA_CB<7> DDR1_SA_ECC7 @S9S_MB_2U_LIB.S9S_MB_2U(SCH_1):M_B_CPU1_SA_CB(7)
 N54 M_B_CPU1_SA_CB<6> DDR1_SA_ECC6 @S9S_MB_2U_LIB.S9S_MB_2U(SCH_1):M_B_CPU1_SA_CB(6)
 K53 M_B_CPU1_SA_CB<5> DDR1_SA_ECC5 @S9S_MB_2U_LIB.S9S_MB_2U(SCH_1):M_B_CPU1_SA_CB(5)
 J54 M_B_CPU1_SA_CB<4> DDR1_SA_ECC4 @S9S_MB_2U_LIB.S9S_MB_2U(SCH_1):M_B_CPU1_SA_CB(4)
 N56 M_B_CPU1_SA_CB<3> DDR1_SA_ECC3 @S9S_MB_2U_LIB.S9S_MB_2U(SCH_1):M_B_CPU1_SA_CB(3)
 M57 M_B_CPU1_SA_CB<2> DDR1_SA_ECC2 @S9S_MB_2U_LIB.S9S_MB_2U(SCH_1):M_B_CPU1_SA_CB(2)
 J56 M_B_CPU1_SA_CB<1> DDR1_SA_ECC1 @S9S_MB_2U_LIB.S9S_MB_2U(SCH_1):M_B_CPU1_SA_CB(1)
 K57 M_B_CPU1_SA_CB<0> DDR1_SA_ECC0 @S9S_MB_2U_LIB.S9S_MB_2U(SCH_1):M_B_CPU1_SA_CB(0)
 W43 M_B_CPU1_SA_PAR DDR1_SA_PAR @S9S_MB_2U_LIB.S9S_MB_2U(SCH_1):M_B_CPU1_SA_PAR
 H42 M_B_CPU1_SB_CA<6> DDR1_SB_CA6 @S9S_MB_2U_LIB.S9S_MB_2U(SCH_1):M_B_CPU1_SB_CA(6)
 N43 M_B_CPU1_SB_CA<5> DDR1_SB_CA5 @S9S_MB_2U_LIB.S9S_MB_2U(SCH_1):M_B_CPU1_SB_CA(5)
 J43 M_B_CPU1_SB_CA<4> DDR1_SB_CA4 @S9S_MB_2U_LIB.S9S_MB_2U(SCH_1):M_B_CPU1_SB_CA(4)
 M44 M_B_CPU1_SB_CA<3> DDR1_SB_CA3 @S9S_MB_2U_LIB.S9S_MB_2U(SCH_1):M_B_CPU1_SB_CA(3)
 K44 M_B_CPU1_SB_CA<2> DDR1_SB_CA2 @S9S_MB_2U_LIB.S9S_MB_2U(SCH_1):M_B_CPU1_SB_CA(2)
 U43 M_B_CPU1_SB_CA<1> DDR1_SB_CA1 @S9S_MB_2U_LIB.S9S_MB_2U(SCH_1):M_B_CPU1_SB_CA(1)
 T44 M_B_CPU1_SB_CA<0> DDR1_SB_CA0 @S9S_MB_2U_LIB.S9S_MB_2U(SCH_1):M_B_CPU1_SB_CA(0)
 M40 M_B_CPU1_SB_CS_N<3> DDR1_SB_CS_N3 @S9S_MB_2U_LIB.S9S_MB_2U(SCH_1):M_B_CPU1_SB_CS_N(3)
 N41 M_B_CPU1_SB_CS_N<2> DDR1_SB_CS_N2 @S9S_MB_2U_LIB.S9S_MB_2U(SCH_1):M_B_CPU1_SB_CS_N(2)
 K40 M_B_CPU1_SB_CS_N<1> DDR1_SB_CS_N1 @S9S_MB_2U_LIB.S9S_MB_2U(SCH_1):M_B_CPU1_SB_CS_N(1)
 J41 M_B_CPU1_SB_CS_N<0> DDR1_SB_CS_N0 @S9S_MB_2U_LIB.S9S_MB_2U(SCH_1):M_B_CPU1_SB_CS_N(0)
 F14 M_B_CPU1_SB_DQ<31> DDR1_SB_DQ31 @S9S_MB_2U_LIB.S9S_MB_2U(SCH_1):M_B_CPU1_SB_DQ(31)
 B14 M_B_CPU1_SB_DQ<30> DDR1_SB_DQ30 @S9S_MB_2U_LIB.S9S_MB_2U(SCH_1):M_B_CPU1_SB_DQ(30)
 E13 M_B_CPU1_SB_DQ<29> DDR1_SB_DQ29 @S9S_MB_2U_LIB.S9S_MB_2U(SCH_1):M_B_CPU1_SB_DQ(29)
 C13 M_B_CPU1_SB_DQ<28> DDR1_SB_DQ28 @S9S_MB_2U_LIB.S9S_MB_2U(SCH_1):M_B_CPU1_SB_DQ(28)
 F16 M_B_CPU1_SB_DQ<27> DDR1_SB_DQ27 @S9S_MB_2U_LIB.S9S_MB_2U(SCH_1):M_B_CPU1_SB_DQ(27)
 E17 M_B_CPU1_SB_DQ<26> DDR1_SB_DQ26 @S9S_MB_2U_LIB.S9S_MB_2U(SCH_1):M_B_CPU1_SB_DQ(26)
 B16 M_B_CPU1_SB_DQ<25> DDR1_SB_DQ25 @S9S_MB_2U_LIB.S9S_MB_2U(SCH_1):M_B_CPU1_SB_DQ(25)
 C17 M_B_CPU1_SB_DQ<24> DDR1_SB_DQ24 @S9S_MB_2U_LIB.S9S_MB_2U(SCH_1):M_B_CPU1_SB_DQ(24)
 M16 M_B_CPU1_SB_DQ<23> DDR1_SB_DQ23 @S9S_MB_2U_LIB.S9S_MB_2U(SCH_1):M_B_CPU1_SB_DQ(23)
 N17 M_B_CPU1_SB_DQ<22> DDR1_SB_DQ22 @S9S_MB_2U_LIB.S9S_MB_2U(SCH_1):M_B_CPU1_SB_DQ(22)
 K16 M_B_CPU1_SB_DQ<21> DDR1_SB_DQ21 @S9S_MB_2U_LIB.S9S_MB_2U(SCH_1):M_B_CPU1_SB_DQ(21)
 J17 M_B_CPU1_SB_DQ<20> DDR1_SB_DQ20 @S9S_MB_2U_LIB.S9S_MB_2U(SCH_1):M_B_CPU1_SB_DQ(20)
 N19 M_B_CPU1_SB_DQ<19> DDR1_SB_DQ19 @S9S_MB_2U_LIB.S9S_MB_2U(SCH_1):M_B_CPU1_SB_DQ(19)
 M20 M_B_CPU1_SB_DQ<18> DDR1_SB_DQ18 @S9S_MB_2U_LIB.S9S_MB_2U(SCH_1):M_B_CPU1_SB_DQ(18)
 J19 M_B_CPU1_SB_DQ<17> DDR1_SB_DQ17 @S9S_MB_2U_LIB.S9S_MB_2U(SCH_1):M_B_CPU1_SB_DQ(17)
 K20 M_B_CPU1_SB_DQ<16> DDR1_SB_DQ16 @S9S_MB_2U_LIB.S9S_MB_2U(SCH_1):M_B_CPU1_SB_DQ(16)
 M22 M_B_CPU1_SB_DQ<15> DDR1_SB_DQ15 @S9S_MB_2U_LIB.S9S_MB_2U(SCH_1):M_B_CPU1_SB_DQ(15)
 N23 M_B_CPU1_SB_DQ<14> DDR1_SB_DQ14 @S9S_MB_2U_LIB.S9S_MB_2U(SCH_1):M_B_CPU1_SB_DQ(14)
 K22 M_B_CPU1_SB_DQ<13> DDR1_SB_DQ13 @S9S_MB_2U_LIB.S9S_MB_2U(SCH_1):M_B_CPU1_SB_DQ(13)
 J23 M_B_CPU1_SB_DQ<12> DDR1_SB_DQ12 @S9S_MB_2U_LIB.S9S_MB_2U(SCH_1):M_B_CPU1_SB_DQ(12)
 N25 M_B_CPU1_SB_DQ<11> DDR1_SB_DQ11 @S9S_MB_2U_LIB.S9S_MB_2U(SCH_1):M_B_CPU1_SB_DQ(11)
 M26 M_B_CPU1_SB_DQ<10> DDR1_SB_DQ10 @S9S_MB_2U_LIB.S9S_MB_2U(SCH_1):M_B_CPU1_SB_DQ(10)
 J25 M_B_CPU1_SB_DQ<9> DDR1_SB_DQ9 @S9S_MB_2U_LIB.S9S_MB_2U(SCH_1):M_B_CPU1_SB_DQ(9)
 K26 M_B_CPU1_SB_DQ<8> DDR1_SB_DQ8 @S9S_MB_2U_LIB.S9S_MB_2U(SCH_1):M_B_CPU1_SB_DQ(8)
 W25 M_B_CPU1_SB_DQ<7> DDR1_SB_DQ7 @S9S_MB_2U_LIB.S9S_MB_2U(SCH_1):M_B_CPU1_SB_DQ(7)
 Y26 M_B_CPU1_SB_DQ<6> DDR1_SB_DQ6 @S9S_MB_2U_LIB.S9S_MB_2U(SCH_1):M_B_CPU1_SB_DQ(6)
 U25 M_B_CPU1_SB_DQ<5> DDR1_SB_DQ5 @S9S_MB_2U_LIB.S9S_MB_2U(SCH_1):M_B_CPU1_SB_DQ(5)
 T26 M_B_CPU1_SB_DQ<4> DDR1_SB_DQ4 @S9S_MB_2U_LIB.S9S_MB_2U(SCH_1):M_B_CPU1_SB_DQ(4)
 Y28 M_B_CPU1_SB_DQ<3> DDR1_SB_DQ3 @S9S_MB_2U_LIB.S9S_MB_2U(SCH_1):M_B_CPU1_SB_DQ(3)
 W29 M_B_CPU1_SB_DQ<2> DDR1_SB_DQ2 @S9S_MB_2U_LIB.S9S_MB_2U(SCH_1):M_B_CPU1_SB_DQ(2)
 T28 M_B_CPU1_SB_DQ<1> DDR1_SB_DQ1 @S9S_MB_2U_LIB.S9S_MB_2U(SCH_1):M_B_CPU1_SB_DQ(1)
 U29 M_B_CPU1_SB_DQ<0> DDR1_SB_DQ0 @S9S_MB_2U_LIB.S9S_MB_2U(SCH_1):M_B_CPU1_SB_DQ(0)
 K36 M_B_CPU1_SB_DQS_DN<9> DDR1_SB_DQS_DN9 @S9S_MB_2U_LIB.S9S_MB_2U(SCH_1):M_B_CPU1_SB_DQS_DN(9)
 E15 M_B_CPU1_SB_DQS_DN<8> DDR1_SB_DQS_DN8 @S9S_MB_2U_LIB.S9S_MB_2U(SCH_1):M_B_CPU1_SB_DQS_DN(8)
 M18 M_B_CPU1_SB_DQS_DN<7> DDR1_SB_DQS_DN7 @S9S_MB_2U_LIB.S9S_MB_2U(SCH_1):M_B_CPU1_SB_DQS_DN(7)
 M24 M_B_CPU1_SB_DQS_DN<6> DDR1_SB_DQS_DN6 @S9S_MB_2U_LIB.S9S_MB_2U(SCH_1):M_B_CPU1_SB_DQS_DN(6)
 W27 M_B_CPU1_SB_DQS_DN<5> DDR1_SB_DQS_DN5 @S9S_MB_2U_LIB.S9S_MB_2U(SCH_1):M_B_CPU1_SB_DQS_DN(5)
 P36 M_B_CPU1_SB_DQS_DN<4> DDR1_SB_DQS_DN4 @S9S_MB_2U_LIB.S9S_MB_2U(SCH_1):M_B_CPU1_SB_DQS_DN(4)
 A15 M_B_CPU1_SB_DQS_DN<3> DDR1_SB_DQS_DN3 @S9S_MB_2U_LIB.S9S_MB_2U(SCH_1):M_B_CPU1_SB_DQS_DN(3)
 H18 M_B_CPU1_SB_DQS_DN<2> DDR1_SB_DQS_DN2 @S9S_MB_2U_LIB.S9S_MB_2U(SCH_1):M_B_CPU1_SB_DQS_DN(2)
 H24 M_B_CPU1_SB_DQS_DN<1> DDR1_SB_DQS_DN1 @S9S_MB_2U_LIB.S9S_MB_2U(SCH_1):M_B_CPU1_SB_DQS_DN(1)
 R27 M_B_CPU1_SB_DQS_DN<0> DDR1_SB_DQS_DN0 @S9S_MB_2U_LIB.S9S_MB_2U(SCH_1):M_B_CPU1_SB_DQS_DN(0)
 H36 M_B_CPU1_SB_DQS_DP<9> DDR1_SB_DQS_DP9 @S9S_MB_2U_LIB.S9S_MB_2U(SCH_1):M_B_CPU1_SB_DQS_DP(9)
 G15 M_B_CPU1_SB_DQS_DP<8> DDR1_SB_DQS_DP8 @S9S_MB_2U_LIB.S9S_MB_2U(SCH_1):M_B_CPU1_SB_DQS_DP(8)
 P18 M_B_CPU1_SB_DQS_DP<7> DDR1_SB_DQS_DP7 @S9S_MB_2U_LIB.S9S_MB_2U(SCH_1):M_B_CPU1_SB_DQS_DP(7)
 P24 M_B_CPU1_SB_DQS_DP<6> DDR1_SB_DQS_DP6 @S9S_MB_2U_LIB.S9S_MB_2U(SCH_1):M_B_CPU1_SB_DQS_DP(6)
AA27 M_B_CPU1_SB_DQS_DP<5> DDR1_SB_DQS_DP5 @S9S_MB_2U_LIB.S9S_MB_2U(SCH_1):M_B_CPU1_SB_DQS_DP(5)
 M36 M_B_CPU1_SB_DQS_DP<4> DDR1_SB_DQS_DP4 @S9S_MB_2U_LIB.S9S_MB_2U(SCH_1):M_B_CPU1_SB_DQS_DP(4)
 C15 M_B_CPU1_SB_DQS_DP<3> DDR1_SB_DQS_DP3 @S9S_MB_2U_LIB.S9S_MB_2U(SCH_1):M_B_CPU1_SB_DQS_DP(3)
 K18 M_B_CPU1_SB_DQS_DP<2> DDR1_SB_DQS_DP2 @S9S_MB_2U_LIB.S9S_MB_2U(SCH_1):M_B_CPU1_SB_DQS_DP(2)
 K24 M_B_CPU1_SB_DQS_DP<1> DDR1_SB_DQS_DP1 @S9S_MB_2U_LIB.S9S_MB_2U(SCH_1):M_B_CPU1_SB_DQS_DP(1)
 U27 M_B_CPU1_SB_DQS_DP<0> DDR1_SB_DQS_DP0 @S9S_MB_2U_LIB.S9S_MB_2U(SCH_1):M_B_CPU1_SB_DQS_DP(0)
 N37 M_B_CPU1_SB_CB<7> DDR1_SB_ECC7 @S9S_MB_2U_LIB.S9S_MB_2U(SCH_1):M_B_CPU1_SB_CB(7)
 M38 M_B_CPU1_SB_CB<6> DDR1_SB_ECC6 @S9S_MB_2U_LIB.S9S_MB_2U(SCH_1):M_B_CPU1_SB_CB(6)
 J37 M_B_CPU1_SB_CB<5> DDR1_SB_ECC5 @S9S_MB_2U_LIB.S9S_MB_2U(SCH_1):M_B_CPU1_SB_CB(5)
 K38 M_B_CPU1_SB_CB<4> DDR1_SB_ECC4 @S9S_MB_2U_LIB.S9S_MB_2U(SCH_1):M_B_CPU1_SB_CB(4)
 M34 M_B_CPU1_SB_CB<3> DDR1_SB_ECC3 @S9S_MB_2U_LIB.S9S_MB_2U(SCH_1):M_B_CPU1_SB_CB(3)
 N35 M_B_CPU1_SB_CB<2> DDR1_SB_ECC2 @S9S_MB_2U_LIB.S9S_MB_2U(SCH_1):M_B_CPU1_SB_CB(2)
 K34 M_B_CPU1_SB_CB<1> DDR1_SB_ECC1 @S9S_MB_2U_LIB.S9S_MB_2U(SCH_1):M_B_CPU1_SB_CB(1)
 J35 M_B_CPU1_SB_CB<0> DDR1_SB_ECC0 @S9S_MB_2U_LIB.S9S_MB_2U(SCH_1):M_B_CPU1_SB_CB(0)
 P42 M_B_CPU1_SB_PAR DDR1_SB_PAR @S9S_MB_2U_LIB.S9S_MB_2U(SCH_1):M_B_CPU1_SB_PAR


DRAWING: @S9S_MB_2U_LIB.S9S_MB_2U(SCH_1):PAGE53 

SOCKET4677_AZIF0045P001C01CS-SA  I91  U1
AT47 M_C_CPU1_ALERT_N DDR2_ALERT_N @S9S_MB_2U_LIB.S9S_MB_2U(SCH_1):M_C_CPU1_ALERT_N
AD47 M_C_CPU1_SA_RSP<1> DDR2_A_RSP1 @S9S_MB_2U_LIB.S9S_MB_2U(SCH_1):M_C_CPU1_SA_RSP(1)
AC48 M_C_CPU1_SA_RSP<0> DDR2_A_RSP0 @S9S_MB_2U_LIB.S9S_MB_2U(SCH_1):M_C_CPU1_SA_RSP(0)
AF47 M_C_CPU1_SB_RSP<1> DDR2_B_RSP1 @S9S_MB_2U_LIB.S9S_MB_2U(SCH_1):M_C_CPU1_SB_RSP(1)
AG48 M_C_CPU1_SB_RSP<0> DDR2_B_RSP0 @S9S_MB_2U_LIB.S9S_MB_2U(SCH_1):M_C_CPU1_SB_RSP(0)
AF49 M_C_CPU1_CLK_DN<1> DDR2_CLK_DN1 @S9S_MB_2U_LIB.S9S_MB_2U(SCH_1):M_C_CPU1_CLK_DN(1)
AB49 M_C_CPU1_CLK_DN<0> DDR2_CLK_DN0 @S9S_MB_2U_LIB.S9S_MB_2U(SCH_1):M_C_CPU1_CLK_DN(0)
AH49 M_C_CPU1_CLK_DP<1> DDR2_CLK_DP1 @S9S_MB_2U_LIB.S9S_MB_2U(SCH_1):M_C_CPU1_CLK_DP(1)
AD49 M_C_CPU1_CLK_DP<0> DDR2_CLK_DP0 @S9S_MB_2U_LIB.S9S_MB_2U(SCH_1):M_C_CPU1_CLK_DP(0)
 U48 M_C_CPU1_SA_CA<6> DDR2_SA_CA6 @S9S_MB_2U_LIB.S9S_MB_2U(SCH_1):M_C_CPU1_SA_CA(6)
 W50 M_C_CPU1_SA_CA<5> DDR2_SA_CA5 @S9S_MB_2U_LIB.S9S_MB_2U(SCH_1):M_C_CPU1_SA_CA(5)
 U50 M_C_CPU1_SA_CA<4> DDR2_SA_CA4 @S9S_MB_2U_LIB.S9S_MB_2U(SCH_1):M_C_CPU1_SA_CA(4)
 Y51 M_C_CPU1_SA_CA<3> DDR2_SA_CA3 @S9S_MB_2U_LIB.S9S_MB_2U(SCH_1):M_C_CPU1_SA_CA(3)
 T51 M_C_CPU1_SA_CA<2> DDR2_SA_CA2 @S9S_MB_2U_LIB.S9S_MB_2U(SCH_1):M_C_CPU1_SA_CA(2)
AA52 M_C_CPU1_SA_CA<1> DDR2_SA_CA1 @S9S_MB_2U_LIB.S9S_MB_2U(SCH_1):M_C_CPU1_SA_CA(1)
 R52 M_C_CPU1_SA_CA<0> DDR2_SA_CA0 @S9S_MB_2U_LIB.S9S_MB_2U(SCH_1):M_C_CPU1_SA_CA(0)
 Y53 M_C_CPU1_SA_CS_N<3> DDR2_SA_CS_N3 @S9S_MB_2U_LIB.S9S_MB_2U(SCH_1):M_C_CPU1_SA_CS_N(3)
 W54 M_C_CPU1_SA_CS_N<2> DDR2_SA_CS_N2 @S9S_MB_2U_LIB.S9S_MB_2U(SCH_1):M_C_CPU1_SA_CS_N(2)
 T53 M_C_CPU1_SA_CS_N<1> DDR2_SA_CS_N1 @S9S_MB_2U_LIB.S9S_MB_2U(SCH_1):M_C_CPU1_SA_CS_N(1)
 U54 M_C_CPU1_SA_CS_N<0> DDR2_SA_CS_N0 @S9S_MB_2U_LIB.S9S_MB_2U(SCH_1):M_C_CPU1_SA_CS_N(0)
AF59 M_C_CPU1_SA_DQ<31> DDR2_SA_DQ31 @S9S_MB_2U_LIB.S9S_MB_2U(SCH_1):M_C_CPU1_SA_DQ(31)
AG60 M_C_CPU1_SA_DQ<30> DDR2_SA_DQ30 @S9S_MB_2U_LIB.S9S_MB_2U(SCH_1):M_C_CPU1_SA_DQ(30)
AD59 M_C_CPU1_SA_DQ<29> DDR2_SA_DQ29 @S9S_MB_2U_LIB.S9S_MB_2U(SCH_1):M_C_CPU1_SA_DQ(29)
AC60 M_C_CPU1_SA_DQ<28> DDR2_SA_DQ28 @S9S_MB_2U_LIB.S9S_MB_2U(SCH_1):M_C_CPU1_SA_DQ(28)
AG62 M_C_CPU1_SA_DQ<27> DDR2_SA_DQ27 @S9S_MB_2U_LIB.S9S_MB_2U(SCH_1):M_C_CPU1_SA_DQ(27)
AF63 M_C_CPU1_SA_DQ<26> DDR2_SA_DQ26 @S9S_MB_2U_LIB.S9S_MB_2U(SCH_1):M_C_CPU1_SA_DQ(26)
AC62 M_C_CPU1_SA_DQ<25> DDR2_SA_DQ25 @S9S_MB_2U_LIB.S9S_MB_2U(SCH_1):M_C_CPU1_SA_DQ(25)
AD63 M_C_CPU1_SA_DQ<24> DDR2_SA_DQ24 @S9S_MB_2U_LIB.S9S_MB_2U(SCH_1):M_C_CPU1_SA_DQ(24)
 W62 M_C_CPU1_SA_DQ<23> DDR2_SA_DQ23 @S9S_MB_2U_LIB.S9S_MB_2U(SCH_1):M_C_CPU1_SA_DQ(23)
 Y63 M_C_CPU1_SA_DQ<22> DDR2_SA_DQ22 @S9S_MB_2U_LIB.S9S_MB_2U(SCH_1):M_C_CPU1_SA_DQ(22)
 U62 M_C_CPU1_SA_DQ<21> DDR2_SA_DQ21 @S9S_MB_2U_LIB.S9S_MB_2U(SCH_1):M_C_CPU1_SA_DQ(21)
 T63 M_C_CPU1_SA_DQ<20> DDR2_SA_DQ20 @S9S_MB_2U_LIB.S9S_MB_2U(SCH_1):M_C_CPU1_SA_DQ(20)
 Y65 M_C_CPU1_SA_DQ<19> DDR2_SA_DQ19 @S9S_MB_2U_LIB.S9S_MB_2U(SCH_1):M_C_CPU1_SA_DQ(19)
 W66 M_C_CPU1_SA_DQ<18> DDR2_SA_DQ18 @S9S_MB_2U_LIB.S9S_MB_2U(SCH_1):M_C_CPU1_SA_DQ(18)
 T65 M_C_CPU1_SA_DQ<17> DDR2_SA_DQ17 @S9S_MB_2U_LIB.S9S_MB_2U(SCH_1):M_C_CPU1_SA_DQ(17)
 U66 M_C_CPU1_SA_DQ<16> DDR2_SA_DQ16 @S9S_MB_2U_LIB.S9S_MB_2U(SCH_1):M_C_CPU1_SA_DQ(16)
AF65 M_C_CPU1_SA_DQ<15> DDR2_SA_DQ15 @S9S_MB_2U_LIB.S9S_MB_2U(SCH_1):M_C_CPU1_SA_DQ(15)
AG66 M_C_CPU1_SA_DQ<14> DDR2_SA_DQ14 @S9S_MB_2U_LIB.S9S_MB_2U(SCH_1):M_C_CPU1_SA_DQ(14)
AD65 M_C_CPU1_SA_DQ<13> DDR2_SA_DQ13 @S9S_MB_2U_LIB.S9S_MB_2U(SCH_1):M_C_CPU1_SA_DQ(13)
AC66 M_C_CPU1_SA_DQ<12> DDR2_SA_DQ12 @S9S_MB_2U_LIB.S9S_MB_2U(SCH_1):M_C_CPU1_SA_DQ(12)
AG68 M_C_CPU1_SA_DQ<11> DDR2_SA_DQ11 @S9S_MB_2U_LIB.S9S_MB_2U(SCH_1):M_C_CPU1_SA_DQ(11)
AF69 M_C_CPU1_SA_DQ<10> DDR2_SA_DQ10 @S9S_MB_2U_LIB.S9S_MB_2U(SCH_1):M_C_CPU1_SA_DQ(10)
AC68 M_C_CPU1_SA_DQ<9> DDR2_SA_DQ9 @S9S_MB_2U_LIB.S9S_MB_2U(SCH_1):M_C_CPU1_SA_DQ(9)
AD69 M_C_CPU1_SA_DQ<8> DDR2_SA_DQ8 @S9S_MB_2U_LIB.S9S_MB_2U(SCH_1):M_C_CPU1_SA_DQ(8)
 W74 M_C_CPU1_SA_DQ<7> DDR2_SA_DQ7 @S9S_MB_2U_LIB.S9S_MB_2U(SCH_1):M_C_CPU1_SA_DQ(7)
 Y75 M_C_CPU1_SA_DQ<6> DDR2_SA_DQ6 @S9S_MB_2U_LIB.S9S_MB_2U(SCH_1):M_C_CPU1_SA_DQ(6)
 U74 M_C_CPU1_SA_DQ<5> DDR2_SA_DQ5 @S9S_MB_2U_LIB.S9S_MB_2U(SCH_1):M_C_CPU1_SA_DQ(5)
 T75 M_C_CPU1_SA_DQ<4> DDR2_SA_DQ4 @S9S_MB_2U_LIB.S9S_MB_2U(SCH_1):M_C_CPU1_SA_DQ(4)
 Y77 M_C_CPU1_SA_DQ<3> DDR2_SA_DQ3 @S9S_MB_2U_LIB.S9S_MB_2U(SCH_1):M_C_CPU1_SA_DQ(3)
 W78 M_C_CPU1_SA_DQ<2> DDR2_SA_DQ2 @S9S_MB_2U_LIB.S9S_MB_2U(SCH_1):M_C_CPU1_SA_DQ(2)
 T77 M_C_CPU1_SA_DQ<1> DDR2_SA_DQ1 @S9S_MB_2U_LIB.S9S_MB_2U(SCH_1):M_C_CPU1_SA_DQ(1)
 U78 M_C_CPU1_SA_DQ<0> DDR2_SA_DQ0 @S9S_MB_2U_LIB.S9S_MB_2U(SCH_1):M_C_CPU1_SA_DQ(0)
AH55 M_C_CPU1_SA_DQS_DN<9> DDR2_SA_DQS_DN9 @S9S_MB_2U_LIB.S9S_MB_2U(SCH_1):M_C_CPU1_SA_DQS_DN(9)
AF61 M_C_CPU1_SA_DQS_DN<8> DDR2_SA_DQS_DN8 @S9S_MB_2U_LIB.S9S_MB_2U(SCH_1):M_C_CPU1_SA_DQS_DN(8)
AA64 M_C_CPU1_SA_DQS_DN<7> DDR2_SA_DQS_DN7 @S9S_MB_2U_LIB.S9S_MB_2U(SCH_1):M_C_CPU1_SA_DQS_DN(7)
AH67 M_C_CPU1_SA_DQS_DN<6> DDR2_SA_DQS_DN6 @S9S_MB_2U_LIB.S9S_MB_2U(SCH_1):M_C_CPU1_SA_DQS_DN(6)
 W76 M_C_CPU1_SA_DQS_DN<5> DDR2_SA_DQS_DN5 @S9S_MB_2U_LIB.S9S_MB_2U(SCH_1):M_C_CPU1_SA_DQS_DN(5)
AD55 M_C_CPU1_SA_DQS_DN<4> DDR2_SA_DQS_DN4 @S9S_MB_2U_LIB.S9S_MB_2U(SCH_1):M_C_CPU1_SA_DQS_DN(4)
AB61 M_C_CPU1_SA_DQS_DN<3> DDR2_SA_DQS_DN3 @S9S_MB_2U_LIB.S9S_MB_2U(SCH_1):M_C_CPU1_SA_DQS_DN(3)
 R64 M_C_CPU1_SA_DQS_DN<2> DDR2_SA_DQS_DN2 @S9S_MB_2U_LIB.S9S_MB_2U(SCH_1):M_C_CPU1_SA_DQS_DN(2)
AB67 M_C_CPU1_SA_DQS_DN<1> DDR2_SA_DQS_DN1 @S9S_MB_2U_LIB.S9S_MB_2U(SCH_1):M_C_CPU1_SA_DQS_DN(1)
 R76 M_C_CPU1_SA_DQS_DN<0> DDR2_SA_DQS_DN0 @S9S_MB_2U_LIB.S9S_MB_2U(SCH_1):M_C_CPU1_SA_DQS_DN(0)
AF55 M_C_CPU1_SA_DQS_DP<9> DDR2_SA_DQS_DP9 @S9S_MB_2U_LIB.S9S_MB_2U(SCH_1):M_C_CPU1_SA_DQS_DP(9)
AH61 M_C_CPU1_SA_DQS_DP<8> DDR2_SA_DQS_DP8 @S9S_MB_2U_LIB.S9S_MB_2U(SCH_1):M_C_CPU1_SA_DQS_DP(8)
 W64 M_C_CPU1_SA_DQS_DP<7> DDR2_SA_DQS_DP7 @S9S_MB_2U_LIB.S9S_MB_2U(SCH_1):M_C_CPU1_SA_DQS_DP(7)
AF67 M_C_CPU1_SA_DQS_DP<6> DDR2_SA_DQS_DP6 @S9S_MB_2U_LIB.S9S_MB_2U(SCH_1):M_C_CPU1_SA_DQS_DP(6)
AA76 M_C_CPU1_SA_DQS_DP<5> DDR2_SA_DQS_DP5 @S9S_MB_2U_LIB.S9S_MB_2U(SCH_1):M_C_CPU1_SA_DQS_DP(5)
AB55 M_C_CPU1_SA_DQS_DP<4> DDR2_SA_DQS_DP4 @S9S_MB_2U_LIB.S9S_MB_2U(SCH_1):M_C_CPU1_SA_DQS_DP(4)
AD61 M_C_CPU1_SA_DQS_DP<3> DDR2_SA_DQS_DP3 @S9S_MB_2U_LIB.S9S_MB_2U(SCH_1):M_C_CPU1_SA_DQS_DP(3)
 U64 M_C_CPU1_SA_DQS_DP<2> DDR2_SA_DQS_DP2 @S9S_MB_2U_LIB.S9S_MB_2U(SCH_1):M_C_CPU1_SA_DQS_DP(2)
AD67 M_C_CPU1_SA_DQS_DP<1> DDR2_SA_DQS_DP1 @S9S_MB_2U_LIB.S9S_MB_2U(SCH_1):M_C_CPU1_SA_DQS_DP(1)
 U76 M_C_CPU1_SA_DQS_DP<0> DDR2_SA_DQS_DP0 @S9S_MB_2U_LIB.S9S_MB_2U(SCH_1):M_C_CPU1_SA_DQS_DP(0)
AF53 M_C_CPU1_SA_CB<7> DDR2_SA_ECC7 @S9S_MB_2U_LIB.S9S_MB_2U(SCH_1):M_C_CPU1_SA_CB(7)
AG54 M_C_CPU1_SA_CB<6> DDR2_SA_ECC6 @S9S_MB_2U_LIB.S9S_MB_2U(SCH_1):M_C_CPU1_SA_CB(6)
AD53 M_C_CPU1_SA_CB<5> DDR2_SA_ECC5 @S9S_MB_2U_LIB.S9S_MB_2U(SCH_1):M_C_CPU1_SA_CB(5)
AC54 M_C_CPU1_SA_CB<4> DDR2_SA_ECC4 @S9S_MB_2U_LIB.S9S_MB_2U(SCH_1):M_C_CPU1_SA_CB(4)
AG56 M_C_CPU1_SA_CB<3> DDR2_SA_ECC3 @S9S_MB_2U_LIB.S9S_MB_2U(SCH_1):M_C_CPU1_SA_CB(3)
AF57 M_C_CPU1_SA_CB<2> DDR2_SA_ECC2 @S9S_MB_2U_LIB.S9S_MB_2U(SCH_1):M_C_CPU1_SA_CB(2)
AC56 M_C_CPU1_SA_CB<1> DDR2_SA_ECC1 @S9S_MB_2U_LIB.S9S_MB_2U(SCH_1):M_C_CPU1_SA_CB(1)
AD57 M_C_CPU1_SA_CB<0> DDR2_SA_ECC0 @S9S_MB_2U_LIB.S9S_MB_2U(SCH_1):M_C_CPU1_SA_CB(0)
 T47 M_C_CPU1_SA_PAR DDR2_SA_PAR @S9S_MB_2U_LIB.S9S_MB_2U(SCH_1):M_C_CPU1_SA_PAR
 R39 M_C_CPU1_SB_CA<6> DDR2_SB_CA6 @S9S_MB_2U_LIB.S9S_MB_2U(SCH_1):M_C_CPU1_SB_CA(6)
 Y40 M_C_CPU1_SB_CA<5> DDR2_SB_CA5 @S9S_MB_2U_LIB.S9S_MB_2U(SCH_1):M_C_CPU1_SB_CA(5)
 T40 M_C_CPU1_SB_CA<4> DDR2_SB_CA4 @S9S_MB_2U_LIB.S9S_MB_2U(SCH_1):M_C_CPU1_SB_CA(4)
 W41 M_C_CPU1_SB_CA<3> DDR2_SB_CA3 @S9S_MB_2U_LIB.S9S_MB_2U(SCH_1):M_C_CPU1_SB_CA(3)
 U41 M_C_CPU1_SB_CA<2> DDR2_SB_CA2 @S9S_MB_2U_LIB.S9S_MB_2U(SCH_1):M_C_CPU1_SB_CA(2)
 Y47 M_C_CPU1_SB_CA<1> DDR2_SB_CA1 @S9S_MB_2U_LIB.S9S_MB_2U(SCH_1):M_C_CPU1_SB_CA(1)
 W48 M_C_CPU1_SB_CA<0> DDR2_SB_CA0 @S9S_MB_2U_LIB.S9S_MB_2U(SCH_1):M_C_CPU1_SB_CA(0)
 W37 M_C_CPU1_SB_CS_N<3> DDR2_SB_CS_N3 @S9S_MB_2U_LIB.S9S_MB_2U(SCH_1):M_C_CPU1_SB_CS_N(3)
 Y38 M_C_CPU1_SB_CS_N<2> DDR2_SB_CS_N2 @S9S_MB_2U_LIB.S9S_MB_2U(SCH_1):M_C_CPU1_SB_CS_N(2)
 U37 M_C_CPU1_SB_CS_N<1> DDR2_SB_CS_N1 @S9S_MB_2U_LIB.S9S_MB_2U(SCH_1):M_C_CPU1_SB_CS_N(1)
 T38 M_C_CPU1_SB_CS_N<0> DDR2_SB_CS_N0 @S9S_MB_2U_LIB.S9S_MB_2U(SCH_1):M_C_CPU1_SB_CS_N(0)
AJ17 M_C_CPU1_SB_DQ<31> DDR2_SB_DQ31 @S9S_MB_2U_LIB.S9S_MB_2U(SCH_1):M_C_CPU1_SB_DQ(31)
AC17 M_C_CPU1_SB_DQ<30> DDR2_SB_DQ30 @S9S_MB_2U_LIB.S9S_MB_2U(SCH_1):M_C_CPU1_SB_DQ(30)
AG17 M_C_CPU1_SB_DQ<29> DDR2_SB_DQ29 @S9S_MB_2U_LIB.S9S_MB_2U(SCH_1):M_C_CPU1_SB_DQ(29)
AA17 M_C_CPU1_SB_DQ<28> DDR2_SB_DQ28 @S9S_MB_2U_LIB.S9S_MB_2U(SCH_1):M_C_CPU1_SB_DQ(28)
AG19 M_C_CPU1_SB_DQ<27> DDR2_SB_DQ27 @S9S_MB_2U_LIB.S9S_MB_2U(SCH_1):M_C_CPU1_SB_DQ(27)
AF20 M_C_CPU1_SB_DQ<26> DDR2_SB_DQ26 @S9S_MB_2U_LIB.S9S_MB_2U(SCH_1):M_C_CPU1_SB_DQ(26)
AC19 M_C_CPU1_SB_DQ<25> DDR2_SB_DQ25 @S9S_MB_2U_LIB.S9S_MB_2U(SCH_1):M_C_CPU1_SB_DQ(25)
AD20 M_C_CPU1_SB_DQ<24> DDR2_SB_DQ24 @S9S_MB_2U_LIB.S9S_MB_2U(SCH_1):M_C_CPU1_SB_DQ(24)
 W19 M_C_CPU1_SB_DQ<23> DDR2_SB_DQ23 @S9S_MB_2U_LIB.S9S_MB_2U(SCH_1):M_C_CPU1_SB_DQ(23)
 Y20 M_C_CPU1_SB_DQ<22> DDR2_SB_DQ22 @S9S_MB_2U_LIB.S9S_MB_2U(SCH_1):M_C_CPU1_SB_DQ(22)
 U19 M_C_CPU1_SB_DQ<21> DDR2_SB_DQ21 @S9S_MB_2U_LIB.S9S_MB_2U(SCH_1):M_C_CPU1_SB_DQ(21)
 T20 M_C_CPU1_SB_DQ<20> DDR2_SB_DQ20 @S9S_MB_2U_LIB.S9S_MB_2U(SCH_1):M_C_CPU1_SB_DQ(20)
 Y22 M_C_CPU1_SB_DQ<19> DDR2_SB_DQ19 @S9S_MB_2U_LIB.S9S_MB_2U(SCH_1):M_C_CPU1_SB_DQ(19)
 W23 M_C_CPU1_SB_DQ<18> DDR2_SB_DQ18 @S9S_MB_2U_LIB.S9S_MB_2U(SCH_1):M_C_CPU1_SB_DQ(18)
 T22 M_C_CPU1_SB_DQ<17> DDR2_SB_DQ17 @S9S_MB_2U_LIB.S9S_MB_2U(SCH_1):M_C_CPU1_SB_DQ(17)
 U23 M_C_CPU1_SB_DQ<16> DDR2_SB_DQ16 @S9S_MB_2U_LIB.S9S_MB_2U(SCH_1):M_C_CPU1_SB_DQ(16)
AF28 M_C_CPU1_SB_DQ<15> DDR2_SB_DQ15 @S9S_MB_2U_LIB.S9S_MB_2U(SCH_1):M_C_CPU1_SB_DQ(15)
AG29 M_C_CPU1_SB_DQ<14> DDR2_SB_DQ14 @S9S_MB_2U_LIB.S9S_MB_2U(SCH_1):M_C_CPU1_SB_DQ(14)
AD28 M_C_CPU1_SB_DQ<13> DDR2_SB_DQ13 @S9S_MB_2U_LIB.S9S_MB_2U(SCH_1):M_C_CPU1_SB_DQ(13)
AC29 M_C_CPU1_SB_DQ<12> DDR2_SB_DQ12 @S9S_MB_2U_LIB.S9S_MB_2U(SCH_1):M_C_CPU1_SB_DQ(12)
AG31 M_C_CPU1_SB_DQ<11> DDR2_SB_DQ11 @S9S_MB_2U_LIB.S9S_MB_2U(SCH_1):M_C_CPU1_SB_DQ(11)
AF32 M_C_CPU1_SB_DQ<10> DDR2_SB_DQ10 @S9S_MB_2U_LIB.S9S_MB_2U(SCH_1):M_C_CPU1_SB_DQ(10)
AC31 M_C_CPU1_SB_DQ<9> DDR2_SB_DQ9 @S9S_MB_2U_LIB.S9S_MB_2U(SCH_1):M_C_CPU1_SB_DQ(9)
AD32 M_C_CPU1_SB_DQ<8> DDR2_SB_DQ8 @S9S_MB_2U_LIB.S9S_MB_2U(SCH_1):M_C_CPU1_SB_DQ(8)
AF34 M_C_CPU1_SB_DQ<7> DDR2_SB_DQ7 @S9S_MB_2U_LIB.S9S_MB_2U(SCH_1):M_C_CPU1_SB_DQ(7)
AG35 M_C_CPU1_SB_DQ<6> DDR2_SB_DQ6 @S9S_MB_2U_LIB.S9S_MB_2U(SCH_1):M_C_CPU1_SB_DQ(6)
AD34 M_C_CPU1_SB_DQ<5> DDR2_SB_DQ5 @S9S_MB_2U_LIB.S9S_MB_2U(SCH_1):M_C_CPU1_SB_DQ(5)
AC35 M_C_CPU1_SB_DQ<4> DDR2_SB_DQ4 @S9S_MB_2U_LIB.S9S_MB_2U(SCH_1):M_C_CPU1_SB_DQ(4)
AG37 M_C_CPU1_SB_DQ<3> DDR2_SB_DQ3 @S9S_MB_2U_LIB.S9S_MB_2U(SCH_1):M_C_CPU1_SB_DQ(3)
AF38 M_C_CPU1_SB_DQ<2> DDR2_SB_DQ2 @S9S_MB_2U_LIB.S9S_MB_2U(SCH_1):M_C_CPU1_SB_DQ(2)
AC37 M_C_CPU1_SB_DQ<1> DDR2_SB_DQ1 @S9S_MB_2U_LIB.S9S_MB_2U(SCH_1):M_C_CPU1_SB_DQ(1)
AD38 M_C_CPU1_SB_DQ<0> DDR2_SB_DQ0 @S9S_MB_2U_LIB.S9S_MB_2U(SCH_1):M_C_CPU1_SB_DQ(0)
 R33 M_C_CPU1_SB_DQS_DN<9> DDR2_SB_DQS_DN9 @S9S_MB_2U_LIB.S9S_MB_2U(SCH_1):M_C_CPU1_SB_DQS_DN(9)
AF18 M_C_CPU1_SB_DQS_DN<8> DDR2_SB_DQS_DN8 @S9S_MB_2U_LIB.S9S_MB_2U(SCH_1):M_C_CPU1_SB_DQS_DN(8)
 W21 M_C_CPU1_SB_DQS_DN<7> DDR2_SB_DQS_DN7 @S9S_MB_2U_LIB.S9S_MB_2U(SCH_1):M_C_CPU1_SB_DQS_DN(7)
AF30 M_C_CPU1_SB_DQS_DN<6> DDR2_SB_DQS_DN6 @S9S_MB_2U_LIB.S9S_MB_2U(SCH_1):M_C_CPU1_SB_DQS_DN(6)
AF36 M_C_CPU1_SB_DQS_DN<5> DDR2_SB_DQS_DN5 @S9S_MB_2U_LIB.S9S_MB_2U(SCH_1):M_C_CPU1_SB_DQS_DN(5)
 W33 M_C_CPU1_SB_DQS_DN<4> DDR2_SB_DQS_DN4 @S9S_MB_2U_LIB.S9S_MB_2U(SCH_1):M_C_CPU1_SB_DQS_DN(4)
AB18 M_C_CPU1_SB_DQS_DN<3> DDR2_SB_DQS_DN3 @S9S_MB_2U_LIB.S9S_MB_2U(SCH_1):M_C_CPU1_SB_DQS_DN(3)
 R21 M_C_CPU1_SB_DQS_DN<2> DDR2_SB_DQS_DN2 @S9S_MB_2U_LIB.S9S_MB_2U(SCH_1):M_C_CPU1_SB_DQS_DN(2)
AB30 M_C_CPU1_SB_DQS_DN<1> DDR2_SB_DQS_DN1 @S9S_MB_2U_LIB.S9S_MB_2U(SCH_1):M_C_CPU1_SB_DQS_DN(1)
AB36 M_C_CPU1_SB_DQS_DN<0> DDR2_SB_DQS_DN0 @S9S_MB_2U_LIB.S9S_MB_2U(SCH_1):M_C_CPU1_SB_DQS_DN(0)
 U33 M_C_CPU1_SB_DQS_DP<9> DDR2_SB_DQS_DP9 @S9S_MB_2U_LIB.S9S_MB_2U(SCH_1):M_C_CPU1_SB_DQS_DP(9)
AH18 M_C_CPU1_SB_DQS_DP<8> DDR2_SB_DQS_DP8 @S9S_MB_2U_LIB.S9S_MB_2U(SCH_1):M_C_CPU1_SB_DQS_DP(8)
AA21 M_C_CPU1_SB_DQS_DP<7> DDR2_SB_DQS_DP7 @S9S_MB_2U_LIB.S9S_MB_2U(SCH_1):M_C_CPU1_SB_DQS_DP(7)
AH30 M_C_CPU1_SB_DQS_DP<6> DDR2_SB_DQS_DP6 @S9S_MB_2U_LIB.S9S_MB_2U(SCH_1):M_C_CPU1_SB_DQS_DP(6)
AH36 M_C_CPU1_SB_DQS_DP<5> DDR2_SB_DQS_DP5 @S9S_MB_2U_LIB.S9S_MB_2U(SCH_1):M_C_CPU1_SB_DQS_DP(5)
AA33 M_C_CPU1_SB_DQS_DP<4> DDR2_SB_DQS_DP4 @S9S_MB_2U_LIB.S9S_MB_2U(SCH_1):M_C_CPU1_SB_DQS_DP(4)
AD18 M_C_CPU1_SB_DQS_DP<3> DDR2_SB_DQS_DP3 @S9S_MB_2U_LIB.S9S_MB_2U(SCH_1):M_C_CPU1_SB_DQS_DP(3)
 U21 M_C_CPU1_SB_DQS_DP<2> DDR2_SB_DQS_DP2 @S9S_MB_2U_LIB.S9S_MB_2U(SCH_1):M_C_CPU1_SB_DQS_DP(2)
AD30 M_C_CPU1_SB_DQS_DP<1> DDR2_SB_DQS_DP1 @S9S_MB_2U_LIB.S9S_MB_2U(SCH_1):M_C_CPU1_SB_DQS_DP(1)
AD36 M_C_CPU1_SB_DQS_DP<0> DDR2_SB_DQS_DP0 @S9S_MB_2U_LIB.S9S_MB_2U(SCH_1):M_C_CPU1_SB_DQS_DP(0)
 Y34 M_C_CPU1_SB_CB<7> DDR2_SB_ECC7 @S9S_MB_2U_LIB.S9S_MB_2U(SCH_1):M_C_CPU1_SB_CB(7)
 W35 M_C_CPU1_SB_CB<6> DDR2_SB_ECC6 @S9S_MB_2U_LIB.S9S_MB_2U(SCH_1):M_C_CPU1_SB_CB(6)
 T34 M_C_CPU1_SB_CB<5> DDR2_SB_ECC5 @S9S_MB_2U_LIB.S9S_MB_2U(SCH_1):M_C_CPU1_SB_CB(5)
 U35 M_C_CPU1_SB_CB<4> DDR2_SB_ECC4 @S9S_MB_2U_LIB.S9S_MB_2U(SCH_1):M_C_CPU1_SB_CB(4)
 W31 M_C_CPU1_SB_CB<3> DDR2_SB_ECC3 @S9S_MB_2U_LIB.S9S_MB_2U(SCH_1):M_C_CPU1_SB_CB(3)
 Y32 M_C_CPU1_SB_CB<2> DDR2_SB_ECC2 @S9S_MB_2U_LIB.S9S_MB_2U(SCH_1):M_C_CPU1_SB_CB(2)
 U31 M_C_CPU1_SB_CB<1> DDR2_SB_ECC1 @S9S_MB_2U_LIB.S9S_MB_2U(SCH_1):M_C_CPU1_SB_CB(1)
 T32 M_C_CPU1_SB_CB<0> DDR2_SB_ECC0 @S9S_MB_2U_LIB.S9S_MB_2U(SCH_1):M_C_CPU1_SB_CB(0)
AA39 M_C_CPU1_SB_PAR DDR2_SB_PAR @S9S_MB_2U_LIB.S9S_MB_2U(SCH_1):M_C_CPU1_SB_PAR


DRAWING: @S9S_MB_2U_LIB.S9S_MB_2U(SCH_1):PAGE54 

SOCKET4677_AZIF0045P001C01CS-SA  I91  U1
AV47 M_D_CPU1_ALERT_N DDR3_ALERT_N @S9S_MB_2U_LIB.S9S_MB_2U(SCH_1):M_D_CPU1_ALERT_N
AC50 M_D_CPU1_SA_RSP<1> DDR3_A_RSP1 @S9S_MB_2U_LIB.S9S_MB_2U(SCH_1):M_D_CPU1_SA_RSP(1)
AD51 M_D_CPU1_SA_RSP<0> DDR3_A_RSP0 @S9S_MB_2U_LIB.S9S_MB_2U(SCH_1):M_D_CPU1_SA_RSP(0)
AG50 M_D_CPU1_SB_RSP<1> DDR3_B_RSP1 @S9S_MB_2U_LIB.S9S_MB_2U(SCH_1):M_D_CPU1_SB_RSP(1)
AF51 M_D_CPU1_SB_RSP<0> DDR3_B_RSP0 @S9S_MB_2U_LIB.S9S_MB_2U(SCH_1):M_D_CPU1_SB_RSP(0)
AN45 M_D_CPU1_CLK_DN<1> DDR3_CLK_DN1 @S9S_MB_2U_LIB.S9S_MB_2U(SCH_1):M_D_CPU1_CLK_DN(1)
AJ45 M_D_CPU1_CLK_DN<0> DDR3_CLK_DN0 @S9S_MB_2U_LIB.S9S_MB_2U(SCH_1):M_D_CPU1_CLK_DN(0)
AR45 M_D_CPU1_CLK_DP<1> DDR3_CLK_DP1 @S9S_MB_2U_LIB.S9S_MB_2U(SCH_1):M_D_CPU1_CLK_DP(1)
AL45 M_D_CPU1_CLK_DP<0> DDR3_CLK_DP0 @S9S_MB_2U_LIB.S9S_MB_2U(SCH_1):M_D_CPU1_CLK_DP(0)
AN43 M_D_CPU1_SA_CA<6> DDR3_SA_CA6 @S9S_MB_2U_LIB.S9S_MB_2U(SCH_1):M_D_CPU1_SA_CA(6)
AN50 M_D_CPU1_SA_CA<5> DDR3_SA_CA5 @S9S_MB_2U_LIB.S9S_MB_2U(SCH_1):M_D_CPU1_SA_CA(5)
AL50 M_D_CPU1_SA_CA<4> DDR3_SA_CA4 @S9S_MB_2U_LIB.S9S_MB_2U(SCH_1):M_D_CPU1_SA_CA(4)
AP51 M_D_CPU1_SA_CA<3> DDR3_SA_CA3 @S9S_MB_2U_LIB.S9S_MB_2U(SCH_1):M_D_CPU1_SA_CA(3)
AK51 M_D_CPU1_SA_CA<2> DDR3_SA_CA2 @S9S_MB_2U_LIB.S9S_MB_2U(SCH_1):M_D_CPU1_SA_CA(2)
AR52 M_D_CPU1_SA_CA<1> DDR3_SA_CA1 @S9S_MB_2U_LIB.S9S_MB_2U(SCH_1):M_D_CPU1_SA_CA(1)
AJ52 M_D_CPU1_SA_CA<0> DDR3_SA_CA0 @S9S_MB_2U_LIB.S9S_MB_2U(SCH_1):M_D_CPU1_SA_CA(0)
AP53 M_D_CPU1_SA_CS_N<3> DDR3_SA_CS_N3 @S9S_MB_2U_LIB.S9S_MB_2U(SCH_1):M_D_CPU1_SA_CS_N(3)
AN54 M_D_CPU1_SA_CS_N<2> DDR3_SA_CS_N2 @S9S_MB_2U_LIB.S9S_MB_2U(SCH_1):M_D_CPU1_SA_CS_N(2)
AK53 M_D_CPU1_SA_CS_N<1> DDR3_SA_CS_N1 @S9S_MB_2U_LIB.S9S_MB_2U(SCH_1):M_D_CPU1_SA_CS_N(1)
AL54 M_D_CPU1_SA_CS_N<0> DDR3_SA_CS_N0 @S9S_MB_2U_LIB.S9S_MB_2U(SCH_1):M_D_CPU1_SA_CS_N(0)
AN62 M_D_CPU1_SA_DQ<31> DDR3_SA_DQ31 @S9S_MB_2U_LIB.S9S_MB_2U(SCH_1):M_D_CPU1_SA_DQ(31)
AP63 M_D_CPU1_SA_DQ<30> DDR3_SA_DQ30 @S9S_MB_2U_LIB.S9S_MB_2U(SCH_1):M_D_CPU1_SA_DQ(30)
AL62 M_D_CPU1_SA_DQ<29> DDR3_SA_DQ29 @S9S_MB_2U_LIB.S9S_MB_2U(SCH_1):M_D_CPU1_SA_DQ(29)
AK63 M_D_CPU1_SA_DQ<28> DDR3_SA_DQ28 @S9S_MB_2U_LIB.S9S_MB_2U(SCH_1):M_D_CPU1_SA_DQ(28)
AP65 M_D_CPU1_SA_DQ<27> DDR3_SA_DQ27 @S9S_MB_2U_LIB.S9S_MB_2U(SCH_1):M_D_CPU1_SA_DQ(27)
AN66 M_D_CPU1_SA_DQ<26> DDR3_SA_DQ26 @S9S_MB_2U_LIB.S9S_MB_2U(SCH_1):M_D_CPU1_SA_DQ(26)
AK65 M_D_CPU1_SA_DQ<25> DDR3_SA_DQ25 @S9S_MB_2U_LIB.S9S_MB_2U(SCH_1):M_D_CPU1_SA_DQ(25)
AL66 M_D_CPU1_SA_DQ<24> DDR3_SA_DQ24 @S9S_MB_2U_LIB.S9S_MB_2U(SCH_1):M_D_CPU1_SA_DQ(24)
AN68 M_D_CPU1_SA_DQ<23> DDR3_SA_DQ23 @S9S_MB_2U_LIB.S9S_MB_2U(SCH_1):M_D_CPU1_SA_DQ(23)
AP69 M_D_CPU1_SA_DQ<22> DDR3_SA_DQ22 @S9S_MB_2U_LIB.S9S_MB_2U(SCH_1):M_D_CPU1_SA_DQ(22)
AL68 M_D_CPU1_SA_DQ<21> DDR3_SA_DQ21 @S9S_MB_2U_LIB.S9S_MB_2U(SCH_1):M_D_CPU1_SA_DQ(21)
AK69 M_D_CPU1_SA_DQ<20> DDR3_SA_DQ20 @S9S_MB_2U_LIB.S9S_MB_2U(SCH_1):M_D_CPU1_SA_DQ(20)
AP71 M_D_CPU1_SA_DQ<19> DDR3_SA_DQ19 @S9S_MB_2U_LIB.S9S_MB_2U(SCH_1):M_D_CPU1_SA_DQ(19)
AN72 M_D_CPU1_SA_DQ<18> DDR3_SA_DQ18 @S9S_MB_2U_LIB.S9S_MB_2U(SCH_1):M_D_CPU1_SA_DQ(18)
AK71 M_D_CPU1_SA_DQ<17> DDR3_SA_DQ17 @S9S_MB_2U_LIB.S9S_MB_2U(SCH_1):M_D_CPU1_SA_DQ(17)
AL72 M_D_CPU1_SA_DQ<16> DDR3_SA_DQ16 @S9S_MB_2U_LIB.S9S_MB_2U(SCH_1):M_D_CPU1_SA_DQ(16)
AN74 M_D_CPU1_SA_DQ<15> DDR3_SA_DQ15 @S9S_MB_2U_LIB.S9S_MB_2U(SCH_1):M_D_CPU1_SA_DQ(15)
AP75 M_D_CPU1_SA_DQ<14> DDR3_SA_DQ14 @S9S_MB_2U_LIB.S9S_MB_2U(SCH_1):M_D_CPU1_SA_DQ(14)
AL74 M_D_CPU1_SA_DQ<13> DDR3_SA_DQ13 @S9S_MB_2U_LIB.S9S_MB_2U(SCH_1):M_D_CPU1_SA_DQ(13)
AK75 M_D_CPU1_SA_DQ<12> DDR3_SA_DQ12 @S9S_MB_2U_LIB.S9S_MB_2U(SCH_1):M_D_CPU1_SA_DQ(12)
AP77 M_D_CPU1_SA_DQ<11> DDR3_SA_DQ11 @S9S_MB_2U_LIB.S9S_MB_2U(SCH_1):M_D_CPU1_SA_DQ(11)
AN78 M_D_CPU1_SA_DQ<10> DDR3_SA_DQ10 @S9S_MB_2U_LIB.S9S_MB_2U(SCH_1):M_D_CPU1_SA_DQ(10)
AK77 M_D_CPU1_SA_DQ<9> DDR3_SA_DQ9 @S9S_MB_2U_LIB.S9S_MB_2U(SCH_1):M_D_CPU1_SA_DQ(9)
AL78 M_D_CPU1_SA_DQ<8> DDR3_SA_DQ8 @S9S_MB_2U_LIB.S9S_MB_2U(SCH_1):M_D_CPU1_SA_DQ(8)
AF71 M_D_CPU1_SA_DQ<7> DDR3_SA_DQ7 @S9S_MB_2U_LIB.S9S_MB_2U(SCH_1):M_D_CPU1_SA_DQ(7)
AG72 M_D_CPU1_SA_DQ<6> DDR3_SA_DQ6 @S9S_MB_2U_LIB.S9S_MB_2U(SCH_1):M_D_CPU1_SA_DQ(6)
AD71 M_D_CPU1_SA_DQ<5> DDR3_SA_DQ5 @S9S_MB_2U_LIB.S9S_MB_2U(SCH_1):M_D_CPU1_SA_DQ(5)
AC72 M_D_CPU1_SA_DQ<4> DDR3_SA_DQ4 @S9S_MB_2U_LIB.S9S_MB_2U(SCH_1):M_D_CPU1_SA_DQ(4)
AG74 M_D_CPU1_SA_DQ<3> DDR3_SA_DQ3 @S9S_MB_2U_LIB.S9S_MB_2U(SCH_1):M_D_CPU1_SA_DQ(3)
AF75 M_D_CPU1_SA_DQ<2> DDR3_SA_DQ2 @S9S_MB_2U_LIB.S9S_MB_2U(SCH_1):M_D_CPU1_SA_DQ(2)
AC74 M_D_CPU1_SA_DQ<1> DDR3_SA_DQ1 @S9S_MB_2U_LIB.S9S_MB_2U(SCH_1):M_D_CPU1_SA_DQ(1)
AD75 M_D_CPU1_SA_DQ<0> DDR3_SA_DQ0 @S9S_MB_2U_LIB.S9S_MB_2U(SCH_1):M_D_CPU1_SA_DQ(0)
AN58 M_D_CPU1_SA_DQS_DN<9> DDR3_SA_DQS_DN9 @S9S_MB_2U_LIB.S9S_MB_2U(SCH_1):M_D_CPU1_SA_DQS_DN(9)
AN64 M_D_CPU1_SA_DQS_DN<8> DDR3_SA_DQS_DN8 @S9S_MB_2U_LIB.S9S_MB_2U(SCH_1):M_D_CPU1_SA_DQS_DN(8)
AN70 M_D_CPU1_SA_DQS_DN<7> DDR3_SA_DQS_DN7 @S9S_MB_2U_LIB.S9S_MB_2U(SCH_1):M_D_CPU1_SA_DQS_DN(7)
AN76 M_D_CPU1_SA_DQS_DN<6> DDR3_SA_DQS_DN6 @S9S_MB_2U_LIB.S9S_MB_2U(SCH_1):M_D_CPU1_SA_DQS_DN(6)
AH73 M_D_CPU1_SA_DQS_DN<5> DDR3_SA_DQS_DN5 @S9S_MB_2U_LIB.S9S_MB_2U(SCH_1):M_D_CPU1_SA_DQS_DN(5)
AJ58 M_D_CPU1_SA_DQS_DN<4> DDR3_SA_DQS_DN4 @S9S_MB_2U_LIB.S9S_MB_2U(SCH_1):M_D_CPU1_SA_DQS_DN(4)
AJ64 M_D_CPU1_SA_DQS_DN<3> DDR3_SA_DQS_DN3 @S9S_MB_2U_LIB.S9S_MB_2U(SCH_1):M_D_CPU1_SA_DQS_DN(3)
AJ70 M_D_CPU1_SA_DQS_DN<2> DDR3_SA_DQS_DN2 @S9S_MB_2U_LIB.S9S_MB_2U(SCH_1):M_D_CPU1_SA_DQS_DN(2)
AJ76 M_D_CPU1_SA_DQS_DN<1> DDR3_SA_DQS_DN1 @S9S_MB_2U_LIB.S9S_MB_2U(SCH_1):M_D_CPU1_SA_DQS_DN(1)
AB73 M_D_CPU1_SA_DQS_DN<0> DDR3_SA_DQS_DN0 @S9S_MB_2U_LIB.S9S_MB_2U(SCH_1):M_D_CPU1_SA_DQS_DN(0)
AR58 M_D_CPU1_SA_DQS_DP<9> DDR3_SA_DQS_DP9 @S9S_MB_2U_LIB.S9S_MB_2U(SCH_1):M_D_CPU1_SA_DQS_DP(9)
AR64 M_D_CPU1_SA_DQS_DP<8> DDR3_SA_DQS_DP8 @S9S_MB_2U_LIB.S9S_MB_2U(SCH_1):M_D_CPU1_SA_DQS_DP(8)
AR70 M_D_CPU1_SA_DQS_DP<7> DDR3_SA_DQS_DP7 @S9S_MB_2U_LIB.S9S_MB_2U(SCH_1):M_D_CPU1_SA_DQS_DP(7)
AR76 M_D_CPU1_SA_DQS_DP<6> DDR3_SA_DQS_DP6 @S9S_MB_2U_LIB.S9S_MB_2U(SCH_1):M_D_CPU1_SA_DQS_DP(6)
AF73 M_D_CPU1_SA_DQS_DP<5> DDR3_SA_DQS_DP5 @S9S_MB_2U_LIB.S9S_MB_2U(SCH_1):M_D_CPU1_SA_DQS_DP(5)
AL58 M_D_CPU1_SA_DQS_DP<4> DDR3_SA_DQS_DP4 @S9S_MB_2U_LIB.S9S_MB_2U(SCH_1):M_D_CPU1_SA_DQS_DP(4)
AL64 M_D_CPU1_SA_DQS_DP<3> DDR3_SA_DQS_DP3 @S9S_MB_2U_LIB.S9S_MB_2U(SCH_1):M_D_CPU1_SA_DQS_DP(3)
AL70 M_D_CPU1_SA_DQS_DP<2> DDR3_SA_DQS_DP2 @S9S_MB_2U_LIB.S9S_MB_2U(SCH_1):M_D_CPU1_SA_DQS_DP(2)
AL76 M_D_CPU1_SA_DQS_DP<1> DDR3_SA_DQS_DP1 @S9S_MB_2U_LIB.S9S_MB_2U(SCH_1):M_D_CPU1_SA_DQS_DP(1)
AD73 M_D_CPU1_SA_DQS_DP<0> DDR3_SA_DQS_DP0 @S9S_MB_2U_LIB.S9S_MB_2U(SCH_1):M_D_CPU1_SA_DQS_DP(0)
AN56 M_D_CPU1_SA_CB<7> DDR3_SA_ECC7 @S9S_MB_2U_LIB.S9S_MB_2U(SCH_1):M_D_CPU1_SA_CB(7)
AP57 M_D_CPU1_SA_CB<6> DDR3_SA_ECC6 @S9S_MB_2U_LIB.S9S_MB_2U(SCH_1):M_D_CPU1_SA_CB(6)
AL56 M_D_CPU1_SA_CB<5> DDR3_SA_ECC5 @S9S_MB_2U_LIB.S9S_MB_2U(SCH_1):M_D_CPU1_SA_CB(5)
AK57 M_D_CPU1_SA_CB<4> DDR3_SA_ECC4 @S9S_MB_2U_LIB.S9S_MB_2U(SCH_1):M_D_CPU1_SA_CB(4)
AP59 M_D_CPU1_SA_CB<3> DDR3_SA_ECC3 @S9S_MB_2U_LIB.S9S_MB_2U(SCH_1):M_D_CPU1_SA_CB(3)
AN60 M_D_CPU1_SA_CB<2> DDR3_SA_ECC2 @S9S_MB_2U_LIB.S9S_MB_2U(SCH_1):M_D_CPU1_SA_CB(2)
AK59 M_D_CPU1_SA_CB<1> DDR3_SA_ECC1 @S9S_MB_2U_LIB.S9S_MB_2U(SCH_1):M_D_CPU1_SA_CB(1)
AL60 M_D_CPU1_SA_CB<0> DDR3_SA_ECC0 @S9S_MB_2U_LIB.S9S_MB_2U(SCH_1):M_D_CPU1_SA_CB(0)
AP44 M_D_CPU1_SA_PAR DDR3_SA_PAR @S9S_MB_2U_LIB.S9S_MB_2U(SCH_1):M_D_CPU1_SA_PAR
AB42 M_D_CPU1_SB_CA<6> DDR3_SB_CA6 @S9S_MB_2U_LIB.S9S_MB_2U(SCH_1):M_D_CPU1_SB_CA(6)
AG43 M_D_CPU1_SB_CA<5> DDR3_SB_CA5 @S9S_MB_2U_LIB.S9S_MB_2U(SCH_1):M_D_CPU1_SB_CA(5)
AC43 M_D_CPU1_SB_CA<4> DDR3_SB_CA4 @S9S_MB_2U_LIB.S9S_MB_2U(SCH_1):M_D_CPU1_SB_CA(4)
AF44 M_D_CPU1_SB_CA<3> DDR3_SB_CA3 @S9S_MB_2U_LIB.S9S_MB_2U(SCH_1):M_D_CPU1_SB_CA(3)
AD44 M_D_CPU1_SB_CA<2> DDR3_SB_CA2 @S9S_MB_2U_LIB.S9S_MB_2U(SCH_1):M_D_CPU1_SB_CA(2)
AL43 M_D_CPU1_SB_CA<1> DDR3_SB_CA1 @S9S_MB_2U_LIB.S9S_MB_2U(SCH_1):M_D_CPU1_SB_CA(1)
AK44 M_D_CPU1_SB_CA<0> DDR3_SB_CA0 @S9S_MB_2U_LIB.S9S_MB_2U(SCH_1):M_D_CPU1_SB_CA(0)
AD40 M_D_CPU1_SB_CS_N<3> DDR3_SB_CS_N3 @S9S_MB_2U_LIB.S9S_MB_2U(SCH_1):M_D_CPU1_SB_CS_N(3)
AF40 M_D_CPU1_SB_CS_N<2> DDR3_SB_CS_N2 @S9S_MB_2U_LIB.S9S_MB_2U(SCH_1):M_D_CPU1_SB_CS_N(2)
AG41 M_D_CPU1_SB_CS_N<1> DDR3_SB_CS_N1 @S9S_MB_2U_LIB.S9S_MB_2U(SCH_1):M_D_CPU1_SB_CS_N(1)
AC41 M_D_CPU1_SB_CS_N<0> DDR3_SB_CS_N0 @S9S_MB_2U_LIB.S9S_MB_2U(SCH_1):M_D_CPU1_SB_CS_N(0)
AN19 M_D_CPU1_SB_DQ<31> DDR3_SB_DQ31 @S9S_MB_2U_LIB.S9S_MB_2U(SCH_1):M_D_CPU1_SB_DQ(31)
AP20 M_D_CPU1_SB_DQ<30> DDR3_SB_DQ30 @S9S_MB_2U_LIB.S9S_MB_2U(SCH_1):M_D_CPU1_SB_DQ(30)
AL19 M_D_CPU1_SB_DQ<29> DDR3_SB_DQ29 @S9S_MB_2U_LIB.S9S_MB_2U(SCH_1):M_D_CPU1_SB_DQ(29)
AK20 M_D_CPU1_SB_DQ<28> DDR3_SB_DQ28 @S9S_MB_2U_LIB.S9S_MB_2U(SCH_1):M_D_CPU1_SB_DQ(28)
AP22 M_D_CPU1_SB_DQ<27> DDR3_SB_DQ27 @S9S_MB_2U_LIB.S9S_MB_2U(SCH_1):M_D_CPU1_SB_DQ(27)
AN23 M_D_CPU1_SB_DQ<26> DDR3_SB_DQ26 @S9S_MB_2U_LIB.S9S_MB_2U(SCH_1):M_D_CPU1_SB_DQ(26)
AK22 M_D_CPU1_SB_DQ<25> DDR3_SB_DQ25 @S9S_MB_2U_LIB.S9S_MB_2U(SCH_1):M_D_CPU1_SB_DQ(25)
AL23 M_D_CPU1_SB_DQ<24> DDR3_SB_DQ24 @S9S_MB_2U_LIB.S9S_MB_2U(SCH_1):M_D_CPU1_SB_DQ(24)
AF22 M_D_CPU1_SB_DQ<23> DDR3_SB_DQ23 @S9S_MB_2U_LIB.S9S_MB_2U(SCH_1):M_D_CPU1_SB_DQ(23)
AG23 M_D_CPU1_SB_DQ<22> DDR3_SB_DQ22 @S9S_MB_2U_LIB.S9S_MB_2U(SCH_1):M_D_CPU1_SB_DQ(22)
AD22 M_D_CPU1_SB_DQ<21> DDR3_SB_DQ21 @S9S_MB_2U_LIB.S9S_MB_2U(SCH_1):M_D_CPU1_SB_DQ(21)
AC23 M_D_CPU1_SB_DQ<20> DDR3_SB_DQ20 @S9S_MB_2U_LIB.S9S_MB_2U(SCH_1):M_D_CPU1_SB_DQ(20)
AG25 M_D_CPU1_SB_DQ<19> DDR3_SB_DQ19 @S9S_MB_2U_LIB.S9S_MB_2U(SCH_1):M_D_CPU1_SB_DQ(19)
AF26 M_D_CPU1_SB_DQ<18> DDR3_SB_DQ18 @S9S_MB_2U_LIB.S9S_MB_2U(SCH_1):M_D_CPU1_SB_DQ(18)
AC25 M_D_CPU1_SB_DQ<17> DDR3_SB_DQ17 @S9S_MB_2U_LIB.S9S_MB_2U(SCH_1):M_D_CPU1_SB_DQ(17)
AD26 M_D_CPU1_SB_DQ<16> DDR3_SB_DQ16 @S9S_MB_2U_LIB.S9S_MB_2U(SCH_1):M_D_CPU1_SB_DQ(16)
AN25 M_D_CPU1_SB_DQ<15> DDR3_SB_DQ15 @S9S_MB_2U_LIB.S9S_MB_2U(SCH_1):M_D_CPU1_SB_DQ(15)
AP26 M_D_CPU1_SB_DQ<14> DDR3_SB_DQ14 @S9S_MB_2U_LIB.S9S_MB_2U(SCH_1):M_D_CPU1_SB_DQ(14)
AL25 M_D_CPU1_SB_DQ<13> DDR3_SB_DQ13 @S9S_MB_2U_LIB.S9S_MB_2U(SCH_1):M_D_CPU1_SB_DQ(13)
AK26 M_D_CPU1_SB_DQ<12> DDR3_SB_DQ12 @S9S_MB_2U_LIB.S9S_MB_2U(SCH_1):M_D_CPU1_SB_DQ(12)
AP28 M_D_CPU1_SB_DQ<11> DDR3_SB_DQ11 @S9S_MB_2U_LIB.S9S_MB_2U(SCH_1):M_D_CPU1_SB_DQ(11)
AN29 M_D_CPU1_SB_DQ<10> DDR3_SB_DQ10 @S9S_MB_2U_LIB.S9S_MB_2U(SCH_1):M_D_CPU1_SB_DQ(10)
AK28 M_D_CPU1_SB_DQ<9> DDR3_SB_DQ9 @S9S_MB_2U_LIB.S9S_MB_2U(SCH_1):M_D_CPU1_SB_DQ(9)
AL29 M_D_CPU1_SB_DQ<8> DDR3_SB_DQ8 @S9S_MB_2U_LIB.S9S_MB_2U(SCH_1):M_D_CPU1_SB_DQ(8)
AN31 M_D_CPU1_SB_DQ<7> DDR3_SB_DQ7 @S9S_MB_2U_LIB.S9S_MB_2U(SCH_1):M_D_CPU1_SB_DQ(7)
AP32 M_D_CPU1_SB_DQ<6> DDR3_SB_DQ6 @S9S_MB_2U_LIB.S9S_MB_2U(SCH_1):M_D_CPU1_SB_DQ(6)
AL31 M_D_CPU1_SB_DQ<5> DDR3_SB_DQ5 @S9S_MB_2U_LIB.S9S_MB_2U(SCH_1):M_D_CPU1_SB_DQ(5)
AK32 M_D_CPU1_SB_DQ<4> DDR3_SB_DQ4 @S9S_MB_2U_LIB.S9S_MB_2U(SCH_1):M_D_CPU1_SB_DQ(4)
AP34 M_D_CPU1_SB_DQ<3> DDR3_SB_DQ3 @S9S_MB_2U_LIB.S9S_MB_2U(SCH_1):M_D_CPU1_SB_DQ(3)
AN35 M_D_CPU1_SB_DQ<2> DDR3_SB_DQ2 @S9S_MB_2U_LIB.S9S_MB_2U(SCH_1):M_D_CPU1_SB_DQ(2)
AK34 M_D_CPU1_SB_DQ<1> DDR3_SB_DQ1 @S9S_MB_2U_LIB.S9S_MB_2U(SCH_1):M_D_CPU1_SB_DQ(1)
AL35 M_D_CPU1_SB_DQ<0> DDR3_SB_DQ0 @S9S_MB_2U_LIB.S9S_MB_2U(SCH_1):M_D_CPU1_SB_DQ(0)
AJ39 M_D_CPU1_SB_DQS_DN<9> DDR3_SB_DQS_DN9 @S9S_MB_2U_LIB.S9S_MB_2U(SCH_1):M_D_CPU1_SB_DQS_DN(9)
AN21 M_D_CPU1_SB_DQS_DN<8> DDR3_SB_DQS_DN8 @S9S_MB_2U_LIB.S9S_MB_2U(SCH_1):M_D_CPU1_SB_DQS_DN(8)
AF24 M_D_CPU1_SB_DQS_DN<7> DDR3_SB_DQS_DN7 @S9S_MB_2U_LIB.S9S_MB_2U(SCH_1):M_D_CPU1_SB_DQS_DN(7)
AN27 M_D_CPU1_SB_DQS_DN<6> DDR3_SB_DQS_DN6 @S9S_MB_2U_LIB.S9S_MB_2U(SCH_1):M_D_CPU1_SB_DQS_DN(6)
AN33 M_D_CPU1_SB_DQS_DN<5> DDR3_SB_DQS_DN5 @S9S_MB_2U_LIB.S9S_MB_2U(SCH_1):M_D_CPU1_SB_DQS_DN(5)
AR39 M_D_CPU1_SB_DQS_DN<4> DDR3_SB_DQS_DN4 @S9S_MB_2U_LIB.S9S_MB_2U(SCH_1):M_D_CPU1_SB_DQS_DN(4)
AJ21 M_D_CPU1_SB_DQS_DN<3> DDR3_SB_DQS_DN3 @S9S_MB_2U_LIB.S9S_MB_2U(SCH_1):M_D_CPU1_SB_DQS_DN(3)
AB24 M_D_CPU1_SB_DQS_DN<2> DDR3_SB_DQS_DN2 @S9S_MB_2U_LIB.S9S_MB_2U(SCH_1):M_D_CPU1_SB_DQS_DN(2)
AJ27 M_D_CPU1_SB_DQS_DN<1> DDR3_SB_DQS_DN1 @S9S_MB_2U_LIB.S9S_MB_2U(SCH_1):M_D_CPU1_SB_DQS_DN(1)
AJ33 M_D_CPU1_SB_DQS_DN<0> DDR3_SB_DQS_DN0 @S9S_MB_2U_LIB.S9S_MB_2U(SCH_1):M_D_CPU1_SB_DQS_DN(0)
AL39 M_D_CPU1_SB_DQS_DP<9> DDR3_SB_DQS_DP9 @S9S_MB_2U_LIB.S9S_MB_2U(SCH_1):M_D_CPU1_SB_DQS_DP(9)
AR21 M_D_CPU1_SB_DQS_DP<8> DDR3_SB_DQS_DP8 @S9S_MB_2U_LIB.S9S_MB_2U(SCH_1):M_D_CPU1_SB_DQS_DP(8)
AH24 M_D_CPU1_SB_DQS_DP<7> DDR3_SB_DQS_DP7 @S9S_MB_2U_LIB.S9S_MB_2U(SCH_1):M_D_CPU1_SB_DQS_DP(7)
AR27 M_D_CPU1_SB_DQS_DP<6> DDR3_SB_DQS_DP6 @S9S_MB_2U_LIB.S9S_MB_2U(SCH_1):M_D_CPU1_SB_DQS_DP(6)
AR33 M_D_CPU1_SB_DQS_DP<5> DDR3_SB_DQS_DP5 @S9S_MB_2U_LIB.S9S_MB_2U(SCH_1):M_D_CPU1_SB_DQS_DP(5)
AN39 M_D_CPU1_SB_DQS_DP<4> DDR3_SB_DQS_DP4 @S9S_MB_2U_LIB.S9S_MB_2U(SCH_1):M_D_CPU1_SB_DQS_DP(4)
AL21 M_D_CPU1_SB_DQS_DP<3> DDR3_SB_DQS_DP3 @S9S_MB_2U_LIB.S9S_MB_2U(SCH_1):M_D_CPU1_SB_DQS_DP(3)
AD24 M_D_CPU1_SB_DQS_DP<2> DDR3_SB_DQS_DP2 @S9S_MB_2U_LIB.S9S_MB_2U(SCH_1):M_D_CPU1_SB_DQS_DP(2)
AL27 M_D_CPU1_SB_DQS_DP<1> DDR3_SB_DQS_DP1 @S9S_MB_2U_LIB.S9S_MB_2U(SCH_1):M_D_CPU1_SB_DQS_DP(1)
AL33 M_D_CPU1_SB_DQS_DP<0> DDR3_SB_DQS_DP0 @S9S_MB_2U_LIB.S9S_MB_2U(SCH_1):M_D_CPU1_SB_DQS_DP(0)
AP40 M_D_CPU1_SB_CB<7> DDR3_SB_ECC7 @S9S_MB_2U_LIB.S9S_MB_2U(SCH_1):M_D_CPU1_SB_CB(7)
AN41 M_D_CPU1_SB_CB<6> DDR3_SB_ECC6 @S9S_MB_2U_LIB.S9S_MB_2U(SCH_1):M_D_CPU1_SB_CB(6)
AK40 M_D_CPU1_SB_CB<5> DDR3_SB_ECC5 @S9S_MB_2U_LIB.S9S_MB_2U(SCH_1):M_D_CPU1_SB_CB(5)
AL41 M_D_CPU1_SB_CB<4> DDR3_SB_ECC4 @S9S_MB_2U_LIB.S9S_MB_2U(SCH_1):M_D_CPU1_SB_CB(4)
AN37 M_D_CPU1_SB_CB<3> DDR3_SB_ECC3 @S9S_MB_2U_LIB.S9S_MB_2U(SCH_1):M_D_CPU1_SB_CB(3)
AP38 M_D_CPU1_SB_CB<2> DDR3_SB_ECC2 @S9S_MB_2U_LIB.S9S_MB_2U(SCH_1):M_D_CPU1_SB_CB(2)
AL37 M_D_CPU1_SB_CB<1> DDR3_SB_ECC1 @S9S_MB_2U_LIB.S9S_MB_2U(SCH_1):M_D_CPU1_SB_CB(1)
AK38 M_D_CPU1_SB_CB<0> DDR3_SB_ECC0 @S9S_MB_2U_LIB.S9S_MB_2U(SCH_1):M_D_CPU1_SB_CB(0)
AH42 M_D_CPU1_SB_PAR DDR3_SB_PAR @S9S_MB_2U_LIB.S9S_MB_2U(SCH_1):M_D_CPU1_SB_PAR


DRAWING: @S9S_MB_2U_LIB.S9S_MB_2U(SCH_1):PAGE55 

SOCKET4677_AZIF0045P001C01CS-SA  I7  U1
CY47 M_E_CPU1_ALERT_N DDR4_ALERT_N @S9S_MB_2U_LIB.S9S_MB_2U(SCH_1):M_E_CPU1_ALERT_N
DC43 M_E_CPU1_SA_RSP<1> DDR4_A_RSP1 @S9S_MB_2U_LIB.S9S_MB_2U(SCH_1):M_E_CPU1_SA_RSP(1)
DD44 M_E_CPU1_SA_RSP<0> DDR4_A_RSP0 @S9S_MB_2U_LIB.S9S_MB_2U(SCH_1):M_E_CPU1_SA_RSP(0)
DG43 M_E_CPU1_SB_RSP<1> DDR4_B_RSP1 @S9S_MB_2U_LIB.S9S_MB_2U(SCH_1):M_E_CPU1_SB_RSP(1)
DF44 M_E_CPU1_SB_RSP<0> DDR4_B_RSP0 @S9S_MB_2U_LIB.S9S_MB_2U(SCH_1):M_E_CPU1_SB_RSP(0)
EE45 M_E_CPU1_CLK_DN<1> DDR4_CLK_DN1 @S9S_MB_2U_LIB.S9S_MB_2U(SCH_1):M_E_CPU1_CLK_DN(1)
EJ45 M_E_CPU1_CLK_DN<0> DDR4_CLK_DN0 @S9S_MB_2U_LIB.S9S_MB_2U(SCH_1):M_E_CPU1_CLK_DN(0)
EC45 M_E_CPU1_CLK_DP<1> DDR4_CLK_DP1 @S9S_MB_2U_LIB.S9S_MB_2U(SCH_1):M_E_CPU1_CLK_DP(1)
EG45 M_E_CPU1_CLK_DP<0> DDR4_CLK_DP0 @S9S_MB_2U_LIB.S9S_MB_2U(SCH_1):M_E_CPU1_CLK_DP(0)
ED44 M_E_CPU1_SA_CA<6> DDR4_SA_CA6 @S9S_MB_2U_LIB.S9S_MB_2U(SCH_1):M_E_CPU1_SA_CA(6)
EP47 M_E_CPU1_SA_CA<5> DDR4_SA_CA5 @S9S_MB_2U_LIB.S9S_MB_2U(SCH_1):M_E_CPU1_SA_CA(5)
EM47 M_E_CPU1_SA_CA<4> DDR4_SA_CA4 @S9S_MB_2U_LIB.S9S_MB_2U(SCH_1):M_E_CPU1_SA_CA(4)
EL48 M_E_CPU1_SA_CA<3> DDR4_SA_CA3 @S9S_MB_2U_LIB.S9S_MB_2U(SCH_1):M_E_CPU1_SA_CA(3)
EK49 M_E_CPU1_SA_CA<2> DDR4_SA_CA2 @S9S_MB_2U_LIB.S9S_MB_2U(SCH_1):M_E_CPU1_SA_CA(2)
ET49 M_E_CPU1_SA_CA<1> DDR4_SA_CA1 @S9S_MB_2U_LIB.S9S_MB_2U(SCH_1):M_E_CPU1_SA_CA(1)
EP49 M_E_CPU1_SA_CA<0> DDR4_SA_CA0 @S9S_MB_2U_LIB.S9S_MB_2U(SCH_1):M_E_CPU1_SA_CA(0)
EL50 M_E_CPU1_SA_CS_N<3> DDR4_SA_CS_N3 @S9S_MB_2U_LIB.S9S_MB_2U(SCH_1):M_E_CPU1_SA_CS_N(3)
EM51 M_E_CPU1_SA_CS_N<2> DDR4_SA_CS_N2 @S9S_MB_2U_LIB.S9S_MB_2U(SCH_1):M_E_CPU1_SA_CS_N(2)
ET51 M_E_CPU1_SA_CS_N<1> DDR4_SA_CS_N1 @S9S_MB_2U_LIB.S9S_MB_2U(SCH_1):M_E_CPU1_SA_CS_N(1)
EP51 M_E_CPU1_SA_CS_N<0> DDR4_SA_CS_N0 @S9S_MB_2U_LIB.S9S_MB_2U(SCH_1):M_E_CPU1_SA_CS_N(0)
EP59 M_E_CPU1_SA_DQ<31> DDR4_SA_DQ31 @S9S_MB_2U_LIB.S9S_MB_2U(SCH_1):M_E_CPU1_SA_DQ(31)
ER60 M_E_CPU1_SA_DQ<30> DDR4_SA_DQ30 @S9S_MB_2U_LIB.S9S_MB_2U(SCH_1):M_E_CPU1_SA_DQ(30)
EM59 M_E_CPU1_SA_DQ<29> DDR4_SA_DQ29 @S9S_MB_2U_LIB.S9S_MB_2U(SCH_1):M_E_CPU1_SA_DQ(29)
EL60 M_E_CPU1_SA_DQ<28> DDR4_SA_DQ28 @S9S_MB_2U_LIB.S9S_MB_2U(SCH_1):M_E_CPU1_SA_DQ(28)
ER62 M_E_CPU1_SA_DQ<27> DDR4_SA_DQ27 @S9S_MB_2U_LIB.S9S_MB_2U(SCH_1):M_E_CPU1_SA_DQ(27)
EP63 M_E_CPU1_SA_DQ<26> DDR4_SA_DQ26 @S9S_MB_2U_LIB.S9S_MB_2U(SCH_1):M_E_CPU1_SA_DQ(26)
EL62 M_E_CPU1_SA_DQ<25> DDR4_SA_DQ25 @S9S_MB_2U_LIB.S9S_MB_2U(SCH_1):M_E_CPU1_SA_DQ(25)
EM63 M_E_CPU1_SA_DQ<24> DDR4_SA_DQ24 @S9S_MB_2U_LIB.S9S_MB_2U(SCH_1):M_E_CPU1_SA_DQ(24)
EP65 M_E_CPU1_SA_DQ<23> DDR4_SA_DQ23 @S9S_MB_2U_LIB.S9S_MB_2U(SCH_1):M_E_CPU1_SA_DQ(23)
EL66 M_E_CPU1_SA_DQ<22> DDR4_SA_DQ22 @S9S_MB_2U_LIB.S9S_MB_2U(SCH_1):M_E_CPU1_SA_DQ(22)
EM65 M_E_CPU1_SA_DQ<21> DDR4_SA_DQ21 @S9S_MB_2U_LIB.S9S_MB_2U(SCH_1):M_E_CPU1_SA_DQ(21)
ER66 M_E_CPU1_SA_DQ<20> DDR4_SA_DQ20 @S9S_MB_2U_LIB.S9S_MB_2U(SCH_1):M_E_CPU1_SA_DQ(20)
ER68 M_E_CPU1_SA_DQ<19> DDR4_SA_DQ19 @S9S_MB_2U_LIB.S9S_MB_2U(SCH_1):M_E_CPU1_SA_DQ(19)
EN70 M_E_CPU1_SA_DQ<18> DDR4_SA_DQ18 @S9S_MB_2U_LIB.S9S_MB_2U(SCH_1):M_E_CPU1_SA_DQ(18)
EM69 M_E_CPU1_SA_DQ<17> DDR4_SA_DQ17 @S9S_MB_2U_LIB.S9S_MB_2U(SCH_1):M_E_CPU1_SA_DQ(17)
EM71 M_E_CPU1_SA_DQ<16> DDR4_SA_DQ16 @S9S_MB_2U_LIB.S9S_MB_2U(SCH_1):M_E_CPU1_SA_DQ(16)
EG68 M_E_CPU1_SA_DQ<15> DDR4_SA_DQ15 @S9S_MB_2U_LIB.S9S_MB_2U(SCH_1):M_E_CPU1_SA_DQ(15)
EH69 M_E_CPU1_SA_DQ<14> DDR4_SA_DQ14 @S9S_MB_2U_LIB.S9S_MB_2U(SCH_1):M_E_CPU1_SA_DQ(14)
EE68 M_E_CPU1_SA_DQ<13> DDR4_SA_DQ13 @S9S_MB_2U_LIB.S9S_MB_2U(SCH_1):M_E_CPU1_SA_DQ(13)
ED69 M_E_CPU1_SA_DQ<12> DDR4_SA_DQ12 @S9S_MB_2U_LIB.S9S_MB_2U(SCH_1):M_E_CPU1_SA_DQ(12)
EH71 M_E_CPU1_SA_DQ<11> DDR4_SA_DQ11 @S9S_MB_2U_LIB.S9S_MB_2U(SCH_1):M_E_CPU1_SA_DQ(11)
EG72 M_E_CPU1_SA_DQ<10> DDR4_SA_DQ10 @S9S_MB_2U_LIB.S9S_MB_2U(SCH_1):M_E_CPU1_SA_DQ(10)
ED71 M_E_CPU1_SA_DQ<9> DDR4_SA_DQ9 @S9S_MB_2U_LIB.S9S_MB_2U(SCH_1):M_E_CPU1_SA_DQ(9)
EE72 M_E_CPU1_SA_DQ<8> DDR4_SA_DQ8 @S9S_MB_2U_LIB.S9S_MB_2U(SCH_1):M_E_CPU1_SA_DQ(8)
ER72 M_E_CPU1_SA_DQ<7> DDR4_SA_DQ7 @S9S_MB_2U_LIB.S9S_MB_2U(SCH_1):M_E_CPU1_SA_DQ(7)
EP73 M_E_CPU1_SA_DQ<6> DDR4_SA_DQ6 @S9S_MB_2U_LIB.S9S_MB_2U(SCH_1):M_E_CPU1_SA_DQ(6)
EK73 M_E_CPU1_SA_DQ<5> DDR4_SA_DQ5 @S9S_MB_2U_LIB.S9S_MB_2U(SCH_1):M_E_CPU1_SA_DQ(5)
EL74 M_E_CPU1_SA_DQ<4> DDR4_SA_DQ4 @S9S_MB_2U_LIB.S9S_MB_2U(SCH_1):M_E_CPU1_SA_DQ(4)
ER76 M_E_CPU1_SA_DQ<3> DDR4_SA_DQ3 @S9S_MB_2U_LIB.S9S_MB_2U(SCH_1):M_E_CPU1_SA_DQ(3)
EP79 M_E_CPU1_SA_DQ<2> DDR4_SA_DQ2 @S9S_MB_2U_LIB.S9S_MB_2U(SCH_1):M_E_CPU1_SA_DQ(2)
EM77 M_E_CPU1_SA_DQ<1> DDR4_SA_DQ1 @S9S_MB_2U_LIB.S9S_MB_2U(SCH_1):M_E_CPU1_SA_DQ(1)
EL78 M_E_CPU1_SA_DQ<0> DDR4_SA_DQ0 @S9S_MB_2U_LIB.S9S_MB_2U(SCH_1):M_E_CPU1_SA_DQ(0)
ET55 M_E_CPU1_SA_DQS_DN<9> DDR4_SA_DQS_DN9 @S9S_MB_2U_LIB.S9S_MB_2U(SCH_1):M_E_CPU1_SA_DQS_DN(9)
ET61 M_E_CPU1_SA_DQS_DN<8> DDR4_SA_DQS_DN8 @S9S_MB_2U_LIB.S9S_MB_2U(SCH_1):M_E_CPU1_SA_DQS_DN(8)
EN68 M_E_CPU1_SA_DQS_DN<7> DDR4_SA_DQS_DN7 @S9S_MB_2U_LIB.S9S_MB_2U(SCH_1):M_E_CPU1_SA_DQS_DN(7)
EJ70 M_E_CPU1_SA_DQS_DN<6> DDR4_SA_DQS_DN6 @S9S_MB_2U_LIB.S9S_MB_2U(SCH_1):M_E_CPU1_SA_DQS_DN(6)
EM75 M_E_CPU1_SA_DQS_DN<5> DDR4_SA_DQS_DN5 @S9S_MB_2U_LIB.S9S_MB_2U(SCH_1):M_E_CPU1_SA_DQS_DN(5)
EM55 M_E_CPU1_SA_DQS_DN<4> DDR4_SA_DQS_DN4 @S9S_MB_2U_LIB.S9S_MB_2U(SCH_1):M_E_CPU1_SA_DQS_DN(4)
EK61 M_E_CPU1_SA_DQS_DN<3> DDR4_SA_DQS_DN3 @S9S_MB_2U_LIB.S9S_MB_2U(SCH_1):M_E_CPU1_SA_DQS_DN(3)
EK67 M_E_CPU1_SA_DQS_DN<2> DDR4_SA_DQS_DN2 @S9S_MB_2U_LIB.S9S_MB_2U(SCH_1):M_E_CPU1_SA_DQS_DN(2)
EC70 M_E_CPU1_SA_DQS_DN<1> DDR4_SA_DQS_DN1 @S9S_MB_2U_LIB.S9S_MB_2U(SCH_1):M_E_CPU1_SA_DQS_DN(1)
EP75 M_E_CPU1_SA_DQS_DN<0> DDR4_SA_DQS_DN0 @S9S_MB_2U_LIB.S9S_MB_2U(SCH_1):M_E_CPU1_SA_DQS_DN(0)
EP55 M_E_CPU1_SA_DQS_DP<9> DDR4_SA_DQS_DP9 @S9S_MB_2U_LIB.S9S_MB_2U(SCH_1):M_E_CPU1_SA_DQS_DP(9)
EP61 M_E_CPU1_SA_DQS_DP<8> DDR4_SA_DQS_DP8 @S9S_MB_2U_LIB.S9S_MB_2U(SCH_1):M_E_CPU1_SA_DQS_DP(8)
EM67 M_E_CPU1_SA_DQS_DP<7> DDR4_SA_DQS_DP7 @S9S_MB_2U_LIB.S9S_MB_2U(SCH_1):M_E_CPU1_SA_DQS_DP(7)
EG70 M_E_CPU1_SA_DQS_DP<6> DDR4_SA_DQS_DP6 @S9S_MB_2U_LIB.S9S_MB_2U(SCH_1):M_E_CPU1_SA_DQS_DP(6)
EN74 M_E_CPU1_SA_DQS_DP<5> DDR4_SA_DQS_DP5 @S9S_MB_2U_LIB.S9S_MB_2U(SCH_1):M_E_CPU1_SA_DQS_DP(5)
EK55 M_E_CPU1_SA_DQS_DP<4> DDR4_SA_DQS_DP4 @S9S_MB_2U_LIB.S9S_MB_2U(SCH_1):M_E_CPU1_SA_DQS_DP(4)
EM61 M_E_CPU1_SA_DQS_DP<3> DDR4_SA_DQS_DP3 @S9S_MB_2U_LIB.S9S_MB_2U(SCH_1):M_E_CPU1_SA_DQS_DP(3)
EL68 M_E_CPU1_SA_DQS_DP<2> DDR4_SA_DQS_DP2 @S9S_MB_2U_LIB.S9S_MB_2U(SCH_1):M_E_CPU1_SA_DQS_DP(2)
EE70 M_E_CPU1_SA_DQS_DP<1> DDR4_SA_DQS_DP1 @S9S_MB_2U_LIB.S9S_MB_2U(SCH_1):M_E_CPU1_SA_DQS_DP(1)
EN76 M_E_CPU1_SA_DQS_DP<0> DDR4_SA_DQS_DP0 @S9S_MB_2U_LIB.S9S_MB_2U(SCH_1):M_E_CPU1_SA_DQS_DP(0)
EP53 M_E_CPU1_SA_CB<7> DDR4_SA_ECC7 @S9S_MB_2U_LIB.S9S_MB_2U(SCH_1):M_E_CPU1_SA_CB(7)
ER54 M_E_CPU1_SA_CB<6> DDR4_SA_ECC6 @S9S_MB_2U_LIB.S9S_MB_2U(SCH_1):M_E_CPU1_SA_CB(6)
EM53 M_E_CPU1_SA_CB<5> DDR4_SA_ECC5 @S9S_MB_2U_LIB.S9S_MB_2U(SCH_1):M_E_CPU1_SA_CB(5)
EL54 M_E_CPU1_SA_CB<4> DDR4_SA_ECC4 @S9S_MB_2U_LIB.S9S_MB_2U(SCH_1):M_E_CPU1_SA_CB(4)
ER56 M_E_CPU1_SA_CB<3> DDR4_SA_ECC3 @S9S_MB_2U_LIB.S9S_MB_2U(SCH_1):M_E_CPU1_SA_CB(3)
EP57 M_E_CPU1_SA_CB<2> DDR4_SA_ECC2 @S9S_MB_2U_LIB.S9S_MB_2U(SCH_1):M_E_CPU1_SA_CB(2)
EL56 M_E_CPU1_SA_CB<1> DDR4_SA_ECC1 @S9S_MB_2U_LIB.S9S_MB_2U(SCH_1):M_E_CPU1_SA_CB(1)
EM57 M_E_CPU1_SA_CB<0> DDR4_SA_ECC0 @S9S_MB_2U_LIB.S9S_MB_2U(SCH_1):M_E_CPU1_SA_CB(0)
EE43 M_E_CPU1_SA_PAR DDR4_SA_PAR @S9S_MB_2U_LIB.S9S_MB_2U(SCH_1):M_E_CPU1_SA_PAR
EK42 M_E_CPU1_SB_CA<6> DDR4_SB_CA6 @S9S_MB_2U_LIB.S9S_MB_2U(SCH_1):M_E_CPU1_SB_CA(6)
ET42 M_E_CPU1_SB_CA<5> DDR4_SB_CA5 @S9S_MB_2U_LIB.S9S_MB_2U(SCH_1):M_E_CPU1_SB_CA(5)
EL43 M_E_CPU1_SB_CA<4> DDR4_SB_CA4 @S9S_MB_2U_LIB.S9S_MB_2U(SCH_1):M_E_CPU1_SB_CA(4)
EP44 M_E_CPU1_SB_CA<3> DDR4_SB_CA3 @S9S_MB_2U_LIB.S9S_MB_2U(SCH_1):M_E_CPU1_SB_CA(3)
EM44 M_E_CPU1_SB_CA<2> DDR4_SB_CA2 @S9S_MB_2U_LIB.S9S_MB_2U(SCH_1):M_E_CPU1_SB_CA(2)
EH44 M_E_CPU1_SB_CA<1> DDR4_SB_CA1 @S9S_MB_2U_LIB.S9S_MB_2U(SCH_1):M_E_CPU1_SB_CA(1)
EG43 M_E_CPU1_SB_CA<0> DDR4_SB_CA0 @S9S_MB_2U_LIB.S9S_MB_2U(SCH_1):M_E_CPU1_SB_CA(0)
EL41 M_E_CPU1_SB_CS_N<3> DDR4_SB_CS_N3 @S9S_MB_2U_LIB.S9S_MB_2U(SCH_1):M_E_CPU1_SB_CS_N(3)
EM40 M_E_CPU1_SB_CS_N<2> DDR4_SB_CS_N2 @S9S_MB_2U_LIB.S9S_MB_2U(SCH_1):M_E_CPU1_SB_CS_N(2)
ET40 M_E_CPU1_SB_CS_N<1> DDR4_SB_CS_N1 @S9S_MB_2U_LIB.S9S_MB_2U(SCH_1):M_E_CPU1_SB_CS_N(1)
EP40 M_E_CPU1_SB_CS_N<0> DDR4_SB_CS_N0 @S9S_MB_2U_LIB.S9S_MB_2U(SCH_1):M_E_CPU1_SB_CS_N(0)
EP16 M_E_CPU1_SB_DQ<31> DDR4_SB_DQ31 @S9S_MB_2U_LIB.S9S_MB_2U(SCH_1):M_E_CPU1_SB_DQ(31)
ER17 M_E_CPU1_SB_DQ<30> DDR4_SB_DQ30 @S9S_MB_2U_LIB.S9S_MB_2U(SCH_1):M_E_CPU1_SB_DQ(30)
EM16 M_E_CPU1_SB_DQ<29> DDR4_SB_DQ29 @S9S_MB_2U_LIB.S9S_MB_2U(SCH_1):M_E_CPU1_SB_DQ(29)
EL17 M_E_CPU1_SB_DQ<28> DDR4_SB_DQ28 @S9S_MB_2U_LIB.S9S_MB_2U(SCH_1):M_E_CPU1_SB_DQ(28)
ER19 M_E_CPU1_SB_DQ<27> DDR4_SB_DQ27 @S9S_MB_2U_LIB.S9S_MB_2U(SCH_1):M_E_CPU1_SB_DQ(27)
EP20 M_E_CPU1_SB_DQ<26> DDR4_SB_DQ26 @S9S_MB_2U_LIB.S9S_MB_2U(SCH_1):M_E_CPU1_SB_DQ(26)
EL19 M_E_CPU1_SB_DQ<25> DDR4_SB_DQ25 @S9S_MB_2U_LIB.S9S_MB_2U(SCH_1):M_E_CPU1_SB_DQ(25)
EM20 M_E_CPU1_SB_DQ<24> DDR4_SB_DQ24 @S9S_MB_2U_LIB.S9S_MB_2U(SCH_1):M_E_CPU1_SB_DQ(24)
EP22 M_E_CPU1_SB_DQ<23> DDR4_SB_DQ23 @S9S_MB_2U_LIB.S9S_MB_2U(SCH_1):M_E_CPU1_SB_DQ(23)
ER23 M_E_CPU1_SB_DQ<22> DDR4_SB_DQ22 @S9S_MB_2U_LIB.S9S_MB_2U(SCH_1):M_E_CPU1_SB_DQ(22)
EM22 M_E_CPU1_SB_DQ<21> DDR4_SB_DQ21 @S9S_MB_2U_LIB.S9S_MB_2U(SCH_1):M_E_CPU1_SB_DQ(21)
EL23 M_E_CPU1_SB_DQ<20> DDR4_SB_DQ20 @S9S_MB_2U_LIB.S9S_MB_2U(SCH_1):M_E_CPU1_SB_DQ(20)
ER25 M_E_CPU1_SB_DQ<19> DDR4_SB_DQ19 @S9S_MB_2U_LIB.S9S_MB_2U(SCH_1):M_E_CPU1_SB_DQ(19)
EP26 M_E_CPU1_SB_DQ<18> DDR4_SB_DQ18 @S9S_MB_2U_LIB.S9S_MB_2U(SCH_1):M_E_CPU1_SB_DQ(18)
EL25 M_E_CPU1_SB_DQ<17> DDR4_SB_DQ17 @S9S_MB_2U_LIB.S9S_MB_2U(SCH_1):M_E_CPU1_SB_DQ(17)
EM26 M_E_CPU1_SB_DQ<16> DDR4_SB_DQ16 @S9S_MB_2U_LIB.S9S_MB_2U(SCH_1):M_E_CPU1_SB_DQ(16)
EP28 M_E_CPU1_SB_DQ<15> DDR4_SB_DQ15 @S9S_MB_2U_LIB.S9S_MB_2U(SCH_1):M_E_CPU1_SB_DQ(15)
ER29 M_E_CPU1_SB_DQ<14> DDR4_SB_DQ14 @S9S_MB_2U_LIB.S9S_MB_2U(SCH_1):M_E_CPU1_SB_DQ(14)
EM28 M_E_CPU1_SB_DQ<13> DDR4_SB_DQ13 @S9S_MB_2U_LIB.S9S_MB_2U(SCH_1):M_E_CPU1_SB_DQ(13)
EL29 M_E_CPU1_SB_DQ<12> DDR4_SB_DQ12 @S9S_MB_2U_LIB.S9S_MB_2U(SCH_1):M_E_CPU1_SB_DQ(12)
ER31 M_E_CPU1_SB_DQ<11> DDR4_SB_DQ11 @S9S_MB_2U_LIB.S9S_MB_2U(SCH_1):M_E_CPU1_SB_DQ(11)
EP32 M_E_CPU1_SB_DQ<10> DDR4_SB_DQ10 @S9S_MB_2U_LIB.S9S_MB_2U(SCH_1):M_E_CPU1_SB_DQ(10)
EL31 M_E_CPU1_SB_DQ<9> DDR4_SB_DQ9 @S9S_MB_2U_LIB.S9S_MB_2U(SCH_1):M_E_CPU1_SB_DQ(9)
EM32 M_E_CPU1_SB_DQ<8> DDR4_SB_DQ8 @S9S_MB_2U_LIB.S9S_MB_2U(SCH_1):M_E_CPU1_SB_DQ(8)
EG25 M_E_CPU1_SB_DQ<7> DDR4_SB_DQ7 @S9S_MB_2U_LIB.S9S_MB_2U(SCH_1):M_E_CPU1_SB_DQ(7)
EH26 M_E_CPU1_SB_DQ<6> DDR4_SB_DQ6 @S9S_MB_2U_LIB.S9S_MB_2U(SCH_1):M_E_CPU1_SB_DQ(6)
EE25 M_E_CPU1_SB_DQ<5> DDR4_SB_DQ5 @S9S_MB_2U_LIB.S9S_MB_2U(SCH_1):M_E_CPU1_SB_DQ(5)
ED26 M_E_CPU1_SB_DQ<4> DDR4_SB_DQ4 @S9S_MB_2U_LIB.S9S_MB_2U(SCH_1):M_E_CPU1_SB_DQ(4)
EH28 M_E_CPU1_SB_DQ<3> DDR4_SB_DQ3 @S9S_MB_2U_LIB.S9S_MB_2U(SCH_1):M_E_CPU1_SB_DQ(3)
EG29 M_E_CPU1_SB_DQ<2> DDR4_SB_DQ2 @S9S_MB_2U_LIB.S9S_MB_2U(SCH_1):M_E_CPU1_SB_DQ(2)
ED28 M_E_CPU1_SB_DQ<1> DDR4_SB_DQ1 @S9S_MB_2U_LIB.S9S_MB_2U(SCH_1):M_E_CPU1_SB_DQ(1)
EE29 M_E_CPU1_SB_DQ<0> DDR4_SB_DQ0 @S9S_MB_2U_LIB.S9S_MB_2U(SCH_1):M_E_CPU1_SB_DQ(0)
EK36 M_E_CPU1_SB_DQS_DN<9> DDR4_SB_DQS_DN9 @S9S_MB_2U_LIB.S9S_MB_2U(SCH_1):M_E_CPU1_SB_DQS_DN(9)
ET18 M_E_CPU1_SB_DQS_DN<8> DDR4_SB_DQS_DN8 @S9S_MB_2U_LIB.S9S_MB_2U(SCH_1):M_E_CPU1_SB_DQS_DN(8)
ET24 M_E_CPU1_SB_DQS_DN<7> DDR4_SB_DQS_DN7 @S9S_MB_2U_LIB.S9S_MB_2U(SCH_1):M_E_CPU1_SB_DQS_DN(7)
ET30 M_E_CPU1_SB_DQS_DN<6> DDR4_SB_DQS_DN6 @S9S_MB_2U_LIB.S9S_MB_2U(SCH_1):M_E_CPU1_SB_DQS_DN(6)
EJ27 M_E_CPU1_SB_DQS_DN<5> DDR4_SB_DQS_DN5 @S9S_MB_2U_LIB.S9S_MB_2U(SCH_1):M_E_CPU1_SB_DQS_DN(5)
ET36 M_E_CPU1_SB_DQS_DN<4> DDR4_SB_DQS_DN4 @S9S_MB_2U_LIB.S9S_MB_2U(SCH_1):M_E_CPU1_SB_DQS_DN(4)
EK18 M_E_CPU1_SB_DQS_DN<3> DDR4_SB_DQS_DN3 @S9S_MB_2U_LIB.S9S_MB_2U(SCH_1):M_E_CPU1_SB_DQS_DN(3)
EK24 M_E_CPU1_SB_DQS_DN<2> DDR4_SB_DQS_DN2 @S9S_MB_2U_LIB.S9S_MB_2U(SCH_1):M_E_CPU1_SB_DQS_DN(2)
EK30 M_E_CPU1_SB_DQS_DN<1> DDR4_SB_DQS_DN1 @S9S_MB_2U_LIB.S9S_MB_2U(SCH_1):M_E_CPU1_SB_DQS_DN(1)
EE27 M_E_CPU1_SB_DQS_DN<0> DDR4_SB_DQS_DN0 @S9S_MB_2U_LIB.S9S_MB_2U(SCH_1):M_E_CPU1_SB_DQS_DN(0)
EM36 M_E_CPU1_SB_DQS_DP<9> DDR4_SB_DQS_DP9 @S9S_MB_2U_LIB.S9S_MB_2U(SCH_1):M_E_CPU1_SB_DQS_DP(9)
EP18 M_E_CPU1_SB_DQS_DP<8> DDR4_SB_DQS_DP8 @S9S_MB_2U_LIB.S9S_MB_2U(SCH_1):M_E_CPU1_SB_DQS_DP(8)
EP24 M_E_CPU1_SB_DQS_DP<7> DDR4_SB_DQS_DP7 @S9S_MB_2U_LIB.S9S_MB_2U(SCH_1):M_E_CPU1_SB_DQS_DP(7)
EP30 M_E_CPU1_SB_DQS_DP<6> DDR4_SB_DQS_DP6 @S9S_MB_2U_LIB.S9S_MB_2U(SCH_1):M_E_CPU1_SB_DQS_DP(6)
EG27 M_E_CPU1_SB_DQS_DP<5> DDR4_SB_DQS_DP5 @S9S_MB_2U_LIB.S9S_MB_2U(SCH_1):M_E_CPU1_SB_DQS_DP(5)
EP36 M_E_CPU1_SB_DQS_DP<4> DDR4_SB_DQS_DP4 @S9S_MB_2U_LIB.S9S_MB_2U(SCH_1):M_E_CPU1_SB_DQS_DP(4)
EM18 M_E_CPU1_SB_DQS_DP<3> DDR4_SB_DQS_DP3 @S9S_MB_2U_LIB.S9S_MB_2U(SCH_1):M_E_CPU1_SB_DQS_DP(3)
EM24 M_E_CPU1_SB_DQS_DP<2> DDR4_SB_DQS_DP2 @S9S_MB_2U_LIB.S9S_MB_2U(SCH_1):M_E_CPU1_SB_DQS_DP(2)
EM30 M_E_CPU1_SB_DQS_DP<1> DDR4_SB_DQS_DP1 @S9S_MB_2U_LIB.S9S_MB_2U(SCH_1):M_E_CPU1_SB_DQS_DP(1)
EC27 M_E_CPU1_SB_DQS_DP<0> DDR4_SB_DQS_DP0 @S9S_MB_2U_LIB.S9S_MB_2U(SCH_1):M_E_CPU1_SB_DQS_DP(0)
ER37 M_E_CPU1_SB_CB<7> DDR4_SB_ECC7 @S9S_MB_2U_LIB.S9S_MB_2U(SCH_1):M_E_CPU1_SB_CB(7)
EP38 M_E_CPU1_SB_CB<6> DDR4_SB_ECC6 @S9S_MB_2U_LIB.S9S_MB_2U(SCH_1):M_E_CPU1_SB_CB(6)
EL37 M_E_CPU1_SB_CB<5> DDR4_SB_ECC5 @S9S_MB_2U_LIB.S9S_MB_2U(SCH_1):M_E_CPU1_SB_CB(5)
EM38 M_E_CPU1_SB_CB<4> DDR4_SB_ECC4 @S9S_MB_2U_LIB.S9S_MB_2U(SCH_1):M_E_CPU1_SB_CB(4)
EP34 M_E_CPU1_SB_CB<3> DDR4_SB_ECC3 @S9S_MB_2U_LIB.S9S_MB_2U(SCH_1):M_E_CPU1_SB_CB(3)
ER35 M_E_CPU1_SB_CB<2> DDR4_SB_ECC2 @S9S_MB_2U_LIB.S9S_MB_2U(SCH_1):M_E_CPU1_SB_CB(2)
EM34 M_E_CPU1_SB_CB<1> DDR4_SB_ECC1 @S9S_MB_2U_LIB.S9S_MB_2U(SCH_1):M_E_CPU1_SB_CB(1)
EL35 M_E_CPU1_SB_CB<0> DDR4_SB_ECC0 @S9S_MB_2U_LIB.S9S_MB_2U(SCH_1):M_E_CPU1_SB_CB(0)
EP42 M_E_CPU1_SB_PAR DDR4_SB_PAR @S9S_MB_2U_LIB.S9S_MB_2U(SCH_1):M_E_CPU1_SB_PAR


DRAWING: @S9S_MB_2U_LIB.S9S_MB_2U(SCH_1):PAGE56 

SOCKET4677_AZIF0045P001C01CS-SA  I168  U1
CW48 M_F_CPU1_ALERT_N DDR5_ALERT_N @S9S_MB_2U_LIB.S9S_MB_2U(SCH_1):M_F_CPU1_ALERT_N
DP47 M_F_CPU1_SA_RSP<1> DDR5_A_RSP1 @S9S_MB_2U_LIB.S9S_MB_2U(SCH_1):M_F_CPU1_SA_RSP(1)
DN48 M_F_CPU1_SA_RSP<0> DDR5_A_RSP0 @S9S_MB_2U_LIB.S9S_MB_2U(SCH_1):M_F_CPU1_SA_RSP(0)
DK47 M_F_CPU1_SB_RSP<1> DDR5_B_RSP1 @S9S_MB_2U_LIB.S9S_MB_2U(SCH_1):M_F_CPU1_SB_RSP(1)
DL48 M_F_CPU1_SB_RSP<0> DDR5_B_RSP0 @S9S_MB_2U_LIB.S9S_MB_2U(SCH_1):M_F_CPU1_SB_RSP(0)
DV49 M_F_CPU1_CLK_DN<1> DDR5_CLK_DN1 @S9S_MB_2U_LIB.S9S_MB_2U(SCH_1):M_F_CPU1_CLK_DN(1)
DY49 M_F_CPU1_CLK_DN<0> DDR5_CLK_DN0 @S9S_MB_2U_LIB.S9S_MB_2U(SCH_1):M_F_CPU1_CLK_DN(0)
DT49 M_F_CPU1_CLK_DP<1> DDR5_CLK_DP1 @S9S_MB_2U_LIB.S9S_MB_2U(SCH_1):M_F_CPU1_CLK_DP(1)
EB49 M_F_CPU1_CLK_DP<0> DDR5_CLK_DP0 @S9S_MB_2U_LIB.S9S_MB_2U(SCH_1):M_F_CPU1_CLK_DP(0)
DY51 M_F_CPU1_SA_CA<6> DDR5_SA_CA6 @S9S_MB_2U_LIB.S9S_MB_2U(SCH_1):M_F_CPU1_SA_CA(6)
EG50 M_F_CPU1_SA_CA<5> DDR5_SA_CA5 @S9S_MB_2U_LIB.S9S_MB_2U(SCH_1):M_F_CPU1_SA_CA(5)
EE50 M_F_CPU1_SA_CA<4> DDR5_SA_CA4 @S9S_MB_2U_LIB.S9S_MB_2U(SCH_1):M_F_CPU1_SA_CA(4)
EH51 M_F_CPU1_SA_CA<3> DDR5_SA_CA3 @S9S_MB_2U_LIB.S9S_MB_2U(SCH_1):M_F_CPU1_SA_CA(3)
ED51 M_F_CPU1_SA_CA<2> DDR5_SA_CA2 @S9S_MB_2U_LIB.S9S_MB_2U(SCH_1):M_F_CPU1_SA_CA(2)
EJ52 M_F_CPU1_SA_CA<1> DDR5_SA_CA1 @S9S_MB_2U_LIB.S9S_MB_2U(SCH_1):M_F_CPU1_SA_CA(1)
EC52 M_F_CPU1_SA_CA<0> DDR5_SA_CA0 @S9S_MB_2U_LIB.S9S_MB_2U(SCH_1):M_F_CPU1_SA_CA(0)
ED53 M_F_CPU1_SA_CS_N<3> DDR5_SA_CS_N3 @S9S_MB_2U_LIB.S9S_MB_2U(SCH_1):M_F_CPU1_SA_CS_N(3)
EE54 M_F_CPU1_SA_CS_N<2> DDR5_SA_CS_N2 @S9S_MB_2U_LIB.S9S_MB_2U(SCH_1):M_F_CPU1_SA_CS_N(2)
EH53 M_F_CPU1_SA_CS_N<1> DDR5_SA_CS_N1 @S9S_MB_2U_LIB.S9S_MB_2U(SCH_1):M_F_CPU1_SA_CS_N(1)
EG54 M_F_CPU1_SA_CS_N<0> DDR5_SA_CS_N0 @S9S_MB_2U_LIB.S9S_MB_2U(SCH_1):M_F_CPU1_SA_CS_N(0)
DY53 M_F_CPU1_SA_DQ<31> DDR5_SA_DQ31 @S9S_MB_2U_LIB.S9S_MB_2U(SCH_1):M_F_CPU1_SA_DQ(31)
EA54 M_F_CPU1_SA_DQ<30> DDR5_SA_DQ30 @S9S_MB_2U_LIB.S9S_MB_2U(SCH_1):M_F_CPU1_SA_DQ(30)
DV53 M_F_CPU1_SA_DQ<29> DDR5_SA_DQ29 @S9S_MB_2U_LIB.S9S_MB_2U(SCH_1):M_F_CPU1_SA_DQ(29)
DU54 M_F_CPU1_SA_DQ<28> DDR5_SA_DQ28 @S9S_MB_2U_LIB.S9S_MB_2U(SCH_1):M_F_CPU1_SA_DQ(28)
EA56 M_F_CPU1_SA_DQ<27> DDR5_SA_DQ27 @S9S_MB_2U_LIB.S9S_MB_2U(SCH_1):M_F_CPU1_SA_DQ(27)
DY57 M_F_CPU1_SA_DQ<26> DDR5_SA_DQ26 @S9S_MB_2U_LIB.S9S_MB_2U(SCH_1):M_F_CPU1_SA_DQ(26)
DU56 M_F_CPU1_SA_DQ<25> DDR5_SA_DQ25 @S9S_MB_2U_LIB.S9S_MB_2U(SCH_1):M_F_CPU1_SA_DQ(25)
DV57 M_F_CPU1_SA_DQ<24> DDR5_SA_DQ24 @S9S_MB_2U_LIB.S9S_MB_2U(SCH_1):M_F_CPU1_SA_DQ(24)
EG62 M_F_CPU1_SA_DQ<23> DDR5_SA_DQ23 @S9S_MB_2U_LIB.S9S_MB_2U(SCH_1):M_F_CPU1_SA_DQ(23)
EH63 M_F_CPU1_SA_DQ<22> DDR5_SA_DQ22 @S9S_MB_2U_LIB.S9S_MB_2U(SCH_1):M_F_CPU1_SA_DQ(22)
EE62 M_F_CPU1_SA_DQ<21> DDR5_SA_DQ21 @S9S_MB_2U_LIB.S9S_MB_2U(SCH_1):M_F_CPU1_SA_DQ(21)
ED63 M_F_CPU1_SA_DQ<20> DDR5_SA_DQ20 @S9S_MB_2U_LIB.S9S_MB_2U(SCH_1):M_F_CPU1_SA_DQ(20)
EH65 M_F_CPU1_SA_DQ<19> DDR5_SA_DQ19 @S9S_MB_2U_LIB.S9S_MB_2U(SCH_1):M_F_CPU1_SA_DQ(19)
EG66 M_F_CPU1_SA_DQ<18> DDR5_SA_DQ18 @S9S_MB_2U_LIB.S9S_MB_2U(SCH_1):M_F_CPU1_SA_DQ(18)
ED65 M_F_CPU1_SA_DQ<17> DDR5_SA_DQ17 @S9S_MB_2U_LIB.S9S_MB_2U(SCH_1):M_F_CPU1_SA_DQ(17)
EE66 M_F_CPU1_SA_DQ<16> DDR5_SA_DQ16 @S9S_MB_2U_LIB.S9S_MB_2U(SCH_1):M_F_CPU1_SA_DQ(16)
DY65 M_F_CPU1_SA_DQ<15> DDR5_SA_DQ15 @S9S_MB_2U_LIB.S9S_MB_2U(SCH_1):M_F_CPU1_SA_DQ(15)
EA66 M_F_CPU1_SA_DQ<14> DDR5_SA_DQ14 @S9S_MB_2U_LIB.S9S_MB_2U(SCH_1):M_F_CPU1_SA_DQ(14)
DV65 M_F_CPU1_SA_DQ<13> DDR5_SA_DQ13 @S9S_MB_2U_LIB.S9S_MB_2U(SCH_1):M_F_CPU1_SA_DQ(13)
DU66 M_F_CPU1_SA_DQ<12> DDR5_SA_DQ12 @S9S_MB_2U_LIB.S9S_MB_2U(SCH_1):M_F_CPU1_SA_DQ(12)
EA68 M_F_CPU1_SA_DQ<11> DDR5_SA_DQ11 @S9S_MB_2U_LIB.S9S_MB_2U(SCH_1):M_F_CPU1_SA_DQ(11)
DY69 M_F_CPU1_SA_DQ<10> DDR5_SA_DQ10 @S9S_MB_2U_LIB.S9S_MB_2U(SCH_1):M_F_CPU1_SA_DQ(10)
DU68 M_F_CPU1_SA_DQ<9> DDR5_SA_DQ9 @S9S_MB_2U_LIB.S9S_MB_2U(SCH_1):M_F_CPU1_SA_DQ(9)
DV69 M_F_CPU1_SA_DQ<8> DDR5_SA_DQ8 @S9S_MB_2U_LIB.S9S_MB_2U(SCH_1):M_F_CPU1_SA_DQ(8)
EG74 M_F_CPU1_SA_DQ<7> DDR5_SA_DQ7 @S9S_MB_2U_LIB.S9S_MB_2U(SCH_1):M_F_CPU1_SA_DQ(7)
EH75 M_F_CPU1_SA_DQ<6> DDR5_SA_DQ6 @S9S_MB_2U_LIB.S9S_MB_2U(SCH_1):M_F_CPU1_SA_DQ(6)
EE74 M_F_CPU1_SA_DQ<5> DDR5_SA_DQ5 @S9S_MB_2U_LIB.S9S_MB_2U(SCH_1):M_F_CPU1_SA_DQ(5)
ED75 M_F_CPU1_SA_DQ<4> DDR5_SA_DQ4 @S9S_MB_2U_LIB.S9S_MB_2U(SCH_1):M_F_CPU1_SA_DQ(4)
EG78 M_F_CPU1_SA_DQ<3> DDR5_SA_DQ3 @S9S_MB_2U_LIB.S9S_MB_2U(SCH_1):M_F_CPU1_SA_DQ(3)
ED77 M_F_CPU1_SA_DQ<2> DDR5_SA_DQ2 @S9S_MB_2U_LIB.S9S_MB_2U(SCH_1):M_F_CPU1_SA_DQ(2)
EH77 M_F_CPU1_SA_DQ<1> DDR5_SA_DQ1 @S9S_MB_2U_LIB.S9S_MB_2U(SCH_1):M_F_CPU1_SA_DQ(1)
EB77 M_F_CPU1_SA_DQ<0> DDR5_SA_DQ0 @S9S_MB_2U_LIB.S9S_MB_2U(SCH_1):M_F_CPU1_SA_DQ(0)
EJ58 M_F_CPU1_SA_DQS_DN<9> DDR5_SA_DQS_DN9 @S9S_MB_2U_LIB.S9S_MB_2U(SCH_1):M_F_CPU1_SA_DQS_DN(9)
EB55 M_F_CPU1_SA_DQS_DN<8> DDR5_SA_DQS_DN8 @S9S_MB_2U_LIB.S9S_MB_2U(SCH_1):M_F_CPU1_SA_DQS_DN(8)
EJ64 M_F_CPU1_SA_DQS_DN<7> DDR5_SA_DQS_DN7 @S9S_MB_2U_LIB.S9S_MB_2U(SCH_1):M_F_CPU1_SA_DQS_DN(7)
EB67 M_F_CPU1_SA_DQS_DN<6> DDR5_SA_DQS_DN6 @S9S_MB_2U_LIB.S9S_MB_2U(SCH_1):M_F_CPU1_SA_DQS_DN(6)
EJ76 M_F_CPU1_SA_DQS_DN<5> DDR5_SA_DQS_DN5 @S9S_MB_2U_LIB.S9S_MB_2U(SCH_1):M_F_CPU1_SA_DQS_DN(5)
EE58 M_F_CPU1_SA_DQS_DN<4> DDR5_SA_DQS_DN4 @S9S_MB_2U_LIB.S9S_MB_2U(SCH_1):M_F_CPU1_SA_DQS_DN(4)
DV55 M_F_CPU1_SA_DQS_DN<3> DDR5_SA_DQS_DN3 @S9S_MB_2U_LIB.S9S_MB_2U(SCH_1):M_F_CPU1_SA_DQS_DN(3)
EC64 M_F_CPU1_SA_DQS_DN<2> DDR5_SA_DQS_DN2 @S9S_MB_2U_LIB.S9S_MB_2U(SCH_1):M_F_CPU1_SA_DQS_DN(2)
DT67 M_F_CPU1_SA_DQS_DN<1> DDR5_SA_DQS_DN1 @S9S_MB_2U_LIB.S9S_MB_2U(SCH_1):M_F_CPU1_SA_DQS_DN(1)
EE76 M_F_CPU1_SA_DQS_DN<0> DDR5_SA_DQS_DN0 @S9S_MB_2U_LIB.S9S_MB_2U(SCH_1):M_F_CPU1_SA_DQS_DN(0)
EG58 M_F_CPU1_SA_DQS_DP<9> DDR5_SA_DQS_DP9 @S9S_MB_2U_LIB.S9S_MB_2U(SCH_1):M_F_CPU1_SA_DQS_DP(9)
DY55 M_F_CPU1_SA_DQS_DP<8> DDR5_SA_DQS_DP8 @S9S_MB_2U_LIB.S9S_MB_2U(SCH_1):M_F_CPU1_SA_DQS_DP(8)
EG64 M_F_CPU1_SA_DQS_DP<7> DDR5_SA_DQS_DP7 @S9S_MB_2U_LIB.S9S_MB_2U(SCH_1):M_F_CPU1_SA_DQS_DP(7)
DY67 M_F_CPU1_SA_DQS_DP<6> DDR5_SA_DQS_DP6 @S9S_MB_2U_LIB.S9S_MB_2U(SCH_1):M_F_CPU1_SA_DQS_DP(6)
EG76 M_F_CPU1_SA_DQS_DP<5> DDR5_SA_DQS_DP5 @S9S_MB_2U_LIB.S9S_MB_2U(SCH_1):M_F_CPU1_SA_DQS_DP(5)
EC58 M_F_CPU1_SA_DQS_DP<4> DDR5_SA_DQS_DP4 @S9S_MB_2U_LIB.S9S_MB_2U(SCH_1):M_F_CPU1_SA_DQS_DP(4)
DT55 M_F_CPU1_SA_DQS_DP<3> DDR5_SA_DQS_DP3 @S9S_MB_2U_LIB.S9S_MB_2U(SCH_1):M_F_CPU1_SA_DQS_DP(3)
EE64 M_F_CPU1_SA_DQS_DP<2> DDR5_SA_DQS_DP2 @S9S_MB_2U_LIB.S9S_MB_2U(SCH_1):M_F_CPU1_SA_DQS_DP(2)
DV67 M_F_CPU1_SA_DQS_DP<1> DDR5_SA_DQS_DP1 @S9S_MB_2U_LIB.S9S_MB_2U(SCH_1):M_F_CPU1_SA_DQS_DP(1)
EC76 M_F_CPU1_SA_DQS_DP<0> DDR5_SA_DQS_DP0 @S9S_MB_2U_LIB.S9S_MB_2U(SCH_1):M_F_CPU1_SA_DQS_DP(0)
EG56 M_F_CPU1_SA_CB<7> DDR5_SA_ECC7 @S9S_MB_2U_LIB.S9S_MB_2U(SCH_1):M_F_CPU1_SA_CB(7)
EH57 M_F_CPU1_SA_CB<6> DDR5_SA_ECC6 @S9S_MB_2U_LIB.S9S_MB_2U(SCH_1):M_F_CPU1_SA_CB(6)
EE56 M_F_CPU1_SA_CB<5> DDR5_SA_ECC5 @S9S_MB_2U_LIB.S9S_MB_2U(SCH_1):M_F_CPU1_SA_CB(5)
ED57 M_F_CPU1_SA_CB<4> DDR5_SA_ECC4 @S9S_MB_2U_LIB.S9S_MB_2U(SCH_1):M_F_CPU1_SA_CB(4)
EH59 M_F_CPU1_SA_CB<3> DDR5_SA_ECC3 @S9S_MB_2U_LIB.S9S_MB_2U(SCH_1):M_F_CPU1_SA_CB(3)
EG60 M_F_CPU1_SA_CB<2> DDR5_SA_ECC2 @S9S_MB_2U_LIB.S9S_MB_2U(SCH_1):M_F_CPU1_SA_CB(2)
ED59 M_F_CPU1_SA_CB<1> DDR5_SA_ECC1 @S9S_MB_2U_LIB.S9S_MB_2U(SCH_1):M_F_CPU1_SA_CB(1)
EE60 M_F_CPU1_SA_CB<0> DDR5_SA_ECC0 @S9S_MB_2U_LIB.S9S_MB_2U(SCH_1):M_F_CPU1_SA_CB(0)
EA50 M_F_CPU1_SA_PAR DDR5_SA_PAR @S9S_MB_2U_LIB.S9S_MB_2U(SCH_1):M_F_CPU1_SA_PAR
EC39 M_F_CPU1_SB_CA<6> DDR5_SB_CA6 @S9S_MB_2U_LIB.S9S_MB_2U(SCH_1):M_F_CPU1_SB_CA(6)
EH40 M_F_CPU1_SB_CA<5> DDR5_SB_CA5 @S9S_MB_2U_LIB.S9S_MB_2U(SCH_1):M_F_CPU1_SB_CA(5)
ED40 M_F_CPU1_SB_CA<4> DDR5_SB_CA4 @S9S_MB_2U_LIB.S9S_MB_2U(SCH_1):M_F_CPU1_SB_CA(4)
EG41 M_F_CPU1_SB_CA<3> DDR5_SB_CA3 @S9S_MB_2U_LIB.S9S_MB_2U(SCH_1):M_F_CPU1_SB_CA(3)
EE41 M_F_CPU1_SB_CA<2> DDR5_SB_CA2 @S9S_MB_2U_LIB.S9S_MB_2U(SCH_1):M_F_CPU1_SB_CA(2)
DU50 M_F_CPU1_SB_CA<1> DDR5_SB_CA1 @S9S_MB_2U_LIB.S9S_MB_2U(SCH_1):M_F_CPU1_SB_CA(1)
DV51 M_F_CPU1_SB_CA<0> DDR5_SB_CA0 @S9S_MB_2U_LIB.S9S_MB_2U(SCH_1):M_F_CPU1_SB_CA(0)
EE37 M_F_CPU1_SB_CS_N<3> DDR5_SB_CS_N3 @S9S_MB_2U_LIB.S9S_MB_2U(SCH_1):M_F_CPU1_SB_CS_N(3)
ED38 M_F_CPU1_SB_CS_N<2> DDR5_SB_CS_N2 @S9S_MB_2U_LIB.S9S_MB_2U(SCH_1):M_F_CPU1_SB_CS_N(2)
EG37 M_F_CPU1_SB_CS_N<1> DDR5_SB_CS_N1 @S9S_MB_2U_LIB.S9S_MB_2U(SCH_1):M_F_CPU1_SB_CS_N(1)
EH38 M_F_CPU1_SB_CS_N<0> DDR5_SB_CS_N0 @S9S_MB_2U_LIB.S9S_MB_2U(SCH_1):M_F_CPU1_SB_CS_N(0)
DR17 M_F_CPU1_SB_DQ<31> DDR5_SB_DQ31 @S9S_MB_2U_LIB.S9S_MB_2U(SCH_1):M_F_CPU1_SB_DQ(31)
EC17 M_F_CPU1_SB_DQ<30> DDR5_SB_DQ30 @S9S_MB_2U_LIB.S9S_MB_2U(SCH_1):M_F_CPU1_SB_DQ(30)
DU17 M_F_CPU1_SB_DQ<29> DDR5_SB_DQ29 @S9S_MB_2U_LIB.S9S_MB_2U(SCH_1):M_F_CPU1_SB_DQ(29)
EA17 M_F_CPU1_SB_DQ<28> DDR5_SB_DQ28 @S9S_MB_2U_LIB.S9S_MB_2U(SCH_1):M_F_CPU1_SB_DQ(28)
EA19 M_F_CPU1_SB_DQ<27> DDR5_SB_DQ27 @S9S_MB_2U_LIB.S9S_MB_2U(SCH_1):M_F_CPU1_SB_DQ(27)
DY20 M_F_CPU1_SB_DQ<26> DDR5_SB_DQ26 @S9S_MB_2U_LIB.S9S_MB_2U(SCH_1):M_F_CPU1_SB_DQ(26)
DU19 M_F_CPU1_SB_DQ<25> DDR5_SB_DQ25 @S9S_MB_2U_LIB.S9S_MB_2U(SCH_1):M_F_CPU1_SB_DQ(25)
DV20 M_F_CPU1_SB_DQ<24> DDR5_SB_DQ24 @S9S_MB_2U_LIB.S9S_MB_2U(SCH_1):M_F_CPU1_SB_DQ(24)
EP10 M_F_CPU1_SB_DQ<23> DDR5_SB_DQ23 @S9S_MB_2U_LIB.S9S_MB_2U(SCH_1):M_F_CPU1_SB_DQ(23)
ER11 M_F_CPU1_SB_DQ<22> DDR5_SB_DQ22 @S9S_MB_2U_LIB.S9S_MB_2U(SCH_1):M_F_CPU1_SB_DQ(22)
EM10 M_F_CPU1_SB_DQ<21> DDR5_SB_DQ21 @S9S_MB_2U_LIB.S9S_MB_2U(SCH_1):M_F_CPU1_SB_DQ(21)
EL11 M_F_CPU1_SB_DQ<20> DDR5_SB_DQ20 @S9S_MB_2U_LIB.S9S_MB_2U(SCH_1):M_F_CPU1_SB_DQ(20)
ER13 M_F_CPU1_SB_DQ<19> DDR5_SB_DQ19 @S9S_MB_2U_LIB.S9S_MB_2U(SCH_1):M_F_CPU1_SB_DQ(19)
EP14 M_F_CPU1_SB_DQ<18> DDR5_SB_DQ18 @S9S_MB_2U_LIB.S9S_MB_2U(SCH_1):M_F_CPU1_SB_DQ(18)
EL13 M_F_CPU1_SB_DQ<17> DDR5_SB_DQ17 @S9S_MB_2U_LIB.S9S_MB_2U(SCH_1):M_F_CPU1_SB_DQ(17)
EM14 M_F_CPU1_SB_DQ<16> DDR5_SB_DQ16 @S9S_MB_2U_LIB.S9S_MB_2U(SCH_1):M_F_CPU1_SB_DQ(16)
EG19 M_F_CPU1_SB_DQ<15> DDR5_SB_DQ15 @S9S_MB_2U_LIB.S9S_MB_2U(SCH_1):M_F_CPU1_SB_DQ(15)
EH20 M_F_CPU1_SB_DQ<14> DDR5_SB_DQ14 @S9S_MB_2U_LIB.S9S_MB_2U(SCH_1):M_F_CPU1_SB_DQ(14)
EE19 M_F_CPU1_SB_DQ<13> DDR5_SB_DQ13 @S9S_MB_2U_LIB.S9S_MB_2U(SCH_1):M_F_CPU1_SB_DQ(13)
ED20 M_F_CPU1_SB_DQ<12> DDR5_SB_DQ12 @S9S_MB_2U_LIB.S9S_MB_2U(SCH_1):M_F_CPU1_SB_DQ(12)
EH22 M_F_CPU1_SB_DQ<11> DDR5_SB_DQ11 @S9S_MB_2U_LIB.S9S_MB_2U(SCH_1):M_F_CPU1_SB_DQ(11)
EG23 M_F_CPU1_SB_DQ<10> DDR5_SB_DQ10 @S9S_MB_2U_LIB.S9S_MB_2U(SCH_1):M_F_CPU1_SB_DQ(10)
ED22 M_F_CPU1_SB_DQ<9> DDR5_SB_DQ9 @S9S_MB_2U_LIB.S9S_MB_2U(SCH_1):M_F_CPU1_SB_DQ(9)
EE23 M_F_CPU1_SB_DQ<8> DDR5_SB_DQ8 @S9S_MB_2U_LIB.S9S_MB_2U(SCH_1):M_F_CPU1_SB_DQ(8)
DY28 M_F_CPU1_SB_DQ<7> DDR5_SB_DQ7 @S9S_MB_2U_LIB.S9S_MB_2U(SCH_1):M_F_CPU1_SB_DQ(7)
EA29 M_F_CPU1_SB_DQ<6> DDR5_SB_DQ6 @S9S_MB_2U_LIB.S9S_MB_2U(SCH_1):M_F_CPU1_SB_DQ(6)
DV28 M_F_CPU1_SB_DQ<5> DDR5_SB_DQ5 @S9S_MB_2U_LIB.S9S_MB_2U(SCH_1):M_F_CPU1_SB_DQ(5)
DU29 M_F_CPU1_SB_DQ<4> DDR5_SB_DQ4 @S9S_MB_2U_LIB.S9S_MB_2U(SCH_1):M_F_CPU1_SB_DQ(4)
EA31 M_F_CPU1_SB_DQ<3> DDR5_SB_DQ3 @S9S_MB_2U_LIB.S9S_MB_2U(SCH_1):M_F_CPU1_SB_DQ(3)
DY32 M_F_CPU1_SB_DQ<2> DDR5_SB_DQ2 @S9S_MB_2U_LIB.S9S_MB_2U(SCH_1):M_F_CPU1_SB_DQ(2)
DU31 M_F_CPU1_SB_DQ<1> DDR5_SB_DQ1 @S9S_MB_2U_LIB.S9S_MB_2U(SCH_1):M_F_CPU1_SB_DQ(1)
DV32 M_F_CPU1_SB_DQ<0> DDR5_SB_DQ0 @S9S_MB_2U_LIB.S9S_MB_2U(SCH_1):M_F_CPU1_SB_DQ(0)
EE33 M_F_CPU1_SB_DQS_DN<9> DDR5_SB_DQS_DN9 @S9S_MB_2U_LIB.S9S_MB_2U(SCH_1):M_F_CPU1_SB_DQS_DN(9)
DY18 M_F_CPU1_SB_DQS_DN<8> DDR5_SB_DQS_DN8 @S9S_MB_2U_LIB.S9S_MB_2U(SCH_1):M_F_CPU1_SB_DQS_DN(8)
ET12 M_F_CPU1_SB_DQS_DN<7> DDR5_SB_DQS_DN7 @S9S_MB_2U_LIB.S9S_MB_2U(SCH_1):M_F_CPU1_SB_DQS_DN(7)
EJ21 M_F_CPU1_SB_DQS_DN<6> DDR5_SB_DQS_DN6 @S9S_MB_2U_LIB.S9S_MB_2U(SCH_1):M_F_CPU1_SB_DQS_DN(6)
EB30 M_F_CPU1_SB_DQS_DN<5> DDR5_SB_DQS_DN5 @S9S_MB_2U_LIB.S9S_MB_2U(SCH_1):M_F_CPU1_SB_DQS_DN(5)
EJ33 M_F_CPU1_SB_DQS_DN<4> DDR5_SB_DQS_DN4 @S9S_MB_2U_LIB.S9S_MB_2U(SCH_1):M_F_CPU1_SB_DQS_DN(4)
DT18 M_F_CPU1_SB_DQS_DN<3> DDR5_SB_DQS_DN3 @S9S_MB_2U_LIB.S9S_MB_2U(SCH_1):M_F_CPU1_SB_DQS_DN(3)
EM12 M_F_CPU1_SB_DQS_DN<2> DDR5_SB_DQS_DN2 @S9S_MB_2U_LIB.S9S_MB_2U(SCH_1):M_F_CPU1_SB_DQS_DN(2)
EE21 M_F_CPU1_SB_DQS_DN<1> DDR5_SB_DQS_DN1 @S9S_MB_2U_LIB.S9S_MB_2U(SCH_1):M_F_CPU1_SB_DQS_DN(1)
DV30 M_F_CPU1_SB_DQS_DN<0> DDR5_SB_DQS_DN0 @S9S_MB_2U_LIB.S9S_MB_2U(SCH_1):M_F_CPU1_SB_DQS_DN(0)
EC33 M_F_CPU1_SB_DQS_DP<9> DDR5_SB_DQS_DP9 @S9S_MB_2U_LIB.S9S_MB_2U(SCH_1):M_F_CPU1_SB_DQS_DP(9)
EB18 M_F_CPU1_SB_DQS_DP<8> DDR5_SB_DQS_DP8 @S9S_MB_2U_LIB.S9S_MB_2U(SCH_1):M_F_CPU1_SB_DQS_DP(8)
EP12 M_F_CPU1_SB_DQS_DP<7> DDR5_SB_DQS_DP7 @S9S_MB_2U_LIB.S9S_MB_2U(SCH_1):M_F_CPU1_SB_DQS_DP(7)
EG21 M_F_CPU1_SB_DQS_DP<6> DDR5_SB_DQS_DP6 @S9S_MB_2U_LIB.S9S_MB_2U(SCH_1):M_F_CPU1_SB_DQS_DP(6)
DY30 M_F_CPU1_SB_DQS_DP<5> DDR5_SB_DQS_DP5 @S9S_MB_2U_LIB.S9S_MB_2U(SCH_1):M_F_CPU1_SB_DQS_DP(5)
EG33 M_F_CPU1_SB_DQS_DP<4> DDR5_SB_DQS_DP4 @S9S_MB_2U_LIB.S9S_MB_2U(SCH_1):M_F_CPU1_SB_DQS_DP(4)
DV18 M_F_CPU1_SB_DQS_DP<3> DDR5_SB_DQS_DP3 @S9S_MB_2U_LIB.S9S_MB_2U(SCH_1):M_F_CPU1_SB_DQS_DP(3)
EK12 M_F_CPU1_SB_DQS_DP<2> DDR5_SB_DQS_DP2 @S9S_MB_2U_LIB.S9S_MB_2U(SCH_1):M_F_CPU1_SB_DQS_DP(2)
EC21 M_F_CPU1_SB_DQS_DP<1> DDR5_SB_DQS_DP1 @S9S_MB_2U_LIB.S9S_MB_2U(SCH_1):M_F_CPU1_SB_DQS_DP(1)
DT30 M_F_CPU1_SB_DQS_DP<0> DDR5_SB_DQS_DP0 @S9S_MB_2U_LIB.S9S_MB_2U(SCH_1):M_F_CPU1_SB_DQS_DP(0)
EH34 M_F_CPU1_SB_CB<7> DDR5_SB_ECC7 @S9S_MB_2U_LIB.S9S_MB_2U(SCH_1):M_F_CPU1_SB_CB(7)
EG35 M_F_CPU1_SB_CB<6> DDR5_SB_ECC6 @S9S_MB_2U_LIB.S9S_MB_2U(SCH_1):M_F_CPU1_SB_CB(6)
ED34 M_F_CPU1_SB_CB<5> DDR5_SB_ECC5 @S9S_MB_2U_LIB.S9S_MB_2U(SCH_1):M_F_CPU1_SB_CB(5)
EE35 M_F_CPU1_SB_CB<4> DDR5_SB_ECC4 @S9S_MB_2U_LIB.S9S_MB_2U(SCH_1):M_F_CPU1_SB_CB(4)
EG31 M_F_CPU1_SB_CB<3> DDR5_SB_ECC3 @S9S_MB_2U_LIB.S9S_MB_2U(SCH_1):M_F_CPU1_SB_CB(3)
EH32 M_F_CPU1_SB_CB<2> DDR5_SB_ECC2 @S9S_MB_2U_LIB.S9S_MB_2U(SCH_1):M_F_CPU1_SB_CB(2)
EE31 M_F_CPU1_SB_CB<1> DDR5_SB_ECC1 @S9S_MB_2U_LIB.S9S_MB_2U(SCH_1):M_F_CPU1_SB_CB(1)
ED32 M_F_CPU1_SB_CB<0> DDR5_SB_ECC0 @S9S_MB_2U_LIB.S9S_MB_2U(SCH_1):M_F_CPU1_SB_CB(0)
EJ39 M_F_CPU1_SB_PAR DDR5_SB_PAR @S9S_MB_2U_LIB.S9S_MB_2U(SCH_1):M_F_CPU1_SB_PAR


DRAWING: @S9S_MB_2U_LIB.S9S_MB_2U(SCH_1):PAGE57 

SOCKET4677_AZIF0045P001C01CS-SA  I168  U1
CW50 M_G_CPU1_ALERT_N DDR6_ALERT_N @S9S_MB_2U_LIB.S9S_MB_2U(SCH_1):M_G_CPU1_ALERT_N
DY47 M_G_CPU1_SA_RSP<1> DDR6_A_RSP1 @S9S_MB_2U_LIB.S9S_MB_2U(SCH_1):M_G_CPU1_SA_RSP(1)
EA48 M_G_CPU1_SA_RSP<0> DDR6_A_RSP0 @S9S_MB_2U_LIB.S9S_MB_2U(SCH_1):M_G_CPU1_SA_RSP(0)
DV47 M_G_CPU1_SB_RSP<1> DDR6_B_RSP1 @S9S_MB_2U_LIB.S9S_MB_2U(SCH_1):M_G_CPU1_SB_RSP(1)
DU48 M_G_CPU1_SB_RSP<0> DDR6_B_RSP0 @S9S_MB_2U_LIB.S9S_MB_2U(SCH_1):M_G_CPU1_SB_RSP(0)
DL45 M_G_CPU1_CLK_DN<1> DDR6_CLK_DN1 @S9S_MB_2U_LIB.S9S_MB_2U(SCH_1):M_G_CPU1_CLK_DN(1)
DR45 M_G_CPU1_CLK_DN<0> DDR6_CLK_DN0 @S9S_MB_2U_LIB.S9S_MB_2U(SCH_1):M_G_CPU1_CLK_DN(0)
DJ45 M_G_CPU1_CLK_DP<1> DDR6_CLK_DP1 @S9S_MB_2U_LIB.S9S_MB_2U(SCH_1):M_G_CPU1_CLK_DP(1)
DN45 M_G_CPU1_CLK_DP<0> DDR6_CLK_DP0 @S9S_MB_2U_LIB.S9S_MB_2U(SCH_1):M_G_CPU1_CLK_DP(0)
DK44 M_G_CPU1_SA_CA<6> DDR6_SA_CA6 @S9S_MB_2U_LIB.S9S_MB_2U(SCH_1):M_G_CPU1_SA_CA(6)
DN50 M_G_CPU1_SA_CA<5> DDR6_SA_CA5 @S9S_MB_2U_LIB.S9S_MB_2U(SCH_1):M_G_CPU1_SA_CA(5)
DL50 M_G_CPU1_SA_CA<4> DDR6_SA_CA4 @S9S_MB_2U_LIB.S9S_MB_2U(SCH_1):M_G_CPU1_SA_CA(4)
DP51 M_G_CPU1_SA_CA<3> DDR6_SA_CA3 @S9S_MB_2U_LIB.S9S_MB_2U(SCH_1):M_G_CPU1_SA_CA(3)
DK51 M_G_CPU1_SA_CA<2> DDR6_SA_CA2 @S9S_MB_2U_LIB.S9S_MB_2U(SCH_1):M_G_CPU1_SA_CA(2)
DR52 M_G_CPU1_SA_CA<1> DDR6_SA_CA1 @S9S_MB_2U_LIB.S9S_MB_2U(SCH_1):M_G_CPU1_SA_CA(1)
DJ52 M_G_CPU1_SA_CA<0> DDR6_SA_CA0 @S9S_MB_2U_LIB.S9S_MB_2U(SCH_1):M_G_CPU1_SA_CA(0)
DK53 M_G_CPU1_SA_CS_N<3> DDR6_SA_CS_N3 @S9S_MB_2U_LIB.S9S_MB_2U(SCH_1):M_G_CPU1_SA_CS_N(3)
DL54 M_G_CPU1_SA_CS_N<2> DDR6_SA_CS_N2 @S9S_MB_2U_LIB.S9S_MB_2U(SCH_1):M_G_CPU1_SA_CS_N(2)
DP53 M_G_CPU1_SA_CS_N<1> DDR6_SA_CS_N1 @S9S_MB_2U_LIB.S9S_MB_2U(SCH_1):M_G_CPU1_SA_CS_N(1)
DN54 M_G_CPU1_SA_CS_N<0> DDR6_SA_CS_N0 @S9S_MB_2U_LIB.S9S_MB_2U(SCH_1):M_G_CPU1_SA_CS_N(0)
DN62 M_G_CPU1_SA_DQ<31> DDR6_SA_DQ31 @S9S_MB_2U_LIB.S9S_MB_2U(SCH_1):M_G_CPU1_SA_DQ(31)
DP63 M_G_CPU1_SA_DQ<30> DDR6_SA_DQ30 @S9S_MB_2U_LIB.S9S_MB_2U(SCH_1):M_G_CPU1_SA_DQ(30)
DL62 M_G_CPU1_SA_DQ<29> DDR6_SA_DQ29 @S9S_MB_2U_LIB.S9S_MB_2U(SCH_1):M_G_CPU1_SA_DQ(29)
DK63 M_G_CPU1_SA_DQ<28> DDR6_SA_DQ28 @S9S_MB_2U_LIB.S9S_MB_2U(SCH_1):M_G_CPU1_SA_DQ(28)
DP65 M_G_CPU1_SA_DQ<27> DDR6_SA_DQ27 @S9S_MB_2U_LIB.S9S_MB_2U(SCH_1):M_G_CPU1_SA_DQ(27)
DN66 M_G_CPU1_SA_DQ<26> DDR6_SA_DQ26 @S9S_MB_2U_LIB.S9S_MB_2U(SCH_1):M_G_CPU1_SA_DQ(26)
DK65 M_G_CPU1_SA_DQ<25> DDR6_SA_DQ25 @S9S_MB_2U_LIB.S9S_MB_2U(SCH_1):M_G_CPU1_SA_DQ(25)
DL66 M_G_CPU1_SA_DQ<24> DDR6_SA_DQ24 @S9S_MB_2U_LIB.S9S_MB_2U(SCH_1):M_G_CPU1_SA_DQ(24)
DY59 M_G_CPU1_SA_DQ<23> DDR6_SA_DQ23 @S9S_MB_2U_LIB.S9S_MB_2U(SCH_1):M_G_CPU1_SA_DQ(23)
EA60 M_G_CPU1_SA_DQ<22> DDR6_SA_DQ22 @S9S_MB_2U_LIB.S9S_MB_2U(SCH_1):M_G_CPU1_SA_DQ(22)
DV59 M_G_CPU1_SA_DQ<21> DDR6_SA_DQ21 @S9S_MB_2U_LIB.S9S_MB_2U(SCH_1):M_G_CPU1_SA_DQ(21)
DU60 M_G_CPU1_SA_DQ<20> DDR6_SA_DQ20 @S9S_MB_2U_LIB.S9S_MB_2U(SCH_1):M_G_CPU1_SA_DQ(20)
EA62 M_G_CPU1_SA_DQ<19> DDR6_SA_DQ19 @S9S_MB_2U_LIB.S9S_MB_2U(SCH_1):M_G_CPU1_SA_DQ(19)
DY63 M_G_CPU1_SA_DQ<18> DDR6_SA_DQ18 @S9S_MB_2U_LIB.S9S_MB_2U(SCH_1):M_G_CPU1_SA_DQ(18)
DU62 M_G_CPU1_SA_DQ<17> DDR6_SA_DQ17 @S9S_MB_2U_LIB.S9S_MB_2U(SCH_1):M_G_CPU1_SA_DQ(17)
DV63 M_G_CPU1_SA_DQ<16> DDR6_SA_DQ16 @S9S_MB_2U_LIB.S9S_MB_2U(SCH_1):M_G_CPU1_SA_DQ(16)
DN68 M_G_CPU1_SA_DQ<15> DDR6_SA_DQ15 @S9S_MB_2U_LIB.S9S_MB_2U(SCH_1):M_G_CPU1_SA_DQ(15)
DP69 M_G_CPU1_SA_DQ<14> DDR6_SA_DQ14 @S9S_MB_2U_LIB.S9S_MB_2U(SCH_1):M_G_CPU1_SA_DQ(14)
DL68 M_G_CPU1_SA_DQ<13> DDR6_SA_DQ13 @S9S_MB_2U_LIB.S9S_MB_2U(SCH_1):M_G_CPU1_SA_DQ(13)
DK69 M_G_CPU1_SA_DQ<12> DDR6_SA_DQ12 @S9S_MB_2U_LIB.S9S_MB_2U(SCH_1):M_G_CPU1_SA_DQ(12)
DP71 M_G_CPU1_SA_DQ<11> DDR6_SA_DQ11 @S9S_MB_2U_LIB.S9S_MB_2U(SCH_1):M_G_CPU1_SA_DQ(11)
DN72 M_G_CPU1_SA_DQ<10> DDR6_SA_DQ10 @S9S_MB_2U_LIB.S9S_MB_2U(SCH_1):M_G_CPU1_SA_DQ(10)
DK71 M_G_CPU1_SA_DQ<9> DDR6_SA_DQ9 @S9S_MB_2U_LIB.S9S_MB_2U(SCH_1):M_G_CPU1_SA_DQ(9)
DL72 M_G_CPU1_SA_DQ<8> DDR6_SA_DQ8 @S9S_MB_2U_LIB.S9S_MB_2U(SCH_1):M_G_CPU1_SA_DQ(8)
DY71 M_G_CPU1_SA_DQ<7> DDR6_SA_DQ7 @S9S_MB_2U_LIB.S9S_MB_2U(SCH_1):M_G_CPU1_SA_DQ(7)
EA72 M_G_CPU1_SA_DQ<6> DDR6_SA_DQ6 @S9S_MB_2U_LIB.S9S_MB_2U(SCH_1):M_G_CPU1_SA_DQ(6)
DV71 M_G_CPU1_SA_DQ<5> DDR6_SA_DQ5 @S9S_MB_2U_LIB.S9S_MB_2U(SCH_1):M_G_CPU1_SA_DQ(5)
DU72 M_G_CPU1_SA_DQ<4> DDR6_SA_DQ4 @S9S_MB_2U_LIB.S9S_MB_2U(SCH_1):M_G_CPU1_SA_DQ(4)
EA74 M_G_CPU1_SA_DQ<3> DDR6_SA_DQ3 @S9S_MB_2U_LIB.S9S_MB_2U(SCH_1):M_G_CPU1_SA_DQ(3)
DY75 M_G_CPU1_SA_DQ<2> DDR6_SA_DQ2 @S9S_MB_2U_LIB.S9S_MB_2U(SCH_1):M_G_CPU1_SA_DQ(2)
DU74 M_G_CPU1_SA_DQ<1> DDR6_SA_DQ1 @S9S_MB_2U_LIB.S9S_MB_2U(SCH_1):M_G_CPU1_SA_DQ(1)
DV75 M_G_CPU1_SA_DQ<0> DDR6_SA_DQ0 @S9S_MB_2U_LIB.S9S_MB_2U(SCH_1):M_G_CPU1_SA_DQ(0)
DR58 M_G_CPU1_SA_DQS_DN<9> DDR6_SA_DQS_DN9 @S9S_MB_2U_LIB.S9S_MB_2U(SCH_1):M_G_CPU1_SA_DQS_DN(9)
DR64 M_G_CPU1_SA_DQS_DN<8> DDR6_SA_DQS_DN8 @S9S_MB_2U_LIB.S9S_MB_2U(SCH_1):M_G_CPU1_SA_DQS_DN(8)
EB61 M_G_CPU1_SA_DQS_DN<7> DDR6_SA_DQS_DN7 @S9S_MB_2U_LIB.S9S_MB_2U(SCH_1):M_G_CPU1_SA_DQS_DN(7)
DR70 M_G_CPU1_SA_DQS_DN<6> DDR6_SA_DQS_DN6 @S9S_MB_2U_LIB.S9S_MB_2U(SCH_1):M_G_CPU1_SA_DQS_DN(6)
EB73 M_G_CPU1_SA_DQS_DN<5> DDR6_SA_DQS_DN5 @S9S_MB_2U_LIB.S9S_MB_2U(SCH_1):M_G_CPU1_SA_DQS_DN(5)
DL58 M_G_CPU1_SA_DQS_DN<4> DDR6_SA_DQS_DN4 @S9S_MB_2U_LIB.S9S_MB_2U(SCH_1):M_G_CPU1_SA_DQS_DN(4)
DL64 M_G_CPU1_SA_DQS_DN<3> DDR6_SA_DQS_DN3 @S9S_MB_2U_LIB.S9S_MB_2U(SCH_1):M_G_CPU1_SA_DQS_DN(3)
DT61 M_G_CPU1_SA_DQS_DN<2> DDR6_SA_DQS_DN2 @S9S_MB_2U_LIB.S9S_MB_2U(SCH_1):M_G_CPU1_SA_DQS_DN(2)
DJ70 M_G_CPU1_SA_DQS_DN<1> DDR6_SA_DQS_DN1 @S9S_MB_2U_LIB.S9S_MB_2U(SCH_1):M_G_CPU1_SA_DQS_DN(1)
DV73 M_G_CPU1_SA_DQS_DN<0> DDR6_SA_DQS_DN0 @S9S_MB_2U_LIB.S9S_MB_2U(SCH_1):M_G_CPU1_SA_DQS_DN(0)
DN58 M_G_CPU1_SA_DQS_DP<9> DDR6_SA_DQS_DP9 @S9S_MB_2U_LIB.S9S_MB_2U(SCH_1):M_G_CPU1_SA_DQS_DP(9)
DN64 M_G_CPU1_SA_DQS_DP<8> DDR6_SA_DQS_DP8 @S9S_MB_2U_LIB.S9S_MB_2U(SCH_1):M_G_CPU1_SA_DQS_DP(8)
DY61 M_G_CPU1_SA_DQS_DP<7> DDR6_SA_DQS_DP7 @S9S_MB_2U_LIB.S9S_MB_2U(SCH_1):M_G_CPU1_SA_DQS_DP(7)
DN70 M_G_CPU1_SA_DQS_DP<6> DDR6_SA_DQS_DP6 @S9S_MB_2U_LIB.S9S_MB_2U(SCH_1):M_G_CPU1_SA_DQS_DP(6)
DY73 M_G_CPU1_SA_DQS_DP<5> DDR6_SA_DQS_DP5 @S9S_MB_2U_LIB.S9S_MB_2U(SCH_1):M_G_CPU1_SA_DQS_DP(5)
DJ58 M_G_CPU1_SA_DQS_DP<4> DDR6_SA_DQS_DP4 @S9S_MB_2U_LIB.S9S_MB_2U(SCH_1):M_G_CPU1_SA_DQS_DP(4)
DJ64 M_G_CPU1_SA_DQS_DP<3> DDR6_SA_DQS_DP3 @S9S_MB_2U_LIB.S9S_MB_2U(SCH_1):M_G_CPU1_SA_DQS_DP(3)
DV61 M_G_CPU1_SA_DQS_DP<2> DDR6_SA_DQS_DP2 @S9S_MB_2U_LIB.S9S_MB_2U(SCH_1):M_G_CPU1_SA_DQS_DP(2)
DL70 M_G_CPU1_SA_DQS_DP<1> DDR6_SA_DQS_DP1 @S9S_MB_2U_LIB.S9S_MB_2U(SCH_1):M_G_CPU1_SA_DQS_DP(1)
DT73 M_G_CPU1_SA_DQS_DP<0> DDR6_SA_DQS_DP0 @S9S_MB_2U_LIB.S9S_MB_2U(SCH_1):M_G_CPU1_SA_DQS_DP(0)
DN56 M_G_CPU1_SA_CB<7> DDR6_SA_ECC7 @S9S_MB_2U_LIB.S9S_MB_2U(SCH_1):M_G_CPU1_SA_CB(7)
DP57 M_G_CPU1_SA_CB<6> DDR6_SA_ECC6 @S9S_MB_2U_LIB.S9S_MB_2U(SCH_1):M_G_CPU1_SA_CB(6)
DL56 M_G_CPU1_SA_CB<5> DDR6_SA_ECC5 @S9S_MB_2U_LIB.S9S_MB_2U(SCH_1):M_G_CPU1_SA_CB(5)
DK57 M_G_CPU1_SA_CB<4> DDR6_SA_ECC4 @S9S_MB_2U_LIB.S9S_MB_2U(SCH_1):M_G_CPU1_SA_CB(4)
DP59 M_G_CPU1_SA_CB<3> DDR6_SA_ECC3 @S9S_MB_2U_LIB.S9S_MB_2U(SCH_1):M_G_CPU1_SA_CB(3)
DN60 M_G_CPU1_SA_CB<2> DDR6_SA_ECC2 @S9S_MB_2U_LIB.S9S_MB_2U(SCH_1):M_G_CPU1_SA_CB(2)
DK59 M_G_CPU1_SA_CB<1> DDR6_SA_ECC1 @S9S_MB_2U_LIB.S9S_MB_2U(SCH_1):M_G_CPU1_SA_CB(1)
DL60 M_G_CPU1_SA_CB<0> DDR6_SA_ECC0 @S9S_MB_2U_LIB.S9S_MB_2U(SCH_1):M_G_CPU1_SA_CB(0)
DL43 M_G_CPU1_SA_PAR DDR6_SA_PAR @S9S_MB_2U_LIB.S9S_MB_2U(SCH_1):M_G_CPU1_SA_PAR
DT42 M_G_CPU1_SB_CA<6> DDR6_SB_CA6 @S9S_MB_2U_LIB.S9S_MB_2U(SCH_1):M_G_CPU1_SB_CA(6)
EA43 M_G_CPU1_SB_CA<5> DDR6_SB_CA5 @S9S_MB_2U_LIB.S9S_MB_2U(SCH_1):M_G_CPU1_SB_CA(5)
DU43 M_G_CPU1_SB_CA<4> DDR6_SB_CA4 @S9S_MB_2U_LIB.S9S_MB_2U(SCH_1):M_G_CPU1_SB_CA(4)
DY44 M_G_CPU1_SB_CA<3> DDR6_SB_CA3 @S9S_MB_2U_LIB.S9S_MB_2U(SCH_1):M_G_CPU1_SB_CA(3)
DV44 M_G_CPU1_SB_CA<2> DDR6_SB_CA2 @S9S_MB_2U_LIB.S9S_MB_2U(SCH_1):M_G_CPU1_SB_CA(2)
DP44 M_G_CPU1_SB_CA<1> DDR6_SB_CA1 @S9S_MB_2U_LIB.S9S_MB_2U(SCH_1):M_G_CPU1_SB_CA(1)
DN43 M_G_CPU1_SB_CA<0> DDR6_SB_CA0 @S9S_MB_2U_LIB.S9S_MB_2U(SCH_1):M_G_CPU1_SB_CA(0)
DV40 M_G_CPU1_SB_CS_N<3> DDR6_SB_CS_N3 @S9S_MB_2U_LIB.S9S_MB_2U(SCH_1):M_G_CPU1_SB_CS_N(3)
DU41 M_G_CPU1_SB_CS_N<2> DDR6_SB_CS_N2 @S9S_MB_2U_LIB.S9S_MB_2U(SCH_1):M_G_CPU1_SB_CS_N(2)
DY40 M_G_CPU1_SB_CS_N<1> DDR6_SB_CS_N1 @S9S_MB_2U_LIB.S9S_MB_2U(SCH_1):M_G_CPU1_SB_CS_N(1)
EA41 M_G_CPU1_SB_CS_N<0> DDR6_SB_CS_N0 @S9S_MB_2U_LIB.S9S_MB_2U(SCH_1):M_G_CPU1_SB_CS_N(0)
 EM4 M_G_CPU1_SB_DQ<31> DDR6_SB_DQ31 @S9S_MB_2U_LIB.S9S_MB_2U(SCH_1):M_G_CPU1_SB_DQ(31)
 EP4 M_G_CPU1_SB_DQ<30> DDR6_SB_DQ30 @S9S_MB_2U_LIB.S9S_MB_2U(SCH_1):M_G_CPU1_SB_DQ(30)
 EJ5 M_G_CPU1_SB_DQ<29> DDR6_SB_DQ29 @S9S_MB_2U_LIB.S9S_MB_2U(SCH_1):M_G_CPU1_SB_DQ(29)
 EK6 M_G_CPU1_SB_DQ<28> DDR6_SB_DQ28 @S9S_MB_2U_LIB.S9S_MB_2U(SCH_1):M_G_CPU1_SB_DQ(28)
 ET8 M_G_CPU1_SB_DQ<27> DDR6_SB_DQ27 @S9S_MB_2U_LIB.S9S_MB_2U(SCH_1):M_G_CPU1_SB_DQ(27)
 EP8 M_G_CPU1_SB_DQ<26> DDR6_SB_DQ26 @S9S_MB_2U_LIB.S9S_MB_2U(SCH_1):M_G_CPU1_SB_DQ(26)
 EH8 M_G_CPU1_SB_DQ<25> DDR6_SB_DQ25 @S9S_MB_2U_LIB.S9S_MB_2U(SCH_1):M_G_CPU1_SB_DQ(25)
 EK8 M_G_CPU1_SB_DQ<24> DDR6_SB_DQ24 @S9S_MB_2U_LIB.S9S_MB_2U(SCH_1):M_G_CPU1_SB_DQ(24)
DY22 M_G_CPU1_SB_DQ<23> DDR6_SB_DQ23 @S9S_MB_2U_LIB.S9S_MB_2U(SCH_1):M_G_CPU1_SB_DQ(23)
EA23 M_G_CPU1_SB_DQ<22> DDR6_SB_DQ22 @S9S_MB_2U_LIB.S9S_MB_2U(SCH_1):M_G_CPU1_SB_DQ(22)
DV22 M_G_CPU1_SB_DQ<21> DDR6_SB_DQ21 @S9S_MB_2U_LIB.S9S_MB_2U(SCH_1):M_G_CPU1_SB_DQ(21)
DU23 M_G_CPU1_SB_DQ<20> DDR6_SB_DQ20 @S9S_MB_2U_LIB.S9S_MB_2U(SCH_1):M_G_CPU1_SB_DQ(20)
EA25 M_G_CPU1_SB_DQ<19> DDR6_SB_DQ19 @S9S_MB_2U_LIB.S9S_MB_2U(SCH_1):M_G_CPU1_SB_DQ(19)
DY26 M_G_CPU1_SB_DQ<18> DDR6_SB_DQ18 @S9S_MB_2U_LIB.S9S_MB_2U(SCH_1):M_G_CPU1_SB_DQ(18)
DU25 M_G_CPU1_SB_DQ<17> DDR6_SB_DQ17 @S9S_MB_2U_LIB.S9S_MB_2U(SCH_1):M_G_CPU1_SB_DQ(17)
DV26 M_G_CPU1_SB_DQ<16> DDR6_SB_DQ16 @S9S_MB_2U_LIB.S9S_MB_2U(SCH_1):M_G_CPU1_SB_DQ(16)
DN25 M_G_CPU1_SB_DQ<15> DDR6_SB_DQ15 @S9S_MB_2U_LIB.S9S_MB_2U(SCH_1):M_G_CPU1_SB_DQ(15)
DP26 M_G_CPU1_SB_DQ<14> DDR6_SB_DQ14 @S9S_MB_2U_LIB.S9S_MB_2U(SCH_1):M_G_CPU1_SB_DQ(14)
DL25 M_G_CPU1_SB_DQ<13> DDR6_SB_DQ13 @S9S_MB_2U_LIB.S9S_MB_2U(SCH_1):M_G_CPU1_SB_DQ(13)
DK26 M_G_CPU1_SB_DQ<12> DDR6_SB_DQ12 @S9S_MB_2U_LIB.S9S_MB_2U(SCH_1):M_G_CPU1_SB_DQ(12)
DP28 M_G_CPU1_SB_DQ<11> DDR6_SB_DQ11 @S9S_MB_2U_LIB.S9S_MB_2U(SCH_1):M_G_CPU1_SB_DQ(11)
DL29 M_G_CPU1_SB_DQ<10> DDR6_SB_DQ10 @S9S_MB_2U_LIB.S9S_MB_2U(SCH_1):M_G_CPU1_SB_DQ(10)
DK28 M_G_CPU1_SB_DQ<9> DDR6_SB_DQ9 @S9S_MB_2U_LIB.S9S_MB_2U(SCH_1):M_G_CPU1_SB_DQ(9)
DN29 M_G_CPU1_SB_DQ<8> DDR6_SB_DQ8 @S9S_MB_2U_LIB.S9S_MB_2U(SCH_1):M_G_CPU1_SB_DQ(8)
DN31 M_G_CPU1_SB_DQ<7> DDR6_SB_DQ7 @S9S_MB_2U_LIB.S9S_MB_2U(SCH_1):M_G_CPU1_SB_DQ(7)
DP32 M_G_CPU1_SB_DQ<6> DDR6_SB_DQ6 @S9S_MB_2U_LIB.S9S_MB_2U(SCH_1):M_G_CPU1_SB_DQ(6)
DL31 M_G_CPU1_SB_DQ<5> DDR6_SB_DQ5 @S9S_MB_2U_LIB.S9S_MB_2U(SCH_1):M_G_CPU1_SB_DQ(5)
DK32 M_G_CPU1_SB_DQ<4> DDR6_SB_DQ4 @S9S_MB_2U_LIB.S9S_MB_2U(SCH_1):M_G_CPU1_SB_DQ(4)
DP34 M_G_CPU1_SB_DQ<3> DDR6_SB_DQ3 @S9S_MB_2U_LIB.S9S_MB_2U(SCH_1):M_G_CPU1_SB_DQ(3)
DN35 M_G_CPU1_SB_DQ<2> DDR6_SB_DQ2 @S9S_MB_2U_LIB.S9S_MB_2U(SCH_1):M_G_CPU1_SB_DQ(2)
DK34 M_G_CPU1_SB_DQ<1> DDR6_SB_DQ1 @S9S_MB_2U_LIB.S9S_MB_2U(SCH_1):M_G_CPU1_SB_DQ(1)
DL35 M_G_CPU1_SB_DQ<0> DDR6_SB_DQ0 @S9S_MB_2U_LIB.S9S_MB_2U(SCH_1):M_G_CPU1_SB_DQ(0)
DV36 M_G_CPU1_SB_DQS_DN<9> DDR6_SB_DQS_DN9 @S9S_MB_2U_LIB.S9S_MB_2U(SCH_1):M_G_CPU1_SB_DQS_DN(9)
 EM6 M_G_CPU1_SB_DQS_DN<8> DDR6_SB_DQS_DN8 @S9S_MB_2U_LIB.S9S_MB_2U(SCH_1):M_G_CPU1_SB_DQS_DN(8)
EB24 M_G_CPU1_SB_DQS_DN<7> DDR6_SB_DQS_DN7 @S9S_MB_2U_LIB.S9S_MB_2U(SCH_1):M_G_CPU1_SB_DQS_DN(7)
DN27 M_G_CPU1_SB_DQS_DN<6> DDR6_SB_DQS_DN6 @S9S_MB_2U_LIB.S9S_MB_2U(SCH_1):M_G_CPU1_SB_DQS_DN(6)
DR33 M_G_CPU1_SB_DQS_DN<5> DDR6_SB_DQS_DN5 @S9S_MB_2U_LIB.S9S_MB_2U(SCH_1):M_G_CPU1_SB_DQS_DN(5)
EB36 M_G_CPU1_SB_DQS_DN<4> DDR6_SB_DQS_DN4 @S9S_MB_2U_LIB.S9S_MB_2U(SCH_1):M_G_CPU1_SB_DQS_DN(4)
 EP6 M_G_CPU1_SB_DQS_DN<3> DDR6_SB_DQS_DN3 @S9S_MB_2U_LIB.S9S_MB_2U(SCH_1):M_G_CPU1_SB_DQS_DN(3)
DV24 M_G_CPU1_SB_DQS_DN<2> DDR6_SB_DQS_DN2 @S9S_MB_2U_LIB.S9S_MB_2U(SCH_1):M_G_CPU1_SB_DQS_DN(2)
DJ27 M_G_CPU1_SB_DQS_DN<1> DDR6_SB_DQS_DN1 @S9S_MB_2U_LIB.S9S_MB_2U(SCH_1):M_G_CPU1_SB_DQS_DN(1)
DJ33 M_G_CPU1_SB_DQS_DN<0> DDR6_SB_DQS_DN0 @S9S_MB_2U_LIB.S9S_MB_2U(SCH_1):M_G_CPU1_SB_DQS_DN(0)
DT36 M_G_CPU1_SB_DQS_DP<9> DDR6_SB_DQS_DP9 @S9S_MB_2U_LIB.S9S_MB_2U(SCH_1):M_G_CPU1_SB_DQS_DP(9)
 EN5 M_G_CPU1_SB_DQS_DP<8> DDR6_SB_DQS_DP8 @S9S_MB_2U_LIB.S9S_MB_2U(SCH_1):M_G_CPU1_SB_DQS_DP(8)
DY24 M_G_CPU1_SB_DQS_DP<7> DDR6_SB_DQS_DP7 @S9S_MB_2U_LIB.S9S_MB_2U(SCH_1):M_G_CPU1_SB_DQS_DP(7)
DR27 M_G_CPU1_SB_DQS_DP<6> DDR6_SB_DQS_DP6 @S9S_MB_2U_LIB.S9S_MB_2U(SCH_1):M_G_CPU1_SB_DQS_DP(6)
DN33 M_G_CPU1_SB_DQS_DP<5> DDR6_SB_DQS_DP5 @S9S_MB_2U_LIB.S9S_MB_2U(SCH_1):M_G_CPU1_SB_DQS_DP(5)
DY36 M_G_CPU1_SB_DQS_DP<4> DDR6_SB_DQS_DP4 @S9S_MB_2U_LIB.S9S_MB_2U(SCH_1):M_G_CPU1_SB_DQS_DP(4)
 EN7 M_G_CPU1_SB_DQS_DP<3> DDR6_SB_DQS_DP3 @S9S_MB_2U_LIB.S9S_MB_2U(SCH_1):M_G_CPU1_SB_DQS_DP(3)
DT24 M_G_CPU1_SB_DQS_DP<2> DDR6_SB_DQS_DP2 @S9S_MB_2U_LIB.S9S_MB_2U(SCH_1):M_G_CPU1_SB_DQS_DP(2)
DL27 M_G_CPU1_SB_DQS_DP<1> DDR6_SB_DQS_DP1 @S9S_MB_2U_LIB.S9S_MB_2U(SCH_1):M_G_CPU1_SB_DQS_DP(1)
DL33 M_G_CPU1_SB_DQS_DP<0> DDR6_SB_DQS_DP0 @S9S_MB_2U_LIB.S9S_MB_2U(SCH_1):M_G_CPU1_SB_DQS_DP(0)
EA37 M_G_CPU1_SB_CB<7> DDR6_SB_ECC7 @S9S_MB_2U_LIB.S9S_MB_2U(SCH_1):M_G_CPU1_SB_CB(7)
DY38 M_G_CPU1_SB_CB<6> DDR6_SB_ECC6 @S9S_MB_2U_LIB.S9S_MB_2U(SCH_1):M_G_CPU1_SB_CB(6)
DU37 M_G_CPU1_SB_CB<5> DDR6_SB_ECC5 @S9S_MB_2U_LIB.S9S_MB_2U(SCH_1):M_G_CPU1_SB_CB(5)
DV38 M_G_CPU1_SB_CB<4> DDR6_SB_ECC4 @S9S_MB_2U_LIB.S9S_MB_2U(SCH_1):M_G_CPU1_SB_CB(4)
DY34 M_G_CPU1_SB_CB<3> DDR6_SB_ECC3 @S9S_MB_2U_LIB.S9S_MB_2U(SCH_1):M_G_CPU1_SB_CB(3)
EA35 M_G_CPU1_SB_CB<2> DDR6_SB_ECC2 @S9S_MB_2U_LIB.S9S_MB_2U(SCH_1):M_G_CPU1_SB_CB(2)
DV34 M_G_CPU1_SB_CB<1> DDR6_SB_ECC1 @S9S_MB_2U_LIB.S9S_MB_2U(SCH_1):M_G_CPU1_SB_CB(1)
DU35 M_G_CPU1_SB_CB<0> DDR6_SB_ECC0 @S9S_MB_2U_LIB.S9S_MB_2U(SCH_1):M_G_CPU1_SB_CB(0)
EB42 M_G_CPU1_SB_PAR DDR6_SB_PAR @S9S_MB_2U_LIB.S9S_MB_2U(SCH_1):M_G_CPU1_SB_PAR


DRAWING: @S9S_MB_2U_LIB.S9S_MB_2U(SCH_1):PAGE58 

SOCKET4677_AZIF0045P001C01CS-SA  I20  U1
CY51 M_H_CPU1_ALERT_N DDR7_ALERT_N @S9S_MB_2U_LIB.S9S_MB_2U(SCH_1):M_H_CPU1_ALERT_N
EH47 M_H_CPU1_SA_RSP<1> DDR7_A_RSP1 @S9S_MB_2U_LIB.S9S_MB_2U(SCH_1):M_H_CPU1_SA_RSP(1)
EG48 M_H_CPU1_SA_RSP<0> DDR7_A_RSP0 @S9S_MB_2U_LIB.S9S_MB_2U(SCH_1):M_H_CPU1_SA_RSP(0)
ED47 M_H_CPU1_SB_RSP<1> DDR7_B_RSP1 @S9S_MB_2U_LIB.S9S_MB_2U(SCH_1):M_H_CPU1_SB_RSP(1)
EE48 M_H_CPU1_SB_RSP<0> DDR7_B_RSP0 @S9S_MB_2U_LIB.S9S_MB_2U(SCH_1):M_H_CPU1_SB_RSP(0)
DD42 M_H_CPU1_CLK_DN<1> DDR7_CLK_DN1 @S9S_MB_2U_LIB.S9S_MB_2U(SCH_1):M_H_CPU1_CLK_DN(1)
DH42 M_H_CPU1_CLK_DN<0> DDR7_CLK_DN0 @S9S_MB_2U_LIB.S9S_MB_2U(SCH_1):M_H_CPU1_CLK_DN(0)
DB42 M_H_CPU1_CLK_DP<1> DDR7_CLK_DP1 @S9S_MB_2U_LIB.S9S_MB_2U(SCH_1):M_H_CPU1_CLK_DP(1)
DF42 M_H_CPU1_CLK_DP<0> DDR7_CLK_DP0 @S9S_MB_2U_LIB.S9S_MB_2U(SCH_1):M_H_CPU1_CLK_DP(0)
DC41 M_H_CPU1_SA_CA<6> DDR7_SA_CA6 @S9S_MB_2U_LIB.S9S_MB_2U(SCH_1):M_H_CPU1_SA_CA(6)
DF47 M_H_CPU1_SA_CA<5> DDR7_SA_CA5 @S9S_MB_2U_LIB.S9S_MB_2U(SCH_1):M_H_CPU1_SA_CA(5)
DD47 M_H_CPU1_SA_CA<4> DDR7_SA_CA4 @S9S_MB_2U_LIB.S9S_MB_2U(SCH_1):M_H_CPU1_SA_CA(4)
DG48 M_H_CPU1_SA_CA<3> DDR7_SA_CA3 @S9S_MB_2U_LIB.S9S_MB_2U(SCH_1):M_H_CPU1_SA_CA(3)
DC48 M_H_CPU1_SA_CA<2> DDR7_SA_CA2 @S9S_MB_2U_LIB.S9S_MB_2U(SCH_1):M_H_CPU1_SA_CA(2)
DH49 M_H_CPU1_SA_CA<1> DDR7_SA_CA1 @S9S_MB_2U_LIB.S9S_MB_2U(SCH_1):M_H_CPU1_SA_CA(1)
DB49 M_H_CPU1_SA_CA<0> DDR7_SA_CA0 @S9S_MB_2U_LIB.S9S_MB_2U(SCH_1):M_H_CPU1_SA_CA(0)
DC50 M_H_CPU1_SA_CS_N<3> DDR7_SA_CS_N3 @S9S_MB_2U_LIB.S9S_MB_2U(SCH_1):M_H_CPU1_SA_CS_N(3)
DD51 M_H_CPU1_SA_CS_N<2> DDR7_SA_CS_N2 @S9S_MB_2U_LIB.S9S_MB_2U(SCH_1):M_H_CPU1_SA_CS_N(2)
DG50 M_H_CPU1_SA_CS_N<1> DDR7_SA_CS_N1 @S9S_MB_2U_LIB.S9S_MB_2U(SCH_1):M_H_CPU1_SA_CS_N(1)
DF51 M_H_CPU1_SA_CS_N<0> DDR7_SA_CS_N0 @S9S_MB_2U_LIB.S9S_MB_2U(SCH_1):M_H_CPU1_SA_CS_N(0)
DF59 M_H_CPU1_SA_DQ<31> DDR7_SA_DQ31 @S9S_MB_2U_LIB.S9S_MB_2U(SCH_1):M_H_CPU1_SA_DQ(31)
DG60 M_H_CPU1_SA_DQ<30> DDR7_SA_DQ30 @S9S_MB_2U_LIB.S9S_MB_2U(SCH_1):M_H_CPU1_SA_DQ(30)
DD59 M_H_CPU1_SA_DQ<29> DDR7_SA_DQ29 @S9S_MB_2U_LIB.S9S_MB_2U(SCH_1):M_H_CPU1_SA_DQ(29)
DC60 M_H_CPU1_SA_DQ<28> DDR7_SA_DQ28 @S9S_MB_2U_LIB.S9S_MB_2U(SCH_1):M_H_CPU1_SA_DQ(28)
DG62 M_H_CPU1_SA_DQ<27> DDR7_SA_DQ27 @S9S_MB_2U_LIB.S9S_MB_2U(SCH_1):M_H_CPU1_SA_DQ(27)
DF63 M_H_CPU1_SA_DQ<26> DDR7_SA_DQ26 @S9S_MB_2U_LIB.S9S_MB_2U(SCH_1):M_H_CPU1_SA_DQ(26)
DC62 M_H_CPU1_SA_DQ<25> DDR7_SA_DQ25 @S9S_MB_2U_LIB.S9S_MB_2U(SCH_1):M_H_CPU1_SA_DQ(25)
DD63 M_H_CPU1_SA_DQ<24> DDR7_SA_DQ24 @S9S_MB_2U_LIB.S9S_MB_2U(SCH_1):M_H_CPU1_SA_DQ(24)
DF65 M_H_CPU1_SA_DQ<23> DDR7_SA_DQ23 @S9S_MB_2U_LIB.S9S_MB_2U(SCH_1):M_H_CPU1_SA_DQ(23)
DG66 M_H_CPU1_SA_DQ<22> DDR7_SA_DQ22 @S9S_MB_2U_LIB.S9S_MB_2U(SCH_1):M_H_CPU1_SA_DQ(22)
DD65 M_H_CPU1_SA_DQ<21> DDR7_SA_DQ21 @S9S_MB_2U_LIB.S9S_MB_2U(SCH_1):M_H_CPU1_SA_DQ(21)
DC66 M_H_CPU1_SA_DQ<20> DDR7_SA_DQ20 @S9S_MB_2U_LIB.S9S_MB_2U(SCH_1):M_H_CPU1_SA_DQ(20)
DG68 M_H_CPU1_SA_DQ<19> DDR7_SA_DQ19 @S9S_MB_2U_LIB.S9S_MB_2U(SCH_1):M_H_CPU1_SA_DQ(19)
DF69 M_H_CPU1_SA_DQ<18> DDR7_SA_DQ18 @S9S_MB_2U_LIB.S9S_MB_2U(SCH_1):M_H_CPU1_SA_DQ(18)
DC68 M_H_CPU1_SA_DQ<17> DDR7_SA_DQ17 @S9S_MB_2U_LIB.S9S_MB_2U(SCH_1):M_H_CPU1_SA_DQ(17)
DD69 M_H_CPU1_SA_DQ<16> DDR7_SA_DQ16 @S9S_MB_2U_LIB.S9S_MB_2U(SCH_1):M_H_CPU1_SA_DQ(16)
DF71 M_H_CPU1_SA_DQ<15> DDR7_SA_DQ15 @S9S_MB_2U_LIB.S9S_MB_2U(SCH_1):M_H_CPU1_SA_DQ(15)
DG72 M_H_CPU1_SA_DQ<14> DDR7_SA_DQ14 @S9S_MB_2U_LIB.S9S_MB_2U(SCH_1):M_H_CPU1_SA_DQ(14)
DD71 M_H_CPU1_SA_DQ<13> DDR7_SA_DQ13 @S9S_MB_2U_LIB.S9S_MB_2U(SCH_1):M_H_CPU1_SA_DQ(13)
DC72 M_H_CPU1_SA_DQ<12> DDR7_SA_DQ12 @S9S_MB_2U_LIB.S9S_MB_2U(SCH_1):M_H_CPU1_SA_DQ(12)
DG74 M_H_CPU1_SA_DQ<11> DDR7_SA_DQ11 @S9S_MB_2U_LIB.S9S_MB_2U(SCH_1):M_H_CPU1_SA_DQ(11)
DF75 M_H_CPU1_SA_DQ<10> DDR7_SA_DQ10 @S9S_MB_2U_LIB.S9S_MB_2U(SCH_1):M_H_CPU1_SA_DQ(10)
DC74 M_H_CPU1_SA_DQ<9> DDR7_SA_DQ9 @S9S_MB_2U_LIB.S9S_MB_2U(SCH_1):M_H_CPU1_SA_DQ(9)
DD75 M_H_CPU1_SA_DQ<8> DDR7_SA_DQ8 @S9S_MB_2U_LIB.S9S_MB_2U(SCH_1):M_H_CPU1_SA_DQ(8)
DN74 M_H_CPU1_SA_DQ<7> DDR7_SA_DQ7 @S9S_MB_2U_LIB.S9S_MB_2U(SCH_1):M_H_CPU1_SA_DQ(7)
DP75 M_H_CPU1_SA_DQ<6> DDR7_SA_DQ6 @S9S_MB_2U_LIB.S9S_MB_2U(SCH_1):M_H_CPU1_SA_DQ(6)
DL74 M_H_CPU1_SA_DQ<5> DDR7_SA_DQ5 @S9S_MB_2U_LIB.S9S_MB_2U(SCH_1):M_H_CPU1_SA_DQ(5)
DK75 M_H_CPU1_SA_DQ<4> DDR7_SA_DQ4 @S9S_MB_2U_LIB.S9S_MB_2U(SCH_1):M_H_CPU1_SA_DQ(4)
DP77 M_H_CPU1_SA_DQ<3> DDR7_SA_DQ3 @S9S_MB_2U_LIB.S9S_MB_2U(SCH_1):M_H_CPU1_SA_DQ(3)
DW78 M_H_CPU1_SA_DQ<2> DDR7_SA_DQ2 @S9S_MB_2U_LIB.S9S_MB_2U(SCH_1):M_H_CPU1_SA_DQ(2)
DT77 M_H_CPU1_SA_DQ<1> DDR7_SA_DQ1 @S9S_MB_2U_LIB.S9S_MB_2U(SCH_1):M_H_CPU1_SA_DQ(1)
DY79 M_H_CPU1_SA_DQ<0> DDR7_SA_DQ0 @S9S_MB_2U_LIB.S9S_MB_2U(SCH_1):M_H_CPU1_SA_DQ(0)
DH55 M_H_CPU1_SA_DQS_DN<9> DDR7_SA_DQS_DN9 @S9S_MB_2U_LIB.S9S_MB_2U(SCH_1):M_H_CPU1_SA_DQS_DN(9)
DH61 M_H_CPU1_SA_DQS_DN<8> DDR7_SA_DQS_DN8 @S9S_MB_2U_LIB.S9S_MB_2U(SCH_1):M_H_CPU1_SA_DQS_DN(8)
DH67 M_H_CPU1_SA_DQS_DN<7> DDR7_SA_DQS_DN7 @S9S_MB_2U_LIB.S9S_MB_2U(SCH_1):M_H_CPU1_SA_DQS_DN(7)
DH73 M_H_CPU1_SA_DQS_DN<6> DDR7_SA_DQS_DN6 @S9S_MB_2U_LIB.S9S_MB_2U(SCH_1):M_H_CPU1_SA_DQS_DN(6)
DR76 M_H_CPU1_SA_DQS_DN<5> DDR7_SA_DQS_DN5 @S9S_MB_2U_LIB.S9S_MB_2U(SCH_1):M_H_CPU1_SA_DQS_DN(5)
DD55 M_H_CPU1_SA_DQS_DN<4> DDR7_SA_DQS_DN4 @S9S_MB_2U_LIB.S9S_MB_2U(SCH_1):M_H_CPU1_SA_DQS_DN(4)
DD61 M_H_CPU1_SA_DQS_DN<3> DDR7_SA_DQS_DN3 @S9S_MB_2U_LIB.S9S_MB_2U(SCH_1):M_H_CPU1_SA_DQS_DN(3)
DD67 M_H_CPU1_SA_DQS_DN<2> DDR7_SA_DQS_DN2 @S9S_MB_2U_LIB.S9S_MB_2U(SCH_1):M_H_CPU1_SA_DQS_DN(2)
DB73 M_H_CPU1_SA_DQS_DN<1> DDR7_SA_DQS_DN1 @S9S_MB_2U_LIB.S9S_MB_2U(SCH_1):M_H_CPU1_SA_DQS_DN(1)
DJ76 M_H_CPU1_SA_DQS_DN<0> DDR7_SA_DQS_DN0 @S9S_MB_2U_LIB.S9S_MB_2U(SCH_1):M_H_CPU1_SA_DQS_DN(0)
DF55 M_H_CPU1_SA_DQS_DP<9> DDR7_SA_DQS_DP9 @S9S_MB_2U_LIB.S9S_MB_2U(SCH_1):M_H_CPU1_SA_DQS_DP(9)
DF61 M_H_CPU1_SA_DQS_DP<8> DDR7_SA_DQS_DP8 @S9S_MB_2U_LIB.S9S_MB_2U(SCH_1):M_H_CPU1_SA_DQS_DP(8)
DF67 M_H_CPU1_SA_DQS_DP<7> DDR7_SA_DQS_DP7 @S9S_MB_2U_LIB.S9S_MB_2U(SCH_1):M_H_CPU1_SA_DQS_DP(7)
DF73 M_H_CPU1_SA_DQS_DP<6> DDR7_SA_DQS_DP6 @S9S_MB_2U_LIB.S9S_MB_2U(SCH_1):M_H_CPU1_SA_DQS_DP(6)
DN76 M_H_CPU1_SA_DQS_DP<5> DDR7_SA_DQS_DP5 @S9S_MB_2U_LIB.S9S_MB_2U(SCH_1):M_H_CPU1_SA_DQS_DP(5)
DB55 M_H_CPU1_SA_DQS_DP<4> DDR7_SA_DQS_DP4 @S9S_MB_2U_LIB.S9S_MB_2U(SCH_1):M_H_CPU1_SA_DQS_DP(4)
DB61 M_H_CPU1_SA_DQS_DP<3> DDR7_SA_DQS_DP3 @S9S_MB_2U_LIB.S9S_MB_2U(SCH_1):M_H_CPU1_SA_DQS_DP(3)
DB67 M_H_CPU1_SA_DQS_DP<2> DDR7_SA_DQS_DP2 @S9S_MB_2U_LIB.S9S_MB_2U(SCH_1):M_H_CPU1_SA_DQS_DP(2)
DD73 M_H_CPU1_SA_DQS_DP<1> DDR7_SA_DQS_DP1 @S9S_MB_2U_LIB.S9S_MB_2U(SCH_1):M_H_CPU1_SA_DQS_DP(1)
DL76 M_H_CPU1_SA_DQS_DP<0> DDR7_SA_DQS_DP0 @S9S_MB_2U_LIB.S9S_MB_2U(SCH_1):M_H_CPU1_SA_DQS_DP(0)
DF53 M_H_CPU1_SA_CB<7> DDR7_SA_ECC7 @S9S_MB_2U_LIB.S9S_MB_2U(SCH_1):M_H_CPU1_SA_CB(7)
DG54 M_H_CPU1_SA_CB<6> DDR7_SA_ECC6 @S9S_MB_2U_LIB.S9S_MB_2U(SCH_1):M_H_CPU1_SA_CB(6)
DD53 M_H_CPU1_SA_CB<5> DDR7_SA_ECC5 @S9S_MB_2U_LIB.S9S_MB_2U(SCH_1):M_H_CPU1_SA_CB(5)
DC54 M_H_CPU1_SA_CB<4> DDR7_SA_ECC4 @S9S_MB_2U_LIB.S9S_MB_2U(SCH_1):M_H_CPU1_SA_CB(4)
DG56 M_H_CPU1_SA_CB<3> DDR7_SA_ECC3 @S9S_MB_2U_LIB.S9S_MB_2U(SCH_1):M_H_CPU1_SA_CB(3)
DF57 M_H_CPU1_SA_CB<2> DDR7_SA_ECC2 @S9S_MB_2U_LIB.S9S_MB_2U(SCH_1):M_H_CPU1_SA_CB(2)
DC56 M_H_CPU1_SA_CB<1> DDR7_SA_ECC1 @S9S_MB_2U_LIB.S9S_MB_2U(SCH_1):M_H_CPU1_SA_CB(1)
DD57 M_H_CPU1_SA_CB<0> DDR7_SA_ECC0 @S9S_MB_2U_LIB.S9S_MB_2U(SCH_1):M_H_CPU1_SA_CB(0)
DD40 M_H_CPU1_SA_PAR DDR7_SA_PAR @S9S_MB_2U_LIB.S9S_MB_2U(SCH_1):M_H_CPU1_SA_PAR
DJ39 M_H_CPU1_SB_CA<6> DDR7_SB_CA6 @S9S_MB_2U_LIB.S9S_MB_2U(SCH_1):M_H_CPU1_SB_CA(6)
DP40 M_H_CPU1_SB_CA<5> DDR7_SB_CA5 @S9S_MB_2U_LIB.S9S_MB_2U(SCH_1):M_H_CPU1_SB_CA(5)
DK40 M_H_CPU1_SB_CA<4> DDR7_SB_CA4 @S9S_MB_2U_LIB.S9S_MB_2U(SCH_1):M_H_CPU1_SB_CA(4)
DN41 M_H_CPU1_SB_CA<3> DDR7_SB_CA3 @S9S_MB_2U_LIB.S9S_MB_2U(SCH_1):M_H_CPU1_SB_CA(3)
DL41 M_H_CPU1_SB_CA<2> DDR7_SB_CA2 @S9S_MB_2U_LIB.S9S_MB_2U(SCH_1):M_H_CPU1_SB_CA(2)
DG41 M_H_CPU1_SB_CA<1> DDR7_SB_CA1 @S9S_MB_2U_LIB.S9S_MB_2U(SCH_1):M_H_CPU1_SB_CA(1)
DF40 M_H_CPU1_SB_CA<0> DDR7_SB_CA0 @S9S_MB_2U_LIB.S9S_MB_2U(SCH_1):M_H_CPU1_SB_CA(0)
DP38 M_H_CPU1_SB_CS_N<3> DDR7_SB_CS_N3 @S9S_MB_2U_LIB.S9S_MB_2U(SCH_1):M_H_CPU1_SB_CS_N(3)
DK38 M_H_CPU1_SB_CS_N<2> DDR7_SB_CS_N2 @S9S_MB_2U_LIB.S9S_MB_2U(SCH_1):M_H_CPU1_SB_CS_N(2)
DN37 M_H_CPU1_SB_CS_N<1> DDR7_SB_CS_N1 @S9S_MB_2U_LIB.S9S_MB_2U(SCH_1):M_H_CPU1_SB_CS_N(1)
DL37 M_H_CPU1_SB_CS_N<0> DDR7_SB_CS_N0 @S9S_MB_2U_LIB.S9S_MB_2U(SCH_1):M_H_CPU1_SB_CS_N(0)
DC17 M_H_CPU1_SB_DQ<31> DDR7_SB_DQ31 @S9S_MB_2U_LIB.S9S_MB_2U(SCH_1):M_H_CPU1_SB_DQ(31)
DJ17 M_H_CPU1_SB_DQ<30> DDR7_SB_DQ30 @S9S_MB_2U_LIB.S9S_MB_2U(SCH_1):M_H_CPU1_SB_DQ(30)
DA17 M_H_CPU1_SB_DQ<29> DDR7_SB_DQ29 @S9S_MB_2U_LIB.S9S_MB_2U(SCH_1):M_H_CPU1_SB_DQ(29)
DG17 M_H_CPU1_SB_DQ<28> DDR7_SB_DQ28 @S9S_MB_2U_LIB.S9S_MB_2U(SCH_1):M_H_CPU1_SB_DQ(28)
DG19 M_H_CPU1_SB_DQ<27> DDR7_SB_DQ27 @S9S_MB_2U_LIB.S9S_MB_2U(SCH_1):M_H_CPU1_SB_DQ(27)
DF20 M_H_CPU1_SB_DQ<26> DDR7_SB_DQ26 @S9S_MB_2U_LIB.S9S_MB_2U(SCH_1):M_H_CPU1_SB_DQ(26)
DC19 M_H_CPU1_SB_DQ<25> DDR7_SB_DQ25 @S9S_MB_2U_LIB.S9S_MB_2U(SCH_1):M_H_CPU1_SB_DQ(25)
DD20 M_H_CPU1_SB_DQ<24> DDR7_SB_DQ24 @S9S_MB_2U_LIB.S9S_MB_2U(SCH_1):M_H_CPU1_SB_DQ(24)
DN19 M_H_CPU1_SB_DQ<23> DDR7_SB_DQ23 @S9S_MB_2U_LIB.S9S_MB_2U(SCH_1):M_H_CPU1_SB_DQ(23)
DP20 M_H_CPU1_SB_DQ<22> DDR7_SB_DQ22 @S9S_MB_2U_LIB.S9S_MB_2U(SCH_1):M_H_CPU1_SB_DQ(22)
DL19 M_H_CPU1_SB_DQ<21> DDR7_SB_DQ21 @S9S_MB_2U_LIB.S9S_MB_2U(SCH_1):M_H_CPU1_SB_DQ(21)
DK20 M_H_CPU1_SB_DQ<20> DDR7_SB_DQ20 @S9S_MB_2U_LIB.S9S_MB_2U(SCH_1):M_H_CPU1_SB_DQ(20)
DP22 M_H_CPU1_SB_DQ<19> DDR7_SB_DQ19 @S9S_MB_2U_LIB.S9S_MB_2U(SCH_1):M_H_CPU1_SB_DQ(19)
DN23 M_H_CPU1_SB_DQ<18> DDR7_SB_DQ18 @S9S_MB_2U_LIB.S9S_MB_2U(SCH_1):M_H_CPU1_SB_DQ(18)
DK22 M_H_CPU1_SB_DQ<17> DDR7_SB_DQ17 @S9S_MB_2U_LIB.S9S_MB_2U(SCH_1):M_H_CPU1_SB_DQ(17)
DL23 M_H_CPU1_SB_DQ<16> DDR7_SB_DQ16 @S9S_MB_2U_LIB.S9S_MB_2U(SCH_1):M_H_CPU1_SB_DQ(16)
DF22 M_H_CPU1_SB_DQ<15> DDR7_SB_DQ15 @S9S_MB_2U_LIB.S9S_MB_2U(SCH_1):M_H_CPU1_SB_DQ(15)
DG23 M_H_CPU1_SB_DQ<14> DDR7_SB_DQ14 @S9S_MB_2U_LIB.S9S_MB_2U(SCH_1):M_H_CPU1_SB_DQ(14)
DD22 M_H_CPU1_SB_DQ<13> DDR7_SB_DQ13 @S9S_MB_2U_LIB.S9S_MB_2U(SCH_1):M_H_CPU1_SB_DQ(13)
DC23 M_H_CPU1_SB_DQ<12> DDR7_SB_DQ12 @S9S_MB_2U_LIB.S9S_MB_2U(SCH_1):M_H_CPU1_SB_DQ(12)
DG25 M_H_CPU1_SB_DQ<11> DDR7_SB_DQ11 @S9S_MB_2U_LIB.S9S_MB_2U(SCH_1):M_H_CPU1_SB_DQ(11)
DF26 M_H_CPU1_SB_DQ<10> DDR7_SB_DQ10 @S9S_MB_2U_LIB.S9S_MB_2U(SCH_1):M_H_CPU1_SB_DQ(10)
DC25 M_H_CPU1_SB_DQ<9> DDR7_SB_DQ9 @S9S_MB_2U_LIB.S9S_MB_2U(SCH_1):M_H_CPU1_SB_DQ(9)
DD26 M_H_CPU1_SB_DQ<8> DDR7_SB_DQ8 @S9S_MB_2U_LIB.S9S_MB_2U(SCH_1):M_H_CPU1_SB_DQ(8)
DD28 M_H_CPU1_SB_DQ<7> DDR7_SB_DQ7 @S9S_MB_2U_LIB.S9S_MB_2U(SCH_1):M_H_CPU1_SB_DQ(7)
DG29 M_H_CPU1_SB_DQ<6> DDR7_SB_DQ6 @S9S_MB_2U_LIB.S9S_MB_2U(SCH_1):M_H_CPU1_SB_DQ(6)
DF28 M_H_CPU1_SB_DQ<5> DDR7_SB_DQ5 @S9S_MB_2U_LIB.S9S_MB_2U(SCH_1):M_H_CPU1_SB_DQ(5)
DC29 M_H_CPU1_SB_DQ<4> DDR7_SB_DQ4 @S9S_MB_2U_LIB.S9S_MB_2U(SCH_1):M_H_CPU1_SB_DQ(4)
DG31 M_H_CPU1_SB_DQ<3> DDR7_SB_DQ3 @S9S_MB_2U_LIB.S9S_MB_2U(SCH_1):M_H_CPU1_SB_DQ(3)
DF32 M_H_CPU1_SB_DQ<2> DDR7_SB_DQ2 @S9S_MB_2U_LIB.S9S_MB_2U(SCH_1):M_H_CPU1_SB_DQ(2)
DC31 M_H_CPU1_SB_DQ<1> DDR7_SB_DQ1 @S9S_MB_2U_LIB.S9S_MB_2U(SCH_1):M_H_CPU1_SB_DQ(1)
DD32 M_H_CPU1_SB_DQ<0> DDR7_SB_DQ0 @S9S_MB_2U_LIB.S9S_MB_2U(SCH_1):M_H_CPU1_SB_DQ(0)
DD36 M_H_CPU1_SB_DQS_DN<9> DDR7_SB_DQS_DN9 @S9S_MB_2U_LIB.S9S_MB_2U(SCH_1):M_H_CPU1_SB_DQS_DN(9)
DF18 M_H_CPU1_SB_DQS_DN<8> DDR7_SB_DQS_DN8 @S9S_MB_2U_LIB.S9S_MB_2U(SCH_1):M_H_CPU1_SB_DQS_DN(8)
DR21 M_H_CPU1_SB_DQS_DN<7> DDR7_SB_DQS_DN7 @S9S_MB_2U_LIB.S9S_MB_2U(SCH_1):M_H_CPU1_SB_DQS_DN(7)
DH24 M_H_CPU1_SB_DQS_DN<6> DDR7_SB_DQS_DN6 @S9S_MB_2U_LIB.S9S_MB_2U(SCH_1):M_H_CPU1_SB_DQS_DN(6)
DH30 M_H_CPU1_SB_DQS_DN<5> DDR7_SB_DQS_DN5 @S9S_MB_2U_LIB.S9S_MB_2U(SCH_1):M_H_CPU1_SB_DQS_DN(5)
DH36 M_H_CPU1_SB_DQS_DN<4> DDR7_SB_DQS_DN4 @S9S_MB_2U_LIB.S9S_MB_2U(SCH_1):M_H_CPU1_SB_DQS_DN(4)
DB18 M_H_CPU1_SB_DQS_DN<3> DDR7_SB_DQS_DN3 @S9S_MB_2U_LIB.S9S_MB_2U(SCH_1):M_H_CPU1_SB_DQS_DN(3)
DL21 M_H_CPU1_SB_DQS_DN<2> DDR7_SB_DQS_DN2 @S9S_MB_2U_LIB.S9S_MB_2U(SCH_1):M_H_CPU1_SB_DQS_DN(2)
DD24 M_H_CPU1_SB_DQS_DN<1> DDR7_SB_DQS_DN1 @S9S_MB_2U_LIB.S9S_MB_2U(SCH_1):M_H_CPU1_SB_DQS_DN(1)
DD30 M_H_CPU1_SB_DQS_DN<0> DDR7_SB_DQS_DN0 @S9S_MB_2U_LIB.S9S_MB_2U(SCH_1):M_H_CPU1_SB_DQS_DN(0)
DB36 M_H_CPU1_SB_DQS_DP<9> DDR7_SB_DQS_DP9 @S9S_MB_2U_LIB.S9S_MB_2U(SCH_1):M_H_CPU1_SB_DQS_DP(9)
DH18 M_H_CPU1_SB_DQS_DP<8> DDR7_SB_DQS_DP8 @S9S_MB_2U_LIB.S9S_MB_2U(SCH_1):M_H_CPU1_SB_DQS_DP(8)
DN21 M_H_CPU1_SB_DQS_DP<7> DDR7_SB_DQS_DP7 @S9S_MB_2U_LIB.S9S_MB_2U(SCH_1):M_H_CPU1_SB_DQS_DP(7)
DF24 M_H_CPU1_SB_DQS_DP<6> DDR7_SB_DQS_DP6 @S9S_MB_2U_LIB.S9S_MB_2U(SCH_1):M_H_CPU1_SB_DQS_DP(6)
DF30 M_H_CPU1_SB_DQS_DP<5> DDR7_SB_DQS_DP5 @S9S_MB_2U_LIB.S9S_MB_2U(SCH_1):M_H_CPU1_SB_DQS_DP(5)
DF36 M_H_CPU1_SB_DQS_DP<4> DDR7_SB_DQS_DP4 @S9S_MB_2U_LIB.S9S_MB_2U(SCH_1):M_H_CPU1_SB_DQS_DP(4)
DD18 M_H_CPU1_SB_DQS_DP<3> DDR7_SB_DQS_DP3 @S9S_MB_2U_LIB.S9S_MB_2U(SCH_1):M_H_CPU1_SB_DQS_DP(3)
DJ21 M_H_CPU1_SB_DQS_DP<2> DDR7_SB_DQS_DP2 @S9S_MB_2U_LIB.S9S_MB_2U(SCH_1):M_H_CPU1_SB_DQS_DP(2)
DB24 M_H_CPU1_SB_DQS_DP<1> DDR7_SB_DQS_DP1 @S9S_MB_2U_LIB.S9S_MB_2U(SCH_1):M_H_CPU1_SB_DQS_DP(1)
DB30 M_H_CPU1_SB_DQS_DP<0> DDR7_SB_DQS_DP0 @S9S_MB_2U_LIB.S9S_MB_2U(SCH_1):M_H_CPU1_SB_DQS_DP(0)
DC37 M_H_CPU1_SB_CB<7> DDR7_SB_ECC7 @S9S_MB_2U_LIB.S9S_MB_2U(SCH_1):M_H_CPU1_SB_CB(7)
DD38 M_H_CPU1_SB_CB<6> DDR7_SB_ECC6 @S9S_MB_2U_LIB.S9S_MB_2U(SCH_1):M_H_CPU1_SB_CB(6)
DG37 M_H_CPU1_SB_CB<5> DDR7_SB_ECC5 @S9S_MB_2U_LIB.S9S_MB_2U(SCH_1):M_H_CPU1_SB_CB(5)
DF38 M_H_CPU1_SB_CB<4> DDR7_SB_ECC4 @S9S_MB_2U_LIB.S9S_MB_2U(SCH_1):M_H_CPU1_SB_CB(4)
DF34 M_H_CPU1_SB_CB<3> DDR7_SB_ECC3 @S9S_MB_2U_LIB.S9S_MB_2U(SCH_1):M_H_CPU1_SB_CB(3)
DG35 M_H_CPU1_SB_CB<2> DDR7_SB_ECC2 @S9S_MB_2U_LIB.S9S_MB_2U(SCH_1):M_H_CPU1_SB_CB(2)
DD34 M_H_CPU1_SB_CB<1> DDR7_SB_ECC1 @S9S_MB_2U_LIB.S9S_MB_2U(SCH_1):M_H_CPU1_SB_CB(1)
DC35 M_H_CPU1_SB_CB<0> DDR7_SB_ECC0 @S9S_MB_2U_LIB.S9S_MB_2U(SCH_1):M_H_CPU1_SB_CB(0)
DR39 M_H_CPU1_SB_PAR DDR7_SB_PAR @S9S_MB_2U_LIB.S9S_MB_2U(SCH_1):M_H_CPU1_SB_PAR


DRAWING: @S9S_MB_2U_LIB.S9S_MB_2U(SCH_1):PAGE59 

SOCKET4677_AZIF0045P001C01CS-SA  I20  U1
BU17 TP_DMI_CPU1_PCH_RX_C_DN<7> DMI_RX_DN7 @S9S_MB_2U_LIB.S9S_MB_2U(SCH_1):TP_DMI_CPU1_PCH_RX_C_DN(7)
BP18 TP_DMI_CPU1_PCH_RX_C_DN<6> DMI_RX_DN6 @S9S_MB_2U_LIB.S9S_MB_2U(SCH_1):TP_DMI_CPU1_PCH_RX_C_DN(6)
BN17 TP_DMI_CPU1_PCH_RX_C_DN<5> DMI_RX_DN5 @S9S_MB_2U_LIB.S9S_MB_2U(SCH_1):TP_DMI_CPU1_PCH_RX_C_DN(5)
BK18 TP_DMI_CPU1_PCH_RX_C_DN<4> DMI_RX_DN4 @S9S_MB_2U_LIB.S9S_MB_2U(SCH_1):TP_DMI_CPU1_PCH_RX_C_DN(4)
BJ17 TP_DMI_CPU1_PCH_RX_C_DN<3> DMI_RX_DN3 @S9S_MB_2U_LIB.S9S_MB_2U(SCH_1):TP_DMI_CPU1_PCH_RX_C_DN(3)
BF18 TP_DMI_CPU1_PCH_RX_C_DN<2> DMI_RX_DN2 @S9S_MB_2U_LIB.S9S_MB_2U(SCH_1):TP_DMI_CPU1_PCH_RX_C_DN(2)
BE17 TP_DMI_CPU1_PCH_RX_C_DN<1> DMI_RX_DN1 @S9S_MB_2U_LIB.S9S_MB_2U(SCH_1):TP_DMI_CPU1_PCH_RX_C_DN(1)
BB18 TP_DMI_CPU1_PCH_RX_C_DN<0> DMI_RX_DN0 @S9S_MB_2U_LIB.S9S_MB_2U(SCH_1):TP_DMI_CPU1_PCH_RX_C_DN(0)
BT18 TP_DMI_CPU1_PCH_RX_C_DP<7> DMI_RX_DP7 @S9S_MB_2U_LIB.S9S_MB_2U(SCH_1):TP_DMI_CPU1_PCH_RX_C_DP(7)
BR19 TP_DMI_CPU1_PCH_RX_C_DP<6> DMI_RX_DP6 @S9S_MB_2U_LIB.S9S_MB_2U(SCH_1):TP_DMI_CPU1_PCH_RX_C_DP(6)
BM18 TP_DMI_CPU1_PCH_RX_C_DP<5> DMI_RX_DP5 @S9S_MB_2U_LIB.S9S_MB_2U(SCH_1):TP_DMI_CPU1_PCH_RX_C_DP(5)
BL19 TP_DMI_CPU1_PCH_RX_C_DP<4> DMI_RX_DP4 @S9S_MB_2U_LIB.S9S_MB_2U(SCH_1):TP_DMI_CPU1_PCH_RX_C_DP(4)
BH18 TP_DMI_CPU1_PCH_RX_C_DP<3> DMI_RX_DP3 @S9S_MB_2U_LIB.S9S_MB_2U(SCH_1):TP_DMI_CPU1_PCH_RX_C_DP(3)
BG19 TP_DMI_CPU1_PCH_RX_C_DP<2> DMI_RX_DP2 @S9S_MB_2U_LIB.S9S_MB_2U(SCH_1):TP_DMI_CPU1_PCH_RX_C_DP(2)
BD18 TP_DMI_CPU1_PCH_RX_C_DP<1> DMI_RX_DP1 @S9S_MB_2U_LIB.S9S_MB_2U(SCH_1):TP_DMI_CPU1_PCH_RX_C_DP(1)
BC19 TP_DMI_CPU1_PCH_RX_C_DP<0> DMI_RX_DP0 @S9S_MB_2U_LIB.S9S_MB_2U(SCH_1):TP_DMI_CPU1_PCH_RX_C_DP(0)
CN17 TP_DMI_CPU1_PCH_TX_DN<7> DMI_TX_DN7 @S9S_MB_2U_LIB.S9S_MB_2U(SCH_1):TP_DMI_CPU1_PCH_TX_DN(7)
CK18 TP_DMI_CPU1_PCH_TX_DN<6> DMI_TX_DN6 @S9S_MB_2U_LIB.S9S_MB_2U(SCH_1):TP_DMI_CPU1_PCH_TX_DN(6)
CJ17 TP_DMI_CPU1_PCH_TX_DN<5> DMI_TX_DN5 @S9S_MB_2U_LIB.S9S_MB_2U(SCH_1):TP_DMI_CPU1_PCH_TX_DN(5)
CF18 TP_DMI_CPU1_PCH_TX_DN<4> DMI_TX_DN4 @S9S_MB_2U_LIB.S9S_MB_2U(SCH_1):TP_DMI_CPU1_PCH_TX_DN(4)
CE17 TP_DMI_CPU1_PCH_TX_DN<3> DMI_TX_DN3 @S9S_MB_2U_LIB.S9S_MB_2U(SCH_1):TP_DMI_CPU1_PCH_TX_DN(3)
CB18 TP_DMI_CPU1_PCH_TX_DN<2> DMI_TX_DN2 @S9S_MB_2U_LIB.S9S_MB_2U(SCH_1):TP_DMI_CPU1_PCH_TX_DN(2)
CA17 TP_DMI_CPU1_PCH_TX_DN<1> DMI_TX_DN1 @S9S_MB_2U_LIB.S9S_MB_2U(SCH_1):TP_DMI_CPU1_PCH_TX_DN(1)
BW19 TP_DMI_CPU1_PCH_TX_DN<0> DMI_TX_DN0 @S9S_MB_2U_LIB.S9S_MB_2U(SCH_1):TP_DMI_CPU1_PCH_TX_DN(0)
CM18 TP_DMI_CPU1_PCH_TX_DP<7> DMI_TX_DP7 @S9S_MB_2U_LIB.S9S_MB_2U(SCH_1):TP_DMI_CPU1_PCH_TX_DP(7)
CL19 TP_DMI_CPU1_PCH_TX_DP<6> DMI_TX_DP6 @S9S_MB_2U_LIB.S9S_MB_2U(SCH_1):TP_DMI_CPU1_PCH_TX_DP(6)
CH18 TP_DMI_CPU1_PCH_TX_DP<5> DMI_TX_DP5 @S9S_MB_2U_LIB.S9S_MB_2U(SCH_1):TP_DMI_CPU1_PCH_TX_DP(5)
CG19 TP_DMI_CPU1_PCH_TX_DP<4> DMI_TX_DP4 @S9S_MB_2U_LIB.S9S_MB_2U(SCH_1):TP_DMI_CPU1_PCH_TX_DP(4)
CD18 TP_DMI_CPU1_PCH_TX_DP<3> DMI_TX_DP3 @S9S_MB_2U_LIB.S9S_MB_2U(SCH_1):TP_DMI_CPU1_PCH_TX_DP(3)
CC19 TP_DMI_CPU1_PCH_TX_DP<2> DMI_TX_DP2 @S9S_MB_2U_LIB.S9S_MB_2U(SCH_1):TP_DMI_CPU1_PCH_TX_DP(2)
BY18 TP_DMI_CPU1_PCH_TX_DP<1> DMI_TX_DP1 @S9S_MB_2U_LIB.S9S_MB_2U(SCH_1):TP_DMI_CPU1_PCH_TX_DP(1)
CA19 TP_DMI_CPU1_PCH_TX_DP<0> DMI_TX_DP0 @S9S_MB_2U_LIB.S9S_MB_2U(SCH_1):TP_DMI_CPU1_PCH_TX_DP(0)


DRAWING: @S9S_MB_2U_LIB.S9S_MB_2U(SCH_1):PAGE60 

SOCKET4677_AZIF0045P001C01CS-SA  I69  U1
BC11 P5E_CPU1_PE1_RX_DN<15> PE1_RX_DN15 @S9S_MB_2U_LIB.S9S_MB_2U(SCH_1):P5E_CPU1_PE1_RX_DN(15)
BF10 P5E_CPU1_PE1_RX_DN<14> PE1_RX_DN14 @S9S_MB_2U_LIB.S9S_MB_2U(SCH_1):P5E_CPU1_PE1_RX_DN(14)
BG11 P5E_CPU1_PE1_RX_DN<13> PE1_RX_DN13 @S9S_MB_2U_LIB.S9S_MB_2U(SCH_1):P5E_CPU1_PE1_RX_DN(13)
BK10 P5E_CPU1_PE1_RX_DN<12> PE1_RX_DN12 @S9S_MB_2U_LIB.S9S_MB_2U(SCH_1):P5E_CPU1_PE1_RX_DN(12)
BL11 P5E_CPU1_PE1_RX_DN<11> PE1_RX_DN11 @S9S_MB_2U_LIB.S9S_MB_2U(SCH_1):P5E_CPU1_PE1_RX_DN(11)
BP10 P5E_CPU1_PE1_RX_DN<10> PE1_RX_DN10 @S9S_MB_2U_LIB.S9S_MB_2U(SCH_1):P5E_CPU1_PE1_RX_DN(10)
BR11 P5E_CPU1_PE1_RX_DN<9> PE1_RX_DN9 @S9S_MB_2U_LIB.S9S_MB_2U(SCH_1):P5E_CPU1_PE1_RX_DN(9)
BV10 P5E_CPU1_PE1_RX_DN<8> PE1_RX_DN8 @S9S_MB_2U_LIB.S9S_MB_2U(SCH_1):P5E_CPU1_PE1_RX_DN(8)
BW11 P5E_CPU1_PE1_RX_DN<7> PE1_RX_DN7 @S9S_MB_2U_LIB.S9S_MB_2U(SCH_1):P5E_CPU1_PE1_RX_DN(7)
CB10 P5E_CPU1_PE1_RX_DN<6> PE1_RX_DN6 @S9S_MB_2U_LIB.S9S_MB_2U(SCH_1):P5E_CPU1_PE1_RX_DN(6)
CC11 P5E_CPU1_PE1_RX_DN<5> PE1_RX_DN5 @S9S_MB_2U_LIB.S9S_MB_2U(SCH_1):P5E_CPU1_PE1_RX_DN(5)
CF10 P5E_CPU1_PE1_RX_DN<4> PE1_RX_DN4 @S9S_MB_2U_LIB.S9S_MB_2U(SCH_1):P5E_CPU1_PE1_RX_DN(4)
CG11 P5E_CPU1_PE1_RX_DN<3> PE1_RX_DN3 @S9S_MB_2U_LIB.S9S_MB_2U(SCH_1):P5E_CPU1_PE1_RX_DN(3)
CK10 P5E_CPU1_PE1_RX_DN<2> PE1_RX_DN2 @S9S_MB_2U_LIB.S9S_MB_2U(SCH_1):P5E_CPU1_PE1_RX_DN(2)
CL11 P5E_CPU1_PE1_RX_DN<1> PE1_RX_DN1 @S9S_MB_2U_LIB.S9S_MB_2U(SCH_1):P5E_CPU1_PE1_RX_DN(1)
CP10 P5E_CPU1_PE1_RX_DN<0> PE1_RX_DN0 @S9S_MB_2U_LIB.S9S_MB_2U(SCH_1):P5E_CPU1_PE1_RX_DN(0)
BD10 P5E_CPU1_PE1_RX_DP<15> PE1_RX_DP15 @S9S_MB_2U_LIB.S9S_MB_2U(SCH_1):P5E_CPU1_PE1_RX_DP(15)
 BE9 P5E_CPU1_PE1_RX_DP<14> PE1_RX_DP14 @S9S_MB_2U_LIB.S9S_MB_2U(SCH_1):P5E_CPU1_PE1_RX_DP(14)
BH10 P5E_CPU1_PE1_RX_DP<13> PE1_RX_DP13 @S9S_MB_2U_LIB.S9S_MB_2U(SCH_1):P5E_CPU1_PE1_RX_DP(13)
 BJ9 P5E_CPU1_PE1_RX_DP<12> PE1_RX_DP12 @S9S_MB_2U_LIB.S9S_MB_2U(SCH_1):P5E_CPU1_PE1_RX_DP(12)
BM10 P5E_CPU1_PE1_RX_DP<11> PE1_RX_DP11 @S9S_MB_2U_LIB.S9S_MB_2U(SCH_1):P5E_CPU1_PE1_RX_DP(11)
 BN9 P5E_CPU1_PE1_RX_DP<10> PE1_RX_DP10 @S9S_MB_2U_LIB.S9S_MB_2U(SCH_1):P5E_CPU1_PE1_RX_DP(10)
BT10 P5E_CPU1_PE1_RX_DP<9> PE1_RX_DP9 @S9S_MB_2U_LIB.S9S_MB_2U(SCH_1):P5E_CPU1_PE1_RX_DP(9)
 BU9 P5E_CPU1_PE1_RX_DP<8> PE1_RX_DP8 @S9S_MB_2U_LIB.S9S_MB_2U(SCH_1):P5E_CPU1_PE1_RX_DP(8)
BY10 P5E_CPU1_PE1_RX_DP<7> PE1_RX_DP7 @S9S_MB_2U_LIB.S9S_MB_2U(SCH_1):P5E_CPU1_PE1_RX_DP(7)
 CA9 P5E_CPU1_PE1_RX_DP<6> PE1_RX_DP6 @S9S_MB_2U_LIB.S9S_MB_2U(SCH_1):P5E_CPU1_PE1_RX_DP(6)
CD10 P5E_CPU1_PE1_RX_DP<5> PE1_RX_DP5 @S9S_MB_2U_LIB.S9S_MB_2U(SCH_1):P5E_CPU1_PE1_RX_DP(5)
 CE9 P5E_CPU1_PE1_RX_DP<4> PE1_RX_DP4 @S9S_MB_2U_LIB.S9S_MB_2U(SCH_1):P5E_CPU1_PE1_RX_DP(4)
CH10 P5E_CPU1_PE1_RX_DP<3> PE1_RX_DP3 @S9S_MB_2U_LIB.S9S_MB_2U(SCH_1):P5E_CPU1_PE1_RX_DP(3)
 CJ9 P5E_CPU1_PE1_RX_DP<2> PE1_RX_DP2 @S9S_MB_2U_LIB.S9S_MB_2U(SCH_1):P5E_CPU1_PE1_RX_DP(2)
CM10 P5E_CPU1_PE1_RX_DP<1> PE1_RX_DP1 @S9S_MB_2U_LIB.S9S_MB_2U(SCH_1):P5E_CPU1_PE1_RX_DP(1)
 CN9 P5E_CPU1_PE1_RX_DP<0> PE1_RX_DP0 @S9S_MB_2U_LIB.S9S_MB_2U(SCH_1):P5E_CPU1_PE1_RX_DP(0)
BE13 P5E_CPU1_PE1_TX_DN<15> PE1_TX_DN15 @S9S_MB_2U_LIB.S9S_MB_2U(SCH_1):P5E_CPU1_PE1_TX_DN(15)
BF14 P5E_CPU1_PE1_TX_DN<14> PE1_TX_DN14 @S9S_MB_2U_LIB.S9S_MB_2U(SCH_1):P5E_CPU1_PE1_TX_DN(14)
BJ13 P5E_CPU1_PE1_TX_DN<13> PE1_TX_DN13 @S9S_MB_2U_LIB.S9S_MB_2U(SCH_1):P5E_CPU1_PE1_TX_DN(13)
BK14 P5E_CPU1_PE1_TX_DN<12> PE1_TX_DN12 @S9S_MB_2U_LIB.S9S_MB_2U(SCH_1):P5E_CPU1_PE1_TX_DN(12)
BN13 P5E_CPU1_PE1_TX_DN<11> PE1_TX_DN11 @S9S_MB_2U_LIB.S9S_MB_2U(SCH_1):P5E_CPU1_PE1_TX_DN(11)
BP14 P5E_CPU1_PE1_TX_DN<10> PE1_TX_DN10 @S9S_MB_2U_LIB.S9S_MB_2U(SCH_1):P5E_CPU1_PE1_TX_DN(10)
BU13 P5E_CPU1_PE1_TX_DN<9> PE1_TX_DN9 @S9S_MB_2U_LIB.S9S_MB_2U(SCH_1):P5E_CPU1_PE1_TX_DN(9)
BV14 P5E_CPU1_PE1_TX_DN<8> PE1_TX_DN8 @S9S_MB_2U_LIB.S9S_MB_2U(SCH_1):P5E_CPU1_PE1_TX_DN(8)
CA13 P5E_CPU1_PE1_TX_DN<7> PE1_TX_DN7 @S9S_MB_2U_LIB.S9S_MB_2U(SCH_1):P5E_CPU1_PE1_TX_DN(7)
CB14 P5E_CPU1_PE1_TX_DN<6> PE1_TX_DN6 @S9S_MB_2U_LIB.S9S_MB_2U(SCH_1):P5E_CPU1_PE1_TX_DN(6)
CE13 P5E_CPU1_PE1_TX_DN<5> PE1_TX_DN5 @S9S_MB_2U_LIB.S9S_MB_2U(SCH_1):P5E_CPU1_PE1_TX_DN(5)
CF14 P5E_CPU1_PE1_TX_DN<4> PE1_TX_DN4 @S9S_MB_2U_LIB.S9S_MB_2U(SCH_1):P5E_CPU1_PE1_TX_DN(4)
CJ13 P5E_CPU1_PE1_TX_DN<3> PE1_TX_DN3 @S9S_MB_2U_LIB.S9S_MB_2U(SCH_1):P5E_CPU1_PE1_TX_DN(3)
CK14 P5E_CPU1_PE1_TX_DN<2> PE1_TX_DN2 @S9S_MB_2U_LIB.S9S_MB_2U(SCH_1):P5E_CPU1_PE1_TX_DN(2)
CN13 P5E_CPU1_PE1_TX_DN<1> PE1_TX_DN1 @S9S_MB_2U_LIB.S9S_MB_2U(SCH_1):P5E_CPU1_PE1_TX_DN(1)
CP14 P5E_CPU1_PE1_TX_DN<0> PE1_TX_DN0 @S9S_MB_2U_LIB.S9S_MB_2U(SCH_1):P5E_CPU1_PE1_TX_DN(0)
BD14 P5E_CPU1_PE1_TX_DP<15> PE1_TX_DP15 @S9S_MB_2U_LIB.S9S_MB_2U(SCH_1):P5E_CPU1_PE1_TX_DP(15)
BG15 P5E_CPU1_PE1_TX_DP<14> PE1_TX_DP14 @S9S_MB_2U_LIB.S9S_MB_2U(SCH_1):P5E_CPU1_PE1_TX_DP(14)
BH14 P5E_CPU1_PE1_TX_DP<13> PE1_TX_DP13 @S9S_MB_2U_LIB.S9S_MB_2U(SCH_1):P5E_CPU1_PE1_TX_DP(13)
BL15 P5E_CPU1_PE1_TX_DP<12> PE1_TX_DP12 @S9S_MB_2U_LIB.S9S_MB_2U(SCH_1):P5E_CPU1_PE1_TX_DP(12)
BM14 P5E_CPU1_PE1_TX_DP<11> PE1_TX_DP11 @S9S_MB_2U_LIB.S9S_MB_2U(SCH_1):P5E_CPU1_PE1_TX_DP(11)
BR15 P5E_CPU1_PE1_TX_DP<10> PE1_TX_DP10 @S9S_MB_2U_LIB.S9S_MB_2U(SCH_1):P5E_CPU1_PE1_TX_DP(10)
BT14 P5E_CPU1_PE1_TX_DP<9> PE1_TX_DP9 @S9S_MB_2U_LIB.S9S_MB_2U(SCH_1):P5E_CPU1_PE1_TX_DP(9)
BW15 P5E_CPU1_PE1_TX_DP<8> PE1_TX_DP8 @S9S_MB_2U_LIB.S9S_MB_2U(SCH_1):P5E_CPU1_PE1_TX_DP(8)
BY14 P5E_CPU1_PE1_TX_DP<7> PE1_TX_DP7 @S9S_MB_2U_LIB.S9S_MB_2U(SCH_1):P5E_CPU1_PE1_TX_DP(7)
CC15 P5E_CPU1_PE1_TX_DP<6> PE1_TX_DP6 @S9S_MB_2U_LIB.S9S_MB_2U(SCH_1):P5E_CPU1_PE1_TX_DP(6)
CD14 P5E_CPU1_PE1_TX_DP<5> PE1_TX_DP5 @S9S_MB_2U_LIB.S9S_MB_2U(SCH_1):P5E_CPU1_PE1_TX_DP(5)
CG15 P5E_CPU1_PE1_TX_DP<4> PE1_TX_DP4 @S9S_MB_2U_LIB.S9S_MB_2U(SCH_1):P5E_CPU1_PE1_TX_DP(4)
CH14 P5E_CPU1_PE1_TX_DP<3> PE1_TX_DP3 @S9S_MB_2U_LIB.S9S_MB_2U(SCH_1):P5E_CPU1_PE1_TX_DP(3)
CL15 P5E_CPU1_PE1_TX_DP<2> PE1_TX_DP2 @S9S_MB_2U_LIB.S9S_MB_2U(SCH_1):P5E_CPU1_PE1_TX_DP(2)
CM14 P5E_CPU1_PE1_TX_DP<1> PE1_TX_DP1 @S9S_MB_2U_LIB.S9S_MB_2U(SCH_1):P5E_CPU1_PE1_TX_DP(1)
CR15 P5E_CPU1_PE1_TX_DP<0> PE1_TX_DP0 @S9S_MB_2U_LIB.S9S_MB_2U(SCH_1):P5E_CPU1_PE1_TX_DP(0)

SOCKET4677_AZIF0045P001C01CS-SA  I80  U1
 BA9 P5E_CPU1_PE0_RX_DN<15> PE0_RX_DN15 @S9S_MB_2U_LIB.S9S_MB_2U(SCH_1):P5E_CPU1_PE0_RX_DN(15)
AV10 P5E_CPU1_PE0_RX_DN<14> PE0_RX_DN14 @S9S_MB_2U_LIB.S9S_MB_2U(SCH_1):P5E_CPU1_PE0_RX_DN(14)
 AU9 P5E_CPU1_PE0_RX_DN<13> PE0_RX_DN13 @S9S_MB_2U_LIB.S9S_MB_2U(SCH_1):P5E_CPU1_PE0_RX_DN(13)
AP10 P5E_CPU1_PE0_RX_DN<12> PE0_RX_DN12 @S9S_MB_2U_LIB.S9S_MB_2U(SCH_1):P5E_CPU1_PE0_RX_DN(12)
AM10 P5E_CPU1_PE0_RX_DN<11> PE0_RX_DN11 @S9S_MB_2U_LIB.S9S_MB_2U(SCH_1):P5E_CPU1_PE0_RX_DN(11)
AK10 P5E_CPU1_PE0_RX_DN<10> PE0_RX_DN10 @S9S_MB_2U_LIB.S9S_MB_2U(SCH_1):P5E_CPU1_PE0_RX_DN(10)
 AJ9 P5E_CPU1_PE0_RX_DN<9> PE0_RX_DN9 @S9S_MB_2U_LIB.S9S_MB_2U(SCH_1):P5E_CPU1_PE0_RX_DN(9)
AF10 P5E_CPU1_PE0_RX_DN<8> PE0_RX_DN8 @S9S_MB_2U_LIB.S9S_MB_2U(SCH_1):P5E_CPU1_PE0_RX_DN(8)
 AE9 P5E_CPU1_PE0_RX_DN<7> PE0_RX_DN7 @S9S_MB_2U_LIB.S9S_MB_2U(SCH_1):P5E_CPU1_PE0_RX_DN(7)
AB10 P5E_CPU1_PE0_RX_DN<6> PE0_RX_DN6 @S9S_MB_2U_LIB.S9S_MB_2U(SCH_1):P5E_CPU1_PE0_RX_DN(6)
 AA9 P5E_CPU1_PE0_RX_DN<5> PE0_RX_DN5 @S9S_MB_2U_LIB.S9S_MB_2U(SCH_1):P5E_CPU1_PE0_RX_DN(5)
 V10 P5E_CPU1_PE0_RX_DN<4> PE0_RX_DN4 @S9S_MB_2U_LIB.S9S_MB_2U(SCH_1):P5E_CPU1_PE0_RX_DN(4)
 T10 P5E_CPU1_PE0_RX_DN<3> PE0_RX_DN3 @S9S_MB_2U_LIB.S9S_MB_2U(SCH_1):P5E_CPU1_PE0_RX_DN(3)
 P10 P5E_CPU1_PE0_RX_DN<2> PE0_RX_DN2 @S9S_MB_2U_LIB.S9S_MB_2U(SCH_1):P5E_CPU1_PE0_RX_DN(2)
 M10 P5E_CPU1_PE0_RX_DN<1> PE0_RX_DN1 @S9S_MB_2U_LIB.S9S_MB_2U(SCH_1):P5E_CPU1_PE0_RX_DN(1)
 K10 P5E_CPU1_PE0_RX_DN<0> PE0_RX_DN0 @S9S_MB_2U_LIB.S9S_MB_2U(SCH_1):P5E_CPU1_PE0_RX_DN(0)
AY10 P5E_CPU1_PE0_RX_DP<15> PE0_RX_DP15 @S9S_MB_2U_LIB.S9S_MB_2U(SCH_1):P5E_CPU1_PE0_RX_DP(15)
AW11 P5E_CPU1_PE0_RX_DP<14> PE0_RX_DP14 @S9S_MB_2U_LIB.S9S_MB_2U(SCH_1):P5E_CPU1_PE0_RX_DP(14)
AT10 P5E_CPU1_PE0_RX_DP<13> PE0_RX_DP13 @S9S_MB_2U_LIB.S9S_MB_2U(SCH_1):P5E_CPU1_PE0_RX_DP(13)
AR11 P5E_CPU1_PE0_RX_DP<12> PE0_RX_DP12 @S9S_MB_2U_LIB.S9S_MB_2U(SCH_1):P5E_CPU1_PE0_RX_DP(12)
 AN9 P5E_CPU1_PE0_RX_DP<11> PE0_RX_DP11 @S9S_MB_2U_LIB.S9S_MB_2U(SCH_1):P5E_CPU1_PE0_RX_DP(11)
AL11 P5E_CPU1_PE0_RX_DP<10> PE0_RX_DP10 @S9S_MB_2U_LIB.S9S_MB_2U(SCH_1):P5E_CPU1_PE0_RX_DP(10)
AH10 P5E_CPU1_PE0_RX_DP<9> PE0_RX_DP9 @S9S_MB_2U_LIB.S9S_MB_2U(SCH_1):P5E_CPU1_PE0_RX_DP(9)
AG11 P5E_CPU1_PE0_RX_DP<8> PE0_RX_DP8 @S9S_MB_2U_LIB.S9S_MB_2U(SCH_1):P5E_CPU1_PE0_RX_DP(8)
AD10 P5E_CPU1_PE0_RX_DP<7> PE0_RX_DP7 @S9S_MB_2U_LIB.S9S_MB_2U(SCH_1):P5E_CPU1_PE0_RX_DP(7)
AC11 P5E_CPU1_PE0_RX_DP<6> PE0_RX_DP6 @S9S_MB_2U_LIB.S9S_MB_2U(SCH_1):P5E_CPU1_PE0_RX_DP(6)
 Y10 P5E_CPU1_PE0_RX_DP<5> PE0_RX_DP5 @S9S_MB_2U_LIB.S9S_MB_2U(SCH_1):P5E_CPU1_PE0_RX_DP(5)
 W11 P5E_CPU1_PE0_RX_DP<4> PE0_RX_DP4 @S9S_MB_2U_LIB.S9S_MB_2U(SCH_1):P5E_CPU1_PE0_RX_DP(4)
  U9 P5E_CPU1_PE0_RX_DP<3> PE0_RX_DP3 @S9S_MB_2U_LIB.S9S_MB_2U(SCH_1):P5E_CPU1_PE0_RX_DP(3)
 R11 P5E_CPU1_PE0_RX_DP<2> PE0_RX_DP2 @S9S_MB_2U_LIB.S9S_MB_2U(SCH_1):P5E_CPU1_PE0_RX_DP(2)
  N9 P5E_CPU1_PE0_RX_DP<1> PE0_RX_DP1 @S9S_MB_2U_LIB.S9S_MB_2U(SCH_1):P5E_CPU1_PE0_RX_DP(1)
 L11 P5E_CPU1_PE0_RX_DP<0> PE0_RX_DP0 @S9S_MB_2U_LIB.S9S_MB_2U(SCH_1):P5E_CPU1_PE0_RX_DP(0)
BB14 P5E_CPU1_PE0_TX_DN<15> PE0_TX_DN15 @S9S_MB_2U_LIB.S9S_MB_2U(SCH_1):P5E_CPU1_PE0_TX_DN(15)
BA13 P5E_CPU1_PE0_TX_DN<14> PE0_TX_DN14 @S9S_MB_2U_LIB.S9S_MB_2U(SCH_1):P5E_CPU1_PE0_TX_DN(14)
AV14 P5E_CPU1_PE0_TX_DN<13> PE0_TX_DN13 @S9S_MB_2U_LIB.S9S_MB_2U(SCH_1):P5E_CPU1_PE0_TX_DN(13)
AU13 P5E_CPU1_PE0_TX_DN<12> PE0_TX_DN12 @S9S_MB_2U_LIB.S9S_MB_2U(SCH_1):P5E_CPU1_PE0_TX_DN(12)
AP14 P5E_CPU1_PE0_TX_DN<11> PE0_TX_DN11 @S9S_MB_2U_LIB.S9S_MB_2U(SCH_1):P5E_CPU1_PE0_TX_DN(11)
AN13 P5E_CPU1_PE0_TX_DN<10> PE0_TX_DN10 @S9S_MB_2U_LIB.S9S_MB_2U(SCH_1):P5E_CPU1_PE0_TX_DN(10)
AK14 P5E_CPU1_PE0_TX_DN<9> PE0_TX_DN9 @S9S_MB_2U_LIB.S9S_MB_2U(SCH_1):P5E_CPU1_PE0_TX_DN(9)
AJ13 P5E_CPU1_PE0_TX_DN<8> PE0_TX_DN8 @S9S_MB_2U_LIB.S9S_MB_2U(SCH_1):P5E_CPU1_PE0_TX_DN(8)
AF14 P5E_CPU1_PE0_TX_DN<7> PE0_TX_DN7 @S9S_MB_2U_LIB.S9S_MB_2U(SCH_1):P5E_CPU1_PE0_TX_DN(7)
AE13 P5E_CPU1_PE0_TX_DN<6> PE0_TX_DN6 @S9S_MB_2U_LIB.S9S_MB_2U(SCH_1):P5E_CPU1_PE0_TX_DN(6)
AB14 P5E_CPU1_PE0_TX_DN<5> PE0_TX_DN5 @S9S_MB_2U_LIB.S9S_MB_2U(SCH_1):P5E_CPU1_PE0_TX_DN(5)
AA13 P5E_CPU1_PE0_TX_DN<4> PE0_TX_DN4 @S9S_MB_2U_LIB.S9S_MB_2U(SCH_1):P5E_CPU1_PE0_TX_DN(4)
 V14 P5E_CPU1_PE0_TX_DN<3> PE0_TX_DN3 @S9S_MB_2U_LIB.S9S_MB_2U(SCH_1):P5E_CPU1_PE0_TX_DN(3)
 U13 P5E_CPU1_PE0_TX_DN<2> PE0_TX_DN2 @S9S_MB_2U_LIB.S9S_MB_2U(SCH_1):P5E_CPU1_PE0_TX_DN(2)
 P14 P5E_CPU1_PE0_TX_DN<1> PE0_TX_DN1 @S9S_MB_2U_LIB.S9S_MB_2U(SCH_1):P5E_CPU1_PE0_TX_DN(1)
 N13 P5E_CPU1_PE0_TX_DN<0> PE0_TX_DN0 @S9S_MB_2U_LIB.S9S_MB_2U(SCH_1):P5E_CPU1_PE0_TX_DN(0)
BC15 P5E_CPU1_PE0_TX_DP<15> PE0_TX_DP15 @S9S_MB_2U_LIB.S9S_MB_2U(SCH_1):P5E_CPU1_PE0_TX_DP(15)
AY14 P5E_CPU1_PE0_TX_DP<14> PE0_TX_DP14 @S9S_MB_2U_LIB.S9S_MB_2U(SCH_1):P5E_CPU1_PE0_TX_DP(14)
AW15 P5E_CPU1_PE0_TX_DP<13> PE0_TX_DP13 @S9S_MB_2U_LIB.S9S_MB_2U(SCH_1):P5E_CPU1_PE0_TX_DP(13)
AT14 P5E_CPU1_PE0_TX_DP<12> PE0_TX_DP12 @S9S_MB_2U_LIB.S9S_MB_2U(SCH_1):P5E_CPU1_PE0_TX_DP(12)
AR15 P5E_CPU1_PE0_TX_DP<11> PE0_TX_DP11 @S9S_MB_2U_LIB.S9S_MB_2U(SCH_1):P5E_CPU1_PE0_TX_DP(11)
AM14 P5E_CPU1_PE0_TX_DP<10> PE0_TX_DP10 @S9S_MB_2U_LIB.S9S_MB_2U(SCH_1):P5E_CPU1_PE0_TX_DP(10)
AL15 P5E_CPU1_PE0_TX_DP<9> PE0_TX_DP9 @S9S_MB_2U_LIB.S9S_MB_2U(SCH_1):P5E_CPU1_PE0_TX_DP(9)
AH14 P5E_CPU1_PE0_TX_DP<8> PE0_TX_DP8 @S9S_MB_2U_LIB.S9S_MB_2U(SCH_1):P5E_CPU1_PE0_TX_DP(8)
AG15 P5E_CPU1_PE0_TX_DP<7> PE0_TX_DP7 @S9S_MB_2U_LIB.S9S_MB_2U(SCH_1):P5E_CPU1_PE0_TX_DP(7)
AD14 P5E_CPU1_PE0_TX_DP<6> PE0_TX_DP6 @S9S_MB_2U_LIB.S9S_MB_2U(SCH_1):P5E_CPU1_PE0_TX_DP(6)
AC15 P5E_CPU1_PE0_TX_DP<5> PE0_TX_DP5 @S9S_MB_2U_LIB.S9S_MB_2U(SCH_1):P5E_CPU1_PE0_TX_DP(5)
 Y14 P5E_CPU1_PE0_TX_DP<4> PE0_TX_DP4 @S9S_MB_2U_LIB.S9S_MB_2U(SCH_1):P5E_CPU1_PE0_TX_DP(4)
 W15 P5E_CPU1_PE0_TX_DP<3> PE0_TX_DP3 @S9S_MB_2U_LIB.S9S_MB_2U(SCH_1):P5E_CPU1_PE0_TX_DP(3)
 T14 P5E_CPU1_PE0_TX_DP<2> PE0_TX_DP2 @S9S_MB_2U_LIB.S9S_MB_2U(SCH_1):P5E_CPU1_PE0_TX_DP(2)
 R15 P5E_CPU1_PE0_TX_DP<1> PE0_TX_DP1 @S9S_MB_2U_LIB.S9S_MB_2U(SCH_1):P5E_CPU1_PE0_TX_DP(1)
 M14 P5E_CPU1_PE0_TX_DP<0> PE0_TX_DP0 @S9S_MB_2U_LIB.S9S_MB_2U(SCH_1):P5E_CPU1_PE0_TX_DP(0)


DRAWING: @S9S_MB_2U_LIB.S9S_MB_2U(SCH_1):PAGE61 

SOCKET4677_AZIF0045P001C01CS-SA  I12  U1
CU90 P5E_CPU1_PE3_RX_DN<15> PE3_RX_DN15 @S9S_MB_2U_LIB.S9S_MB_2U(SCH_1):P5E_CPU1_PE3_RX_DN(15)
CV89 P5E_CPU1_PE3_RX_DN<14> PE3_RX_DN14 @S9S_MB_2U_LIB.S9S_MB_2U(SCH_1):P5E_CPU1_PE3_RX_DN(14)
DA90 P5E_CPU1_PE3_RX_DN<13> PE3_RX_DN13 @S9S_MB_2U_LIB.S9S_MB_2U(SCH_1):P5E_CPU1_PE3_RX_DN(13)
DB89 P5E_CPU1_PE3_RX_DN<12> PE3_RX_DN12 @S9S_MB_2U_LIB.S9S_MB_2U(SCH_1):P5E_CPU1_PE3_RX_DN(12)
DD91 P5E_CPU1_PE3_RX_DN<11> PE3_RX_DN11 @S9S_MB_2U_LIB.S9S_MB_2U(SCH_1):P5E_CPU1_PE3_RX_DN(11)
DG90 P5E_CPU1_PE3_RX_DN<10> PE3_RX_DN10 @S9S_MB_2U_LIB.S9S_MB_2U(SCH_1):P5E_CPU1_PE3_RX_DN(10)
DH91 P5E_CPU1_PE3_RX_DN<9> PE3_RX_DN9 @S9S_MB_2U_LIB.S9S_MB_2U(SCH_1):P5E_CPU1_PE3_RX_DN(9)
DL90 P5E_CPU1_PE3_RX_DN<8> PE3_RX_DN8 @S9S_MB_2U_LIB.S9S_MB_2U(SCH_1):P5E_CPU1_PE3_RX_DN(8)
DN90 P5E_CPU1_PE3_RX_DN<7> PE3_RX_DN7 @S9S_MB_2U_LIB.S9S_MB_2U(SCH_1):P5E_CPU1_PE3_RX_DN(7)
DP89 P5E_CPU1_PE3_RX_DN<6> PE3_RX_DN6 @S9S_MB_2U_LIB.S9S_MB_2U(SCH_1):P5E_CPU1_PE3_RX_DN(6)
DU90 P5E_CPU1_PE3_RX_DN<5> PE3_RX_DN5 @S9S_MB_2U_LIB.S9S_MB_2U(SCH_1):P5E_CPU1_PE3_RX_DN(5)
DV89 P5E_CPU1_PE3_RX_DN<4> PE3_RX_DN4 @S9S_MB_2U_LIB.S9S_MB_2U(SCH_1):P5E_CPU1_PE3_RX_DN(4)
DY91 P5E_CPU1_PE3_RX_DN<3> PE3_RX_DN3 @S9S_MB_2U_LIB.S9S_MB_2U(SCH_1):P5E_CPU1_PE3_RX_DN(3)
EC90 P5E_CPU1_PE3_RX_DN<2> PE3_RX_DN2 @S9S_MB_2U_LIB.S9S_MB_2U(SCH_1):P5E_CPU1_PE3_RX_DN(2)
ED91 P5E_CPU1_PE3_RX_DN<1> PE3_RX_DN1 @S9S_MB_2U_LIB.S9S_MB_2U(SCH_1):P5E_CPU1_PE3_RX_DN(1)
EH89 P5E_CPU1_PE3_RX_DN<0> PE3_RX_DN0 @S9S_MB_2U_LIB.S9S_MB_2U(SCH_1):P5E_CPU1_PE3_RX_DN(0)
CT91 P5E_CPU1_PE3_RX_DP<15> PE3_RX_DP15 @S9S_MB_2U_LIB.S9S_MB_2U(SCH_1):P5E_CPU1_PE3_RX_DP(15)
CW90 P5E_CPU1_PE3_RX_DP<14> PE3_RX_DP14 @S9S_MB_2U_LIB.S9S_MB_2U(SCH_1):P5E_CPU1_PE3_RX_DP(14)
CY91 P5E_CPU1_PE3_RX_DP<13> PE3_RX_DP13 @S9S_MB_2U_LIB.S9S_MB_2U(SCH_1):P5E_CPU1_PE3_RX_DP(13)
DC90 P5E_CPU1_PE3_RX_DP<12> PE3_RX_DP12 @S9S_MB_2U_LIB.S9S_MB_2U(SCH_1):P5E_CPU1_PE3_RX_DP(12)
DE90 P5E_CPU1_PE3_RX_DP<11> PE3_RX_DP11 @S9S_MB_2U_LIB.S9S_MB_2U(SCH_1):P5E_CPU1_PE3_RX_DP(11)
DF89 P5E_CPU1_PE3_RX_DP<10> PE3_RX_DP10 @S9S_MB_2U_LIB.S9S_MB_2U(SCH_1):P5E_CPU1_PE3_RX_DP(10)
DJ90 P5E_CPU1_PE3_RX_DP<9> PE3_RX_DP9 @S9S_MB_2U_LIB.S9S_MB_2U(SCH_1):P5E_CPU1_PE3_RX_DP(9)
DK89 P5E_CPU1_PE3_RX_DP<8> PE3_RX_DP8 @S9S_MB_2U_LIB.S9S_MB_2U(SCH_1):P5E_CPU1_PE3_RX_DP(8)
DM91 P5E_CPU1_PE3_RX_DP<7> PE3_RX_DP7 @S9S_MB_2U_LIB.S9S_MB_2U(SCH_1):P5E_CPU1_PE3_RX_DP(7)
DR90 P5E_CPU1_PE3_RX_DP<6> PE3_RX_DP6 @S9S_MB_2U_LIB.S9S_MB_2U(SCH_1):P5E_CPU1_PE3_RX_DP(6)
DT91 P5E_CPU1_PE3_RX_DP<5> PE3_RX_DP5 @S9S_MB_2U_LIB.S9S_MB_2U(SCH_1):P5E_CPU1_PE3_RX_DP(5)
DW90 P5E_CPU1_PE3_RX_DP<4> PE3_RX_DP4 @S9S_MB_2U_LIB.S9S_MB_2U(SCH_1):P5E_CPU1_PE3_RX_DP(4)
EA90 P5E_CPU1_PE3_RX_DP<3> PE3_RX_DP3 @S9S_MB_2U_LIB.S9S_MB_2U(SCH_1):P5E_CPU1_PE3_RX_DP(3)
EB89 P5E_CPU1_PE3_RX_DP<2> PE3_RX_DP2 @S9S_MB_2U_LIB.S9S_MB_2U(SCH_1):P5E_CPU1_PE3_RX_DP(2)
EE90 P5E_CPU1_PE3_RX_DP<1> PE3_RX_DP1 @S9S_MB_2U_LIB.S9S_MB_2U(SCH_1):P5E_CPU1_PE3_RX_DP(1)
EJ90 P5E_CPU1_PE3_RX_DP<0> PE3_RX_DP0 @S9S_MB_2U_LIB.S9S_MB_2U(SCH_1):P5E_CPU1_PE3_RX_DP(0)
CP85 P5E_CPU1_PE3_TX_DN<15> PE3_TX_DN15 @S9S_MB_2U_LIB.S9S_MB_2U(SCH_1):P5E_CPU1_PE3_TX_DN(15)
CT87 P5E_CPU1_PE3_TX_DN<14> PE3_TX_DN14 @S9S_MB_2U_LIB.S9S_MB_2U(SCH_1):P5E_CPU1_PE3_TX_DN(14)
CV85 P5E_CPU1_PE3_TX_DN<13> PE3_TX_DN13 @S9S_MB_2U_LIB.S9S_MB_2U(SCH_1):P5E_CPU1_PE3_TX_DN(13)
CY87 P5E_CPU1_PE3_TX_DN<12> PE3_TX_DN12 @S9S_MB_2U_LIB.S9S_MB_2U(SCH_1):P5E_CPU1_PE3_TX_DN(12)
DB85 P5E_CPU1_PE3_TX_DN<11> PE3_TX_DN11 @S9S_MB_2U_LIB.S9S_MB_2U(SCH_1):P5E_CPU1_PE3_TX_DN(11)
DD87 P5E_CPU1_PE3_TX_DN<10> PE3_TX_DN10 @S9S_MB_2U_LIB.S9S_MB_2U(SCH_1):P5E_CPU1_PE3_TX_DN(10)
DF85 P5E_CPU1_PE3_TX_DN<9> PE3_TX_DN9 @S9S_MB_2U_LIB.S9S_MB_2U(SCH_1):P5E_CPU1_PE3_TX_DN(9)
DH87 P5E_CPU1_PE3_TX_DN<8> PE3_TX_DN8 @S9S_MB_2U_LIB.S9S_MB_2U(SCH_1):P5E_CPU1_PE3_TX_DN(8)
DK85 P5E_CPU1_PE3_TX_DN<7> PE3_TX_DN7 @S9S_MB_2U_LIB.S9S_MB_2U(SCH_1):P5E_CPU1_PE3_TX_DN(7)
DM87 P5E_CPU1_PE3_TX_DN<6> PE3_TX_DN6 @S9S_MB_2U_LIB.S9S_MB_2U(SCH_1):P5E_CPU1_PE3_TX_DN(6)
DP85 P5E_CPU1_PE3_TX_DN<5> PE3_TX_DN5 @S9S_MB_2U_LIB.S9S_MB_2U(SCH_1):P5E_CPU1_PE3_TX_DN(5)
DT87 P5E_CPU1_PE3_TX_DN<4> PE3_TX_DN4 @S9S_MB_2U_LIB.S9S_MB_2U(SCH_1):P5E_CPU1_PE3_TX_DN(4)
DV85 P5E_CPU1_PE3_TX_DN<3> PE3_TX_DN3 @S9S_MB_2U_LIB.S9S_MB_2U(SCH_1):P5E_CPU1_PE3_TX_DN(3)
DY87 P5E_CPU1_PE3_TX_DN<2> PE3_TX_DN2 @S9S_MB_2U_LIB.S9S_MB_2U(SCH_1):P5E_CPU1_PE3_TX_DN(2)
EB85 P5E_CPU1_PE3_TX_DN<1> PE3_TX_DN1 @S9S_MB_2U_LIB.S9S_MB_2U(SCH_1):P5E_CPU1_PE3_TX_DN(1)
EE86 P5E_CPU1_PE3_TX_DN<0> PE3_TX_DN0 @S9S_MB_2U_LIB.S9S_MB_2U(SCH_1):P5E_CPU1_PE3_TX_DN(0)
CR86 P5E_CPU1_PE3_TX_DP<15> PE3_TX_DP15 @S9S_MB_2U_LIB.S9S_MB_2U(SCH_1):P5E_CPU1_PE3_TX_DP(15)
CU86 P5E_CPU1_PE3_TX_DP<14> PE3_TX_DP14 @S9S_MB_2U_LIB.S9S_MB_2U(SCH_1):P5E_CPU1_PE3_TX_DP(14)
CW86 P5E_CPU1_PE3_TX_DP<13> PE3_TX_DP13 @S9S_MB_2U_LIB.S9S_MB_2U(SCH_1):P5E_CPU1_PE3_TX_DP(13)
DA86 P5E_CPU1_PE3_TX_DP<12> PE3_TX_DP12 @S9S_MB_2U_LIB.S9S_MB_2U(SCH_1):P5E_CPU1_PE3_TX_DP(12)
DC86 P5E_CPU1_PE3_TX_DP<11> PE3_TX_DP11 @S9S_MB_2U_LIB.S9S_MB_2U(SCH_1):P5E_CPU1_PE3_TX_DP(11)
DE86 P5E_CPU1_PE3_TX_DP<10> PE3_TX_DP10 @S9S_MB_2U_LIB.S9S_MB_2U(SCH_1):P5E_CPU1_PE3_TX_DP(10)
DG86 P5E_CPU1_PE3_TX_DP<9> PE3_TX_DP9 @S9S_MB_2U_LIB.S9S_MB_2U(SCH_1):P5E_CPU1_PE3_TX_DP(9)
DJ86 P5E_CPU1_PE3_TX_DP<8> PE3_TX_DP8 @S9S_MB_2U_LIB.S9S_MB_2U(SCH_1):P5E_CPU1_PE3_TX_DP(8)
DL86 P5E_CPU1_PE3_TX_DP<7> PE3_TX_DP7 @S9S_MB_2U_LIB.S9S_MB_2U(SCH_1):P5E_CPU1_PE3_TX_DP(7)
DN86 P5E_CPU1_PE3_TX_DP<6> PE3_TX_DP6 @S9S_MB_2U_LIB.S9S_MB_2U(SCH_1):P5E_CPU1_PE3_TX_DP(6)
DR86 P5E_CPU1_PE3_TX_DP<5> PE3_TX_DP5 @S9S_MB_2U_LIB.S9S_MB_2U(SCH_1):P5E_CPU1_PE3_TX_DP(5)
DU86 P5E_CPU1_PE3_TX_DP<4> PE3_TX_DP4 @S9S_MB_2U_LIB.S9S_MB_2U(SCH_1):P5E_CPU1_PE3_TX_DP(4)
DW86 P5E_CPU1_PE3_TX_DP<3> PE3_TX_DP3 @S9S_MB_2U_LIB.S9S_MB_2U(SCH_1):P5E_CPU1_PE3_TX_DP(3)
EA86 P5E_CPU1_PE3_TX_DP<2> PE3_TX_DP2 @S9S_MB_2U_LIB.S9S_MB_2U(SCH_1):P5E_CPU1_PE3_TX_DP(2)
EC86 P5E_CPU1_PE3_TX_DP<1> PE3_TX_DP1 @S9S_MB_2U_LIB.S9S_MB_2U(SCH_1):P5E_CPU1_PE3_TX_DP(1)
ED87 P5E_CPU1_PE3_TX_DP<0> PE3_TX_DP0 @S9S_MB_2U_LIB.S9S_MB_2U(SCH_1):P5E_CPU1_PE3_TX_DP(0)

SOCKET4677_AZIF0045P001C01CS-SA  I54  U1
EH10 P5E_CPU1_PE2_RX_DN<15> PE2_RX_DN15 @S9S_MB_2U_LIB.S9S_MB_2U(SCH_1):P5E_CPU1_PE2_RX_DN(15)
 EE9 P5E_CPU1_PE2_RX_DN<14> PE2_RX_DN14 @S9S_MB_2U_LIB.S9S_MB_2U(SCH_1):P5E_CPU1_PE2_RX_DN(14)
ED10 P5E_CPU1_PE2_RX_DN<13> PE2_RX_DN13 @S9S_MB_2U_LIB.S9S_MB_2U(SCH_1):P5E_CPU1_PE2_RX_DN(13)
 EA9 P5E_CPU1_PE2_RX_DN<12> PE2_RX_DN12 @S9S_MB_2U_LIB.S9S_MB_2U(SCH_1):P5E_CPU1_PE2_RX_DN(12)
DY10 P5E_CPU1_PE2_RX_DN<11> PE2_RX_DN11 @S9S_MB_2U_LIB.S9S_MB_2U(SCH_1):P5E_CPU1_PE2_RX_DN(11)
 DU9 P5E_CPU1_PE2_RX_DN<10> PE2_RX_DN10 @S9S_MB_2U_LIB.S9S_MB_2U(SCH_1):P5E_CPU1_PE2_RX_DN(10)
DT10 P5E_CPU1_PE2_RX_DN<9> PE2_RX_DN9 @S9S_MB_2U_LIB.S9S_MB_2U(SCH_1):P5E_CPU1_PE2_RX_DN(9)
 DN9 P5E_CPU1_PE2_RX_DN<8> PE2_RX_DN8 @S9S_MB_2U_LIB.S9S_MB_2U(SCH_1):P5E_CPU1_PE2_RX_DN(8)
DM10 P5E_CPU1_PE2_RX_DN<7> PE2_RX_DN7 @S9S_MB_2U_LIB.S9S_MB_2U(SCH_1):P5E_CPU1_PE2_RX_DN(7)
 DJ9 P5E_CPU1_PE2_RX_DN<6> PE2_RX_DN6 @S9S_MB_2U_LIB.S9S_MB_2U(SCH_1):P5E_CPU1_PE2_RX_DN(6)
DH10 P5E_CPU1_PE2_RX_DN<5> PE2_RX_DN5 @S9S_MB_2U_LIB.S9S_MB_2U(SCH_1):P5E_CPU1_PE2_RX_DN(5)
 DE9 P5E_CPU1_PE2_RX_DN<4> PE2_RX_DN4 @S9S_MB_2U_LIB.S9S_MB_2U(SCH_1):P5E_CPU1_PE2_RX_DN(4)
DD10 P5E_CPU1_PE2_RX_DN<3> PE2_RX_DN3 @S9S_MB_2U_LIB.S9S_MB_2U(SCH_1):P5E_CPU1_PE2_RX_DN(3)
 DA9 P5E_CPU1_PE2_RX_DN<2> PE2_RX_DN2 @S9S_MB_2U_LIB.S9S_MB_2U(SCH_1):P5E_CPU1_PE2_RX_DN(2)
CY10 P5E_CPU1_PE2_RX_DN<1> PE2_RX_DN1 @S9S_MB_2U_LIB.S9S_MB_2U(SCH_1):P5E_CPU1_PE2_RX_DN(1)
 CU9 P5E_CPU1_PE2_RX_DN<0> PE2_RX_DN0 @S9S_MB_2U_LIB.S9S_MB_2U(SCH_1):P5E_CPU1_PE2_RX_DN(0)
EG11 P5E_CPU1_PE2_RX_DP<15> PE2_RX_DP15 @S9S_MB_2U_LIB.S9S_MB_2U(SCH_1):P5E_CPU1_PE2_RX_DP(15)
EF10 P5E_CPU1_PE2_RX_DP<14> PE2_RX_DP14 @S9S_MB_2U_LIB.S9S_MB_2U(SCH_1):P5E_CPU1_PE2_RX_DP(14)
EC11 P5E_CPU1_PE2_RX_DP<13> PE2_RX_DP13 @S9S_MB_2U_LIB.S9S_MB_2U(SCH_1):P5E_CPU1_PE2_RX_DP(13)
EB10 P5E_CPU1_PE2_RX_DP<12> PE2_RX_DP12 @S9S_MB_2U_LIB.S9S_MB_2U(SCH_1):P5E_CPU1_PE2_RX_DP(12)
DW11 P5E_CPU1_PE2_RX_DP<11> PE2_RX_DP11 @S9S_MB_2U_LIB.S9S_MB_2U(SCH_1):P5E_CPU1_PE2_RX_DP(11)
DV10 P5E_CPU1_PE2_RX_DP<10> PE2_RX_DP10 @S9S_MB_2U_LIB.S9S_MB_2U(SCH_1):P5E_CPU1_PE2_RX_DP(10)
DR11 P5E_CPU1_PE2_RX_DP<9> PE2_RX_DP9 @S9S_MB_2U_LIB.S9S_MB_2U(SCH_1):P5E_CPU1_PE2_RX_DP(9)
DP10 P5E_CPU1_PE2_RX_DP<8> PE2_RX_DP8 @S9S_MB_2U_LIB.S9S_MB_2U(SCH_1):P5E_CPU1_PE2_RX_DP(8)
DL11 P5E_CPU1_PE2_RX_DP<7> PE2_RX_DP7 @S9S_MB_2U_LIB.S9S_MB_2U(SCH_1):P5E_CPU1_PE2_RX_DP(7)
DK10 P5E_CPU1_PE2_RX_DP<6> PE2_RX_DP6 @S9S_MB_2U_LIB.S9S_MB_2U(SCH_1):P5E_CPU1_PE2_RX_DP(6)
DG11 P5E_CPU1_PE2_RX_DP<5> PE2_RX_DP5 @S9S_MB_2U_LIB.S9S_MB_2U(SCH_1):P5E_CPU1_PE2_RX_DP(5)
DF10 P5E_CPU1_PE2_RX_DP<4> PE2_RX_DP4 @S9S_MB_2U_LIB.S9S_MB_2U(SCH_1):P5E_CPU1_PE2_RX_DP(4)
DC11 P5E_CPU1_PE2_RX_DP<3> PE2_RX_DP3 @S9S_MB_2U_LIB.S9S_MB_2U(SCH_1):P5E_CPU1_PE2_RX_DP(3)
DB10 P5E_CPU1_PE2_RX_DP<2> PE2_RX_DP2 @S9S_MB_2U_LIB.S9S_MB_2U(SCH_1):P5E_CPU1_PE2_RX_DP(2)
CW11 P5E_CPU1_PE2_RX_DP<1> PE2_RX_DP1 @S9S_MB_2U_LIB.S9S_MB_2U(SCH_1):P5E_CPU1_PE2_RX_DP(1)
CV10 P5E_CPU1_PE2_RX_DP<0> PE2_RX_DP0 @S9S_MB_2U_LIB.S9S_MB_2U(SCH_1):P5E_CPU1_PE2_RX_DP(0)
EF14 P5E_CPU1_PE2_TX_DN<15> PE2_TX_DN15 @S9S_MB_2U_LIB.S9S_MB_2U(SCH_1):P5E_CPU1_PE2_TX_DN(15)
EE13 P5E_CPU1_PE2_TX_DN<14> PE2_TX_DN14 @S9S_MB_2U_LIB.S9S_MB_2U(SCH_1):P5E_CPU1_PE2_TX_DN(14)
EB14 P5E_CPU1_PE2_TX_DN<13> PE2_TX_DN13 @S9S_MB_2U_LIB.S9S_MB_2U(SCH_1):P5E_CPU1_PE2_TX_DN(13)
EA13 P5E_CPU1_PE2_TX_DN<12> PE2_TX_DN12 @S9S_MB_2U_LIB.S9S_MB_2U(SCH_1):P5E_CPU1_PE2_TX_DN(12)
DV14 P5E_CPU1_PE2_TX_DN<11> PE2_TX_DN11 @S9S_MB_2U_LIB.S9S_MB_2U(SCH_1):P5E_CPU1_PE2_TX_DN(11)
DU13 P5E_CPU1_PE2_TX_DN<10> PE2_TX_DN10 @S9S_MB_2U_LIB.S9S_MB_2U(SCH_1):P5E_CPU1_PE2_TX_DN(10)
DP14 P5E_CPU1_PE2_TX_DN<9> PE2_TX_DN9 @S9S_MB_2U_LIB.S9S_MB_2U(SCH_1):P5E_CPU1_PE2_TX_DN(9)
DN13 P5E_CPU1_PE2_TX_DN<8> PE2_TX_DN8 @S9S_MB_2U_LIB.S9S_MB_2U(SCH_1):P5E_CPU1_PE2_TX_DN(8)
DK14 P5E_CPU1_PE2_TX_DN<7> PE2_TX_DN7 @S9S_MB_2U_LIB.S9S_MB_2U(SCH_1):P5E_CPU1_PE2_TX_DN(7)
DJ13 P5E_CPU1_PE2_TX_DN<6> PE2_TX_DN6 @S9S_MB_2U_LIB.S9S_MB_2U(SCH_1):P5E_CPU1_PE2_TX_DN(6)
DF14 P5E_CPU1_PE2_TX_DN<5> PE2_TX_DN5 @S9S_MB_2U_LIB.S9S_MB_2U(SCH_1):P5E_CPU1_PE2_TX_DN(5)
DE13 P5E_CPU1_PE2_TX_DN<4> PE2_TX_DN4 @S9S_MB_2U_LIB.S9S_MB_2U(SCH_1):P5E_CPU1_PE2_TX_DN(4)
DB14 P5E_CPU1_PE2_TX_DN<3> PE2_TX_DN3 @S9S_MB_2U_LIB.S9S_MB_2U(SCH_1):P5E_CPU1_PE2_TX_DN(3)
DA13 P5E_CPU1_PE2_TX_DN<2> PE2_TX_DN2 @S9S_MB_2U_LIB.S9S_MB_2U(SCH_1):P5E_CPU1_PE2_TX_DN(2)
CV14 P5E_CPU1_PE2_TX_DN<1> PE2_TX_DN1 @S9S_MB_2U_LIB.S9S_MB_2U(SCH_1):P5E_CPU1_PE2_TX_DN(1)
CU13 P5E_CPU1_PE2_TX_DN<0> PE2_TX_DN0 @S9S_MB_2U_LIB.S9S_MB_2U(SCH_1):P5E_CPU1_PE2_TX_DN(0)
EG15 P5E_CPU1_PE2_TX_DP<15> PE2_TX_DP15 @S9S_MB_2U_LIB.S9S_MB_2U(SCH_1):P5E_CPU1_PE2_TX_DP(15)
ED14 P5E_CPU1_PE2_TX_DP<14> PE2_TX_DP14 @S9S_MB_2U_LIB.S9S_MB_2U(SCH_1):P5E_CPU1_PE2_TX_DP(14)
EC15 P5E_CPU1_PE2_TX_DP<13> PE2_TX_DP13 @S9S_MB_2U_LIB.S9S_MB_2U(SCH_1):P5E_CPU1_PE2_TX_DP(13)
DY14 P5E_CPU1_PE2_TX_DP<12> PE2_TX_DP12 @S9S_MB_2U_LIB.S9S_MB_2U(SCH_1):P5E_CPU1_PE2_TX_DP(12)
DW15 P5E_CPU1_PE2_TX_DP<11> PE2_TX_DP11 @S9S_MB_2U_LIB.S9S_MB_2U(SCH_1):P5E_CPU1_PE2_TX_DP(11)
DT14 P5E_CPU1_PE2_TX_DP<10> PE2_TX_DP10 @S9S_MB_2U_LIB.S9S_MB_2U(SCH_1):P5E_CPU1_PE2_TX_DP(10)
DR15 P5E_CPU1_PE2_TX_DP<9> PE2_TX_DP9 @S9S_MB_2U_LIB.S9S_MB_2U(SCH_1):P5E_CPU1_PE2_TX_DP(9)
DM14 P5E_CPU1_PE2_TX_DP<8> PE2_TX_DP8 @S9S_MB_2U_LIB.S9S_MB_2U(SCH_1):P5E_CPU1_PE2_TX_DP(8)
DL15 P5E_CPU1_PE2_TX_DP<7> PE2_TX_DP7 @S9S_MB_2U_LIB.S9S_MB_2U(SCH_1):P5E_CPU1_PE2_TX_DP(7)
DH14 P5E_CPU1_PE2_TX_DP<6> PE2_TX_DP6 @S9S_MB_2U_LIB.S9S_MB_2U(SCH_1):P5E_CPU1_PE2_TX_DP(6)
DG15 P5E_CPU1_PE2_TX_DP<5> PE2_TX_DP5 @S9S_MB_2U_LIB.S9S_MB_2U(SCH_1):P5E_CPU1_PE2_TX_DP(5)
DD14 P5E_CPU1_PE2_TX_DP<4> PE2_TX_DP4 @S9S_MB_2U_LIB.S9S_MB_2U(SCH_1):P5E_CPU1_PE2_TX_DP(4)
DC15 P5E_CPU1_PE2_TX_DP<3> PE2_TX_DP3 @S9S_MB_2U_LIB.S9S_MB_2U(SCH_1):P5E_CPU1_PE2_TX_DP(3)
CY14 P5E_CPU1_PE2_TX_DP<2> PE2_TX_DP2 @S9S_MB_2U_LIB.S9S_MB_2U(SCH_1):P5E_CPU1_PE2_TX_DP(2)
CW15 P5E_CPU1_PE2_TX_DP<1> PE2_TX_DP1 @S9S_MB_2U_LIB.S9S_MB_2U(SCH_1):P5E_CPU1_PE2_TX_DP(1)
CT14 P5E_CPU1_PE2_TX_DP<0> PE2_TX_DP0 @S9S_MB_2U_LIB.S9S_MB_2U(SCH_1):P5E_CPU1_PE2_TX_DP(0)


DRAWING: @S9S_MB_2U_LIB.S9S_MB_2U(SCH_1):PAGE62 

SOCKET4677_AZIF0045P001C01CS-SA  I18  U1
BB89 P5E_CPU1_PE4_RX_DN<15> PE4_RX_DN15 @S9S_MB_2U_LIB.S9S_MB_2U(SCH_1):P5E_CPU1_PE4_RX_DN(15)
AY91 P5E_CPU1_PE4_RX_DN<14> PE4_RX_DN14 @S9S_MB_2U_LIB.S9S_MB_2U(SCH_1):P5E_CPU1_PE4_RX_DN(14)
AV89 P5E_CPU1_PE4_RX_DN<13> PE4_RX_DN13 @S9S_MB_2U_LIB.S9S_MB_2U(SCH_1):P5E_CPU1_PE4_RX_DN(13)
AT91 P5E_CPU1_PE4_RX_DN<12> PE4_RX_DN12 @S9S_MB_2U_LIB.S9S_MB_2U(SCH_1):P5E_CPU1_PE4_RX_DN(12)
AP89 P5E_CPU1_PE4_RX_DN<11> PE4_RX_DN11 @S9S_MB_2U_LIB.S9S_MB_2U(SCH_1):P5E_CPU1_PE4_RX_DN(11)
AM91 P5E_CPU1_PE4_RX_DN<10> PE4_RX_DN10 @S9S_MB_2U_LIB.S9S_MB_2U(SCH_1):P5E_CPU1_PE4_RX_DN(10)
AK89 P5E_CPU1_PE4_RX_DN<9> PE4_RX_DN9 @S9S_MB_2U_LIB.S9S_MB_2U(SCH_1):P5E_CPU1_PE4_RX_DN(9)
AH91 P5E_CPU1_PE4_RX_DN<8> PE4_RX_DN8 @S9S_MB_2U_LIB.S9S_MB_2U(SCH_1):P5E_CPU1_PE4_RX_DN(8)
AF89 P5E_CPU1_PE4_RX_DN<7> PE4_RX_DN7 @S9S_MB_2U_LIB.S9S_MB_2U(SCH_1):P5E_CPU1_PE4_RX_DN(7)
AD91 P5E_CPU1_PE4_RX_DN<6> PE4_RX_DN6 @S9S_MB_2U_LIB.S9S_MB_2U(SCH_1):P5E_CPU1_PE4_RX_DN(6)
AB89 P5E_CPU1_PE4_RX_DN<5> PE4_RX_DN5 @S9S_MB_2U_LIB.S9S_MB_2U(SCH_1):P5E_CPU1_PE4_RX_DN(5)
 Y91 P5E_CPU1_PE4_RX_DN<4> PE4_RX_DN4 @S9S_MB_2U_LIB.S9S_MB_2U(SCH_1):P5E_CPU1_PE4_RX_DN(4)
 V89 P5E_CPU1_PE4_RX_DN<3> PE4_RX_DN3 @S9S_MB_2U_LIB.S9S_MB_2U(SCH_1):P5E_CPU1_PE4_RX_DN(3)
 T91 P5E_CPU1_PE4_RX_DN<2> PE4_RX_DN2 @S9S_MB_2U_LIB.S9S_MB_2U(SCH_1):P5E_CPU1_PE4_RX_DN(2)
 P89 P5E_CPU1_PE4_RX_DN<1> PE4_RX_DN1 @S9S_MB_2U_LIB.S9S_MB_2U(SCH_1):P5E_CPU1_PE4_RX_DN(1)
 J90 P5E_CPU1_PE4_RX_DN<0> PE4_RX_DN0 @S9S_MB_2U_LIB.S9S_MB_2U(SCH_1):P5E_CPU1_PE4_RX_DN(0)
BA90 P5E_CPU1_PE4_RX_DP<15> PE4_RX_DP15 @S9S_MB_2U_LIB.S9S_MB_2U(SCH_1):P5E_CPU1_PE4_RX_DP(15)
AW90 P5E_CPU1_PE4_RX_DP<14> PE4_RX_DP14 @S9S_MB_2U_LIB.S9S_MB_2U(SCH_1):P5E_CPU1_PE4_RX_DP(14)
AU90 P5E_CPU1_PE4_RX_DP<13> PE4_RX_DP13 @S9S_MB_2U_LIB.S9S_MB_2U(SCH_1):P5E_CPU1_PE4_RX_DP(13)
AR90 P5E_CPU1_PE4_RX_DP<12> PE4_RX_DP12 @S9S_MB_2U_LIB.S9S_MB_2U(SCH_1):P5E_CPU1_PE4_RX_DP(12)
AN90 P5E_CPU1_PE4_RX_DP<11> PE4_RX_DP11 @S9S_MB_2U_LIB.S9S_MB_2U(SCH_1):P5E_CPU1_PE4_RX_DP(11)
AL90 P5E_CPU1_PE4_RX_DP<10> PE4_RX_DP10 @S9S_MB_2U_LIB.S9S_MB_2U(SCH_1):P5E_CPU1_PE4_RX_DP(10)
AJ90 P5E_CPU1_PE4_RX_DP<9> PE4_RX_DP9 @S9S_MB_2U_LIB.S9S_MB_2U(SCH_1):P5E_CPU1_PE4_RX_DP(9)
AG90 P5E_CPU1_PE4_RX_DP<8> PE4_RX_DP8 @S9S_MB_2U_LIB.S9S_MB_2U(SCH_1):P5E_CPU1_PE4_RX_DP(8)
AE90 P5E_CPU1_PE4_RX_DP<7> PE4_RX_DP7 @S9S_MB_2U_LIB.S9S_MB_2U(SCH_1):P5E_CPU1_PE4_RX_DP(7)
AC90 P5E_CPU1_PE4_RX_DP<6> PE4_RX_DP6 @S9S_MB_2U_LIB.S9S_MB_2U(SCH_1):P5E_CPU1_PE4_RX_DP(6)
AA90 P5E_CPU1_PE4_RX_DP<5> PE4_RX_DP5 @S9S_MB_2U_LIB.S9S_MB_2U(SCH_1):P5E_CPU1_PE4_RX_DP(5)
 W90 P5E_CPU1_PE4_RX_DP<4> PE4_RX_DP4 @S9S_MB_2U_LIB.S9S_MB_2U(SCH_1):P5E_CPU1_PE4_RX_DP(4)
 U90 P5E_CPU1_PE4_RX_DP<3> PE4_RX_DP3 @S9S_MB_2U_LIB.S9S_MB_2U(SCH_1):P5E_CPU1_PE4_RX_DP(3)
 R90 P5E_CPU1_PE4_RX_DP<2> PE4_RX_DP2 @S9S_MB_2U_LIB.S9S_MB_2U(SCH_1):P5E_CPU1_PE4_RX_DP(2)
 N90 P5E_CPU1_PE4_RX_DP<1> PE4_RX_DP1 @S9S_MB_2U_LIB.S9S_MB_2U(SCH_1):P5E_CPU1_PE4_RX_DP(1)
 K89 P5E_CPU1_PE4_RX_DP<0> PE4_RX_DP0 @S9S_MB_2U_LIB.S9S_MB_2U(SCH_1):P5E_CPU1_PE4_RX_DP(0)
BA86 P5E_CPU1_PE4_TX_DN<15> PE4_TX_DN15 @S9S_MB_2U_LIB.S9S_MB_2U(SCH_1):P5E_CPU1_PE4_TX_DN(15)
AW86 P5E_CPU1_PE4_TX_DN<14> PE4_TX_DN14 @S9S_MB_2U_LIB.S9S_MB_2U(SCH_1):P5E_CPU1_PE4_TX_DN(14)
AU86 P5E_CPU1_PE4_TX_DN<13> PE4_TX_DN13 @S9S_MB_2U_LIB.S9S_MB_2U(SCH_1):P5E_CPU1_PE4_TX_DN(13)
AR86 P5E_CPU1_PE4_TX_DN<12> PE4_TX_DN12 @S9S_MB_2U_LIB.S9S_MB_2U(SCH_1):P5E_CPU1_PE4_TX_DN(12)
AP85 P5E_CPU1_PE4_TX_DN<11> PE4_TX_DN11 @S9S_MB_2U_LIB.S9S_MB_2U(SCH_1):P5E_CPU1_PE4_TX_DN(11)
AL86 P5E_CPU1_PE4_TX_DN<10> PE4_TX_DN10 @S9S_MB_2U_LIB.S9S_MB_2U(SCH_1):P5E_CPU1_PE4_TX_DN(10)
AJ86 P5E_CPU1_PE4_TX_DN<9> PE4_TX_DN9 @S9S_MB_2U_LIB.S9S_MB_2U(SCH_1):P5E_CPU1_PE4_TX_DN(9)
AG86 P5E_CPU1_PE4_TX_DN<8> PE4_TX_DN8 @S9S_MB_2U_LIB.S9S_MB_2U(SCH_1):P5E_CPU1_PE4_TX_DN(8)
AE86 P5E_CPU1_PE4_TX_DN<7> PE4_TX_DN7 @S9S_MB_2U_LIB.S9S_MB_2U(SCH_1):P5E_CPU1_PE4_TX_DN(7)
AC86 P5E_CPU1_PE4_TX_DN<6> PE4_TX_DN6 @S9S_MB_2U_LIB.S9S_MB_2U(SCH_1):P5E_CPU1_PE4_TX_DN(6)
AA86 P5E_CPU1_PE4_TX_DN<5> PE4_TX_DN5 @S9S_MB_2U_LIB.S9S_MB_2U(SCH_1):P5E_CPU1_PE4_TX_DN(5)
 W86 P5E_CPU1_PE4_TX_DN<4> PE4_TX_DN4 @S9S_MB_2U_LIB.S9S_MB_2U(SCH_1):P5E_CPU1_PE4_TX_DN(4)
 U86 P5E_CPU1_PE4_TX_DN<3> PE4_TX_DN3 @S9S_MB_2U_LIB.S9S_MB_2U(SCH_1):P5E_CPU1_PE4_TX_DN(3)
 R86 P5E_CPU1_PE4_TX_DN<2> PE4_TX_DN2 @S9S_MB_2U_LIB.S9S_MB_2U(SCH_1):P5E_CPU1_PE4_TX_DN(2)
 P85 P5E_CPU1_PE4_TX_DN<1> PE4_TX_DN1 @S9S_MB_2U_LIB.S9S_MB_2U(SCH_1):P5E_CPU1_PE4_TX_DN(1)
 L86 P5E_CPU1_PE4_TX_DN<0> PE4_TX_DN0 @S9S_MB_2U_LIB.S9S_MB_2U(SCH_1):P5E_CPU1_PE4_TX_DN(0)
BB85 P5E_CPU1_PE4_TX_DP<15> PE4_TX_DP15 @S9S_MB_2U_LIB.S9S_MB_2U(SCH_1):P5E_CPU1_PE4_TX_DP(15)
AY87 P5E_CPU1_PE4_TX_DP<14> PE4_TX_DP14 @S9S_MB_2U_LIB.S9S_MB_2U(SCH_1):P5E_CPU1_PE4_TX_DP(14)
AV85 P5E_CPU1_PE4_TX_DP<13> PE4_TX_DP13 @S9S_MB_2U_LIB.S9S_MB_2U(SCH_1):P5E_CPU1_PE4_TX_DP(13)
AT87 P5E_CPU1_PE4_TX_DP<12> PE4_TX_DP12 @S9S_MB_2U_LIB.S9S_MB_2U(SCH_1):P5E_CPU1_PE4_TX_DP(12)
AN86 P5E_CPU1_PE4_TX_DP<11> PE4_TX_DP11 @S9S_MB_2U_LIB.S9S_MB_2U(SCH_1):P5E_CPU1_PE4_TX_DP(11)
AM87 P5E_CPU1_PE4_TX_DP<10> PE4_TX_DP10 @S9S_MB_2U_LIB.S9S_MB_2U(SCH_1):P5E_CPU1_PE4_TX_DP(10)
AK85 P5E_CPU1_PE4_TX_DP<9> PE4_TX_DP9 @S9S_MB_2U_LIB.S9S_MB_2U(SCH_1):P5E_CPU1_PE4_TX_DP(9)
AH87 P5E_CPU1_PE4_TX_DP<8> PE4_TX_DP8 @S9S_MB_2U_LIB.S9S_MB_2U(SCH_1):P5E_CPU1_PE4_TX_DP(8)
AF85 P5E_CPU1_PE4_TX_DP<7> PE4_TX_DP7 @S9S_MB_2U_LIB.S9S_MB_2U(SCH_1):P5E_CPU1_PE4_TX_DP(7)
AD87 P5E_CPU1_PE4_TX_DP<6> PE4_TX_DP6 @S9S_MB_2U_LIB.S9S_MB_2U(SCH_1):P5E_CPU1_PE4_TX_DP(6)
AB85 P5E_CPU1_PE4_TX_DP<5> PE4_TX_DP5 @S9S_MB_2U_LIB.S9S_MB_2U(SCH_1):P5E_CPU1_PE4_TX_DP(5)
 Y87 P5E_CPU1_PE4_TX_DP<4> PE4_TX_DP4 @S9S_MB_2U_LIB.S9S_MB_2U(SCH_1):P5E_CPU1_PE4_TX_DP(4)
 V85 P5E_CPU1_PE4_TX_DP<3> PE4_TX_DP3 @S9S_MB_2U_LIB.S9S_MB_2U(SCH_1):P5E_CPU1_PE4_TX_DP(3)
 T87 P5E_CPU1_PE4_TX_DP<2> PE4_TX_DP2 @S9S_MB_2U_LIB.S9S_MB_2U(SCH_1):P5E_CPU1_PE4_TX_DP(2)
 N86 P5E_CPU1_PE4_TX_DP<1> PE4_TX_DP1 @S9S_MB_2U_LIB.S9S_MB_2U(SCH_1):P5E_CPU1_PE4_TX_DP(1)
 M87 P5E_CPU1_PE4_TX_DP<0> PE4_TX_DP0 @S9S_MB_2U_LIB.S9S_MB_2U(SCH_1):P5E_CPU1_PE4_TX_DP(0)


DRAWING: @S9S_MB_2U_LIB.S9S_MB_2U(SCH_1):PAGE63 

SOCKET4677_AZIF0045P001C01CS-SA  I51  U1
 BU5 UPI_CPU0_CPU1_P1P0_DN<23> UPI0_RX_DN23 @S9S_MB_2U_LIB.S9S_MB_2U(SCH_1):UPI_CPU0_CPU1_P1P0_DN(23)
 BR7 UPI_CPU0_CPU1_P1P0_DN<22> UPI0_RX_DN22 @S9S_MB_2U_LIB.S9S_MB_2U(SCH_1):UPI_CPU0_CPU1_P1P0_DN(22)
 BN5 UPI_CPU0_CPU1_P1P0_DN<21> UPI0_RX_DN21 @S9S_MB_2U_LIB.S9S_MB_2U(SCH_1):UPI_CPU0_CPU1_P1P0_DN(21)
 BK6 UPI_CPU0_CPU1_P1P0_DN<20> UPI0_RX_DN20 @S9S_MB_2U_LIB.S9S_MB_2U(SCH_1):UPI_CPU0_CPU1_P1P0_DN(20)
 BJ5 UPI_CPU0_CPU1_P1P0_DN<19> UPI0_RX_DN19 @S9S_MB_2U_LIB.S9S_MB_2U(SCH_1):UPI_CPU0_CPU1_P1P0_DN(19)
 BF6 UPI_CPU0_CPU1_P1P0_DN<18> UPI0_RX_DN18 @S9S_MB_2U_LIB.S9S_MB_2U(SCH_1):UPI_CPU0_CPU1_P1P0_DN(18)
 BE5 UPI_CPU0_CPU1_P1P0_DN<17> UPI0_RX_DN17 @S9S_MB_2U_LIB.S9S_MB_2U(SCH_1):UPI_CPU0_CPU1_P1P0_DN(17)
 BB6 UPI_CPU0_CPU1_P1P0_DN<16> UPI0_RX_DN16 @S9S_MB_2U_LIB.S9S_MB_2U(SCH_1):UPI_CPU0_CPU1_P1P0_DN(16)
 BA5 UPI_CPU0_CPU1_P1P0_DN<15> UPI0_RX_DN15 @S9S_MB_2U_LIB.S9S_MB_2U(SCH_1):UPI_CPU0_CPU1_P1P0_DN(15)
 AV6 UPI_CPU0_CPU1_P1P0_DN<14> UPI0_RX_DN14 @S9S_MB_2U_LIB.S9S_MB_2U(SCH_1):UPI_CPU0_CPU1_P1P0_DN(14)
 AU5 UPI_CPU0_CPU1_P1P0_DN<13> UPI0_RX_DN13 @S9S_MB_2U_LIB.S9S_MB_2U(SCH_1):UPI_CPU0_CPU1_P1P0_DN(13)
 AP6 UPI_CPU0_CPU1_P1P0_DN<12> UPI0_RX_DN12 @S9S_MB_2U_LIB.S9S_MB_2U(SCH_1):UPI_CPU0_CPU1_P1P0_DN(12)
 AN5 UPI_CPU0_CPU1_P1P0_DN<11> UPI0_RX_DN11 @S9S_MB_2U_LIB.S9S_MB_2U(SCH_1):UPI_CPU0_CPU1_P1P0_DN(11)
 AK6 UPI_CPU0_CPU1_P1P0_DN<10> UPI0_RX_DN10 @S9S_MB_2U_LIB.S9S_MB_2U(SCH_1):UPI_CPU0_CPU1_P1P0_DN(10)
 AH6 UPI_CPU0_CPU1_P1P0_DN<9> UPI0_RX_DN9 @S9S_MB_2U_LIB.S9S_MB_2U(SCH_1):UPI_CPU0_CPU1_P1P0_DN(9)
 AF6 UPI_CPU0_CPU1_P1P0_DN<8> UPI0_RX_DN8 @S9S_MB_2U_LIB.S9S_MB_2U(SCH_1):UPI_CPU0_CPU1_P1P0_DN(8)
 AE5 UPI_CPU0_CPU1_P1P0_DN<7> UPI0_RX_DN7 @S9S_MB_2U_LIB.S9S_MB_2U(SCH_1):UPI_CPU0_CPU1_P1P0_DN(7)
 AB6 UPI_CPU0_CPU1_P1P0_DN<6> UPI0_RX_DN6 @S9S_MB_2U_LIB.S9S_MB_2U(SCH_1):UPI_CPU0_CPU1_P1P0_DN(6)
 AA5 UPI_CPU0_CPU1_P1P0_DN<5> UPI0_RX_DN5 @S9S_MB_2U_LIB.S9S_MB_2U(SCH_1):UPI_CPU0_CPU1_P1P0_DN(5)
  V6 UPI_CPU0_CPU1_P1P0_DN<4> UPI0_RX_DN4 @S9S_MB_2U_LIB.S9S_MB_2U(SCH_1):UPI_CPU0_CPU1_P1P0_DN(4)
  U5 UPI_CPU0_CPU1_P1P0_DN<3> UPI0_RX_DN3 @S9S_MB_2U_LIB.S9S_MB_2U(SCH_1):UPI_CPU0_CPU1_P1P0_DN(3)
  P6 UPI_CPU0_CPU1_P1P0_DN<2> UPI0_RX_DN2 @S9S_MB_2U_LIB.S9S_MB_2U(SCH_1):UPI_CPU0_CPU1_P1P0_DN(2)
  N5 UPI_CPU0_CPU1_P1P0_DN<1> UPI0_RX_DN1 @S9S_MB_2U_LIB.S9S_MB_2U(SCH_1):UPI_CPU0_CPU1_P1P0_DN(1)
  K6 UPI_CPU0_CPU1_P1P0_DN<0> UPI0_RX_DN0 @S9S_MB_2U_LIB.S9S_MB_2U(SCH_1):UPI_CPU0_CPU1_P1P0_DN(0)
 BT6 UPI_CPU0_CPU1_P1P0_DP<23> UPI0_RX_DP23 @S9S_MB_2U_LIB.S9S_MB_2U(SCH_1):UPI_CPU0_CPU1_P1P0_DP(23)
 BP6 UPI_CPU0_CPU1_P1P0_DP<22> UPI0_RX_DP22 @S9S_MB_2U_LIB.S9S_MB_2U(SCH_1):UPI_CPU0_CPU1_P1P0_DP(22)
 BM6 UPI_CPU0_CPU1_P1P0_DP<21> UPI0_RX_DP21 @S9S_MB_2U_LIB.S9S_MB_2U(SCH_1):UPI_CPU0_CPU1_P1P0_DP(21)
 BL7 UPI_CPU0_CPU1_P1P0_DP<20> UPI0_RX_DP20 @S9S_MB_2U_LIB.S9S_MB_2U(SCH_1):UPI_CPU0_CPU1_P1P0_DP(20)
 BH6 UPI_CPU0_CPU1_P1P0_DP<19> UPI0_RX_DP19 @S9S_MB_2U_LIB.S9S_MB_2U(SCH_1):UPI_CPU0_CPU1_P1P0_DP(19)
 BG7 UPI_CPU0_CPU1_P1P0_DP<18> UPI0_RX_DP18 @S9S_MB_2U_LIB.S9S_MB_2U(SCH_1):UPI_CPU0_CPU1_P1P0_DP(18)
 BD6 UPI_CPU0_CPU1_P1P0_DP<17> UPI0_RX_DP17 @S9S_MB_2U_LIB.S9S_MB_2U(SCH_1):UPI_CPU0_CPU1_P1P0_DP(17)
 BC7 UPI_CPU0_CPU1_P1P0_DP<16> UPI0_RX_DP16 @S9S_MB_2U_LIB.S9S_MB_2U(SCH_1):UPI_CPU0_CPU1_P1P0_DP(16)
 AY6 UPI_CPU0_CPU1_P1P0_DP<15> UPI0_RX_DP15 @S9S_MB_2U_LIB.S9S_MB_2U(SCH_1):UPI_CPU0_CPU1_P1P0_DP(15)
 AW7 UPI_CPU0_CPU1_P1P0_DP<14> UPI0_RX_DP14 @S9S_MB_2U_LIB.S9S_MB_2U(SCH_1):UPI_CPU0_CPU1_P1P0_DP(14)
 AT6 UPI_CPU0_CPU1_P1P0_DP<13> UPI0_RX_DP13 @S9S_MB_2U_LIB.S9S_MB_2U(SCH_1):UPI_CPU0_CPU1_P1P0_DP(13)
 AR7 UPI_CPU0_CPU1_P1P0_DP<12> UPI0_RX_DP12 @S9S_MB_2U_LIB.S9S_MB_2U(SCH_1):UPI_CPU0_CPU1_P1P0_DP(12)
 AM6 UPI_CPU0_CPU1_P1P0_DP<11> UPI0_RX_DP11 @S9S_MB_2U_LIB.S9S_MB_2U(SCH_1):UPI_CPU0_CPU1_P1P0_DP(11)
 AL7 UPI_CPU0_CPU1_P1P0_DP<10> UPI0_RX_DP10 @S9S_MB_2U_LIB.S9S_MB_2U(SCH_1):UPI_CPU0_CPU1_P1P0_DP(10)
 AJ5 UPI_CPU0_CPU1_P1P0_DP<9> UPI0_RX_DP9 @S9S_MB_2U_LIB.S9S_MB_2U(SCH_1):UPI_CPU0_CPU1_P1P0_DP(9)
 AG7 UPI_CPU0_CPU1_P1P0_DP<8> UPI0_RX_DP8 @S9S_MB_2U_LIB.S9S_MB_2U(SCH_1):UPI_CPU0_CPU1_P1P0_DP(8)
 AD6 UPI_CPU0_CPU1_P1P0_DP<7> UPI0_RX_DP7 @S9S_MB_2U_LIB.S9S_MB_2U(SCH_1):UPI_CPU0_CPU1_P1P0_DP(7)
 AC7 UPI_CPU0_CPU1_P1P0_DP<6> UPI0_RX_DP6 @S9S_MB_2U_LIB.S9S_MB_2U(SCH_1):UPI_CPU0_CPU1_P1P0_DP(6)
  Y6 UPI_CPU0_CPU1_P1P0_DP<5> UPI0_RX_DP5 @S9S_MB_2U_LIB.S9S_MB_2U(SCH_1):UPI_CPU0_CPU1_P1P0_DP(5)
  W7 UPI_CPU0_CPU1_P1P0_DP<4> UPI0_RX_DP4 @S9S_MB_2U_LIB.S9S_MB_2U(SCH_1):UPI_CPU0_CPU1_P1P0_DP(4)
  T6 UPI_CPU0_CPU1_P1P0_DP<3> UPI0_RX_DP3 @S9S_MB_2U_LIB.S9S_MB_2U(SCH_1):UPI_CPU0_CPU1_P1P0_DP(3)
  R7 UPI_CPU0_CPU1_P1P0_DP<2> UPI0_RX_DP2 @S9S_MB_2U_LIB.S9S_MB_2U(SCH_1):UPI_CPU0_CPU1_P1P0_DP(2)
  M6 UPI_CPU0_CPU1_P1P0_DP<1> UPI0_RX_DP1 @S9S_MB_2U_LIB.S9S_MB_2U(SCH_1):UPI_CPU0_CPU1_P1P0_DP(1)
  L7 UPI_CPU0_CPU1_P1P0_DP<0> UPI0_RX_DP0 @S9S_MB_2U_LIB.S9S_MB_2U(SCH_1):UPI_CPU0_CPU1_P1P0_DP(0)
 BT2 UPI_CPU1_CPU0_P0P1_DN<23> UPI0_TX_DN23 @S9S_MB_2U_LIB.S9S_MB_2U(SCH_1):UPI_CPU1_CPU0_P0P1_DN(23)
 BR3 UPI_CPU1_CPU0_P0P1_DN<22> UPI0_TX_DN22 @S9S_MB_2U_LIB.S9S_MB_2U(SCH_1):UPI_CPU1_CPU0_P0P1_DN(22)
 BM2 UPI_CPU1_CPU0_P0P1_DN<21> UPI0_TX_DN21 @S9S_MB_2U_LIB.S9S_MB_2U(SCH_1):UPI_CPU1_CPU0_P0P1_DN(21)
 BK2 UPI_CPU1_CPU0_P0P1_DN<20> UPI0_TX_DN20 @S9S_MB_2U_LIB.S9S_MB_2U(SCH_1):UPI_CPU1_CPU0_P0P1_DN(20)
 BH2 UPI_CPU1_CPU0_P0P1_DN<19> UPI0_TX_DN19 @S9S_MB_2U_LIB.S9S_MB_2U(SCH_1):UPI_CPU1_CPU0_P0P1_DN(19)
 BF2 UPI_CPU1_CPU0_P0P1_DN<18> UPI0_TX_DN18 @S9S_MB_2U_LIB.S9S_MB_2U(SCH_1):UPI_CPU1_CPU0_P0P1_DN(18)
 BD2 UPI_CPU1_CPU0_P0P1_DN<17> UPI0_TX_DN17 @S9S_MB_2U_LIB.S9S_MB_2U(SCH_1):UPI_CPU1_CPU0_P0P1_DN(17)
 BB2 UPI_CPU1_CPU0_P0P1_DN<16> UPI0_TX_DN16 @S9S_MB_2U_LIB.S9S_MB_2U(SCH_1):UPI_CPU1_CPU0_P0P1_DN(16)
 AY2 UPI_CPU1_CPU0_P0P1_DN<15> UPI0_TX_DN15 @S9S_MB_2U_LIB.S9S_MB_2U(SCH_1):UPI_CPU1_CPU0_P0P1_DN(15)
 AU1 UPI_CPU1_CPU0_P0P1_DN<14> UPI0_TX_DN14 @S9S_MB_2U_LIB.S9S_MB_2U(SCH_1):UPI_CPU1_CPU0_P0P1_DN(14)
 AT2 UPI_CPU1_CPU0_P0P1_DN<13> UPI0_TX_DN13 @S9S_MB_2U_LIB.S9S_MB_2U(SCH_1):UPI_CPU1_CPU0_P0P1_DN(13)
 AP2 UPI_CPU1_CPU0_P0P1_DN<12> UPI0_TX_DN12 @S9S_MB_2U_LIB.S9S_MB_2U(SCH_1):UPI_CPU1_CPU0_P0P1_DN(12)
 AM2 UPI_CPU1_CPU0_P0P1_DN<11> UPI0_TX_DN11 @S9S_MB_2U_LIB.S9S_MB_2U(SCH_1):UPI_CPU1_CPU0_P0P1_DN(11)
 AK2 UPI_CPU1_CPU0_P0P1_DN<10> UPI0_TX_DN10 @S9S_MB_2U_LIB.S9S_MB_2U(SCH_1):UPI_CPU1_CPU0_P0P1_DN(10)
 AH2 UPI_CPU1_CPU0_P0P1_DN<9> UPI0_TX_DN9 @S9S_MB_2U_LIB.S9S_MB_2U(SCH_1):UPI_CPU1_CPU0_P0P1_DN(9)
 AF2 UPI_CPU1_CPU0_P0P1_DN<8> UPI0_TX_DN8 @S9S_MB_2U_LIB.S9S_MB_2U(SCH_1):UPI_CPU1_CPU0_P0P1_DN(8)
 AD2 UPI_CPU1_CPU0_P0P1_DN<7> UPI0_TX_DN7 @S9S_MB_2U_LIB.S9S_MB_2U(SCH_1):UPI_CPU1_CPU0_P0P1_DN(7)
 AA1 UPI_CPU1_CPU0_P0P1_DN<6> UPI0_TX_DN6 @S9S_MB_2U_LIB.S9S_MB_2U(SCH_1):UPI_CPU1_CPU0_P0P1_DN(6)
  Y2 UPI_CPU1_CPU0_P0P1_DN<5> UPI0_TX_DN5 @S9S_MB_2U_LIB.S9S_MB_2U(SCH_1):UPI_CPU1_CPU0_P0P1_DN(5)
  U1 UPI_CPU1_CPU0_P0P1_DN<4> UPI0_TX_DN4 @S9S_MB_2U_LIB.S9S_MB_2U(SCH_1):UPI_CPU1_CPU0_P0P1_DN(4)
  T2 UPI_CPU1_CPU0_P0P1_DN<3> UPI0_TX_DN3 @S9S_MB_2U_LIB.S9S_MB_2U(SCH_1):UPI_CPU1_CPU0_P0P1_DN(3)
  N1 UPI_CPU1_CPU0_P0P1_DN<2> UPI0_TX_DN2 @S9S_MB_2U_LIB.S9S_MB_2U(SCH_1):UPI_CPU1_CPU0_P0P1_DN(2)
  M2 UPI_CPU1_CPU0_P0P1_DN<1> UPI0_TX_DN1 @S9S_MB_2U_LIB.S9S_MB_2U(SCH_1):UPI_CPU1_CPU0_P0P1_DN(1)
  K4 UPI_CPU1_CPU0_P0P1_DN<0> UPI0_TX_DN0 @S9S_MB_2U_LIB.S9S_MB_2U(SCH_1):UPI_CPU1_CPU0_P0P1_DN(0)
 BU3 UPI_CPU1_CPU0_P0P1_DP<23> UPI0_TX_DP23 @S9S_MB_2U_LIB.S9S_MB_2U(SCH_1):UPI_CPU1_CPU0_P0P1_DP(23)
 BN3 UPI_CPU1_CPU0_P0P1_DP<22> UPI0_TX_DP22 @S9S_MB_2U_LIB.S9S_MB_2U(SCH_1):UPI_CPU1_CPU0_P0P1_DP(22)
 BL3 UPI_CPU1_CPU0_P0P1_DP<21> UPI0_TX_DP21 @S9S_MB_2U_LIB.S9S_MB_2U(SCH_1):UPI_CPU1_CPU0_P0P1_DP(21)
 BJ1 UPI_CPU1_CPU0_P0P1_DP<20> UPI0_TX_DP20 @S9S_MB_2U_LIB.S9S_MB_2U(SCH_1):UPI_CPU1_CPU0_P0P1_DP(20)
 BG3 UPI_CPU1_CPU0_P0P1_DP<19> UPI0_TX_DP19 @S9S_MB_2U_LIB.S9S_MB_2U(SCH_1):UPI_CPU1_CPU0_P0P1_DP(19)
 BE1 UPI_CPU1_CPU0_P0P1_DP<18> UPI0_TX_DP18 @S9S_MB_2U_LIB.S9S_MB_2U(SCH_1):UPI_CPU1_CPU0_P0P1_DP(18)
 BC3 UPI_CPU1_CPU0_P0P1_DP<17> UPI0_TX_DP17 @S9S_MB_2U_LIB.S9S_MB_2U(SCH_1):UPI_CPU1_CPU0_P0P1_DP(17)
 BA1 UPI_CPU1_CPU0_P0P1_DP<16> UPI0_TX_DP16 @S9S_MB_2U_LIB.S9S_MB_2U(SCH_1):UPI_CPU1_CPU0_P0P1_DP(16)
 AW3 UPI_CPU1_CPU0_P0P1_DP<15> UPI0_TX_DP15 @S9S_MB_2U_LIB.S9S_MB_2U(SCH_1):UPI_CPU1_CPU0_P0P1_DP(15)
 AV2 UPI_CPU1_CPU0_P0P1_DP<14> UPI0_TX_DP14 @S9S_MB_2U_LIB.S9S_MB_2U(SCH_1):UPI_CPU1_CPU0_P0P1_DP(14)
 AR3 UPI_CPU1_CPU0_P0P1_DP<13> UPI0_TX_DP13 @S9S_MB_2U_LIB.S9S_MB_2U(SCH_1):UPI_CPU1_CPU0_P0P1_DP(13)
 AN1 UPI_CPU1_CPU0_P0P1_DP<12> UPI0_TX_DP12 @S9S_MB_2U_LIB.S9S_MB_2U(SCH_1):UPI_CPU1_CPU0_P0P1_DP(12)
 AL3 UPI_CPU1_CPU0_P0P1_DP<11> UPI0_TX_DP11 @S9S_MB_2U_LIB.S9S_MB_2U(SCH_1):UPI_CPU1_CPU0_P0P1_DP(11)
 AJ1 UPI_CPU1_CPU0_P0P1_DP<10> UPI0_TX_DP10 @S9S_MB_2U_LIB.S9S_MB_2U(SCH_1):UPI_CPU1_CPU0_P0P1_DP(10)
 AG3 UPI_CPU1_CPU0_P0P1_DP<9> UPI0_TX_DP9 @S9S_MB_2U_LIB.S9S_MB_2U(SCH_1):UPI_CPU1_CPU0_P0P1_DP(9)
 AE1 UPI_CPU1_CPU0_P0P1_DP<8> UPI0_TX_DP8 @S9S_MB_2U_LIB.S9S_MB_2U(SCH_1):UPI_CPU1_CPU0_P0P1_DP(8)
 AC3 UPI_CPU1_CPU0_P0P1_DP<7> UPI0_TX_DP7 @S9S_MB_2U_LIB.S9S_MB_2U(SCH_1):UPI_CPU1_CPU0_P0P1_DP(7)
 AB2 UPI_CPU1_CPU0_P0P1_DP<6> UPI0_TX_DP6 @S9S_MB_2U_LIB.S9S_MB_2U(SCH_1):UPI_CPU1_CPU0_P0P1_DP(6)
  W3 UPI_CPU1_CPU0_P0P1_DP<5> UPI0_TX_DP5 @S9S_MB_2U_LIB.S9S_MB_2U(SCH_1):UPI_CPU1_CPU0_P0P1_DP(5)
  V2 UPI_CPU1_CPU0_P0P1_DP<4> UPI0_TX_DP4 @S9S_MB_2U_LIB.S9S_MB_2U(SCH_1):UPI_CPU1_CPU0_P0P1_DP(4)
  R3 UPI_CPU1_CPU0_P0P1_DP<3> UPI0_TX_DP3 @S9S_MB_2U_LIB.S9S_MB_2U(SCH_1):UPI_CPU1_CPU0_P0P1_DP(3)
  P2 UPI_CPU1_CPU0_P0P1_DP<2> UPI0_TX_DP2 @S9S_MB_2U_LIB.S9S_MB_2U(SCH_1):UPI_CPU1_CPU0_P0P1_DP(2)
  L3 UPI_CPU1_CPU0_P0P1_DP<1> UPI0_TX_DP1 @S9S_MB_2U_LIB.S9S_MB_2U(SCH_1):UPI_CPU1_CPU0_P0P1_DP(1)
  J3 UPI_CPU1_CPU0_P0P1_DP<0> UPI0_TX_DP0 @S9S_MB_2U_LIB.S9S_MB_2U(SCH_1):UPI_CPU1_CPU0_P0P1_DP(0)


DRAWING: @S9S_MB_2U_LIB.S9S_MB_2U(SCH_1):PAGE64 

SOCKET4677_AZIF0045P001C01CS-SA  I21  U1
 CB2 UPI_CPU0_CPU1_P0P1_DN<23> UPI1_RX_DN23 @S9S_MB_2U_LIB.S9S_MB_2U(SCH_1):UPI_CPU0_CPU1_P0P1_DN(23)
 CD2 UPI_CPU0_CPU1_P0P1_DN<22> UPI1_RX_DN22 @S9S_MB_2U_LIB.S9S_MB_2U(SCH_1):UPI_CPU0_CPU1_P0P1_DN(22)
 CF2 UPI_CPU0_CPU1_P0P1_DN<21> UPI1_RX_DN21 @S9S_MB_2U_LIB.S9S_MB_2U(SCH_1):UPI_CPU0_CPU1_P0P1_DN(21)
 CH2 UPI_CPU0_CPU1_P0P1_DN<20> UPI1_RX_DN20 @S9S_MB_2U_LIB.S9S_MB_2U(SCH_1):UPI_CPU0_CPU1_P0P1_DN(20)
 CJ1 UPI_CPU0_CPU1_P0P1_DN<19> UPI1_RX_DN19 @S9S_MB_2U_LIB.S9S_MB_2U(SCH_1):UPI_CPU0_CPU1_P0P1_DN(19)
 CL3 UPI_CPU0_CPU1_P0P1_DN<18> UPI1_RX_DN18 @S9S_MB_2U_LIB.S9S_MB_2U(SCH_1):UPI_CPU0_CPU1_P0P1_DN(18)
 CN1 UPI_CPU0_CPU1_P0P1_DN<17> UPI1_RX_DN17 @S9S_MB_2U_LIB.S9S_MB_2U(SCH_1):UPI_CPU0_CPU1_P0P1_DN(17)
 CR3 UPI_CPU0_CPU1_P0P1_DN<16> UPI1_RX_DN16 @S9S_MB_2U_LIB.S9S_MB_2U(SCH_1):UPI_CPU0_CPU1_P0P1_DN(16)
 CV2 UPI_CPU0_CPU1_P0P1_DN<15> UPI1_RX_DN15 @S9S_MB_2U_LIB.S9S_MB_2U(SCH_1):UPI_CPU0_CPU1_P0P1_DN(15)
 CY2 UPI_CPU0_CPU1_P0P1_DN<14> UPI1_RX_DN14 @S9S_MB_2U_LIB.S9S_MB_2U(SCH_1):UPI_CPU0_CPU1_P0P1_DN(14)
 DB2 UPI_CPU0_CPU1_P0P1_DN<13> UPI1_RX_DN13 @S9S_MB_2U_LIB.S9S_MB_2U(SCH_1):UPI_CPU0_CPU1_P0P1_DN(13)
 DD2 UPI_CPU0_CPU1_P0P1_DN<12> UPI1_RX_DN12 @S9S_MB_2U_LIB.S9S_MB_2U(SCH_1):UPI_CPU0_CPU1_P0P1_DN(12)
 DE1 UPI_CPU0_CPU1_P0P1_DN<11> UPI1_RX_DN11 @S9S_MB_2U_LIB.S9S_MB_2U(SCH_1):UPI_CPU0_CPU1_P0P1_DN(11)
 DG3 UPI_CPU0_CPU1_P0P1_DN<10> UPI1_RX_DN10 @S9S_MB_2U_LIB.S9S_MB_2U(SCH_1):UPI_CPU0_CPU1_P0P1_DN(10)
 DJ1 UPI_CPU0_CPU1_P0P1_DN<9> UPI1_RX_DN9 @S9S_MB_2U_LIB.S9S_MB_2U(SCH_1):UPI_CPU0_CPU1_P0P1_DN(9)
 DL3 UPI_CPU0_CPU1_P0P1_DN<8> UPI1_RX_DN8 @S9S_MB_2U_LIB.S9S_MB_2U(SCH_1):UPI_CPU0_CPU1_P0P1_DN(8)
 DN1 UPI_CPU0_CPU1_P0P1_DN<7> UPI1_RX_DN7 @S9S_MB_2U_LIB.S9S_MB_2U(SCH_1):UPI_CPU0_CPU1_P0P1_DN(7)
 DT2 UPI_CPU0_CPU1_P0P1_DN<6> UPI1_RX_DN6 @S9S_MB_2U_LIB.S9S_MB_2U(SCH_1):UPI_CPU0_CPU1_P0P1_DN(6)
 DU1 UPI_CPU0_CPU1_P0P1_DN<5> UPI1_RX_DN5 @S9S_MB_2U_LIB.S9S_MB_2U(SCH_1):UPI_CPU0_CPU1_P0P1_DN(5)
 DY2 UPI_CPU0_CPU1_P0P1_DN<4> UPI1_RX_DN4 @S9S_MB_2U_LIB.S9S_MB_2U(SCH_1):UPI_CPU0_CPU1_P0P1_DN(4)
 EA1 UPI_CPU0_CPU1_P0P1_DN<3> UPI1_RX_DN3 @S9S_MB_2U_LIB.S9S_MB_2U(SCH_1):UPI_CPU0_CPU1_P0P1_DN(3)
 ED2 UPI_CPU0_CPU1_P0P1_DN<2> UPI1_RX_DN2 @S9S_MB_2U_LIB.S9S_MB_2U(SCH_1):UPI_CPU0_CPU1_P0P1_DN(2)
 EE3 UPI_CPU0_CPU1_P0P1_DN<1> UPI1_RX_DN1 @S9S_MB_2U_LIB.S9S_MB_2U(SCH_1):UPI_CPU0_CPU1_P0P1_DN(1)
 EH2 UPI_CPU0_CPU1_P0P1_DN<0> UPI1_RX_DN0 @S9S_MB_2U_LIB.S9S_MB_2U(SCH_1):UPI_CPU0_CPU1_P0P1_DN(0)
 BY2 UPI_CPU0_CPU1_P0P1_DP<23> UPI1_RX_DP23 @S9S_MB_2U_LIB.S9S_MB_2U(SCH_1):UPI_CPU0_CPU1_P0P1_DP(23)
 CC3 UPI_CPU0_CPU1_P0P1_DP<22> UPI1_RX_DP22 @S9S_MB_2U_LIB.S9S_MB_2U(SCH_1):UPI_CPU0_CPU1_P0P1_DP(22)
 CE1 UPI_CPU0_CPU1_P0P1_DP<21> UPI1_RX_DP21 @S9S_MB_2U_LIB.S9S_MB_2U(SCH_1):UPI_CPU0_CPU1_P0P1_DP(21)
 CG3 UPI_CPU0_CPU1_P0P1_DP<20> UPI1_RX_DP20 @S9S_MB_2U_LIB.S9S_MB_2U(SCH_1):UPI_CPU0_CPU1_P0P1_DP(20)
 CK2 UPI_CPU0_CPU1_P0P1_DP<19> UPI1_RX_DP19 @S9S_MB_2U_LIB.S9S_MB_2U(SCH_1):UPI_CPU0_CPU1_P0P1_DP(19)
 CM2 UPI_CPU0_CPU1_P0P1_DP<18> UPI1_RX_DP18 @S9S_MB_2U_LIB.S9S_MB_2U(SCH_1):UPI_CPU0_CPU1_P0P1_DP(18)
 CP2 UPI_CPU0_CPU1_P0P1_DP<17> UPI1_RX_DP17 @S9S_MB_2U_LIB.S9S_MB_2U(SCH_1):UPI_CPU0_CPU1_P0P1_DP(17)
 CT2 UPI_CPU0_CPU1_P0P1_DP<16> UPI1_RX_DP16 @S9S_MB_2U_LIB.S9S_MB_2U(SCH_1):UPI_CPU0_CPU1_P0P1_DP(16)
 CU1 UPI_CPU0_CPU1_P0P1_DP<15> UPI1_RX_DP15 @S9S_MB_2U_LIB.S9S_MB_2U(SCH_1):UPI_CPU0_CPU1_P0P1_DP(15)
 CW3 UPI_CPU0_CPU1_P0P1_DP<14> UPI1_RX_DP14 @S9S_MB_2U_LIB.S9S_MB_2U(SCH_1):UPI_CPU0_CPU1_P0P1_DP(14)
 DA1 UPI_CPU0_CPU1_P0P1_DP<13> UPI1_RX_DP13 @S9S_MB_2U_LIB.S9S_MB_2U(SCH_1):UPI_CPU0_CPU1_P0P1_DP(13)
 DC3 UPI_CPU0_CPU1_P0P1_DP<12> UPI1_RX_DP12 @S9S_MB_2U_LIB.S9S_MB_2U(SCH_1):UPI_CPU0_CPU1_P0P1_DP(12)
 DF2 UPI_CPU0_CPU1_P0P1_DP<11> UPI1_RX_DP11 @S9S_MB_2U_LIB.S9S_MB_2U(SCH_1):UPI_CPU0_CPU1_P0P1_DP(11)
 DH2 UPI_CPU0_CPU1_P0P1_DP<10> UPI1_RX_DP10 @S9S_MB_2U_LIB.S9S_MB_2U(SCH_1):UPI_CPU0_CPU1_P0P1_DP(10)
 DK2 UPI_CPU0_CPU1_P0P1_DP<9> UPI1_RX_DP9 @S9S_MB_2U_LIB.S9S_MB_2U(SCH_1):UPI_CPU0_CPU1_P0P1_DP(9)
 DM2 UPI_CPU0_CPU1_P0P1_DP<8> UPI1_RX_DP8 @S9S_MB_2U_LIB.S9S_MB_2U(SCH_1):UPI_CPU0_CPU1_P0P1_DP(8)
 DP2 UPI_CPU0_CPU1_P0P1_DP<7> UPI1_RX_DP7 @S9S_MB_2U_LIB.S9S_MB_2U(SCH_1):UPI_CPU0_CPU1_P0P1_DP(7)
 DR3 UPI_CPU0_CPU1_P0P1_DP<6> UPI1_RX_DP6 @S9S_MB_2U_LIB.S9S_MB_2U(SCH_1):UPI_CPU0_CPU1_P0P1_DP(6)
 DV2 UPI_CPU0_CPU1_P0P1_DP<5> UPI1_RX_DP5 @S9S_MB_2U_LIB.S9S_MB_2U(SCH_1):UPI_CPU0_CPU1_P0P1_DP(5)
 DW3 UPI_CPU0_CPU1_P0P1_DP<4> UPI1_RX_DP4 @S9S_MB_2U_LIB.S9S_MB_2U(SCH_1):UPI_CPU0_CPU1_P0P1_DP(4)
 EB2 UPI_CPU0_CPU1_P0P1_DP<3> UPI1_RX_DP3 @S9S_MB_2U_LIB.S9S_MB_2U(SCH_1):UPI_CPU0_CPU1_P0P1_DP(3)
 EC3 UPI_CPU0_CPU1_P0P1_DP<2> UPI1_RX_DP2 @S9S_MB_2U_LIB.S9S_MB_2U(SCH_1):UPI_CPU0_CPU1_P0P1_DP(2)
 EG3 UPI_CPU0_CPU1_P0P1_DP<1> UPI1_RX_DP1 @S9S_MB_2U_LIB.S9S_MB_2U(SCH_1):UPI_CPU0_CPU1_P0P1_DP(1)
 EJ3 UPI_CPU0_CPU1_P0P1_DP<0> UPI1_RX_DP0 @S9S_MB_2U_LIB.S9S_MB_2U(SCH_1):UPI_CPU0_CPU1_P0P1_DP(0)
 BY6 UPI_CPU1_CPU0_P1P0_DN<23> UPI1_TX_DN23 @S9S_MB_2U_LIB.S9S_MB_2U(SCH_1):UPI_CPU1_CPU0_P1P0_DN(23)
 CA5 UPI_CPU1_CPU0_P1P0_DN<22> UPI1_TX_DN22 @S9S_MB_2U_LIB.S9S_MB_2U(SCH_1):UPI_CPU1_CPU0_P1P0_DN(22)
 CD6 UPI_CPU1_CPU0_P1P0_DN<21> UPI1_TX_DN21 @S9S_MB_2U_LIB.S9S_MB_2U(SCH_1):UPI_CPU1_CPU0_P1P0_DN(21)
 CE5 UPI_CPU1_CPU0_P1P0_DN<20> UPI1_TX_DN20 @S9S_MB_2U_LIB.S9S_MB_2U(SCH_1):UPI_CPU1_CPU0_P1P0_DN(20)
 CH6 UPI_CPU1_CPU0_P1P0_DN<19> UPI1_TX_DN19 @S9S_MB_2U_LIB.S9S_MB_2U(SCH_1):UPI_CPU1_CPU0_P1P0_DN(19)
 CJ5 UPI_CPU1_CPU0_P1P0_DN<18> UPI1_TX_DN18 @S9S_MB_2U_LIB.S9S_MB_2U(SCH_1):UPI_CPU1_CPU0_P1P0_DN(18)
 CM6 UPI_CPU1_CPU0_P1P0_DN<17> UPI1_TX_DN17 @S9S_MB_2U_LIB.S9S_MB_2U(SCH_1):UPI_CPU1_CPU0_P1P0_DN(17)
 CN5 UPI_CPU1_CPU0_P1P0_DN<16> UPI1_TX_DN16 @S9S_MB_2U_LIB.S9S_MB_2U(SCH_1):UPI_CPU1_CPU0_P1P0_DN(16)
 CT6 UPI_CPU1_CPU0_P1P0_DN<15> UPI1_TX_DN15 @S9S_MB_2U_LIB.S9S_MB_2U(SCH_1):UPI_CPU1_CPU0_P1P0_DN(15)
 CU5 UPI_CPU1_CPU0_P1P0_DN<14> UPI1_TX_DN14 @S9S_MB_2U_LIB.S9S_MB_2U(SCH_1):UPI_CPU1_CPU0_P1P0_DN(14)
 CY6 UPI_CPU1_CPU0_P1P0_DN<13> UPI1_TX_DN13 @S9S_MB_2U_LIB.S9S_MB_2U(SCH_1):UPI_CPU1_CPU0_P1P0_DN(13)
 DA5 UPI_CPU1_CPU0_P1P0_DN<12> UPI1_TX_DN12 @S9S_MB_2U_LIB.S9S_MB_2U(SCH_1):UPI_CPU1_CPU0_P1P0_DN(12)
 DD6 UPI_CPU1_CPU0_P1P0_DN<11> UPI1_TX_DN11 @S9S_MB_2U_LIB.S9S_MB_2U(SCH_1):UPI_CPU1_CPU0_P1P0_DN(11)
 DE5 UPI_CPU1_CPU0_P1P0_DN<10> UPI1_TX_DN10 @S9S_MB_2U_LIB.S9S_MB_2U(SCH_1):UPI_CPU1_CPU0_P1P0_DN(10)
 DH6 UPI_CPU1_CPU0_P1P0_DN<9> UPI1_TX_DN9 @S9S_MB_2U_LIB.S9S_MB_2U(SCH_1):UPI_CPU1_CPU0_P1P0_DN(9)
 DK6 UPI_CPU1_CPU0_P1P0_DN<8> UPI1_TX_DN8 @S9S_MB_2U_LIB.S9S_MB_2U(SCH_1):UPI_CPU1_CPU0_P1P0_DN(8)
 DL7 UPI_CPU1_CPU0_P1P0_DN<7> UPI1_TX_DN7 @S9S_MB_2U_LIB.S9S_MB_2U(SCH_1):UPI_CPU1_CPU0_P1P0_DN(7)
 DP6 UPI_CPU1_CPU0_P1P0_DN<6> UPI1_TX_DN6 @S9S_MB_2U_LIB.S9S_MB_2U(SCH_1):UPI_CPU1_CPU0_P1P0_DN(6)
 DT6 UPI_CPU1_CPU0_P1P0_DN<5> UPI1_TX_DN5 @S9S_MB_2U_LIB.S9S_MB_2U(SCH_1):UPI_CPU1_CPU0_P1P0_DN(5)
 DV6 UPI_CPU1_CPU0_P1P0_DN<4> UPI1_TX_DN4 @S9S_MB_2U_LIB.S9S_MB_2U(SCH_1):UPI_CPU1_CPU0_P1P0_DN(4)
 DY6 UPI_CPU1_CPU0_P1P0_DN<3> UPI1_TX_DN3 @S9S_MB_2U_LIB.S9S_MB_2U(SCH_1):UPI_CPU1_CPU0_P1P0_DN(3)
 EB6 UPI_CPU1_CPU0_P1P0_DN<2> UPI1_TX_DN2 @S9S_MB_2U_LIB.S9S_MB_2U(SCH_1):UPI_CPU1_CPU0_P1P0_DN(2)
 EC7 UPI_CPU1_CPU0_P1P0_DN<1> UPI1_TX_DN1 @S9S_MB_2U_LIB.S9S_MB_2U(SCH_1):UPI_CPU1_CPU0_P1P0_DN(1)
 EF6 UPI_CPU1_CPU0_P1P0_DN<0> UPI1_TX_DN0 @S9S_MB_2U_LIB.S9S_MB_2U(SCH_1):UPI_CPU1_CPU0_P1P0_DN(0)
 BW7 UPI_CPU1_CPU0_P1P0_DP<23> UPI1_TX_DP23 @S9S_MB_2U_LIB.S9S_MB_2U(SCH_1):UPI_CPU1_CPU0_P1P0_DP(23)
 CB6 UPI_CPU1_CPU0_P1P0_DP<22> UPI1_TX_DP22 @S9S_MB_2U_LIB.S9S_MB_2U(SCH_1):UPI_CPU1_CPU0_P1P0_DP(22)
 CC7 UPI_CPU1_CPU0_P1P0_DP<21> UPI1_TX_DP21 @S9S_MB_2U_LIB.S9S_MB_2U(SCH_1):UPI_CPU1_CPU0_P1P0_DP(21)
 CF6 UPI_CPU1_CPU0_P1P0_DP<20> UPI1_TX_DP20 @S9S_MB_2U_LIB.S9S_MB_2U(SCH_1):UPI_CPU1_CPU0_P1P0_DP(20)
 CG7 UPI_CPU1_CPU0_P1P0_DP<19> UPI1_TX_DP19 @S9S_MB_2U_LIB.S9S_MB_2U(SCH_1):UPI_CPU1_CPU0_P1P0_DP(19)
 CK6 UPI_CPU1_CPU0_P1P0_DP<18> UPI1_TX_DP18 @S9S_MB_2U_LIB.S9S_MB_2U(SCH_1):UPI_CPU1_CPU0_P1P0_DP(18)
 CL7 UPI_CPU1_CPU0_P1P0_DP<17> UPI1_TX_DP17 @S9S_MB_2U_LIB.S9S_MB_2U(SCH_1):UPI_CPU1_CPU0_P1P0_DP(17)
 CP6 UPI_CPU1_CPU0_P1P0_DP<16> UPI1_TX_DP16 @S9S_MB_2U_LIB.S9S_MB_2U(SCH_1):UPI_CPU1_CPU0_P1P0_DP(16)
 CR7 UPI_CPU1_CPU0_P1P0_DP<15> UPI1_TX_DP15 @S9S_MB_2U_LIB.S9S_MB_2U(SCH_1):UPI_CPU1_CPU0_P1P0_DP(15)
 CV6 UPI_CPU1_CPU0_P1P0_DP<14> UPI1_TX_DP14 @S9S_MB_2U_LIB.S9S_MB_2U(SCH_1):UPI_CPU1_CPU0_P1P0_DP(14)
 CW7 UPI_CPU1_CPU0_P1P0_DP<13> UPI1_TX_DP13 @S9S_MB_2U_LIB.S9S_MB_2U(SCH_1):UPI_CPU1_CPU0_P1P0_DP(13)
 DB6 UPI_CPU1_CPU0_P1P0_DP<12> UPI1_TX_DP12 @S9S_MB_2U_LIB.S9S_MB_2U(SCH_1):UPI_CPU1_CPU0_P1P0_DP(12)
 DC7 UPI_CPU1_CPU0_P1P0_DP<11> UPI1_TX_DP11 @S9S_MB_2U_LIB.S9S_MB_2U(SCH_1):UPI_CPU1_CPU0_P1P0_DP(11)
 DF6 UPI_CPU1_CPU0_P1P0_DP<10> UPI1_TX_DP10 @S9S_MB_2U_LIB.S9S_MB_2U(SCH_1):UPI_CPU1_CPU0_P1P0_DP(10)
 DG7 UPI_CPU1_CPU0_P1P0_DP<9> UPI1_TX_DP9 @S9S_MB_2U_LIB.S9S_MB_2U(SCH_1):UPI_CPU1_CPU0_P1P0_DP(9)
 DJ5 UPI_CPU1_CPU0_P1P0_DP<8> UPI1_TX_DP8 @S9S_MB_2U_LIB.S9S_MB_2U(SCH_1):UPI_CPU1_CPU0_P1P0_DP(8)
 DM6 UPI_CPU1_CPU0_P1P0_DP<7> UPI1_TX_DP7 @S9S_MB_2U_LIB.S9S_MB_2U(SCH_1):UPI_CPU1_CPU0_P1P0_DP(7)
 DN5 UPI_CPU1_CPU0_P1P0_DP<6> UPI1_TX_DP6 @S9S_MB_2U_LIB.S9S_MB_2U(SCH_1):UPI_CPU1_CPU0_P1P0_DP(6)
 DR7 UPI_CPU1_CPU0_P1P0_DP<5> UPI1_TX_DP5 @S9S_MB_2U_LIB.S9S_MB_2U(SCH_1):UPI_CPU1_CPU0_P1P0_DP(5)
 DU5 UPI_CPU1_CPU0_P1P0_DP<4> UPI1_TX_DP4 @S9S_MB_2U_LIB.S9S_MB_2U(SCH_1):UPI_CPU1_CPU0_P1P0_DP(4)
 DW7 UPI_CPU1_CPU0_P1P0_DP<3> UPI1_TX_DP3 @S9S_MB_2U_LIB.S9S_MB_2U(SCH_1):UPI_CPU1_CPU0_P1P0_DP(3)
 EA5 UPI_CPU1_CPU0_P1P0_DP<2> UPI1_TX_DP2 @S9S_MB_2U_LIB.S9S_MB_2U(SCH_1):UPI_CPU1_CPU0_P1P0_DP(2)
 ED6 UPI_CPU1_CPU0_P1P0_DP<1> UPI1_TX_DP1 @S9S_MB_2U_LIB.S9S_MB_2U(SCH_1):UPI_CPU1_CPU0_P1P0_DP(1)
 EE5 UPI_CPU1_CPU0_P1P0_DP<0> UPI1_TX_DP0 @S9S_MB_2U_LIB.S9S_MB_2U(SCH_1):UPI_CPU1_CPU0_P1P0_DP(0)


DRAWING: @S9S_MB_2U_LIB.S9S_MB_2U(SCH_1):PAGE65 

SOCKET4677_AZIF0045P001C01CS-SA  I16  U1
BD73 UPI_CPU0_CPU1_P2P2_DN<23> UPI2_RX_DN23 @S9S_MB_2U_LIB.S9S_MB_2U(SCH_1):UPI_CPU0_CPU1_P2P2_DN(23)
BK73 UPI_CPU0_CPU1_P2P2_DN<22> UPI2_RX_DN22 @S9S_MB_2U_LIB.S9S_MB_2U(SCH_1):UPI_CPU0_CPU1_P2P2_DN(22)
BN74 UPI_CPU0_CPU1_P2P2_DN<21> UPI2_RX_DN21 @S9S_MB_2U_LIB.S9S_MB_2U(SCH_1):UPI_CPU0_CPU1_P2P2_DN(21)
BG74 UPI_CPU0_CPU1_P2P2_DN<20> UPI2_RX_DN20 @S9S_MB_2U_LIB.S9S_MB_2U(SCH_1):UPI_CPU0_CPU1_P2P2_DN(20)
BL76 UPI_CPU0_CPU1_P2P2_DN<19> UPI2_RX_DN19 @S9S_MB_2U_LIB.S9S_MB_2U(SCH_1):UPI_CPU0_CPU1_P2P2_DN(19)
BJ76 UPI_CPU0_CPU1_P2P2_DN<18> UPI2_RX_DN18 @S9S_MB_2U_LIB.S9S_MB_2U(SCH_1):UPI_CPU0_CPU1_P2P2_DN(18)
BH75 UPI_CPU0_CPU1_P2P2_DN<17> UPI2_RX_DN17 @S9S_MB_2U_LIB.S9S_MB_2U(SCH_1):UPI_CPU0_CPU1_P2P2_DN(17)
AW74 UPI_CPU0_CPU1_P2P2_DN<16> UPI2_RX_DN16 @S9S_MB_2U_LIB.S9S_MB_2U(SCH_1):UPI_CPU0_CPU1_P2P2_DN(16)
BB75 UPI_CPU0_CPU1_P2P2_DN<15> UPI2_RX_DN15 @S9S_MB_2U_LIB.S9S_MB_2U(SCH_1):UPI_CPU0_CPU1_P2P2_DN(15)
AY75 UPI_CPU0_CPU1_P2P2_DN<14> UPI2_RX_DN14 @S9S_MB_2U_LIB.S9S_MB_2U(SCH_1):UPI_CPU0_CPU1_P2P2_DN(14)
AV73 UPI_CPU0_CPU1_P2P2_DN<13> UPI2_RX_DN13 @S9S_MB_2U_LIB.S9S_MB_2U(SCH_1):UPI_CPU0_CPU1_P2P2_DN(13)
BA72 UPI_CPU0_CPU1_P2P2_DN<12> UPI2_RX_DN12 @S9S_MB_2U_LIB.S9S_MB_2U(SCH_1):UPI_CPU0_CPU1_P2P2_DN(12)
AG82 UPI_CPU0_CPU1_P2P2_DN<11> UPI2_RX_DN11 @S9S_MB_2U_LIB.S9S_MB_2U(SCH_1):UPI_CPU0_CPU1_P2P2_DN(11)
AJ80 UPI_CPU0_CPU1_P2P2_DN<10> UPI2_RX_DN10 @S9S_MB_2U_LIB.S9S_MB_2U(SCH_1):UPI_CPU0_CPU1_P2P2_DN(10)
AE82 UPI_CPU0_CPU1_P2P2_DN<9> UPI2_RX_DN9 @S9S_MB_2U_LIB.S9S_MB_2U(SCH_1):UPI_CPU0_CPU1_P2P2_DN(9)
AF79 UPI_CPU0_CPU1_P2P2_DN<8> UPI2_RX_DN8 @S9S_MB_2U_LIB.S9S_MB_2U(SCH_1):UPI_CPU0_CPU1_P2P2_DN(8)
AD81 UPI_CPU0_CPU1_P2P2_DN<7> UPI2_RX_DN7 @S9S_MB_2U_LIB.S9S_MB_2U(SCH_1):UPI_CPU0_CPU1_P2P2_DN(7)
AC80 UPI_CPU0_CPU1_P2P2_DN<6> UPI2_RX_DN6 @S9S_MB_2U_LIB.S9S_MB_2U(SCH_1):UPI_CPU0_CPU1_P2P2_DN(6)
 L80 UPI_CPU0_CPU1_P2P2_DN<5> UPI2_RX_DN5 @S9S_MB_2U_LIB.S9S_MB_2U(SCH_1):UPI_CPU0_CPU1_P2P2_DN(5)
 J82 UPI_CPU0_CPU1_P2P2_DN<4> UPI2_RX_DN4 @S9S_MB_2U_LIB.S9S_MB_2U(SCH_1):UPI_CPU0_CPU1_P2P2_DN(4)
 K79 UPI_CPU0_CPU1_P2P2_DN<3> UPI2_RX_DN3 @S9S_MB_2U_LIB.S9S_MB_2U(SCH_1):UPI_CPU0_CPU1_P2P2_DN(3)
 G82 UPI_CPU0_CPU1_P2P2_DN<2> UPI2_RX_DN2 @S9S_MB_2U_LIB.S9S_MB_2U(SCH_1):UPI_CPU0_CPU1_P2P2_DN(2)
 F81 UPI_CPU0_CPU1_P2P2_DN<1> UPI2_RX_DN1 @S9S_MB_2U_LIB.S9S_MB_2U(SCH_1):UPI_CPU0_CPU1_P2P2_DN(1)
 E80 UPI_CPU0_CPU1_P2P2_DN<0> UPI2_RX_DN0 @S9S_MB_2U_LIB.S9S_MB_2U(SCH_1):UPI_CPU0_CPU1_P2P2_DN(0)
BC74 UPI_CPU0_CPU1_P2P2_DP<23> UPI2_RX_DP23 @S9S_MB_2U_LIB.S9S_MB_2U(SCH_1):UPI_CPU0_CPU1_P2P2_DP(23)
BL74 UPI_CPU0_CPU1_P2P2_DP<22> UPI2_RX_DP22 @S9S_MB_2U_LIB.S9S_MB_2U(SCH_1):UPI_CPU0_CPU1_P2P2_DP(22)
BM75 UPI_CPU0_CPU1_P2P2_DP<21> UPI2_RX_DP21 @S9S_MB_2U_LIB.S9S_MB_2U(SCH_1):UPI_CPU0_CPU1_P2P2_DP(21)
BJ74 UPI_CPU0_CPU1_P2P2_DP<20> UPI2_RX_DP20 @S9S_MB_2U_LIB.S9S_MB_2U(SCH_1):UPI_CPU0_CPU1_P2P2_DP(20)
BN76 UPI_CPU0_CPU1_P2P2_DP<19> UPI2_RX_DP19 @S9S_MB_2U_LIB.S9S_MB_2U(SCH_1):UPI_CPU0_CPU1_P2P2_DP(19)
BK77 UPI_CPU0_CPU1_P2P2_DP<18> UPI2_RX_DP18 @S9S_MB_2U_LIB.S9S_MB_2U(SCH_1):UPI_CPU0_CPU1_P2P2_DP(18)
BG76 UPI_CPU0_CPU1_P2P2_DP<17> UPI2_RX_DP17 @S9S_MB_2U_LIB.S9S_MB_2U(SCH_1):UPI_CPU0_CPU1_P2P2_DP(17)
AV75 UPI_CPU0_CPU1_P2P2_DP<16> UPI2_RX_DP16 @S9S_MB_2U_LIB.S9S_MB_2U(SCH_1):UPI_CPU0_CPU1_P2P2_DP(16)
BD75 UPI_CPU0_CPU1_P2P2_DP<15> UPI2_RX_DP15 @S9S_MB_2U_LIB.S9S_MB_2U(SCH_1):UPI_CPU0_CPU1_P2P2_DP(15)
BA76 UPI_CPU0_CPU1_P2P2_DP<14> UPI2_RX_DP14 @S9S_MB_2U_LIB.S9S_MB_2U(SCH_1):UPI_CPU0_CPU1_P2P2_DP(14)
AY73 UPI_CPU0_CPU1_P2P2_DP<13> UPI2_RX_DP13 @S9S_MB_2U_LIB.S9S_MB_2U(SCH_1):UPI_CPU0_CPU1_P2P2_DP(13)
BB73 UPI_CPU0_CPU1_P2P2_DP<12> UPI2_RX_DP12 @S9S_MB_2U_LIB.S9S_MB_2U(SCH_1):UPI_CPU0_CPU1_P2P2_DP(12)
AJ82 UPI_CPU0_CPU1_P2P2_DP<11> UPI2_RX_DP11 @S9S_MB_2U_LIB.S9S_MB_2U(SCH_1):UPI_CPU0_CPU1_P2P2_DP(11)
AH81 UPI_CPU0_CPU1_P2P2_DP<10> UPI2_RX_DP10 @S9S_MB_2U_LIB.S9S_MB_2U(SCH_1):UPI_CPU0_CPU1_P2P2_DP(10)
AF83 UPI_CPU0_CPU1_P2P2_DP<9> UPI2_RX_DP9 @S9S_MB_2U_LIB.S9S_MB_2U(SCH_1):UPI_CPU0_CPU1_P2P2_DP(9)
AG80 UPI_CPU0_CPU1_P2P2_DP<8> UPI2_RX_DP8 @S9S_MB_2U_LIB.S9S_MB_2U(SCH_1):UPI_CPU0_CPU1_P2P2_DP(8)
AC82 UPI_CPU0_CPU1_P2P2_DP<7> UPI2_RX_DP7 @S9S_MB_2U_LIB.S9S_MB_2U(SCH_1):UPI_CPU0_CPU1_P2P2_DP(7)
AE80 UPI_CPU0_CPU1_P2P2_DP<6> UPI2_RX_DP6 @S9S_MB_2U_LIB.S9S_MB_2U(SCH_1):UPI_CPU0_CPU1_P2P2_DP(6)
 K81 UPI_CPU0_CPU1_P2P2_DP<5> UPI2_RX_DP5 @S9S_MB_2U_LIB.S9S_MB_2U(SCH_1):UPI_CPU0_CPU1_P2P2_DP(5)
 L82 UPI_CPU0_CPU1_P2P2_DP<4> UPI2_RX_DP4 @S9S_MB_2U_LIB.S9S_MB_2U(SCH_1):UPI_CPU0_CPU1_P2P2_DP(4)
 M79 UPI_CPU0_CPU1_P2P2_DP<3> UPI2_RX_DP3 @S9S_MB_2U_LIB.S9S_MB_2U(SCH_1):UPI_CPU0_CPU1_P2P2_DP(3)
 H83 UPI_CPU0_CPU1_P2P2_DP<2> UPI2_RX_DP2 @S9S_MB_2U_LIB.S9S_MB_2U(SCH_1):UPI_CPU0_CPU1_P2P2_DP(2)
 E82 UPI_CPU0_CPU1_P2P2_DP<1> UPI2_RX_DP1 @S9S_MB_2U_LIB.S9S_MB_2U(SCH_1):UPI_CPU0_CPU1_P2P2_DP(1)
 G80 UPI_CPU0_CPU1_P2P2_DP<0> UPI2_RX_DP0 @S9S_MB_2U_LIB.S9S_MB_2U(SCH_1):UPI_CPU0_CPU1_P2P2_DP(0)
BM71 UPI_CPU1_CPU0_P2P2_DN<23> UPI2_TX_DN23 @S9S_MB_2U_LIB.S9S_MB_2U(SCH_1):UPI_CPU1_CPU0_P2P2_DN(23)
BG80 UPI_CPU1_CPU0_P2P2_DN<22> UPI2_TX_DN22 @S9S_MB_2U_LIB.S9S_MB_2U(SCH_1):UPI_CPU1_CPU0_P2P2_DN(22)
BF81 UPI_CPU1_CPU0_P2P2_DN<21> UPI2_TX_DN21 @S9S_MB_2U_LIB.S9S_MB_2U(SCH_1):UPI_CPU1_CPU0_P2P2_DN(21)
BD79 UPI_CPU1_CPU0_P2P2_DN<20> UPI2_TX_DN20 @S9S_MB_2U_LIB.S9S_MB_2U(SCH_1):UPI_CPU1_CPU0_P2P2_DN(20)
BE82 UPI_CPU1_CPU0_P2P2_DN<19> UPI2_TX_DN19 @S9S_MB_2U_LIB.S9S_MB_2U(SCH_1):UPI_CPU1_CPU0_P2P2_DN(19)
BC82 UPI_CPU1_CPU0_P2P2_DN<18> UPI2_TX_DN18 @S9S_MB_2U_LIB.S9S_MB_2U(SCH_1):UPI_CPU1_CPU0_P2P2_DN(18)
BA80 UPI_CPU1_CPU0_P2P2_DN<17> UPI2_TX_DN17 @S9S_MB_2U_LIB.S9S_MB_2U(SCH_1):UPI_CPU1_CPU0_P2P2_DN(17)
AV81 UPI_CPU1_CPU0_P2P2_DN<16> UPI2_TX_DN16 @S9S_MB_2U_LIB.S9S_MB_2U(SCH_1):UPI_CPU1_CPU0_P2P2_DN(16)
AT83 UPI_CPU1_CPU0_P2P2_DN<15> UPI2_TX_DN15 @S9S_MB_2U_LIB.S9S_MB_2U(SCH_1):UPI_CPU1_CPU0_P2P2_DN(15)
AR80 UPI_CPU1_CPU0_P2P2_DN<14> UPI2_TX_DN14 @S9S_MB_2U_LIB.S9S_MB_2U(SCH_1):UPI_CPU1_CPU0_P2P2_DN(14)
AN82 UPI_CPU1_CPU0_P2P2_DN<13> UPI2_TX_DN13 @S9S_MB_2U_LIB.S9S_MB_2U(SCH_1):UPI_CPU1_CPU0_P2P2_DN(13)
AM81 UPI_CPU1_CPU0_P2P2_DN<12> UPI2_TX_DN12 @S9S_MB_2U_LIB.S9S_MB_2U(SCH_1):UPI_CPU1_CPU0_P2P2_DN(12)
AU78 UPI_CPU1_CPU0_P2P2_DN<11> UPI2_TX_DN11 @S9S_MB_2U_LIB.S9S_MB_2U(SCH_1):UPI_CPU1_CPU0_P2P2_DN(11)
AW78 UPI_CPU1_CPU0_P2P2_DN<10> UPI2_TX_DN10 @S9S_MB_2U_LIB.S9S_MB_2U(SCH_1):UPI_CPU1_CPU0_P2P2_DN(10)
 Y81 UPI_CPU1_CPU0_P2P2_DN<9> UPI2_TX_DN9 @S9S_MB_2U_LIB.S9S_MB_2U(SCH_1):UPI_CPU1_CPU0_P2P2_DN(9)
 V83 UPI_CPU1_CPU0_P2P2_DN<8> UPI2_TX_DN8 @S9S_MB_2U_LIB.S9S_MB_2U(SCH_1):UPI_CPU1_CPU0_P2P2_DN(8)
 U80 UPI_CPU1_CPU0_P2P2_DN<7> UPI2_TX_DN7 @S9S_MB_2U_LIB.S9S_MB_2U(SCH_1):UPI_CPU1_CPU0_P2P2_DN(7)
 R82 UPI_CPU1_CPU0_P2P2_DN<6> UPI2_TX_DN6 @S9S_MB_2U_LIB.S9S_MB_2U(SCH_1):UPI_CPU1_CPU0_P2P2_DN(6)
 P81 UPI_CPU1_CPU0_P2P2_DN<5> UPI2_TX_DN5 @S9S_MB_2U_LIB.S9S_MB_2U(SCH_1):UPI_CPU1_CPU0_P2P2_DN(5)
 H85 UPI_CPU1_CPU0_P2P2_DN<4> UPI2_TX_DN4 @S9S_MB_2U_LIB.S9S_MB_2U(SCH_1):UPI_CPU1_CPU0_P2P2_DN(4)
 F87 UPI_CPU1_CPU0_P2P2_DN<3> UPI2_TX_DN3 @S9S_MB_2U_LIB.S9S_MB_2U(SCH_1):UPI_CPU1_CPU0_P2P2_DN(3)
 D87 UPI_CPU1_CPU0_P2P2_DN<2> UPI2_TX_DN2 @S9S_MB_2U_LIB.S9S_MB_2U(SCH_1):UPI_CPU1_CPU0_P2P2_DN(2)
 E84 UPI_CPU1_CPU0_P2P2_DN<1> UPI2_TX_DN1 @S9S_MB_2U_LIB.S9S_MB_2U(SCH_1):UPI_CPU1_CPU0_P2P2_DN(1)
 B85 UPI_CPU1_CPU0_P2P2_DN<0> UPI2_TX_DN0 @S9S_MB_2U_LIB.S9S_MB_2U(SCH_1):UPI_CPU1_CPU0_P2P2_DN(0)
BN72 UPI_CPU1_CPU0_P2P2_DP<23> UPI2_TX_DP23 @S9S_MB_2U_LIB.S9S_MB_2U(SCH_1):UPI_CPU1_CPU0_P2P2_DP(23)
BE80 UPI_CPU1_CPU0_P2P2_DP<22> UPI2_TX_DP22 @S9S_MB_2U_LIB.S9S_MB_2U(SCH_1):UPI_CPU1_CPU0_P2P2_DP(22)
BG82 UPI_CPU1_CPU0_P2P2_DP<21> UPI2_TX_DP21 @S9S_MB_2U_LIB.S9S_MB_2U(SCH_1):UPI_CPU1_CPU0_P2P2_DP(21)
BC80 UPI_CPU1_CPU0_P2P2_DP<20> UPI2_TX_DP20 @S9S_MB_2U_LIB.S9S_MB_2U(SCH_1):UPI_CPU1_CPU0_P2P2_DP(20)
BD83 UPI_CPU1_CPU0_P2P2_DP<19> UPI2_TX_DP19 @S9S_MB_2U_LIB.S9S_MB_2U(SCH_1):UPI_CPU1_CPU0_P2P2_DP(19)
BA82 UPI_CPU1_CPU0_P2P2_DP<18> UPI2_TX_DP18 @S9S_MB_2U_LIB.S9S_MB_2U(SCH_1):UPI_CPU1_CPU0_P2P2_DP(18)
BB81 UPI_CPU1_CPU0_P2P2_DP<17> UPI2_TX_DP17 @S9S_MB_2U_LIB.S9S_MB_2U(SCH_1):UPI_CPU1_CPU0_P2P2_DP(17)
AU82 UPI_CPU1_CPU0_P2P2_DP<16> UPI2_TX_DP16 @S9S_MB_2U_LIB.S9S_MB_2U(SCH_1):UPI_CPU1_CPU0_P2P2_DP(16)
AV83 UPI_CPU1_CPU0_P2P2_DP<15> UPI2_TX_DP15 @S9S_MB_2U_LIB.S9S_MB_2U(SCH_1):UPI_CPU1_CPU0_P2P2_DP(15)
AT81 UPI_CPU1_CPU0_P2P2_DP<14> UPI2_TX_DP14 @S9S_MB_2U_LIB.S9S_MB_2U(SCH_1):UPI_CPU1_CPU0_P2P2_DP(14)
AM83 UPI_CPU1_CPU0_P2P2_DP<13> UPI2_TX_DP13 @S9S_MB_2U_LIB.S9S_MB_2U(SCH_1):UPI_CPU1_CPU0_P2P2_DP(13)
AP81 UPI_CPU1_CPU0_P2P2_DP<12> UPI2_TX_DP12 @S9S_MB_2U_LIB.S9S_MB_2U(SCH_1):UPI_CPU1_CPU0_P2P2_DP(12)
AV79 UPI_CPU1_CPU0_P2P2_DP<11> UPI2_TX_DP11 @S9S_MB_2U_LIB.S9S_MB_2U(SCH_1):UPI_CPU1_CPU0_P2P2_DP(11)
BA78 UPI_CPU1_CPU0_P2P2_DP<10> UPI2_TX_DP10 @S9S_MB_2U_LIB.S9S_MB_2U(SCH_1):UPI_CPU1_CPU0_P2P2_DP(10)
 W82 UPI_CPU1_CPU0_P2P2_DP<9> UPI2_TX_DP9 @S9S_MB_2U_LIB.S9S_MB_2U(SCH_1):UPI_CPU1_CPU0_P2P2_DP(9)
 Y83 UPI_CPU1_CPU0_P2P2_DP<8> UPI2_TX_DP8 @S9S_MB_2U_LIB.S9S_MB_2U(SCH_1):UPI_CPU1_CPU0_P2P2_DP(8)
 V81 UPI_CPU1_CPU0_P2P2_DP<7> UPI2_TX_DP7 @S9S_MB_2U_LIB.S9S_MB_2U(SCH_1):UPI_CPU1_CPU0_P2P2_DP(7)
 P83 UPI_CPU1_CPU0_P2P2_DP<6> UPI2_TX_DP6 @S9S_MB_2U_LIB.S9S_MB_2U(SCH_1):UPI_CPU1_CPU0_P2P2_DP(6)
 T81 UPI_CPU1_CPU0_P2P2_DP<5> UPI2_TX_DP5 @S9S_MB_2U_LIB.S9S_MB_2U(SCH_1):UPI_CPU1_CPU0_P2P2_DP(5)
 G86 UPI_CPU1_CPU0_P2P2_DP<4> UPI2_TX_DP4 @S9S_MB_2U_LIB.S9S_MB_2U(SCH_1):UPI_CPU1_CPU0_P2P2_DP(4)
 H87 UPI_CPU1_CPU0_P2P2_DP<3> UPI2_TX_DP3 @S9S_MB_2U_LIB.S9S_MB_2U(SCH_1):UPI_CPU1_CPU0_P2P2_DP(3)
 E88 UPI_CPU1_CPU0_P2P2_DP<2> UPI2_TX_DP2 @S9S_MB_2U_LIB.S9S_MB_2U(SCH_1):UPI_CPU1_CPU0_P2P2_DP(2)
 F85 UPI_CPU1_CPU0_P2P2_DP<1> UPI2_TX_DP1 @S9S_MB_2U_LIB.S9S_MB_2U(SCH_1):UPI_CPU1_CPU0_P2P2_DP(1)
 D85 UPI_CPU1_CPU0_P2P2_DP<0> UPI2_TX_DP0 @S9S_MB_2U_LIB.S9S_MB_2U(SCH_1):UPI_CPU1_CPU0_P2P2_DP(0)


DRAWING: @S9S_MB_2U_LIB.S9S_MB_2U(SCH_1):PAGE66 

SOCKET4677_AZIF0045P001C01CS-SA  I16  U1
DA78    GND UPI3_RX_DN23 @S9S_MB_2U_LIB.S9S_MB_2U(SCH_1):GND
CT79    GND UPI3_RX_DN22 @S9S_MB_2U_LIB.S9S_MB_2U(SCH_1):GND
CN80    GND UPI3_RX_DN21 @S9S_MB_2U_LIB.S9S_MB_2U(SCH_1):GND
CP81    GND UPI3_RX_DN20 @S9S_MB_2U_LIB.S9S_MB_2U(SCH_1):GND
CW80    GND UPI3_RX_DN19 @S9S_MB_2U_LIB.S9S_MB_2U(SCH_1):GND
CR82    GND UPI3_RX_DN18 @S9S_MB_2U_LIB.S9S_MB_2U(SCH_1):GND
CU82    GND UPI3_RX_DN17 @S9S_MB_2U_LIB.S9S_MB_2U(SCH_1):GND
DF77    GND UPI3_RX_DN16 @S9S_MB_2U_LIB.S9S_MB_2U(SCH_1):GND
DB81    GND UPI3_RX_DN15 @S9S_MB_2U_LIB.S9S_MB_2U(SCH_1):GND
DC82    GND UPI3_RX_DN14 @S9S_MB_2U_LIB.S9S_MB_2U(SCH_1):GND
DE80    GND UPI3_RX_DN13 @S9S_MB_2U_LIB.S9S_MB_2U(SCH_1):GND
DF83    GND UPI3_RX_DN12 @S9S_MB_2U_LIB.S9S_MB_2U(SCH_1):GND
DH81    GND UPI3_RX_DN11 @S9S_MB_2U_LIB.S9S_MB_2U(SCH_1):GND
DG78    GND UPI3_RX_DN10 @S9S_MB_2U_LIB.S9S_MB_2U(SCH_1):GND
DJ78    GND UPI3_RX_DN9 @S9S_MB_2U_LIB.S9S_MB_2U(SCH_1):GND
DY81    GND UPI3_RX_DN8 @S9S_MB_2U_LIB.S9S_MB_2U(SCH_1):GND
EA82    GND UPI3_RX_DN7 @S9S_MB_2U_LIB.S9S_MB_2U(SCH_1):GND
EC80    GND UPI3_RX_DN6 @S9S_MB_2U_LIB.S9S_MB_2U(SCH_1):GND
ED83    GND UPI3_RX_DN5 @S9S_MB_2U_LIB.S9S_MB_2U(SCH_1):GND
EF81    GND UPI3_RX_DN4 @S9S_MB_2U_LIB.S9S_MB_2U(SCH_1):GND
EK81    GND UPI3_RX_DN3 @S9S_MB_2U_LIB.S9S_MB_2U(SCH_1):GND
EL82    GND UPI3_RX_DN2 @S9S_MB_2U_LIB.S9S_MB_2U(SCH_1):GND
EP81    GND UPI3_RX_DN1 @S9S_MB_2U_LIB.S9S_MB_2U(SCH_1):GND
EJ80    GND UPI3_RX_DN0 @S9S_MB_2U_LIB.S9S_MB_2U(SCH_1):GND
DB79    GND UPI3_RX_DP23 @S9S_MB_2U_LIB.S9S_MB_2U(SCH_1):GND
CU80    GND UPI3_RX_DP22 @S9S_MB_2U_LIB.S9S_MB_2U(SCH_1):GND
CR80    GND UPI3_RX_DP21 @S9S_MB_2U_LIB.S9S_MB_2U(SCH_1):GND
CN82    GND UPI3_RX_DP20 @S9S_MB_2U_LIB.S9S_MB_2U(SCH_1):GND
CV81    GND UPI3_RX_DP19 @S9S_MB_2U_LIB.S9S_MB_2U(SCH_1):GND
CT83    GND UPI3_RX_DP18 @S9S_MB_2U_LIB.S9S_MB_2U(SCH_1):GND
CW82    GND UPI3_RX_DP17 @S9S_MB_2U_LIB.S9S_MB_2U(SCH_1):GND
DE78    GND UPI3_RX_DP16 @S9S_MB_2U_LIB.S9S_MB_2U(SCH_1):GND
DD81    GND UPI3_RX_DP15 @S9S_MB_2U_LIB.S9S_MB_2U(SCH_1):GND
DB83    GND UPI3_RX_DP14 @S9S_MB_2U_LIB.S9S_MB_2U(SCH_1):GND
DF81    GND UPI3_RX_DP13 @S9S_MB_2U_LIB.S9S_MB_2U(SCH_1):GND
DH83    GND UPI3_RX_DP12 @S9S_MB_2U_LIB.S9S_MB_2U(SCH_1):GND
DG82    GND UPI3_RX_DP11 @S9S_MB_2U_LIB.S9S_MB_2U(SCH_1):GND
DH79    GND UPI3_RX_DP10 @S9S_MB_2U_LIB.S9S_MB_2U(SCH_1):GND
DL78    GND UPI3_RX_DP9 @S9S_MB_2U_LIB.S9S_MB_2U(SCH_1):GND
EB81    GND UPI3_RX_DP8 @S9S_MB_2U_LIB.S9S_MB_2U(SCH_1):GND
DY83    GND UPI3_RX_DP7 @S9S_MB_2U_LIB.S9S_MB_2U(SCH_1):GND
ED81    GND UPI3_RX_DP6 @S9S_MB_2U_LIB.S9S_MB_2U(SCH_1):GND
EF83    GND UPI3_RX_DP5 @S9S_MB_2U_LIB.S9S_MB_2U(SCH_1):GND
EE82    GND UPI3_RX_DP4 @S9S_MB_2U_LIB.S9S_MB_2U(SCH_1):GND
EJ82    GND UPI3_RX_DP3 @S9S_MB_2U_LIB.S9S_MB_2U(SCH_1):GND
EN82    GND UPI3_RX_DP2 @S9S_MB_2U_LIB.S9S_MB_2U(SCH_1):GND
ER82    GND UPI3_RX_DP1 @S9S_MB_2U_LIB.S9S_MB_2U(SCH_1):GND
EL80    GND UPI3_RX_DP0 @S9S_MB_2U_LIB.S9S_MB_2U(SCH_1):GND
CF73     NC UPI3_TX_DN23     NC
CV73     NC UPI3_TX_DN22     NC
CJ74     NC UPI3_TX_DN21     NC
CF75     NC UPI3_TX_DN20     NC
CG76     NC UPI3_TX_DN19     NC
CM75     NC UPI3_TX_DN18     NC
CH77     NC UPI3_TX_DN17     NC
CK77     NC UPI3_TX_DN16     NC
CR74     NC UPI3_TX_DN15     NC
CT75     NC UPI3_TX_DN14     NC
CU76     NC UPI3_TX_DN13     NC
CW76     NC UPI3_TX_DN12     NC
DL80     NC UPI3_TX_DN11     NC
DM81     NC UPI3_TX_DN10     NC
DN82     NC UPI3_TX_DN9     NC
DP79     NC UPI3_TX_DN8     NC
DR82     NC UPI3_TX_DN7     NC
DU80     NC UPI3_TX_DN6     NC
EK87     NC UPI3_TX_DN5     NC
EJ86     NC UPI3_TX_DN4     NC
EM87     NC UPI3_TX_DN3     NC
EP85     NC UPI3_TX_DN2     NC
EL84     NC UPI3_TX_DN1     NC
EH85     NC UPI3_TX_DN0     NC
CD73     NC UPI3_TX_DP23     NC
CW74     NC UPI3_TX_DP22     NC
CK75     NC UPI3_TX_DP21     NC
CH75     NC UPI3_TX_DP20     NC
CF77     NC UPI3_TX_DP19     NC
CL76     NC UPI3_TX_DP18     NC
CJ78     NC UPI3_TX_DP17     NC
CM77     NC UPI3_TX_DP16     NC
CU74     NC UPI3_TX_DP15     NC
CR76     NC UPI3_TX_DP14     NC
CV77     NC UPI3_TX_DP13     NC
DA76     NC UPI3_TX_DP12     NC
DN80     NC UPI3_TX_DP11     NC
DL82     NC UPI3_TX_DP10     NC
DP83     NC UPI3_TX_DP9     NC
DR80     NC UPI3_TX_DP8     NC
DU82     NC UPI3_TX_DP7     NC
DT81     NC UPI3_TX_DP6     NC
EL88     NC UPI3_TX_DP5     NC
EH87     NC UPI3_TX_DP4     NC
EP87     NC UPI3_TX_DP3     NC
EN86     NC UPI3_TX_DP2     NC
EM85     NC UPI3_TX_DP1     NC
EK85     NC UPI3_TX_DP0     NC


DRAWING: @S9S_MB_2U_LIB.S9S_MB_2U(SCH_1):PAGE67 

SOCKET4677_AZIF0045P001C01CS-SA  I1  U1
CM89 PVCCIN_CPU1 VCCIN339 @S9S_MB_2U_LIB.S9S_MB_2U(SCH_1):PVCCIN_CPU1
CP89 PVCCIN_CPU1 VCCIN338 @S9S_MB_2U_LIB.S9S_MB_2U(SCH_1):PVCCIN_CPU1
CN90 PVCCIN_CPU1 VCCIN337 @S9S_MB_2U_LIB.S9S_MB_2U(SCH_1):PVCCIN_CPU1
CN88 PVCCIN_CPU1 VCCIN336 @S9S_MB_2U_LIB.S9S_MB_2U(SCH_1):PVCCIN_CPU1
CM91 PVCCIN_CPU1 VCCIN335 @S9S_MB_2U_LIB.S9S_MB_2U(SCH_1):PVCCIN_CPU1
CM87 PVCCIN_CPU1 VCCIN334 @S9S_MB_2U_LIB.S9S_MB_2U(SCH_1):PVCCIN_CPU1
CL90 PVCCIN_CPU1 VCCIN333 @S9S_MB_2U_LIB.S9S_MB_2U(SCH_1):PVCCIN_CPU1
CL88 PVCCIN_CPU1 VCCIN332 @S9S_MB_2U_LIB.S9S_MB_2U(SCH_1):PVCCIN_CPU1
CL86 PVCCIN_CPU1 VCCIN331 @S9S_MB_2U_LIB.S9S_MB_2U(SCH_1):PVCCIN_CPU1
CL84 PVCCIN_CPU1 VCCIN330 @S9S_MB_2U_LIB.S9S_MB_2U(SCH_1):PVCCIN_CPU1
CK91 PVCCIN_CPU1 VCCIN329 @S9S_MB_2U_LIB.S9S_MB_2U(SCH_1):PVCCIN_CPU1
CK89 PVCCIN_CPU1 VCCIN328 @S9S_MB_2U_LIB.S9S_MB_2U(SCH_1):PVCCIN_CPU1
CK87 PVCCIN_CPU1 VCCIN327 @S9S_MB_2U_LIB.S9S_MB_2U(SCH_1):PVCCIN_CPU1
CK85 PVCCIN_CPU1 VCCIN326 @S9S_MB_2U_LIB.S9S_MB_2U(SCH_1):PVCCIN_CPU1
CK83 PVCCIN_CPU1 VCCIN325 @S9S_MB_2U_LIB.S9S_MB_2U(SCH_1):PVCCIN_CPU1
CJ90 PVCCIN_CPU1 VCCIN324 @S9S_MB_2U_LIB.S9S_MB_2U(SCH_1):PVCCIN_CPU1
CJ88 PVCCIN_CPU1 VCCIN323 @S9S_MB_2U_LIB.S9S_MB_2U(SCH_1):PVCCIN_CPU1
CJ86 PVCCIN_CPU1 VCCIN322 @S9S_MB_2U_LIB.S9S_MB_2U(SCH_1):PVCCIN_CPU1
CJ84 PVCCIN_CPU1 VCCIN321 @S9S_MB_2U_LIB.S9S_MB_2U(SCH_1):PVCCIN_CPU1
CJ82 PVCCIN_CPU1 VCCIN320 @S9S_MB_2U_LIB.S9S_MB_2U(SCH_1):PVCCIN_CPU1
CH91 PVCCIN_CPU1 VCCIN319 @S9S_MB_2U_LIB.S9S_MB_2U(SCH_1):PVCCIN_CPU1
CH81 PVCCIN_CPU1 VCCIN318 @S9S_MB_2U_LIB.S9S_MB_2U(SCH_1):PVCCIN_CPU1
CG90 PVCCIN_CPU1 VCCIN317 @S9S_MB_2U_LIB.S9S_MB_2U(SCH_1):PVCCIN_CPU1
CG88 PVCCIN_CPU1 VCCIN316 @S9S_MB_2U_LIB.S9S_MB_2U(SCH_1):PVCCIN_CPU1
CG86 PVCCIN_CPU1 VCCIN315 @S9S_MB_2U_LIB.S9S_MB_2U(SCH_1):PVCCIN_CPU1
CG84 PVCCIN_CPU1 VCCIN314 @S9S_MB_2U_LIB.S9S_MB_2U(SCH_1):PVCCIN_CPU1
CG82 PVCCIN_CPU1 VCCIN313 @S9S_MB_2U_LIB.S9S_MB_2U(SCH_1):PVCCIN_CPU1
CG80 PVCCIN_CPU1 VCCIN312 @S9S_MB_2U_LIB.S9S_MB_2U(SCH_1):PVCCIN_CPU1
CF91 PVCCIN_CPU1 VCCIN311 @S9S_MB_2U_LIB.S9S_MB_2U(SCH_1):PVCCIN_CPU1
CF89 PVCCIN_CPU1 VCCIN310 @S9S_MB_2U_LIB.S9S_MB_2U(SCH_1):PVCCIN_CPU1
CF87 PVCCIN_CPU1 VCCIN309 @S9S_MB_2U_LIB.S9S_MB_2U(SCH_1):PVCCIN_CPU1
CF85 PVCCIN_CPU1 VCCIN308 @S9S_MB_2U_LIB.S9S_MB_2U(SCH_1):PVCCIN_CPU1
CF83 PVCCIN_CPU1 VCCIN307 @S9S_MB_2U_LIB.S9S_MB_2U(SCH_1):PVCCIN_CPU1
CF81 PVCCIN_CPU1 VCCIN306 @S9S_MB_2U_LIB.S9S_MB_2U(SCH_1):PVCCIN_CPU1
CF79 PVCCIN_CPU1 VCCIN305 @S9S_MB_2U_LIB.S9S_MB_2U(SCH_1):PVCCIN_CPU1
CE90 PVCCIN_CPU1 VCCIN304 @S9S_MB_2U_LIB.S9S_MB_2U(SCH_1):PVCCIN_CPU1
CE88 PVCCIN_CPU1 VCCIN303 @S9S_MB_2U_LIB.S9S_MB_2U(SCH_1):PVCCIN_CPU1
CE86 PVCCIN_CPU1 VCCIN302 @S9S_MB_2U_LIB.S9S_MB_2U(SCH_1):PVCCIN_CPU1
CE84 PVCCIN_CPU1 VCCIN301 @S9S_MB_2U_LIB.S9S_MB_2U(SCH_1):PVCCIN_CPU1
CE82 PVCCIN_CPU1 VCCIN300 @S9S_MB_2U_LIB.S9S_MB_2U(SCH_1):PVCCIN_CPU1
CE80 PVCCIN_CPU1 VCCIN299 @S9S_MB_2U_LIB.S9S_MB_2U(SCH_1):PVCCIN_CPU1
CD89 PVCCIN_CPU1 VCCIN298 @S9S_MB_2U_LIB.S9S_MB_2U(SCH_1):PVCCIN_CPU1
CD87 PVCCIN_CPU1 VCCIN297 @S9S_MB_2U_LIB.S9S_MB_2U(SCH_1):PVCCIN_CPU1
CD85 PVCCIN_CPU1 VCCIN296 @S9S_MB_2U_LIB.S9S_MB_2U(SCH_1):PVCCIN_CPU1
CD83 PVCCIN_CPU1 VCCIN295 @S9S_MB_2U_LIB.S9S_MB_2U(SCH_1):PVCCIN_CPU1
CD81 PVCCIN_CPU1 VCCIN294 @S9S_MB_2U_LIB.S9S_MB_2U(SCH_1):PVCCIN_CPU1
CD79 PVCCIN_CPU1 VCCIN293 @S9S_MB_2U_LIB.S9S_MB_2U(SCH_1):PVCCIN_CPU1
CD59 PVCCIN_CPU1 VCCIN292 @S9S_MB_2U_LIB.S9S_MB_2U(SCH_1):PVCCIN_CPU1
CD57 PVCCIN_CPU1 VCCIN291 @S9S_MB_2U_LIB.S9S_MB_2U(SCH_1):PVCCIN_CPU1
CD55 PVCCIN_CPU1 VCCIN290 @S9S_MB_2U_LIB.S9S_MB_2U(SCH_1):PVCCIN_CPU1
CD53 PVCCIN_CPU1 VCCIN289 @S9S_MB_2U_LIB.S9S_MB_2U(SCH_1):PVCCIN_CPU1
CD51 PVCCIN_CPU1 VCCIN288 @S9S_MB_2U_LIB.S9S_MB_2U(SCH_1):PVCCIN_CPU1
CD49 PVCCIN_CPU1 VCCIN287 @S9S_MB_2U_LIB.S9S_MB_2U(SCH_1):PVCCIN_CPU1
CD47 PVCCIN_CPU1 VCCIN286 @S9S_MB_2U_LIB.S9S_MB_2U(SCH_1):PVCCIN_CPU1
CD44 PVCCIN_CPU1 VCCIN285 @S9S_MB_2U_LIB.S9S_MB_2U(SCH_1):PVCCIN_CPU1
CD42 PVCCIN_CPU1 VCCIN284 @S9S_MB_2U_LIB.S9S_MB_2U(SCH_1):PVCCIN_CPU1
CD40 PVCCIN_CPU1 VCCIN283 @S9S_MB_2U_LIB.S9S_MB_2U(SCH_1):PVCCIN_CPU1
CD38 PVCCIN_CPU1 VCCIN282 @S9S_MB_2U_LIB.S9S_MB_2U(SCH_1):PVCCIN_CPU1
CD36 PVCCIN_CPU1 VCCIN281 @S9S_MB_2U_LIB.S9S_MB_2U(SCH_1):PVCCIN_CPU1
CD34 PVCCIN_CPU1 VCCIN280 @S9S_MB_2U_LIB.S9S_MB_2U(SCH_1):PVCCIN_CPU1
CD32 PVCCIN_CPU1 VCCIN279 @S9S_MB_2U_LIB.S9S_MB_2U(SCH_1):PVCCIN_CPU1
CC90 PVCCIN_CPU1 VCCIN278 @S9S_MB_2U_LIB.S9S_MB_2U(SCH_1):PVCCIN_CPU1
CC88 PVCCIN_CPU1 VCCIN277 @S9S_MB_2U_LIB.S9S_MB_2U(SCH_1):PVCCIN_CPU1
CC86 PVCCIN_CPU1 VCCIN276 @S9S_MB_2U_LIB.S9S_MB_2U(SCH_1):PVCCIN_CPU1
CC84 PVCCIN_CPU1 VCCIN275 @S9S_MB_2U_LIB.S9S_MB_2U(SCH_1):PVCCIN_CPU1
CC82 PVCCIN_CPU1 VCCIN274 @S9S_MB_2U_LIB.S9S_MB_2U(SCH_1):PVCCIN_CPU1
CC80 PVCCIN_CPU1 VCCIN273 @S9S_MB_2U_LIB.S9S_MB_2U(SCH_1):PVCCIN_CPU1
CC78 PVCCIN_CPU1 VCCIN272 @S9S_MB_2U_LIB.S9S_MB_2U(SCH_1):PVCCIN_CPU1
CC76 PVCCIN_CPU1 VCCIN271 @S9S_MB_2U_LIB.S9S_MB_2U(SCH_1):PVCCIN_CPU1
CC60 PVCCIN_CPU1 VCCIN270 @S9S_MB_2U_LIB.S9S_MB_2U(SCH_1):PVCCIN_CPU1
CC58 PVCCIN_CPU1 VCCIN269 @S9S_MB_2U_LIB.S9S_MB_2U(SCH_1):PVCCIN_CPU1
CC56 PVCCIN_CPU1 VCCIN268 @S9S_MB_2U_LIB.S9S_MB_2U(SCH_1):PVCCIN_CPU1
CC54 PVCCIN_CPU1 VCCIN267 @S9S_MB_2U_LIB.S9S_MB_2U(SCH_1):PVCCIN_CPU1
CC52 PVCCIN_CPU1 VCCIN266 @S9S_MB_2U_LIB.S9S_MB_2U(SCH_1):PVCCIN_CPU1
CC50 PVCCIN_CPU1 VCCIN265 @S9S_MB_2U_LIB.S9S_MB_2U(SCH_1):PVCCIN_CPU1
CC48 PVCCIN_CPU1 VCCIN264 @S9S_MB_2U_LIB.S9S_MB_2U(SCH_1):PVCCIN_CPU1
CC45 PVCCIN_CPU1 VCCIN263 @S9S_MB_2U_LIB.S9S_MB_2U(SCH_1):PVCCIN_CPU1
CC43 PVCCIN_CPU1 VCCIN262 @S9S_MB_2U_LIB.S9S_MB_2U(SCH_1):PVCCIN_CPU1
CC41 PVCCIN_CPU1 VCCIN261 @S9S_MB_2U_LIB.S9S_MB_2U(SCH_1):PVCCIN_CPU1
CC39 PVCCIN_CPU1 VCCIN260 @S9S_MB_2U_LIB.S9S_MB_2U(SCH_1):PVCCIN_CPU1
CC37 PVCCIN_CPU1 VCCIN259 @S9S_MB_2U_LIB.S9S_MB_2U(SCH_1):PVCCIN_CPU1
CC35 PVCCIN_CPU1 VCCIN258 @S9S_MB_2U_LIB.S9S_MB_2U(SCH_1):PVCCIN_CPU1
CC33 PVCCIN_CPU1 VCCIN257 @S9S_MB_2U_LIB.S9S_MB_2U(SCH_1):PVCCIN_CPU1
CB77 PVCCIN_CPU1 VCCIN256 @S9S_MB_2U_LIB.S9S_MB_2U(SCH_1):PVCCIN_CPU1
CB75 PVCCIN_CPU1 VCCIN255 @S9S_MB_2U_LIB.S9S_MB_2U(SCH_1):PVCCIN_CPU1
CB61 PVCCIN_CPU1 VCCIN254 @S9S_MB_2U_LIB.S9S_MB_2U(SCH_1):PVCCIN_CPU1
CA90 PVCCIN_CPU1 VCCIN253 @S9S_MB_2U_LIB.S9S_MB_2U(SCH_1):PVCCIN_CPU1
CA88 PVCCIN_CPU1 VCCIN252 @S9S_MB_2U_LIB.S9S_MB_2U(SCH_1):PVCCIN_CPU1
CA86 PVCCIN_CPU1 VCCIN251 @S9S_MB_2U_LIB.S9S_MB_2U(SCH_1):PVCCIN_CPU1
CA84 PVCCIN_CPU1 VCCIN250 @S9S_MB_2U_LIB.S9S_MB_2U(SCH_1):PVCCIN_CPU1
CA82 PVCCIN_CPU1 VCCIN249 @S9S_MB_2U_LIB.S9S_MB_2U(SCH_1):PVCCIN_CPU1
CA80 PVCCIN_CPU1 VCCIN248 @S9S_MB_2U_LIB.S9S_MB_2U(SCH_1):PVCCIN_CPU1
CA78 PVCCIN_CPU1 VCCIN247 @S9S_MB_2U_LIB.S9S_MB_2U(SCH_1):PVCCIN_CPU1
CA76 PVCCIN_CPU1 VCCIN246 @S9S_MB_2U_LIB.S9S_MB_2U(SCH_1):PVCCIN_CPU1
CA74 PVCCIN_CPU1 VCCIN245 @S9S_MB_2U_LIB.S9S_MB_2U(SCH_1):PVCCIN_CPU1
CA72 PVCCIN_CPU1 VCCIN244 @S9S_MB_2U_LIB.S9S_MB_2U(SCH_1):PVCCIN_CPU1
CA70 PVCCIN_CPU1 VCCIN243 @S9S_MB_2U_LIB.S9S_MB_2U(SCH_1):PVCCIN_CPU1
CA68 PVCCIN_CPU1 VCCIN242 @S9S_MB_2U_LIB.S9S_MB_2U(SCH_1):PVCCIN_CPU1
CA66 PVCCIN_CPU1 VCCIN241 @S9S_MB_2U_LIB.S9S_MB_2U(SCH_1):PVCCIN_CPU1
CA64 PVCCIN_CPU1 VCCIN240 @S9S_MB_2U_LIB.S9S_MB_2U(SCH_1):PVCCIN_CPU1
CA62 PVCCIN_CPU1 VCCIN239 @S9S_MB_2U_LIB.S9S_MB_2U(SCH_1):PVCCIN_CPU1
CA60 PVCCIN_CPU1 VCCIN238 @S9S_MB_2U_LIB.S9S_MB_2U(SCH_1):PVCCIN_CPU1
CA58 PVCCIN_CPU1 VCCIN237 @S9S_MB_2U_LIB.S9S_MB_2U(SCH_1):PVCCIN_CPU1
CA56 PVCCIN_CPU1 VCCIN236 @S9S_MB_2U_LIB.S9S_MB_2U(SCH_1):PVCCIN_CPU1
CA54 PVCCIN_CPU1 VCCIN235 @S9S_MB_2U_LIB.S9S_MB_2U(SCH_1):PVCCIN_CPU1
CA52 PVCCIN_CPU1 VCCIN234 @S9S_MB_2U_LIB.S9S_MB_2U(SCH_1):PVCCIN_CPU1
CA50 PVCCIN_CPU1 VCCIN233 @S9S_MB_2U_LIB.S9S_MB_2U(SCH_1):PVCCIN_CPU1
CA48 PVCCIN_CPU1 VCCIN232 @S9S_MB_2U_LIB.S9S_MB_2U(SCH_1):PVCCIN_CPU1
CA45 PVCCIN_CPU1 VCCIN231 @S9S_MB_2U_LIB.S9S_MB_2U(SCH_1):PVCCIN_CPU1
CA43 PVCCIN_CPU1 VCCIN230 @S9S_MB_2U_LIB.S9S_MB_2U(SCH_1):PVCCIN_CPU1
CA41 PVCCIN_CPU1 VCCIN229 @S9S_MB_2U_LIB.S9S_MB_2U(SCH_1):PVCCIN_CPU1
CA39 PVCCIN_CPU1 VCCIN228 @S9S_MB_2U_LIB.S9S_MB_2U(SCH_1):PVCCIN_CPU1
CA37 PVCCIN_CPU1 VCCIN227 @S9S_MB_2U_LIB.S9S_MB_2U(SCH_1):PVCCIN_CPU1
CA35 PVCCIN_CPU1 VCCIN226 @S9S_MB_2U_LIB.S9S_MB_2U(SCH_1):PVCCIN_CPU1
CA33 PVCCIN_CPU1 VCCIN225 @S9S_MB_2U_LIB.S9S_MB_2U(SCH_1):PVCCIN_CPU1
BY89 PVCCIN_CPU1 VCCIN224 @S9S_MB_2U_LIB.S9S_MB_2U(SCH_1):PVCCIN_CPU1
BY87 PVCCIN_CPU1 VCCIN223 @S9S_MB_2U_LIB.S9S_MB_2U(SCH_1):PVCCIN_CPU1
BY85 PVCCIN_CPU1 VCCIN222 @S9S_MB_2U_LIB.S9S_MB_2U(SCH_1):PVCCIN_CPU1
BY83 PVCCIN_CPU1 VCCIN221 @S9S_MB_2U_LIB.S9S_MB_2U(SCH_1):PVCCIN_CPU1
BY81 PVCCIN_CPU1 VCCIN220 @S9S_MB_2U_LIB.S9S_MB_2U(SCH_1):PVCCIN_CPU1
BY79 PVCCIN_CPU1 VCCIN219 @S9S_MB_2U_LIB.S9S_MB_2U(SCH_1):PVCCIN_CPU1
BY77 PVCCIN_CPU1 VCCIN218 @S9S_MB_2U_LIB.S9S_MB_2U(SCH_1):PVCCIN_CPU1
BY75 PVCCIN_CPU1 VCCIN217 @S9S_MB_2U_LIB.S9S_MB_2U(SCH_1):PVCCIN_CPU1
BY73 PVCCIN_CPU1 VCCIN216 @S9S_MB_2U_LIB.S9S_MB_2U(SCH_1):PVCCIN_CPU1
BY71 PVCCIN_CPU1 VCCIN215 @S9S_MB_2U_LIB.S9S_MB_2U(SCH_1):PVCCIN_CPU1
BY69 PVCCIN_CPU1 VCCIN214 @S9S_MB_2U_LIB.S9S_MB_2U(SCH_1):PVCCIN_CPU1
BY67 PVCCIN_CPU1 VCCIN213 @S9S_MB_2U_LIB.S9S_MB_2U(SCH_1):PVCCIN_CPU1
BY65 PVCCIN_CPU1 VCCIN212 @S9S_MB_2U_LIB.S9S_MB_2U(SCH_1):PVCCIN_CPU1
BY63 PVCCIN_CPU1 VCCIN211 @S9S_MB_2U_LIB.S9S_MB_2U(SCH_1):PVCCIN_CPU1
BY61 PVCCIN_CPU1 VCCIN210 @S9S_MB_2U_LIB.S9S_MB_2U(SCH_1):PVCCIN_CPU1
BY59 PVCCIN_CPU1 VCCIN209 @S9S_MB_2U_LIB.S9S_MB_2U(SCH_1):PVCCIN_CPU1
BY57 PVCCIN_CPU1 VCCIN208 @S9S_MB_2U_LIB.S9S_MB_2U(SCH_1):PVCCIN_CPU1
BY55 PVCCIN_CPU1 VCCIN207 @S9S_MB_2U_LIB.S9S_MB_2U(SCH_1):PVCCIN_CPU1
BY53 PVCCIN_CPU1 VCCIN206 @S9S_MB_2U_LIB.S9S_MB_2U(SCH_1):PVCCIN_CPU1
BY51 PVCCIN_CPU1 VCCIN205 @S9S_MB_2U_LIB.S9S_MB_2U(SCH_1):PVCCIN_CPU1
BY49 PVCCIN_CPU1 VCCIN204 @S9S_MB_2U_LIB.S9S_MB_2U(SCH_1):PVCCIN_CPU1
BY47 PVCCIN_CPU1 VCCIN203 @S9S_MB_2U_LIB.S9S_MB_2U(SCH_1):PVCCIN_CPU1
BY44 PVCCIN_CPU1 VCCIN202 @S9S_MB_2U_LIB.S9S_MB_2U(SCH_1):PVCCIN_CPU1
BY42 PVCCIN_CPU1 VCCIN201 @S9S_MB_2U_LIB.S9S_MB_2U(SCH_1):PVCCIN_CPU1
BY40 PVCCIN_CPU1 VCCIN200 @S9S_MB_2U_LIB.S9S_MB_2U(SCH_1):PVCCIN_CPU1
BY38 PVCCIN_CPU1 VCCIN199 @S9S_MB_2U_LIB.S9S_MB_2U(SCH_1):PVCCIN_CPU1
BY36 PVCCIN_CPU1 VCCIN198 @S9S_MB_2U_LIB.S9S_MB_2U(SCH_1):PVCCIN_CPU1
BY34 PVCCIN_CPU1 VCCIN197 @S9S_MB_2U_LIB.S9S_MB_2U(SCH_1):PVCCIN_CPU1
BY32 PVCCIN_CPU1 VCCIN196 @S9S_MB_2U_LIB.S9S_MB_2U(SCH_1):PVCCIN_CPU1
BW90 PVCCIN_CPU1 VCCIN195 @S9S_MB_2U_LIB.S9S_MB_2U(SCH_1):PVCCIN_CPU1
BW88 PVCCIN_CPU1 VCCIN194 @S9S_MB_2U_LIB.S9S_MB_2U(SCH_1):PVCCIN_CPU1
BW86 PVCCIN_CPU1 VCCIN193 @S9S_MB_2U_LIB.S9S_MB_2U(SCH_1):PVCCIN_CPU1
BW84 PVCCIN_CPU1 VCCIN192 @S9S_MB_2U_LIB.S9S_MB_2U(SCH_1):PVCCIN_CPU1
BW82 PVCCIN_CPU1 VCCIN191 @S9S_MB_2U_LIB.S9S_MB_2U(SCH_1):PVCCIN_CPU1
BW80 PVCCIN_CPU1 VCCIN190 @S9S_MB_2U_LIB.S9S_MB_2U(SCH_1):PVCCIN_CPU1

SOCKET4677_AZIF0045P001C01CS-SA  I3  U1
BW78 PVCCIN_CPU1 VCCIN189 @S9S_MB_2U_LIB.S9S_MB_2U(SCH_1):PVCCIN_CPU1
BW76 PVCCIN_CPU1 VCCIN188 @S9S_MB_2U_LIB.S9S_MB_2U(SCH_1):PVCCIN_CPU1
BW74 PVCCIN_CPU1 VCCIN187 @S9S_MB_2U_LIB.S9S_MB_2U(SCH_1):PVCCIN_CPU1
BW72 PVCCIN_CPU1 VCCIN186 @S9S_MB_2U_LIB.S9S_MB_2U(SCH_1):PVCCIN_CPU1
BW70 PVCCIN_CPU1 VCCIN185 @S9S_MB_2U_LIB.S9S_MB_2U(SCH_1):PVCCIN_CPU1
BW68 PVCCIN_CPU1 VCCIN184 @S9S_MB_2U_LIB.S9S_MB_2U(SCH_1):PVCCIN_CPU1
BW66 PVCCIN_CPU1 VCCIN183 @S9S_MB_2U_LIB.S9S_MB_2U(SCH_1):PVCCIN_CPU1
BW64 PVCCIN_CPU1 VCCIN182 @S9S_MB_2U_LIB.S9S_MB_2U(SCH_1):PVCCIN_CPU1
BW62 PVCCIN_CPU1 VCCIN181 @S9S_MB_2U_LIB.S9S_MB_2U(SCH_1):PVCCIN_CPU1
BW60 PVCCIN_CPU1 VCCIN180 @S9S_MB_2U_LIB.S9S_MB_2U(SCH_1):PVCCIN_CPU1
BW58 PVCCIN_CPU1 VCCIN179 @S9S_MB_2U_LIB.S9S_MB_2U(SCH_1):PVCCIN_CPU1
BW56 PVCCIN_CPU1 VCCIN178 @S9S_MB_2U_LIB.S9S_MB_2U(SCH_1):PVCCIN_CPU1
BW54 PVCCIN_CPU1 VCCIN177 @S9S_MB_2U_LIB.S9S_MB_2U(SCH_1):PVCCIN_CPU1
BW52 PVCCIN_CPU1 VCCIN176 @S9S_MB_2U_LIB.S9S_MB_2U(SCH_1):PVCCIN_CPU1
BW50 PVCCIN_CPU1 VCCIN175 @S9S_MB_2U_LIB.S9S_MB_2U(SCH_1):PVCCIN_CPU1
BW48 PVCCIN_CPU1 VCCIN174 @S9S_MB_2U_LIB.S9S_MB_2U(SCH_1):PVCCIN_CPU1
BW45 PVCCIN_CPU1 VCCIN173 @S9S_MB_2U_LIB.S9S_MB_2U(SCH_1):PVCCIN_CPU1
BW43 PVCCIN_CPU1 VCCIN172 @S9S_MB_2U_LIB.S9S_MB_2U(SCH_1):PVCCIN_CPU1
BW41 PVCCIN_CPU1 VCCIN171 @S9S_MB_2U_LIB.S9S_MB_2U(SCH_1):PVCCIN_CPU1
BW39 PVCCIN_CPU1 VCCIN170 @S9S_MB_2U_LIB.S9S_MB_2U(SCH_1):PVCCIN_CPU1
BW37 PVCCIN_CPU1 VCCIN169 @S9S_MB_2U_LIB.S9S_MB_2U(SCH_1):PVCCIN_CPU1
BW35 PVCCIN_CPU1 VCCIN168 @S9S_MB_2U_LIB.S9S_MB_2U(SCH_1):PVCCIN_CPU1
BW33 PVCCIN_CPU1 VCCIN167 @S9S_MB_2U_LIB.S9S_MB_2U(SCH_1):PVCCIN_CPU1
BV89 PVCCIN_CPU1 VCCIN166 @S9S_MB_2U_LIB.S9S_MB_2U(SCH_1):PVCCIN_CPU1
BV87 PVCCIN_CPU1 VCCIN165 @S9S_MB_2U_LIB.S9S_MB_2U(SCH_1):PVCCIN_CPU1
BV85 PVCCIN_CPU1 VCCIN164 @S9S_MB_2U_LIB.S9S_MB_2U(SCH_1):PVCCIN_CPU1
BV83 PVCCIN_CPU1 VCCIN163 @S9S_MB_2U_LIB.S9S_MB_2U(SCH_1):PVCCIN_CPU1
BV81 PVCCIN_CPU1 VCCIN162 @S9S_MB_2U_LIB.S9S_MB_2U(SCH_1):PVCCIN_CPU1
BV79 PVCCIN_CPU1 VCCIN161 @S9S_MB_2U_LIB.S9S_MB_2U(SCH_1):PVCCIN_CPU1
BV77 PVCCIN_CPU1 VCCIN160 @S9S_MB_2U_LIB.S9S_MB_2U(SCH_1):PVCCIN_CPU1
BV75 PVCCIN_CPU1 VCCIN159 @S9S_MB_2U_LIB.S9S_MB_2U(SCH_1):PVCCIN_CPU1
BV73 PVCCIN_CPU1 VCCIN158 @S9S_MB_2U_LIB.S9S_MB_2U(SCH_1):PVCCIN_CPU1
BV71 PVCCIN_CPU1 VCCIN157 @S9S_MB_2U_LIB.S9S_MB_2U(SCH_1):PVCCIN_CPU1
BV69 PVCCIN_CPU1 VCCIN156 @S9S_MB_2U_LIB.S9S_MB_2U(SCH_1):PVCCIN_CPU1
BV67 PVCCIN_CPU1 VCCIN155 @S9S_MB_2U_LIB.S9S_MB_2U(SCH_1):PVCCIN_CPU1
BV65 PVCCIN_CPU1 VCCIN154 @S9S_MB_2U_LIB.S9S_MB_2U(SCH_1):PVCCIN_CPU1
BV63 PVCCIN_CPU1 VCCIN153 @S9S_MB_2U_LIB.S9S_MB_2U(SCH_1):PVCCIN_CPU1
BV61 PVCCIN_CPU1 VCCIN152 @S9S_MB_2U_LIB.S9S_MB_2U(SCH_1):PVCCIN_CPU1
BV59 PVCCIN_CPU1 VCCIN151 @S9S_MB_2U_LIB.S9S_MB_2U(SCH_1):PVCCIN_CPU1
BV57 PVCCIN_CPU1 VCCIN150 @S9S_MB_2U_LIB.S9S_MB_2U(SCH_1):PVCCIN_CPU1
BV55 PVCCIN_CPU1 VCCIN149 @S9S_MB_2U_LIB.S9S_MB_2U(SCH_1):PVCCIN_CPU1
BV53 PVCCIN_CPU1 VCCIN148 @S9S_MB_2U_LIB.S9S_MB_2U(SCH_1):PVCCIN_CPU1
BV51 PVCCIN_CPU1 VCCIN147 @S9S_MB_2U_LIB.S9S_MB_2U(SCH_1):PVCCIN_CPU1
BV49 PVCCIN_CPU1 VCCIN146 @S9S_MB_2U_LIB.S9S_MB_2U(SCH_1):PVCCIN_CPU1
BV47 PVCCIN_CPU1 VCCIN145 @S9S_MB_2U_LIB.S9S_MB_2U(SCH_1):PVCCIN_CPU1
BV44 PVCCIN_CPU1 VCCIN144 @S9S_MB_2U_LIB.S9S_MB_2U(SCH_1):PVCCIN_CPU1
BV42 PVCCIN_CPU1 VCCIN143 @S9S_MB_2U_LIB.S9S_MB_2U(SCH_1):PVCCIN_CPU1
BV40 PVCCIN_CPU1 VCCIN142 @S9S_MB_2U_LIB.S9S_MB_2U(SCH_1):PVCCIN_CPU1
BV38 PVCCIN_CPU1 VCCIN141 @S9S_MB_2U_LIB.S9S_MB_2U(SCH_1):PVCCIN_CPU1
BV36 PVCCIN_CPU1 VCCIN140 @S9S_MB_2U_LIB.S9S_MB_2U(SCH_1):PVCCIN_CPU1
BV34 PVCCIN_CPU1 VCCIN139 @S9S_MB_2U_LIB.S9S_MB_2U(SCH_1):PVCCIN_CPU1
BV32 PVCCIN_CPU1 VCCIN138 @S9S_MB_2U_LIB.S9S_MB_2U(SCH_1):PVCCIN_CPU1
BU90 PVCCIN_CPU1 VCCIN137 @S9S_MB_2U_LIB.S9S_MB_2U(SCH_1):PVCCIN_CPU1
BU88 PVCCIN_CPU1 VCCIN136 @S9S_MB_2U_LIB.S9S_MB_2U(SCH_1):PVCCIN_CPU1
BU86 PVCCIN_CPU1 VCCIN135 @S9S_MB_2U_LIB.S9S_MB_2U(SCH_1):PVCCIN_CPU1
BU84 PVCCIN_CPU1 VCCIN134 @S9S_MB_2U_LIB.S9S_MB_2U(SCH_1):PVCCIN_CPU1
BU82 PVCCIN_CPU1 VCCIN133 @S9S_MB_2U_LIB.S9S_MB_2U(SCH_1):PVCCIN_CPU1
BU80 PVCCIN_CPU1 VCCIN132 @S9S_MB_2U_LIB.S9S_MB_2U(SCH_1):PVCCIN_CPU1
BU78 PVCCIN_CPU1 VCCIN131 @S9S_MB_2U_LIB.S9S_MB_2U(SCH_1):PVCCIN_CPU1
BU76 PVCCIN_CPU1 VCCIN130 @S9S_MB_2U_LIB.S9S_MB_2U(SCH_1):PVCCIN_CPU1
BU74 PVCCIN_CPU1 VCCIN129 @S9S_MB_2U_LIB.S9S_MB_2U(SCH_1):PVCCIN_CPU1
BU72 PVCCIN_CPU1 VCCIN128 @S9S_MB_2U_LIB.S9S_MB_2U(SCH_1):PVCCIN_CPU1
BU70 PVCCIN_CPU1 VCCIN127 @S9S_MB_2U_LIB.S9S_MB_2U(SCH_1):PVCCIN_CPU1
BU68 PVCCIN_CPU1 VCCIN126 @S9S_MB_2U_LIB.S9S_MB_2U(SCH_1):PVCCIN_CPU1
BU66 PVCCIN_CPU1 VCCIN125 @S9S_MB_2U_LIB.S9S_MB_2U(SCH_1):PVCCIN_CPU1
BU64 PVCCIN_CPU1 VCCIN124 @S9S_MB_2U_LIB.S9S_MB_2U(SCH_1):PVCCIN_CPU1
BU62 PVCCIN_CPU1 VCCIN123 @S9S_MB_2U_LIB.S9S_MB_2U(SCH_1):PVCCIN_CPU1
BU60 PVCCIN_CPU1 VCCIN122 @S9S_MB_2U_LIB.S9S_MB_2U(SCH_1):PVCCIN_CPU1
BU58 PVCCIN_CPU1 VCCIN121 @S9S_MB_2U_LIB.S9S_MB_2U(SCH_1):PVCCIN_CPU1
BU56 PVCCIN_CPU1 VCCIN120 @S9S_MB_2U_LIB.S9S_MB_2U(SCH_1):PVCCIN_CPU1
BU54 PVCCIN_CPU1 VCCIN119 @S9S_MB_2U_LIB.S9S_MB_2U(SCH_1):PVCCIN_CPU1
BU52 PVCCIN_CPU1 VCCIN118 @S9S_MB_2U_LIB.S9S_MB_2U(SCH_1):PVCCIN_CPU1
BU50 PVCCIN_CPU1 VCCIN117 @S9S_MB_2U_LIB.S9S_MB_2U(SCH_1):PVCCIN_CPU1
BU48 PVCCIN_CPU1 VCCIN116 @S9S_MB_2U_LIB.S9S_MB_2U(SCH_1):PVCCIN_CPU1
BU45 PVCCIN_CPU1 VCCIN115 @S9S_MB_2U_LIB.S9S_MB_2U(SCH_1):PVCCIN_CPU1
BU43 PVCCIN_CPU1 VCCIN114 @S9S_MB_2U_LIB.S9S_MB_2U(SCH_1):PVCCIN_CPU1
BU41 PVCCIN_CPU1 VCCIN113 @S9S_MB_2U_LIB.S9S_MB_2U(SCH_1):PVCCIN_CPU1
BU39 PVCCIN_CPU1 VCCIN112 @S9S_MB_2U_LIB.S9S_MB_2U(SCH_1):PVCCIN_CPU1
BU37 PVCCIN_CPU1 VCCIN111 @S9S_MB_2U_LIB.S9S_MB_2U(SCH_1):PVCCIN_CPU1
BU35 PVCCIN_CPU1 VCCIN110 @S9S_MB_2U_LIB.S9S_MB_2U(SCH_1):PVCCIN_CPU1
BU33 PVCCIN_CPU1 VCCIN109 @S9S_MB_2U_LIB.S9S_MB_2U(SCH_1):PVCCIN_CPU1
BT89 PVCCIN_CPU1 VCCIN108 @S9S_MB_2U_LIB.S9S_MB_2U(SCH_1):PVCCIN_CPU1
BT87 PVCCIN_CPU1 VCCIN107 @S9S_MB_2U_LIB.S9S_MB_2U(SCH_1):PVCCIN_CPU1
BT85 PVCCIN_CPU1 VCCIN106 @S9S_MB_2U_LIB.S9S_MB_2U(SCH_1):PVCCIN_CPU1
BT83 PVCCIN_CPU1 VCCIN105 @S9S_MB_2U_LIB.S9S_MB_2U(SCH_1):PVCCIN_CPU1
BT81 PVCCIN_CPU1 VCCIN104 @S9S_MB_2U_LIB.S9S_MB_2U(SCH_1):PVCCIN_CPU1
BT79 PVCCIN_CPU1 VCCIN103 @S9S_MB_2U_LIB.S9S_MB_2U(SCH_1):PVCCIN_CPU1
BT77 PVCCIN_CPU1 VCCIN102 @S9S_MB_2U_LIB.S9S_MB_2U(SCH_1):PVCCIN_CPU1
BT75 PVCCIN_CPU1 VCCIN101 @S9S_MB_2U_LIB.S9S_MB_2U(SCH_1):PVCCIN_CPU1
BT73 PVCCIN_CPU1 VCCIN100 @S9S_MB_2U_LIB.S9S_MB_2U(SCH_1):PVCCIN_CPU1
BT71 PVCCIN_CPU1 VCCIN99 @S9S_MB_2U_LIB.S9S_MB_2U(SCH_1):PVCCIN_CPU1
BT69 PVCCIN_CPU1 VCCIN98 @S9S_MB_2U_LIB.S9S_MB_2U(SCH_1):PVCCIN_CPU1
BT67 PVCCIN_CPU1 VCCIN97 @S9S_MB_2U_LIB.S9S_MB_2U(SCH_1):PVCCIN_CPU1
BT65 PVCCIN_CPU1 VCCIN96 @S9S_MB_2U_LIB.S9S_MB_2U(SCH_1):PVCCIN_CPU1
BT63 PVCCIN_CPU1 VCCIN95 @S9S_MB_2U_LIB.S9S_MB_2U(SCH_1):PVCCIN_CPU1
BT61 PVCCIN_CPU1 VCCIN94 @S9S_MB_2U_LIB.S9S_MB_2U(SCH_1):PVCCIN_CPU1
BT59 PVCCIN_CPU1 VCCIN93 @S9S_MB_2U_LIB.S9S_MB_2U(SCH_1):PVCCIN_CPU1
BT57 PVCCIN_CPU1 VCCIN92 @S9S_MB_2U_LIB.S9S_MB_2U(SCH_1):PVCCIN_CPU1
BT55 PVCCIN_CPU1 VCCIN91 @S9S_MB_2U_LIB.S9S_MB_2U(SCH_1):PVCCIN_CPU1
BT53 PVCCIN_CPU1 VCCIN90 @S9S_MB_2U_LIB.S9S_MB_2U(SCH_1):PVCCIN_CPU1
BT51 PVCCIN_CPU1 VCCIN89 @S9S_MB_2U_LIB.S9S_MB_2U(SCH_1):PVCCIN_CPU1
BT49 PVCCIN_CPU1 VCCIN88 @S9S_MB_2U_LIB.S9S_MB_2U(SCH_1):PVCCIN_CPU1
BT47 PVCCIN_CPU1 VCCIN87 @S9S_MB_2U_LIB.S9S_MB_2U(SCH_1):PVCCIN_CPU1
BT44 PVCCIN_CPU1 VCCIN86 @S9S_MB_2U_LIB.S9S_MB_2U(SCH_1):PVCCIN_CPU1
BT42 PVCCIN_CPU1 VCCIN85 @S9S_MB_2U_LIB.S9S_MB_2U(SCH_1):PVCCIN_CPU1
BT40 PVCCIN_CPU1 VCCIN84 @S9S_MB_2U_LIB.S9S_MB_2U(SCH_1):PVCCIN_CPU1
BT38 PVCCIN_CPU1 VCCIN83 @S9S_MB_2U_LIB.S9S_MB_2U(SCH_1):PVCCIN_CPU1
BT36 PVCCIN_CPU1 VCCIN82 @S9S_MB_2U_LIB.S9S_MB_2U(SCH_1):PVCCIN_CPU1
BT34 PVCCIN_CPU1 VCCIN81 @S9S_MB_2U_LIB.S9S_MB_2U(SCH_1):PVCCIN_CPU1
BT32 PVCCIN_CPU1 VCCIN80 @S9S_MB_2U_LIB.S9S_MB_2U(SCH_1):PVCCIN_CPU1
BR78 PVCCIN_CPU1 VCCIN79 @S9S_MB_2U_LIB.S9S_MB_2U(SCH_1):PVCCIN_CPU1
BR62 PVCCIN_CPU1 VCCIN78 @S9S_MB_2U_LIB.S9S_MB_2U(SCH_1):PVCCIN_CPU1
BR60 PVCCIN_CPU1 VCCIN77 @S9S_MB_2U_LIB.S9S_MB_2U(SCH_1):PVCCIN_CPU1
BP89 PVCCIN_CPU1 VCCIN76 @S9S_MB_2U_LIB.S9S_MB_2U(SCH_1):PVCCIN_CPU1
BP87 PVCCIN_CPU1 VCCIN75 @S9S_MB_2U_LIB.S9S_MB_2U(SCH_1):PVCCIN_CPU1
BP85 PVCCIN_CPU1 VCCIN74 @S9S_MB_2U_LIB.S9S_MB_2U(SCH_1):PVCCIN_CPU1
BP83 PVCCIN_CPU1 VCCIN73 @S9S_MB_2U_LIB.S9S_MB_2U(SCH_1):PVCCIN_CPU1
BP81 PVCCIN_CPU1 VCCIN72 @S9S_MB_2U_LIB.S9S_MB_2U(SCH_1):PVCCIN_CPU1
BP79 PVCCIN_CPU1 VCCIN71 @S9S_MB_2U_LIB.S9S_MB_2U(SCH_1):PVCCIN_CPU1
BP61 PVCCIN_CPU1 VCCIN70 @S9S_MB_2U_LIB.S9S_MB_2U(SCH_1):PVCCIN_CPU1
BP59 PVCCIN_CPU1 VCCIN69 @S9S_MB_2U_LIB.S9S_MB_2U(SCH_1):PVCCIN_CPU1
BP57 PVCCIN_CPU1 VCCIN68 @S9S_MB_2U_LIB.S9S_MB_2U(SCH_1):PVCCIN_CPU1
BP55 PVCCIN_CPU1 VCCIN67 @S9S_MB_2U_LIB.S9S_MB_2U(SCH_1):PVCCIN_CPU1
BP53 PVCCIN_CPU1 VCCIN66 @S9S_MB_2U_LIB.S9S_MB_2U(SCH_1):PVCCIN_CPU1
BP51 PVCCIN_CPU1 VCCIN65 @S9S_MB_2U_LIB.S9S_MB_2U(SCH_1):PVCCIN_CPU1
BP49 PVCCIN_CPU1 VCCIN64 @S9S_MB_2U_LIB.S9S_MB_2U(SCH_1):PVCCIN_CPU1
BP47 PVCCIN_CPU1 VCCIN63 @S9S_MB_2U_LIB.S9S_MB_2U(SCH_1):PVCCIN_CPU1
BP44 PVCCIN_CPU1 VCCIN62 @S9S_MB_2U_LIB.S9S_MB_2U(SCH_1):PVCCIN_CPU1
BP42 PVCCIN_CPU1 VCCIN61 @S9S_MB_2U_LIB.S9S_MB_2U(SCH_1):PVCCIN_CPU1
BP40 PVCCIN_CPU1 VCCIN60 @S9S_MB_2U_LIB.S9S_MB_2U(SCH_1):PVCCIN_CPU1
BP38 PVCCIN_CPU1 VCCIN59 @S9S_MB_2U_LIB.S9S_MB_2U(SCH_1):PVCCIN_CPU1
BP36 PVCCIN_CPU1 VCCIN58 @S9S_MB_2U_LIB.S9S_MB_2U(SCH_1):PVCCIN_CPU1
BP34 PVCCIN_CPU1 VCCIN57 @S9S_MB_2U_LIB.S9S_MB_2U(SCH_1):PVCCIN_CPU1
BP32 PVCCIN_CPU1 VCCIN56 @S9S_MB_2U_LIB.S9S_MB_2U(SCH_1):PVCCIN_CPU1
BN90 PVCCIN_CPU1 VCCIN55 @S9S_MB_2U_LIB.S9S_MB_2U(SCH_1):PVCCIN_CPU1
BN88 PVCCIN_CPU1 VCCIN54 @S9S_MB_2U_LIB.S9S_MB_2U(SCH_1):PVCCIN_CPU1
BN86 PVCCIN_CPU1 VCCIN53 @S9S_MB_2U_LIB.S9S_MB_2U(SCH_1):PVCCIN_CPU1
BN84 PVCCIN_CPU1 VCCIN52 @S9S_MB_2U_LIB.S9S_MB_2U(SCH_1):PVCCIN_CPU1
BN82 PVCCIN_CPU1 VCCIN51 @S9S_MB_2U_LIB.S9S_MB_2U(SCH_1):PVCCIN_CPU1
BN80 PVCCIN_CPU1 VCCIN50 @S9S_MB_2U_LIB.S9S_MB_2U(SCH_1):PVCCIN_CPU1
BN78 PVCCIN_CPU1 VCCIN49 @S9S_MB_2U_LIB.S9S_MB_2U(SCH_1):PVCCIN_CPU1
BN60 PVCCIN_CPU1 VCCIN48 @S9S_MB_2U_LIB.S9S_MB_2U(SCH_1):PVCCIN_CPU1
BN58 PVCCIN_CPU1 VCCIN47 @S9S_MB_2U_LIB.S9S_MB_2U(SCH_1):PVCCIN_CPU1
BN56 PVCCIN_CPU1 VCCIN46 @S9S_MB_2U_LIB.S9S_MB_2U(SCH_1):PVCCIN_CPU1
BN54 PVCCIN_CPU1 VCCIN45 @S9S_MB_2U_LIB.S9S_MB_2U(SCH_1):PVCCIN_CPU1
BN52 PVCCIN_CPU1 VCCIN44 @S9S_MB_2U_LIB.S9S_MB_2U(SCH_1):PVCCIN_CPU1
BN50 PVCCIN_CPU1 VCCIN43 @S9S_MB_2U_LIB.S9S_MB_2U(SCH_1):PVCCIN_CPU1
BN48 PVCCIN_CPU1 VCCIN42 @S9S_MB_2U_LIB.S9S_MB_2U(SCH_1):PVCCIN_CPU1
BN45 PVCCIN_CPU1 VCCIN41 @S9S_MB_2U_LIB.S9S_MB_2U(SCH_1):PVCCIN_CPU1
BN43 PVCCIN_CPU1 VCCIN40 @S9S_MB_2U_LIB.S9S_MB_2U(SCH_1):PVCCIN_CPU1


DRAWING: @S9S_MB_2U_LIB.S9S_MB_2U(SCH_1):PAGE68 

SOCKET4677_AZIF0045P001C01CS-SA  I1  U1
BN41 PVCCIN_CPU1 VCCIN39 @S9S_MB_2U_LIB.S9S_MB_2U(SCH_1):PVCCIN_CPU1
BN39 PVCCIN_CPU1 VCCIN38 @S9S_MB_2U_LIB.S9S_MB_2U(SCH_1):PVCCIN_CPU1
BN37 PVCCIN_CPU1 VCCIN37 @S9S_MB_2U_LIB.S9S_MB_2U(SCH_1):PVCCIN_CPU1
BN35 PVCCIN_CPU1 VCCIN36 @S9S_MB_2U_LIB.S9S_MB_2U(SCH_1):PVCCIN_CPU1
BN33 PVCCIN_CPU1 VCCIN35 @S9S_MB_2U_LIB.S9S_MB_2U(SCH_1):PVCCIN_CPU1
BM91 PVCCIN_CPU1 VCCIN34 @S9S_MB_2U_LIB.S9S_MB_2U(SCH_1):PVCCIN_CPU1
BM89 PVCCIN_CPU1 VCCIN33 @S9S_MB_2U_LIB.S9S_MB_2U(SCH_1):PVCCIN_CPU1
BM87 PVCCIN_CPU1 VCCIN32 @S9S_MB_2U_LIB.S9S_MB_2U(SCH_1):PVCCIN_CPU1
BM85 PVCCIN_CPU1 VCCIN31 @S9S_MB_2U_LIB.S9S_MB_2U(SCH_1):PVCCIN_CPU1
BM83 PVCCIN_CPU1 VCCIN30 @S9S_MB_2U_LIB.S9S_MB_2U(SCH_1):PVCCIN_CPU1
BM81 PVCCIN_CPU1 VCCIN29 @S9S_MB_2U_LIB.S9S_MB_2U(SCH_1):PVCCIN_CPU1
BM79 PVCCIN_CPU1 VCCIN28 @S9S_MB_2U_LIB.S9S_MB_2U(SCH_1):PVCCIN_CPU1
BL90 PVCCIN_CPU1 VCCIN27 @S9S_MB_2U_LIB.S9S_MB_2U(SCH_1):PVCCIN_CPU1
BL88 PVCCIN_CPU1 VCCIN26 @S9S_MB_2U_LIB.S9S_MB_2U(SCH_1):PVCCIN_CPU1
BL86 PVCCIN_CPU1 VCCIN25 @S9S_MB_2U_LIB.S9S_MB_2U(SCH_1):PVCCIN_CPU1
BL84 PVCCIN_CPU1 VCCIN24 @S9S_MB_2U_LIB.S9S_MB_2U(SCH_1):PVCCIN_CPU1
BL82 PVCCIN_CPU1 VCCIN23 @S9S_MB_2U_LIB.S9S_MB_2U(SCH_1):PVCCIN_CPU1
BL80 PVCCIN_CPU1 VCCIN22 @S9S_MB_2U_LIB.S9S_MB_2U(SCH_1):PVCCIN_CPU1
BK91 PVCCIN_CPU1 VCCIN21 @S9S_MB_2U_LIB.S9S_MB_2U(SCH_1):PVCCIN_CPU1
BK89 PVCCIN_CPU1 VCCIN20 @S9S_MB_2U_LIB.S9S_MB_2U(SCH_1):PVCCIN_CPU1
BK87 PVCCIN_CPU1 VCCIN19 @S9S_MB_2U_LIB.S9S_MB_2U(SCH_1):PVCCIN_CPU1
BK85 PVCCIN_CPU1 VCCIN18 @S9S_MB_2U_LIB.S9S_MB_2U(SCH_1):PVCCIN_CPU1
BK83 PVCCIN_CPU1 VCCIN17 @S9S_MB_2U_LIB.S9S_MB_2U(SCH_1):PVCCIN_CPU1
BK81 PVCCIN_CPU1 VCCIN16 @S9S_MB_2U_LIB.S9S_MB_2U(SCH_1):PVCCIN_CPU1
BH91 PVCCIN_CPU1 VCCIN15 @S9S_MB_2U_LIB.S9S_MB_2U(SCH_1):PVCCIN_CPU1
BH89 PVCCIN_CPU1 VCCIN14 @S9S_MB_2U_LIB.S9S_MB_2U(SCH_1):PVCCIN_CPU1
BH87 PVCCIN_CPU1 VCCIN13 @S9S_MB_2U_LIB.S9S_MB_2U(SCH_1):PVCCIN_CPU1
BH85 PVCCIN_CPU1 VCCIN12 @S9S_MB_2U_LIB.S9S_MB_2U(SCH_1):PVCCIN_CPU1
BG90 PVCCIN_CPU1 VCCIN11 @S9S_MB_2U_LIB.S9S_MB_2U(SCH_1):PVCCIN_CPU1
BG88 PVCCIN_CPU1 VCCIN10 @S9S_MB_2U_LIB.S9S_MB_2U(SCH_1):PVCCIN_CPU1
BG86 PVCCIN_CPU1 VCCIN9 @S9S_MB_2U_LIB.S9S_MB_2U(SCH_1):PVCCIN_CPU1
BG84 PVCCIN_CPU1 VCCIN8 @S9S_MB_2U_LIB.S9S_MB_2U(SCH_1):PVCCIN_CPU1
BF91 PVCCIN_CPU1 VCCIN7 @S9S_MB_2U_LIB.S9S_MB_2U(SCH_1):PVCCIN_CPU1
BF89 PVCCIN_CPU1 VCCIN6 @S9S_MB_2U_LIB.S9S_MB_2U(SCH_1):PVCCIN_CPU1
BF87 PVCCIN_CPU1 VCCIN5 @S9S_MB_2U_LIB.S9S_MB_2U(SCH_1):PVCCIN_CPU1
BF85 PVCCIN_CPU1 VCCIN4 @S9S_MB_2U_LIB.S9S_MB_2U(SCH_1):PVCCIN_CPU1
BE90 PVCCIN_CPU1 VCCIN3 @S9S_MB_2U_LIB.S9S_MB_2U(SCH_1):PVCCIN_CPU1
BE88 PVCCIN_CPU1 VCCIN2 @S9S_MB_2U_LIB.S9S_MB_2U(SCH_1):PVCCIN_CPU1
BE86 PVCCIN_CPU1 VCCIN1 @S9S_MB_2U_LIB.S9S_MB_2U(SCH_1):PVCCIN_CPU1
BD91 PVCCIN_CPU1 VCCIN0 @S9S_MB_2U_LIB.S9S_MB_2U(SCH_1):PVCCIN_CPU1
DA21 PVCCINFAON_CPU1 VCCINFAON53 @S9S_MB_2U_LIB.S9S_MB_2U(SCH_1):PVCCINFAON_CPU1
CW62 PVCCINFAON_CPU1 VCCINFAON52 @S9S_MB_2U_LIB.S9S_MB_2U(SCH_1):PVCCINFAON_CPU1
CV63 PVCCINFAON_CPU1 VCCINFAON51 @S9S_MB_2U_LIB.S9S_MB_2U(SCH_1):PVCCINFAON_CPU1
CV61 PVCCINFAON_CPU1 VCCINFAON50 @S9S_MB_2U_LIB.S9S_MB_2U(SCH_1):PVCCINFAON_CPU1
CT63 PVCCINFAON_CPU1 VCCINFAON49 @S9S_MB_2U_LIB.S9S_MB_2U(SCH_1):PVCCINFAON_CPU1
CP63 PVCCINFAON_CPU1 VCCINFAON48 @S9S_MB_2U_LIB.S9S_MB_2U(SCH_1):PVCCINFAON_CPU1
CN19 PVCCINFAON_CPU1 VCCINFAON47 @S9S_MB_2U_LIB.S9S_MB_2U(SCH_1):PVCCINFAON_CPU1
CJ19 PVCCINFAON_CPU1 VCCINFAON46 @S9S_MB_2U_LIB.S9S_MB_2U(SCH_1):PVCCINFAON_CPU1
CJ11 PVCCINFAON_CPU1 VCCINFAON45 @S9S_MB_2U_LIB.S9S_MB_2U(SCH_1):PVCCINFAON_CPU1
CE19 PVCCINFAON_CPU1 VCCINFAON44 @S9S_MB_2U_LIB.S9S_MB_2U(SCH_1):PVCCINFAON_CPU1
CA15 PVCCINFAON_CPU1 VCCINFAON43 @S9S_MB_2U_LIB.S9S_MB_2U(SCH_1):PVCCINFAON_CPU1
BN15 PVCCINFAON_CPU1 VCCINFAON42 @S9S_MB_2U_LIB.S9S_MB_2U(SCH_1):PVCCINFAON_CPU1
BK61 PVCCINFAON_CPU1 VCCINFAON41 @S9S_MB_2U_LIB.S9S_MB_2U(SCH_1):PVCCINFAON_CPU1
BJ60 PVCCINFAON_CPU1 VCCINFAON40 @S9S_MB_2U_LIB.S9S_MB_2U(SCH_1):PVCCINFAON_CPU1
BJ15 PVCCINFAON_CPU1 VCCINFAON39 @S9S_MB_2U_LIB.S9S_MB_2U(SCH_1):PVCCINFAON_CPU1
BG60 PVCCINFAON_CPU1 VCCINFAON38 @S9S_MB_2U_LIB.S9S_MB_2U(SCH_1):PVCCINFAON_CPU1
BE60 PVCCINFAON_CPU1 VCCINFAON37 @S9S_MB_2U_LIB.S9S_MB_2U(SCH_1):PVCCINFAON_CPU1
BE15 PVCCINFAON_CPU1 VCCINFAON36 @S9S_MB_2U_LIB.S9S_MB_2U(SCH_1):PVCCINFAON_CPU1
BC60 PVCCINFAON_CPU1 VCCINFAON35 @S9S_MB_2U_LIB.S9S_MB_2U(SCH_1):PVCCINFAON_CPU1
BA15 PVCCINFAON_CPU1 VCCINFAON34 @S9S_MB_2U_LIB.S9S_MB_2U(SCH_1):PVCCINFAON_CPU1
AY18 PVCCINFAON_CPU1 VCCINFAON33 @S9S_MB_2U_LIB.S9S_MB_2U(SCH_1):PVCCINFAON_CPU1

Q_CAP_C0402-10UF,6.3V,20%,X6S,A  I4  C71
   1 P3V3_AUX      A @S9S_MB_2U_LIB.S9S_MB_2U(SCH_1):P3V3_AUX
   2    GND      B @S9S_MB_2U_LIB.S9S_MB_2U(SCH_1):GND

SOCKET4677_AZIF0045P001C01CS-SA  I8  U1
BC21 P3V3_AUX VCC_3P3_AUX0 @S9S_MB_2U_LIB.S9S_MB_2U(SCH_1):P3V3_AUX
BA21 P3V3_AUX VCC_3P3_AUX1 @S9S_MB_2U_LIB.S9S_MB_2U(SCH_1):P3V3_AUX
CY53 PVCCD_HV_CPU1 VCCD_HV28 @S9S_MB_2U_LIB.S9S_MB_2U(SCH_1):PVCCD_HV_CPU1
CY36 PVCCD_HV_CPU1 VCCD_HV27 @S9S_MB_2U_LIB.S9S_MB_2U(SCH_1):PVCCD_HV_CPU1
CW54 PVCCD_HV_CPU1 VCCD_HV24 @S9S_MB_2U_LIB.S9S_MB_2U(SCH_1):PVCCD_HV_CPU1
CY34 PVCCD_HV_CPU1 VCCD_HV26 @S9S_MB_2U_LIB.S9S_MB_2U(SCH_1):PVCCD_HV_CPU1
CW56 PVCCD_HV_CPU1 VCCD_HV25 @S9S_MB_2U_LIB.S9S_MB_2U(SCH_1):PVCCD_HV_CPU1
CW52 PVCCD_HV_CPU1 VCCD_HV23 @S9S_MB_2U_LIB.S9S_MB_2U(SCH_1):PVCCD_HV_CPU1
CW37 PVCCD_HV_CPU1 VCCD_HV22 @S9S_MB_2U_LIB.S9S_MB_2U(SCH_1):PVCCD_HV_CPU1
CW35 PVCCD_HV_CPU1 VCCD_HV21 @S9S_MB_2U_LIB.S9S_MB_2U(SCH_1):PVCCD_HV_CPU1
 CE7 PVCCD_HV_CPU1 VCCD_HV20 @S9S_MB_2U_LIB.S9S_MB_2U(SCH_1):PVCCD_HV_CPU1
 CA7 PVCCD_HV_CPU1 VCCD_HV19 @S9S_MB_2U_LIB.S9S_MB_2U(SCH_1):PVCCD_HV_CPU1
 BN7 PVCCD_HV_CPU1 VCCD_HV18 @S9S_MB_2U_LIB.S9S_MB_2U(SCH_1):PVCCD_HV_CPU1
 BJ7 PVCCD_HV_CPU1 VCCD_HV17 @S9S_MB_2U_LIB.S9S_MB_2U(SCH_1):PVCCD_HV_CPU1
 BJ3 PVCCD_HV_CPU1 VCCD_HV16 @S9S_MB_2U_LIB.S9S_MB_2U(SCH_1):PVCCD_HV_CPU1
BJ11 PVCCD_HV_CPU1 VCCD_HV15 @S9S_MB_2U_LIB.S9S_MB_2U(SCH_1):PVCCD_HV_CPU1
 BE7 PVCCD_HV_CPU1 VCCD_HV14 @S9S_MB_2U_LIB.S9S_MB_2U(SCH_1):PVCCD_HV_CPU1
 BE3 PVCCD_HV_CPU1 VCCD_HV13 @S9S_MB_2U_LIB.S9S_MB_2U(SCH_1):PVCCD_HV_CPU1
BE11 PVCCD_HV_CPU1 VCCD_HV12 @S9S_MB_2U_LIB.S9S_MB_2U(SCH_1):PVCCD_HV_CPU1
 BA7 PVCCD_HV_CPU1 VCCD_HV11 @S9S_MB_2U_LIB.S9S_MB_2U(SCH_1):PVCCD_HV_CPU1
 BA3 PVCCD_HV_CPU1 VCCD_HV10 @S9S_MB_2U_LIB.S9S_MB_2U(SCH_1):PVCCD_HV_CPU1
AV55 PVCCD_HV_CPU1 VCCD_HV9 @S9S_MB_2U_LIB.S9S_MB_2U(SCH_1):PVCCD_HV_CPU1
AV53 PVCCD_HV_CPU1 VCCD_HV8 @S9S_MB_2U_LIB.S9S_MB_2U(SCH_1):PVCCD_HV_CPU1
AV36 PVCCD_HV_CPU1 VCCD_HV7 @S9S_MB_2U_LIB.S9S_MB_2U(SCH_1):PVCCD_HV_CPU1
AV34 PVCCD_HV_CPU1 VCCD_HV6 @S9S_MB_2U_LIB.S9S_MB_2U(SCH_1):PVCCD_HV_CPU1
 AU7 PVCCD_HV_CPU1 VCCD_HV5 @S9S_MB_2U_LIB.S9S_MB_2U(SCH_1):PVCCD_HV_CPU1
AU54 PVCCD_HV_CPU1 VCCD_HV4 @S9S_MB_2U_LIB.S9S_MB_2U(SCH_1):PVCCD_HV_CPU1
AU35 PVCCD_HV_CPU1 VCCD_HV3 @S9S_MB_2U_LIB.S9S_MB_2U(SCH_1):PVCCD_HV_CPU1
 AU3 PVCCD_HV_CPU1 VCCD_HV2 @S9S_MB_2U_LIB.S9S_MB_2U(SCH_1):PVCCD_HV_CPU1
AT55 PVCCD_HV_CPU1 VCCD_HV1 @S9S_MB_2U_LIB.S9S_MB_2U(SCH_1):PVCCD_HV_CPU1
AT36 PVCCD_HV_CPU1 VCCD_HV0 @S9S_MB_2U_LIB.S9S_MB_2U(SCH_1):PVCCD_HV_CPU1
  N3 PVCCFA_EHV_CPU1 VCCFA_EHV8 @S9S_MB_2U_LIB.S9S_MB_2U(SCH_1):PVCCFA_EHV_CPU1
  U3 PVCCFA_EHV_CPU1 VCCFA_EHV9 @S9S_MB_2U_LIB.S9S_MB_2U(SCH_1):PVCCFA_EHV_CPU1
AW60 PVCCFA_EHV_CPU1 VCCFA_EHV7 @S9S_MB_2U_LIB.S9S_MB_2U(SCH_1):PVCCFA_EHV_CPU1
AV61 PVCCFA_EHV_CPU1 VCCFA_EHV6 @S9S_MB_2U_LIB.S9S_MB_2U(SCH_1):PVCCFA_EHV_CPU1
AU60 PVCCFA_EHV_CPU1 VCCFA_EHV5 @S9S_MB_2U_LIB.S9S_MB_2U(SCH_1):PVCCFA_EHV_CPU1
AT61 PVCCFA_EHV_CPU1 VCCFA_EHV4 @S9S_MB_2U_LIB.S9S_MB_2U(SCH_1):PVCCFA_EHV_CPU1
 AN3 PVCCFA_EHV_CPU1 VCCFA_EHV3 @S9S_MB_2U_LIB.S9S_MB_2U(SCH_1):PVCCFA_EHV_CPU1
 AJ3 PVCCFA_EHV_CPU1 VCCFA_EHV2 @S9S_MB_2U_LIB.S9S_MB_2U(SCH_1):PVCCFA_EHV_CPU1
 AE3 PVCCFA_EHV_CPU1 VCCFA_EHV1 @S9S_MB_2U_LIB.S9S_MB_2U(SCH_1):PVCCFA_EHV_CPU1
 AA3 PVCCFA_EHV_CPU1 VCCFA_EHV0 @S9S_MB_2U_LIB.S9S_MB_2U(SCH_1):PVCCFA_EHV_CPU1
DJ11 PVCCINFAON_CPU1 VCCINFAON59 @S9S_MB_2U_LIB.S9S_MB_2U(SCH_1):PVCCINFAON_CPU1
 DE7 PVCCINFAON_CPU1 VCCINFAON58 @S9S_MB_2U_LIB.S9S_MB_2U(SCH_1):PVCCINFAON_CPU1
 DA7 PVCCINFAON_CPU1 VCCINFAON57 @S9S_MB_2U_LIB.S9S_MB_2U(SCH_1):PVCCINFAON_CPU1
 DA3 PVCCINFAON_CPU1 VCCINFAON56 @S9S_MB_2U_LIB.S9S_MB_2U(SCH_1):PVCCINFAON_CPU1
CW64 PVCCINFAON_CPU1 VCCINFAON55 @S9S_MB_2U_LIB.S9S_MB_2U(SCH_1):PVCCINFAON_CPU1
CR66 PVCCINFAON_CPU1 VCCINFAON54 @S9S_MB_2U_LIB.S9S_MB_2U(SCH_1):PVCCINFAON_CPU1
 DJ7 PVCCINFAON_CPU1 VCCINFAON32 @S9S_MB_2U_LIB.S9S_MB_2U(SCH_1):PVCCINFAON_CPU1
 DJ3 PVCCINFAON_CPU1 VCCINFAON31 @S9S_MB_2U_LIB.S9S_MB_2U(SCH_1):PVCCINFAON_CPU1
DJ15 PVCCINFAON_CPU1 VCCINFAON30 @S9S_MB_2U_LIB.S9S_MB_2U(SCH_1):PVCCINFAON_CPU1
 DE3 PVCCINFAON_CPU1 VCCINFAON29 @S9S_MB_2U_LIB.S9S_MB_2U(SCH_1):PVCCINFAON_CPU1
DE15 PVCCINFAON_CPU1 VCCINFAON28 @S9S_MB_2U_LIB.S9S_MB_2U(SCH_1):PVCCINFAON_CPU1
DE11 PVCCINFAON_CPU1 VCCINFAON27 @S9S_MB_2U_LIB.S9S_MB_2U(SCH_1):PVCCINFAON_CPU1
DA64 PVCCINFAON_CPU1 VCCINFAON26 @S9S_MB_2U_LIB.S9S_MB_2U(SCH_1):PVCCINFAON_CPU1
DA15 PVCCINFAON_CPU1 VCCINFAON25 @S9S_MB_2U_LIB.S9S_MB_2U(SCH_1):PVCCINFAON_CPU1
DA11 PVCCINFAON_CPU1 VCCINFAON24 @S9S_MB_2U_LIB.S9S_MB_2U(SCH_1):PVCCINFAON_CPU1
CY67 PVCCINFAON_CPU1 VCCINFAON23 @S9S_MB_2U_LIB.S9S_MB_2U(SCH_1):PVCCINFAON_CPU1
CY65 PVCCINFAON_CPU1 VCCINFAON22 @S9S_MB_2U_LIB.S9S_MB_2U(SCH_1):PVCCINFAON_CPU1
CW66 PVCCINFAON_CPU1 VCCINFAON21 @S9S_MB_2U_LIB.S9S_MB_2U(SCH_1):PVCCINFAON_CPU1
CV67 PVCCINFAON_CPU1 VCCINFAON20 @S9S_MB_2U_LIB.S9S_MB_2U(SCH_1):PVCCINFAON_CPU1
CV65 PVCCINFAON_CPU1 VCCINFAON19 @S9S_MB_2U_LIB.S9S_MB_2U(SCH_1):PVCCINFAON_CPU1
 CU7 PVCCINFAON_CPU1 VCCINFAON18 @S9S_MB_2U_LIB.S9S_MB_2U(SCH_1):PVCCINFAON_CPU1
CU64 PVCCINFAON_CPU1 VCCINFAON17 @S9S_MB_2U_LIB.S9S_MB_2U(SCH_1):PVCCINFAON_CPU1
 CU3 PVCCINFAON_CPU1 VCCINFAON16 @S9S_MB_2U_LIB.S9S_MB_2U(SCH_1):PVCCINFAON_CPU1
CU15 PVCCINFAON_CPU1 VCCINFAON15 @S9S_MB_2U_LIB.S9S_MB_2U(SCH_1):PVCCINFAON_CPU1
CU11 PVCCINFAON_CPU1 VCCINFAON14 @S9S_MB_2U_LIB.S9S_MB_2U(SCH_1):PVCCINFAON_CPU1
CT67 PVCCINFAON_CPU1 VCCINFAON13 @S9S_MB_2U_LIB.S9S_MB_2U(SCH_1):PVCCINFAON_CPU1
CT65 PVCCINFAON_CPU1 VCCINFAON12 @S9S_MB_2U_LIB.S9S_MB_2U(SCH_1):PVCCINFAON_CPU1
CP67 PVCCINFAON_CPU1 VCCINFAON11 @S9S_MB_2U_LIB.S9S_MB_2U(SCH_1):PVCCINFAON_CPU1
CP65 PVCCINFAON_CPU1 VCCINFAON10 @S9S_MB_2U_LIB.S9S_MB_2U(SCH_1):PVCCINFAON_CPU1
 CN7 PVCCINFAON_CPU1 VCCINFAON9 @S9S_MB_2U_LIB.S9S_MB_2U(SCH_1):PVCCINFAON_CPU1
CN66 PVCCINFAON_CPU1 VCCINFAON8 @S9S_MB_2U_LIB.S9S_MB_2U(SCH_1):PVCCINFAON_CPU1
CN64 PVCCINFAON_CPU1 VCCINFAON7 @S9S_MB_2U_LIB.S9S_MB_2U(SCH_1):PVCCINFAON_CPU1
 CN3 PVCCINFAON_CPU1 VCCINFAON6 @S9S_MB_2U_LIB.S9S_MB_2U(SCH_1):PVCCINFAON_CPU1
CN15 PVCCINFAON_CPU1 VCCINFAON5 @S9S_MB_2U_LIB.S9S_MB_2U(SCH_1):PVCCINFAON_CPU1
CN11 PVCCINFAON_CPU1 VCCINFAON4 @S9S_MB_2U_LIB.S9S_MB_2U(SCH_1):PVCCINFAON_CPU1
 CJ7 PVCCINFAON_CPU1 VCCINFAON3 @S9S_MB_2U_LIB.S9S_MB_2U(SCH_1):PVCCINFAON_CPU1
 CJ3 PVCCINFAON_CPU1 VCCINFAON2 @S9S_MB_2U_LIB.S9S_MB_2U(SCH_1):PVCCINFAON_CPU1
CJ15 PVCCINFAON_CPU1 VCCINFAON1 @S9S_MB_2U_LIB.S9S_MB_2U(SCH_1):PVCCINFAON_CPU1
CE15 PVCCINFAON_CPU1 VCCINFAON0 @S9S_MB_2U_LIB.S9S_MB_2U(SCH_1):PVCCINFAON_CPU1
BN19 PVNN_MAIN_CPU1 VCCVNN3 @S9S_MB_2U_LIB.S9S_MB_2U(SCH_1):PVNN_MAIN_CPU1
BJ19 PVNN_MAIN_CPU1 VCCVNN2 @S9S_MB_2U_LIB.S9S_MB_2U(SCH_1):PVNN_MAIN_CPU1
BE19 PVNN_MAIN_CPU1 VCCVNN1 @S9S_MB_2U_LIB.S9S_MB_2U(SCH_1):PVNN_MAIN_CPU1
BA19 PVNN_MAIN_CPU1 VCCVNN0 @S9S_MB_2U_LIB.S9S_MB_2U(SCH_1):PVNN_MAIN_CPU1
CG68 PVPP_HBM_CPU1 VPP_HBM @S9S_MB_2U_LIB.S9S_MB_2U(SCH_1):PVPP_HBM_CPU1
CF67 PVPP_HBM_CPU1 VPP_HBM1 @S9S_MB_2U_LIB.S9S_MB_2U(SCH_1):PVPP_HBM_CPU1
CE68 PVPP_HBM_CPU1 VPP_HBM2 @S9S_MB_2U_LIB.S9S_MB_2U(SCH_1):PVPP_HBM_CPU1
CD67 PVPP_HBM_CPU1 VPP_HBM3 @S9S_MB_2U_LIB.S9S_MB_2U(SCH_1):PVPP_HBM_CPU1
CC68 PVPP_HBM_CPU1 VPP_HBM4 @S9S_MB_2U_LIB.S9S_MB_2U(SCH_1):PVPP_HBM_CPU1


DRAWING: @S9S_MB_2U_LIB.S9S_MB_2U(SCH_1):PAGE69 

SOCKET4677_AZIF0045P001C01CS-SA  I1  U1
 Y89 PVCCFA_EHV_FIVRA_CPU1 VCCFA_EHV_FIVRA104 @S9S_MB_2U_LIB.S9S_MB_2U(SCH_1):PVCCFA_EHV_FIVRA_CPU1
 Y85 PVCCFA_EHV_FIVRA_CPU1 VCCFA_EHV_FIVRA103 @S9S_MB_2U_LIB.S9S_MB_2U(SCH_1):PVCCFA_EHV_FIVRA_CPU1
 Y79 PVCCFA_EHV_FIVRA_CPU1 VCCFA_EHV_FIVRA102 @S9S_MB_2U_LIB.S9S_MB_2U(SCH_1):PVCCFA_EHV_FIVRA_CPU1
 W80 PVCCFA_EHV_FIVRA_CPU1 VCCFA_EHV_FIVRA101 @S9S_MB_2U_LIB.S9S_MB_2U(SCH_1):PVCCFA_EHV_FIVRA_CPU1
  U7 PVCCFA_EHV_FIVRA_CPU1 VCCFA_EHV_FIVRA100 @S9S_MB_2U_LIB.S9S_MB_2U(SCH_1):PVCCFA_EHV_FIVRA_CPU1
 U15 PVCCFA_EHV_FIVRA_CPU1 VCCFA_EHV_FIVRA99 @S9S_MB_2U_LIB.S9S_MB_2U(SCH_1):PVCCFA_EHV_FIVRA_CPU1
 U11 PVCCFA_EHV_FIVRA_CPU1 VCCFA_EHV_FIVRA98 @S9S_MB_2U_LIB.S9S_MB_2U(SCH_1):PVCCFA_EHV_FIVRA_CPU1
 T89 PVCCFA_EHV_FIVRA_CPU1 VCCFA_EHV_FIVRA97 @S9S_MB_2U_LIB.S9S_MB_2U(SCH_1):PVCCFA_EHV_FIVRA_CPU1
 T85 PVCCFA_EHV_FIVRA_CPU1 VCCFA_EHV_FIVRA96 @S9S_MB_2U_LIB.S9S_MB_2U(SCH_1):PVCCFA_EHV_FIVRA_CPU1
 R80 PVCCFA_EHV_FIVRA_CPU1 VCCFA_EHV_FIVRA95 @S9S_MB_2U_LIB.S9S_MB_2U(SCH_1):PVCCFA_EHV_FIVRA_CPU1
 P79 PVCCFA_EHV_FIVRA_CPU1 VCCFA_EHV_FIVRA94 @S9S_MB_2U_LIB.S9S_MB_2U(SCH_1):PVCCFA_EHV_FIVRA_CPU1
  N7 PVCCFA_EHV_FIVRA_CPU1 VCCFA_EHV_FIVRA93 @S9S_MB_2U_LIB.S9S_MB_2U(SCH_1):PVCCFA_EHV_FIVRA_CPU1
 N11 PVCCFA_EHV_FIVRA_CPU1 VCCFA_EHV_FIVRA92 @S9S_MB_2U_LIB.S9S_MB_2U(SCH_1):PVCCFA_EHV_FIVRA_CPU1
 M89 PVCCFA_EHV_FIVRA_CPU1 VCCFA_EHV_FIVRA91 @S9S_MB_2U_LIB.S9S_MB_2U(SCH_1):PVCCFA_EHV_FIVRA_CPU1
 M85 PVCCFA_EHV_FIVRA_CPU1 VCCFA_EHV_FIVRA90 @S9S_MB_2U_LIB.S9S_MB_2U(SCH_1):PVCCFA_EHV_FIVRA_CPU1
 L84 PVCCFA_EHV_FIVRA_CPU1 VCCFA_EHV_FIVRA89 @S9S_MB_2U_LIB.S9S_MB_2U(SCH_1):PVCCFA_EHV_FIVRA_CPU1
 K87 PVCCFA_EHV_FIVRA_CPU1 VCCFA_EHV_FIVRA88 @S9S_MB_2U_LIB.S9S_MB_2U(SCH_1):PVCCFA_EHV_FIVRA_CPU1
 J80 PVCCFA_EHV_FIVRA_CPU1 VCCFA_EHV_FIVRA87 @S9S_MB_2U_LIB.S9S_MB_2U(SCH_1):PVCCFA_EHV_FIVRA_CPU1
  J7 PVCCFA_EHV_FIVRA_CPU1 VCCFA_EHV_FIVRA86 @S9S_MB_2U_LIB.S9S_MB_2U(SCH_1):PVCCFA_EHV_FIVRA_CPU1
 J11 PVCCFA_EHV_FIVRA_CPU1 VCCFA_EHV_FIVRA85 @S9S_MB_2U_LIB.S9S_MB_2U(SCH_1):PVCCFA_EHV_FIVRA_CPU1
 H89 PVCCFA_EHV_FIVRA_CPU1 VCCFA_EHV_FIVRA84 @S9S_MB_2U_LIB.S9S_MB_2U(SCH_1):PVCCFA_EHV_FIVRA_CPU1
EN84 PVCCFA_EHV_FIVRA_CPU1 VCCFA_EHV_FIVRA83 @S9S_MB_2U_LIB.S9S_MB_2U(SCH_1):PVCCFA_EHV_FIVRA_CPU1
EJ84 PVCCFA_EHV_FIVRA_CPU1 VCCFA_EHV_FIVRA82 @S9S_MB_2U_LIB.S9S_MB_2U(SCH_1):PVCCFA_EHV_FIVRA_CPU1
EJ15 PVCCFA_EHV_FIVRA_CPU1 VCCFA_EHV_FIVRA81 @S9S_MB_2U_LIB.S9S_MB_2U(SCH_1):PVCCFA_EHV_FIVRA_CPU1
EG80 PVCCFA_EHV_FIVRA_CPU1 VCCFA_EHV_FIVRA80 @S9S_MB_2U_LIB.S9S_MB_2U(SCH_1):PVCCFA_EHV_FIVRA_CPU1
EF79 PVCCFA_EHV_FIVRA_CPU1 VCCFA_EHV_FIVRA79 @S9S_MB_2U_LIB.S9S_MB_2U(SCH_1):PVCCFA_EHV_FIVRA_CPU1
EE84 PVCCFA_EHV_FIVRA_CPU1 VCCFA_EHV_FIVRA78 @S9S_MB_2U_LIB.S9S_MB_2U(SCH_1):PVCCFA_EHV_FIVRA_CPU1
 EE7 PVCCFA_EHV_FIVRA_CPU1 VCCFA_EHV_FIVRA77 @S9S_MB_2U_LIB.S9S_MB_2U(SCH_1):PVCCFA_EHV_FIVRA_CPU1
EE15 PVCCFA_EHV_FIVRA_CPU1 VCCFA_EHV_FIVRA76 @S9S_MB_2U_LIB.S9S_MB_2U(SCH_1):PVCCFA_EHV_FIVRA_CPU1
EE11 PVCCFA_EHV_FIVRA_CPU1 VCCFA_EHV_FIVRA75 @S9S_MB_2U_LIB.S9S_MB_2U(SCH_1):PVCCFA_EHV_FIVRA_CPU1
ED89 PVCCFA_EHV_FIVRA_CPU1 VCCFA_EHV_FIVRA74 @S9S_MB_2U_LIB.S9S_MB_2U(SCH_1):PVCCFA_EHV_FIVRA_CPU1
ED85 PVCCFA_EHV_FIVRA_CPU1 VCCFA_EHV_FIVRA73 @S9S_MB_2U_LIB.S9S_MB_2U(SCH_1):PVCCFA_EHV_FIVRA_CPU1
ED79 PVCCFA_EHV_FIVRA_CPU1 VCCFA_EHV_FIVRA72 @S9S_MB_2U_LIB.S9S_MB_2U(SCH_1):PVCCFA_EHV_FIVRA_CPU1
EC78 PVCCFA_EHV_FIVRA_CPU1 VCCFA_EHV_FIVRA71 @S9S_MB_2U_LIB.S9S_MB_2U(SCH_1):PVCCFA_EHV_FIVRA_CPU1
 EA7 PVCCFA_EHV_FIVRA_CPU1 VCCFA_EHV_FIVRA70 @S9S_MB_2U_LIB.S9S_MB_2U(SCH_1):PVCCFA_EHV_FIVRA_CPU1
 EA3 PVCCFA_EHV_FIVRA_CPU1 VCCFA_EHV_FIVRA69 @S9S_MB_2U_LIB.S9S_MB_2U(SCH_1):PVCCFA_EHV_FIVRA_CPU1
EA15 PVCCFA_EHV_FIVRA_CPU1 VCCFA_EHV_FIVRA68 @S9S_MB_2U_LIB.S9S_MB_2U(SCH_1):PVCCFA_EHV_FIVRA_CPU1
EA11 PVCCFA_EHV_FIVRA_CPU1 VCCFA_EHV_FIVRA67 @S9S_MB_2U_LIB.S9S_MB_2U(SCH_1):PVCCFA_EHV_FIVRA_CPU1
DY89 PVCCFA_EHV_FIVRA_CPU1 VCCFA_EHV_FIVRA66 @S9S_MB_2U_LIB.S9S_MB_2U(SCH_1):PVCCFA_EHV_FIVRA_CPU1
DY85 PVCCFA_EHV_FIVRA_CPU1 VCCFA_EHV_FIVRA65 @S9S_MB_2U_LIB.S9S_MB_2U(SCH_1):PVCCFA_EHV_FIVRA_CPU1
 DU7 PVCCFA_EHV_FIVRA_CPU1 VCCFA_EHV_FIVRA64 @S9S_MB_2U_LIB.S9S_MB_2U(SCH_1):PVCCFA_EHV_FIVRA_CPU1
 DU3 PVCCFA_EHV_FIVRA_CPU1 VCCFA_EHV_FIVRA63 @S9S_MB_2U_LIB.S9S_MB_2U(SCH_1):PVCCFA_EHV_FIVRA_CPU1
DU15 PVCCFA_EHV_FIVRA_CPU1 VCCFA_EHV_FIVRA62 @S9S_MB_2U_LIB.S9S_MB_2U(SCH_1):PVCCFA_EHV_FIVRA_CPU1
DU11 PVCCFA_EHV_FIVRA_CPU1 VCCFA_EHV_FIVRA61 @S9S_MB_2U_LIB.S9S_MB_2U(SCH_1):PVCCFA_EHV_FIVRA_CPU1
DT89 PVCCFA_EHV_FIVRA_CPU1 VCCFA_EHV_FIVRA60 @S9S_MB_2U_LIB.S9S_MB_2U(SCH_1):PVCCFA_EHV_FIVRA_CPU1
DT85 PVCCFA_EHV_FIVRA_CPU1 VCCFA_EHV_FIVRA59 @S9S_MB_2U_LIB.S9S_MB_2U(SCH_1):PVCCFA_EHV_FIVRA_CPU1
DT79 PVCCFA_EHV_FIVRA_CPU1 VCCFA_EHV_FIVRA58 @S9S_MB_2U_LIB.S9S_MB_2U(SCH_1):PVCCFA_EHV_FIVRA_CPU1
 DN7 PVCCFA_EHV_FIVRA_CPU1 VCCFA_EHV_FIVRA57 @S9S_MB_2U_LIB.S9S_MB_2U(SCH_1):PVCCFA_EHV_FIVRA_CPU1
 DN3 PVCCFA_EHV_FIVRA_CPU1 VCCFA_EHV_FIVRA56 @S9S_MB_2U_LIB.S9S_MB_2U(SCH_1):PVCCFA_EHV_FIVRA_CPU1
DN15 PVCCFA_EHV_FIVRA_CPU1 VCCFA_EHV_FIVRA55 @S9S_MB_2U_LIB.S9S_MB_2U(SCH_1):PVCCFA_EHV_FIVRA_CPU1
DN11 PVCCFA_EHV_FIVRA_CPU1 VCCFA_EHV_FIVRA54 @S9S_MB_2U_LIB.S9S_MB_2U(SCH_1):PVCCFA_EHV_FIVRA_CPU1
DM89 PVCCFA_EHV_FIVRA_CPU1 VCCFA_EHV_FIVRA53 @S9S_MB_2U_LIB.S9S_MB_2U(SCH_1):PVCCFA_EHV_FIVRA_CPU1
DM85 PVCCFA_EHV_FIVRA_CPU1 VCCFA_EHV_FIVRA52 @S9S_MB_2U_LIB.S9S_MB_2U(SCH_1):PVCCFA_EHV_FIVRA_CPU1
DM83 PVCCFA_EHV_FIVRA_CPU1 VCCFA_EHV_FIVRA51 @S9S_MB_2U_LIB.S9S_MB_2U(SCH_1):PVCCFA_EHV_FIVRA_CPU1
DH89 PVCCFA_EHV_FIVRA_CPU1 VCCFA_EHV_FIVRA50 @S9S_MB_2U_LIB.S9S_MB_2U(SCH_1):PVCCFA_EHV_FIVRA_CPU1
DD89 PVCCFA_EHV_FIVRA_CPU1 VCCFA_EHV_FIVRA49 @S9S_MB_2U_LIB.S9S_MB_2U(SCH_1):PVCCFA_EHV_FIVRA_CPU1
DD85 PVCCFA_EHV_FIVRA_CPU1 VCCFA_EHV_FIVRA48 @S9S_MB_2U_LIB.S9S_MB_2U(SCH_1):PVCCFA_EHV_FIVRA_CPU1
DD83 PVCCFA_EHV_FIVRA_CPU1 VCCFA_EHV_FIVRA47 @S9S_MB_2U_LIB.S9S_MB_2U(SCH_1):PVCCFA_EHV_FIVRA_CPU1
DD77 PVCCFA_EHV_FIVRA_CPU1 VCCFA_EHV_FIVRA46 @S9S_MB_2U_LIB.S9S_MB_2U(SCH_1):PVCCFA_EHV_FIVRA_CPU1
CY89 PVCCFA_EHV_FIVRA_CPU1 VCCFA_EHV_FIVRA45 @S9S_MB_2U_LIB.S9S_MB_2U(SCH_1):PVCCFA_EHV_FIVRA_CPU1
CY85 PVCCFA_EHV_FIVRA_CPU1 VCCFA_EHV_FIVRA44 @S9S_MB_2U_LIB.S9S_MB_2U(SCH_1):PVCCFA_EHV_FIVRA_CPU1
CY79 PVCCFA_EHV_FIVRA_CPU1 VCCFA_EHV_FIVRA43 @S9S_MB_2U_LIB.S9S_MB_2U(SCH_1):PVCCFA_EHV_FIVRA_CPU1
CY75 PVCCFA_EHV_FIVRA_CPU1 VCCFA_EHV_FIVRA42 @S9S_MB_2U_LIB.S9S_MB_2U(SCH_1):PVCCFA_EHV_FIVRA_CPU1
CT85 PVCCFA_EHV_FIVRA_CPU1 VCCFA_EHV_FIVRA41 @S9S_MB_2U_LIB.S9S_MB_2U(SCH_1):PVCCFA_EHV_FIVRA_CPU1
CT77 PVCCFA_EHV_FIVRA_CPU1 VCCFA_EHV_FIVRA40 @S9S_MB_2U_LIB.S9S_MB_2U(SCH_1):PVCCFA_EHV_FIVRA_CPU1
CP73 PVCCFA_EHV_FIVRA_CPU1 VCCFA_EHV_FIVRA39 @S9S_MB_2U_LIB.S9S_MB_2U(SCH_1):PVCCFA_EHV_FIVRA_CPU1
CN78 PVCCFA_EHV_FIVRA_CPU1 VCCFA_EHV_FIVRA38 @S9S_MB_2U_LIB.S9S_MB_2U(SCH_1):PVCCFA_EHV_FIVRA_CPU1
CM73 PVCCFA_EHV_FIVRA_CPU1 VCCFA_EHV_FIVRA37 @S9S_MB_2U_LIB.S9S_MB_2U(SCH_1):PVCCFA_EHV_FIVRA_CPU1
CK79 PVCCFA_EHV_FIVRA_CPU1 VCCFA_EHV_FIVRA36 @S9S_MB_2U_LIB.S9S_MB_2U(SCH_1):PVCCFA_EHV_FIVRA_CPU1
CK73 PVCCFA_EHV_FIVRA_CPU1 VCCFA_EHV_FIVRA35 @S9S_MB_2U_LIB.S9S_MB_2U(SCH_1):PVCCFA_EHV_FIVRA_CPU1
CE74 PVCCFA_EHV_FIVRA_CPU1 VCCFA_EHV_FIVRA34 @S9S_MB_2U_LIB.S9S_MB_2U(SCH_1):PVCCFA_EHV_FIVRA_CPU1
 C88 PVCCFA_EHV_FIVRA_CPU1 VCCFA_EHV_FIVRA33 @S9S_MB_2U_LIB.S9S_MB_2U(SCH_1):PVCCFA_EHV_FIVRA_CPU1
 C84 PVCCFA_EHV_FIVRA_CPU1 VCCFA_EHV_FIVRA32 @S9S_MB_2U_LIB.S9S_MB_2U(SCH_1):PVCCFA_EHV_FIVRA_CPU1
BJ78 PVCCFA_EHV_FIVRA_CPU1 VCCFA_EHV_FIVRA31 @S9S_MB_2U_LIB.S9S_MB_2U(SCH_1):PVCCFA_EHV_FIVRA_CPU1
BJ72 PVCCFA_EHV_FIVRA_CPU1 VCCFA_EHV_FIVRA30 @S9S_MB_2U_LIB.S9S_MB_2U(SCH_1):PVCCFA_EHV_FIVRA_CPU1
BH79 PVCCFA_EHV_FIVRA_CPU1 VCCFA_EHV_FIVRA29 @S9S_MB_2U_LIB.S9S_MB_2U(SCH_1):PVCCFA_EHV_FIVRA_CPU1
BF77 PVCCFA_EHV_FIVRA_CPU1 VCCFA_EHV_FIVRA28 @S9S_MB_2U_LIB.S9S_MB_2U(SCH_1):PVCCFA_EHV_FIVRA_CPU1
BE72 PVCCFA_EHV_FIVRA_CPU1 VCCFA_EHV_FIVRA27 @S9S_MB_2U_LIB.S9S_MB_2U(SCH_1):PVCCFA_EHV_FIVRA_CPU1
AY89 PVCCFA_EHV_FIVRA_CPU1 VCCFA_EHV_FIVRA26 @S9S_MB_2U_LIB.S9S_MB_2U(SCH_1):PVCCFA_EHV_FIVRA_CPU1
AW76 PVCCFA_EHV_FIVRA_CPU1 VCCFA_EHV_FIVRA25 @S9S_MB_2U_LIB.S9S_MB_2U(SCH_1):PVCCFA_EHV_FIVRA_CPU1
AU15 PVCCFA_EHV_FIVRA_CPU1 VCCFA_EHV_FIVRA24 @S9S_MB_2U_LIB.S9S_MB_2U(SCH_1):PVCCFA_EHV_FIVRA_CPU1
AT89 PVCCFA_EHV_FIVRA_CPU1 VCCFA_EHV_FIVRA23 @S9S_MB_2U_LIB.S9S_MB_2U(SCH_1):PVCCFA_EHV_FIVRA_CPU1
AT73 PVCCFA_EHV_FIVRA_CPU1 VCCFA_EHV_FIVRA22 @S9S_MB_2U_LIB.S9S_MB_2U(SCH_1):PVCCFA_EHV_FIVRA_CPU1
AN80 PVCCFA_EHV_FIVRA_CPU1 VCCFA_EHV_FIVRA21 @S9S_MB_2U_LIB.S9S_MB_2U(SCH_1):PVCCFA_EHV_FIVRA_CPU1
 AN7 PVCCFA_EHV_FIVRA_CPU1 VCCFA_EHV_FIVRA20 @S9S_MB_2U_LIB.S9S_MB_2U(SCH_1):PVCCFA_EHV_FIVRA_CPU1
AN15 PVCCFA_EHV_FIVRA_CPU1 VCCFA_EHV_FIVRA19 @S9S_MB_2U_LIB.S9S_MB_2U(SCH_1):PVCCFA_EHV_FIVRA_CPU1
AN11 PVCCFA_EHV_FIVRA_CPU1 VCCFA_EHV_FIVRA18 @S9S_MB_2U_LIB.S9S_MB_2U(SCH_1):PVCCFA_EHV_FIVRA_CPU1
AM89 PVCCFA_EHV_FIVRA_CPU1 VCCFA_EHV_FIVRA17 @S9S_MB_2U_LIB.S9S_MB_2U(SCH_1):PVCCFA_EHV_FIVRA_CPU1
AM85 PVCCFA_EHV_FIVRA_CPU1 VCCFA_EHV_FIVRA16 @S9S_MB_2U_LIB.S9S_MB_2U(SCH_1):PVCCFA_EHV_FIVRA_CPU1
AM79 PVCCFA_EHV_FIVRA_CPU1 VCCFA_EHV_FIVRA15 @S9S_MB_2U_LIB.S9S_MB_2U(SCH_1):PVCCFA_EHV_FIVRA_CPU1
 AJ7 PVCCFA_EHV_FIVRA_CPU1 VCCFA_EHV_FIVRA14 @S9S_MB_2U_LIB.S9S_MB_2U(SCH_1):PVCCFA_EHV_FIVRA_CPU1
AJ15 PVCCFA_EHV_FIVRA_CPU1 VCCFA_EHV_FIVRA13 @S9S_MB_2U_LIB.S9S_MB_2U(SCH_1):PVCCFA_EHV_FIVRA_CPU1
AJ11 PVCCFA_EHV_FIVRA_CPU1 VCCFA_EHV_FIVRA12 @S9S_MB_2U_LIB.S9S_MB_2U(SCH_1):PVCCFA_EHV_FIVRA_CPU1
AH89 PVCCFA_EHV_FIVRA_CPU1 VCCFA_EHV_FIVRA11 @S9S_MB_2U_LIB.S9S_MB_2U(SCH_1):PVCCFA_EHV_FIVRA_CPU1
AH85 PVCCFA_EHV_FIVRA_CPU1 VCCFA_EHV_FIVRA10 @S9S_MB_2U_LIB.S9S_MB_2U(SCH_1):PVCCFA_EHV_FIVRA_CPU1
AG78 PVCCFA_EHV_FIVRA_CPU1 VCCFA_EHV_FIVRA9 @S9S_MB_2U_LIB.S9S_MB_2U(SCH_1):PVCCFA_EHV_FIVRA_CPU1
AF77 PVCCFA_EHV_FIVRA_CPU1 VCCFA_EHV_FIVRA8 @S9S_MB_2U_LIB.S9S_MB_2U(SCH_1):PVCCFA_EHV_FIVRA_CPU1
 AE7 PVCCFA_EHV_FIVRA_CPU1 VCCFA_EHV_FIVRA7 @S9S_MB_2U_LIB.S9S_MB_2U(SCH_1):PVCCFA_EHV_FIVRA_CPU1
AE15 PVCCFA_EHV_FIVRA_CPU1 VCCFA_EHV_FIVRA6 @S9S_MB_2U_LIB.S9S_MB_2U(SCH_1):PVCCFA_EHV_FIVRA_CPU1
AE11 PVCCFA_EHV_FIVRA_CPU1 VCCFA_EHV_FIVRA5 @S9S_MB_2U_LIB.S9S_MB_2U(SCH_1):PVCCFA_EHV_FIVRA_CPU1
AD89 PVCCFA_EHV_FIVRA_CPU1 VCCFA_EHV_FIVRA4 @S9S_MB_2U_LIB.S9S_MB_2U(SCH_1):PVCCFA_EHV_FIVRA_CPU1
AD85 PVCCFA_EHV_FIVRA_CPU1 VCCFA_EHV_FIVRA3 @S9S_MB_2U_LIB.S9S_MB_2U(SCH_1):PVCCFA_EHV_FIVRA_CPU1
 AA7 PVCCFA_EHV_FIVRA_CPU1 VCCFA_EHV_FIVRA2 @S9S_MB_2U_LIB.S9S_MB_2U(SCH_1):PVCCFA_EHV_FIVRA_CPU1
AA15 PVCCFA_EHV_FIVRA_CPU1 VCCFA_EHV_FIVRA1 @S9S_MB_2U_LIB.S9S_MB_2U(SCH_1):PVCCFA_EHV_FIVRA_CPU1
AA11 PVCCFA_EHV_FIVRA_CPU1 VCCFA_EHV_FIVRA0 @S9S_MB_2U_LIB.S9S_MB_2U(SCH_1):PVCCFA_EHV_FIVRA_CPU1


DRAWING: @S9S_MB_2U_LIB.S9S_MB_2U(SCH_1):PAGE70 

SOCKET4677_AZIF0045P001C01CS-SA  I2  U1
ER41    GND VSS1834 @S9S_MB_2U_LIB.S9S_MB_2U(SCH_1):GND
ER43    GND VSS1835 @S9S_MB_2U_LIB.S9S_MB_2U(SCH_1):GND
ER48    GND VSS1836 @S9S_MB_2U_LIB.S9S_MB_2U(SCH_1):GND
ER50    GND VSS1837 @S9S_MB_2U_LIB.S9S_MB_2U(SCH_1):GND
ET57    GND VSS1569 @S9S_MB_2U_LIB.S9S_MB_2U(SCH_1):GND
ET38    GND VSS1565 @S9S_MB_2U_LIB.S9S_MB_2U(SCH_1):GND
ET34    GND VSS1563 @S9S_MB_2U_LIB.S9S_MB_2U(SCH_1):GND
ET28    GND VSS1562 @S9S_MB_2U_LIB.S9S_MB_2U(SCH_1):GND
ET22    GND VSS1561 @S9S_MB_2U_LIB.S9S_MB_2U(SCH_1):GND
ET16    GND VSS1559 @S9S_MB_2U_LIB.S9S_MB_2U(SCH_1):GND
ET10    GND VSS1557 @S9S_MB_2U_LIB.S9S_MB_2U(SCH_1):GND
ER86    GND VSS1556 @S9S_MB_2U_LIB.S9S_MB_2U(SCH_1):GND
ER84    GND VSS1555 @S9S_MB_2U_LIB.S9S_MB_2U(SCH_1):GND
ER80    GND VSS1554 @S9S_MB_2U_LIB.S9S_MB_2U(SCH_1):GND
ER78    GND VSS1553 @S9S_MB_2U_LIB.S9S_MB_2U(SCH_1):GND
ER74    GND VSS1552 @S9S_MB_2U_LIB.S9S_MB_2U(SCH_1):GND
ER70    GND VSS1551 @S9S_MB_2U_LIB.S9S_MB_2U(SCH_1):GND
 ER7    GND VSS1550 @S9S_MB_2U_LIB.S9S_MB_2U(SCH_1):GND
 ER5    GND VSS1549 @S9S_MB_2U_LIB.S9S_MB_2U(SCH_1):GND
ER33    GND VSS1548 @S9S_MB_2U_LIB.S9S_MB_2U(SCH_1):GND
ER27    GND VSS1547 @S9S_MB_2U_LIB.S9S_MB_2U(SCH_1):GND
EP83    GND VSS1545 @S9S_MB_2U_LIB.S9S_MB_2U(SCH_1):GND
EP67    GND VSS1543 @S9S_MB_2U_LIB.S9S_MB_2U(SCH_1):GND
EN80    GND VSS1542 @S9S_MB_2U_LIB.S9S_MB_2U(SCH_1):GND
EN78    GND VSS1541 @S9S_MB_2U_LIB.S9S_MB_2U(SCH_1):GND
EN64    GND VSS1540 @S9S_MB_2U_LIB.S9S_MB_2U(SCH_1):GND
EN56    GND VSS1539 @S9S_MB_2U_LIB.S9S_MB_2U(SCH_1):GND
EN54    GND VSS1537 @S9S_MB_2U_LIB.S9S_MB_2U(SCH_1):GND
EN52    GND VSS1533 @S9S_MB_2U_LIB.S9S_MB_2U(SCH_1):GND
EN50    GND VSS1531 @S9S_MB_2U_LIB.S9S_MB_2U(SCH_1):GND
EN48    GND VSS1530 @S9S_MB_2U_LIB.S9S_MB_2U(SCH_1):GND
EN45    GND VSS1529 @S9S_MB_2U_LIB.S9S_MB_2U(SCH_1):GND
EN43    GND VSS1528 @S9S_MB_2U_LIB.S9S_MB_2U(SCH_1):GND
EN41    GND VSS1526 @S9S_MB_2U_LIB.S9S_MB_2U(SCH_1):GND
EN37    GND VSS1525 @S9S_MB_2U_LIB.S9S_MB_2U(SCH_1):GND
EN35    GND VSS1524 @S9S_MB_2U_LIB.S9S_MB_2U(SCH_1):GND
EN33    GND VSS1522 @S9S_MB_2U_LIB.S9S_MB_2U(SCH_1):GND
EN31    GND VSS1520 @S9S_MB_2U_LIB.S9S_MB_2U(SCH_1):GND
EN29    GND VSS1518 @S9S_MB_2U_LIB.S9S_MB_2U(SCH_1):GND
EN27    GND VSS1517 @S9S_MB_2U_LIB.S9S_MB_2U(SCH_1):GND
EN25    GND VSS1515 @S9S_MB_2U_LIB.S9S_MB_2U(SCH_1):GND
EN23    GND VSS1513 @S9S_MB_2U_LIB.S9S_MB_2U(SCH_1):GND
EN21    GND VSS1512 @S9S_MB_2U_LIB.S9S_MB_2U(SCH_1):GND
EN19    GND VSS1506 @S9S_MB_2U_LIB.S9S_MB_2U(SCH_1):GND
EN17    GND VSS1505 @S9S_MB_2U_LIB.S9S_MB_2U(SCH_1):GND
EN15    GND VSS1503 @S9S_MB_2U_LIB.S9S_MB_2U(SCH_1):GND
EN13    GND VSS1501 @S9S_MB_2U_LIB.S9S_MB_2U(SCH_1):GND
EN11    GND VSS1500 @S9S_MB_2U_LIB.S9S_MB_2U(SCH_1):GND
EM83    GND VSS1499 @S9S_MB_2U_LIB.S9S_MB_2U(SCH_1):GND
EM81    GND VSS1498 @S9S_MB_2U_LIB.S9S_MB_2U(SCH_1):GND
 EM8    GND VSS1497 @S9S_MB_2U_LIB.S9S_MB_2U(SCH_1):GND
EM73    GND VSS1496 @S9S_MB_2U_LIB.S9S_MB_2U(SCH_1):GND
ET59    GND VSS1493 @S9S_MB_2U_LIB.S9S_MB_2U(SCH_1):GND
EM42    GND VSS1492 @S9S_MB_2U_LIB.S9S_MB_2U(SCH_1):GND
ET53    GND VSS1491 @S9S_MB_2U_LIB.S9S_MB_2U(SCH_1):GND
EL76    GND VSS1489 @S9S_MB_2U_LIB.S9S_MB_2U(SCH_1):GND
EL64    GND VSS1488 @S9S_MB_2U_LIB.S9S_MB_2U(SCH_1):GND
 EL5    GND VSS1486 @S9S_MB_2U_LIB.S9S_MB_2U(SCH_1):GND
EL45    GND VSS1485 @S9S_MB_2U_LIB.S9S_MB_2U(SCH_1):GND
ET32    GND VSS1484 @S9S_MB_2U_LIB.S9S_MB_2U(SCH_1):GND
EL39    GND VSS1483 @S9S_MB_2U_LIB.S9S_MB_2U(SCH_1):GND
ET26    GND VSS1482 @S9S_MB_2U_LIB.S9S_MB_2U(SCH_1):GND
EL33    GND VSS1481 @S9S_MB_2U_LIB.S9S_MB_2U(SCH_1):GND
ET20    GND VSS1480 @S9S_MB_2U_LIB.S9S_MB_2U(SCH_1):GND
 EL3    GND VSS1479 @S9S_MB_2U_LIB.S9S_MB_2U(SCH_1):GND
ET14    GND VSS1478 @S9S_MB_2U_LIB.S9S_MB_2U(SCH_1):GND
EL27    GND VSS1477 @S9S_MB_2U_LIB.S9S_MB_2U(SCH_1):GND
 ER9    GND VSS1476 @S9S_MB_2U_LIB.S9S_MB_2U(SCH_1):GND
EL21    GND VSS1475 @S9S_MB_2U_LIB.S9S_MB_2U(SCH_1):GND
EK75    GND VSS1474 @S9S_MB_2U_LIB.S9S_MB_2U(SCH_1):GND
EK69    GND VSS1473 @S9S_MB_2U_LIB.S9S_MB_2U(SCH_1):GND
EK65    GND VSS1472 @S9S_MB_2U_LIB.S9S_MB_2U(SCH_1):GND
EK57    GND VSS1471 @S9S_MB_2U_LIB.S9S_MB_2U(SCH_1):GND
EK47    GND VSS1470 @S9S_MB_2U_LIB.S9S_MB_2U(SCH_1):GND
EK40    GND VSS1469 @S9S_MB_2U_LIB.S9S_MB_2U(SCH_1):GND
ER64    GND VSS1468 @S9S_MB_2U_LIB.S9S_MB_2U(SCH_1):GND
ER58    GND VSS1467 @S9S_MB_2U_LIB.S9S_MB_2U(SCH_1):GND
 EK4    GND VSS1466 @S9S_MB_2U_LIB.S9S_MB_2U(SCH_1):GND
EK38    GND VSS1465 @S9S_MB_2U_LIB.S9S_MB_2U(SCH_1):GND
ER52    GND VSS1464 @S9S_MB_2U_LIB.S9S_MB_2U(SCH_1):GND
EK34    GND VSS1463 @S9S_MB_2U_LIB.S9S_MB_2U(SCH_1):GND
ER39    GND VSS1462 @S9S_MB_2U_LIB.S9S_MB_2U(SCH_1):GND
EK32    GND VSS1461 @S9S_MB_2U_LIB.S9S_MB_2U(SCH_1):GND
EK28    GND VSS1460 @S9S_MB_2U_LIB.S9S_MB_2U(SCH_1):GND
EK22    GND VSS1459 @S9S_MB_2U_LIB.S9S_MB_2U(SCH_1):GND
 EK2    GND VSS1458 @S9S_MB_2U_LIB.S9S_MB_2U(SCH_1):GND
ER21    GND VSS1457 @S9S_MB_2U_LIB.S9S_MB_2U(SCH_1):GND
ER15    GND VSS1456 @S9S_MB_2U_LIB.S9S_MB_2U(SCH_1):GND
EK14    GND VSS1455 @S9S_MB_2U_LIB.S9S_MB_2U(SCH_1):GND
EP77    GND VSS1454 @S9S_MB_2U_LIB.S9S_MB_2U(SCH_1):GND
EP71    GND VSS1453 @S9S_MB_2U_LIB.S9S_MB_2U(SCH_1):GND
EP69    GND VSS1452 @S9S_MB_2U_LIB.S9S_MB_2U(SCH_1):GND
EK10    GND VSS1451 @S9S_MB_2U_LIB.S9S_MB_2U(SCH_1):GND
 EJ9    GND VSS1450 @S9S_MB_2U_LIB.S9S_MB_2U(SCH_1):GND
EJ88    GND VSS1449 @S9S_MB_2U_LIB.S9S_MB_2U(SCH_1):GND
EJ78    GND VSS1448 @S9S_MB_2U_LIB.S9S_MB_2U(SCH_1):GND
EJ74    GND VSS1447 @S9S_MB_2U_LIB.S9S_MB_2U(SCH_1):GND
 EN9    GND VSS1446 @S9S_MB_2U_LIB.S9S_MB_2U(SCH_1):GND
EN88    GND VSS1445 @S9S_MB_2U_LIB.S9S_MB_2U(SCH_1):GND
 EJ7    GND VSS1444 @S9S_MB_2U_LIB.S9S_MB_2U(SCH_1):GND
EJ66    GND VSS1443 @S9S_MB_2U_LIB.S9S_MB_2U(SCH_1):GND
EJ60    GND VSS1442 @S9S_MB_2U_LIB.S9S_MB_2U(SCH_1):GND
EN72    GND VSS1441 @S9S_MB_2U_LIB.S9S_MB_2U(SCH_1):GND
EN66    GND VSS1440 @S9S_MB_2U_LIB.S9S_MB_2U(SCH_1):GND
EJ56    GND VSS1439 @S9S_MB_2U_LIB.S9S_MB_2U(SCH_1):GND
EN62    GND VSS1438 @S9S_MB_2U_LIB.S9S_MB_2U(SCH_1):GND
EN60    GND VSS1437 @S9S_MB_2U_LIB.S9S_MB_2U(SCH_1):GND
EN58    GND VSS1436 @S9S_MB_2U_LIB.S9S_MB_2U(SCH_1):GND
EJ50    GND VSS1435 @S9S_MB_2U_LIB.S9S_MB_2U(SCH_1):GND
EJ48    GND VSS1434 @S9S_MB_2U_LIB.S9S_MB_2U(SCH_1):GND
EJ43    GND VSS1433 @S9S_MB_2U_LIB.S9S_MB_2U(SCH_1):GND
EJ41    GND VSS1432 @S9S_MB_2U_LIB.S9S_MB_2U(SCH_1):GND
EJ37    GND VSS1431 @S9S_MB_2U_LIB.S9S_MB_2U(SCH_1):GND
EJ31    GND VSS1430 @S9S_MB_2U_LIB.S9S_MB_2U(SCH_1):GND
EJ29    GND VSS1429 @S9S_MB_2U_LIB.S9S_MB_2U(SCH_1):GND
EJ23    GND VSS1428 @S9S_MB_2U_LIB.S9S_MB_2U(SCH_1):GND
EN39    GND VSS1427 @S9S_MB_2U_LIB.S9S_MB_2U(SCH_1):GND
EJ19    GND VSS1426 @S9S_MB_2U_LIB.S9S_MB_2U(SCH_1):GND
EJ13    GND VSS1425 @S9S_MB_2U_LIB.S9S_MB_2U(SCH_1):GND
EH83    GND VSS1424 @S9S_MB_2U_LIB.S9S_MB_2U(SCH_1):GND
EH81    GND VSS1423 @S9S_MB_2U_LIB.S9S_MB_2U(SCH_1):GND
EH73    GND VSS1422 @S9S_MB_2U_LIB.S9S_MB_2U(SCH_1):GND
EH49    GND VSS1421 @S9S_MB_2U_LIB.S9S_MB_2U(SCH_1):GND
EH36    GND VSS1419 @S9S_MB_2U_LIB.S9S_MB_2U(SCH_1):GND
EM79    GND VSS1409 @S9S_MB_2U_LIB.S9S_MB_2U(SCH_1):GND
EM49    GND VSS1405 @S9S_MB_2U_LIB.S9S_MB_2U(SCH_1):GND
 EL9    GND VSS1401 @S9S_MB_2U_LIB.S9S_MB_2U(SCH_1):GND
EL86    GND VSS1400 @S9S_MB_2U_LIB.S9S_MB_2U(SCH_1):GND
EL72    GND VSS1398 @S9S_MB_2U_LIB.S9S_MB_2U(SCH_1):GND
EL70    GND VSS1397 @S9S_MB_2U_LIB.S9S_MB_2U(SCH_1):GND
 EL7    GND VSS1396 @S9S_MB_2U_LIB.S9S_MB_2U(SCH_1):GND
EL58    GND VSS1394 @S9S_MB_2U_LIB.S9S_MB_2U(SCH_1):GND
EL52    GND VSS1391 @S9S_MB_2U_LIB.S9S_MB_2U(SCH_1):GND
EL15    GND VSS1381 @S9S_MB_2U_LIB.S9S_MB_2U(SCH_1):GND
EK89    GND VSS1380 @S9S_MB_2U_LIB.S9S_MB_2U(SCH_1):GND
EK83    GND VSS1379 @S9S_MB_2U_LIB.S9S_MB_2U(SCH_1):GND
EK79    GND VSS1378 @S9S_MB_2U_LIB.S9S_MB_2U(SCH_1):GND
EK77    GND VSS1377 @S9S_MB_2U_LIB.S9S_MB_2U(SCH_1):GND
EK71    GND VSS1375 @S9S_MB_2U_LIB.S9S_MB_2U(SCH_1):GND
EK63    GND VSS1372 @S9S_MB_2U_LIB.S9S_MB_2U(SCH_1):GND
EK59    GND VSS1371 @S9S_MB_2U_LIB.S9S_MB_2U(SCH_1):GND
EK53    GND VSS1369 @S9S_MB_2U_LIB.S9S_MB_2U(SCH_1):GND
EK51    GND VSS1368 @S9S_MB_2U_LIB.S9S_MB_2U(SCH_1):GND
EK44    GND VSS1366 @S9S_MB_2U_LIB.S9S_MB_2U(SCH_1):GND
EK26    GND VSS1359 @S9S_MB_2U_LIB.S9S_MB_2U(SCH_1):GND
EK20    GND VSS1357 @S9S_MB_2U_LIB.S9S_MB_2U(SCH_1):GND
EK16    GND VSS1355 @S9S_MB_2U_LIB.S9S_MB_2U(SCH_1):GND
EJ72    GND VSS1347 @S9S_MB_2U_LIB.S9S_MB_2U(SCH_1):GND
EJ68    GND VSS1345 @S9S_MB_2U_LIB.S9S_MB_2U(SCH_1):GND
EJ62    GND VSS1343 @S9S_MB_2U_LIB.S9S_MB_2U(SCH_1):GND
EJ54    GND VSS1340 @S9S_MB_2U_LIB.S9S_MB_2U(SCH_1):GND
EJ35    GND VSS1334 @S9S_MB_2U_LIB.S9S_MB_2U(SCH_1):GND
EJ25    GND VSS1331 @S9S_MB_2U_LIB.S9S_MB_2U(SCH_1):GND
EJ17    GND VSS1328 @S9S_MB_2U_LIB.S9S_MB_2U(SCH_1):GND
EJ11    GND VSS1325 @S9S_MB_2U_LIB.S9S_MB_2U(SCH_1):GND
EH79    GND VSS1322 @S9S_MB_2U_LIB.S9S_MB_2U(SCH_1):GND
EH67    GND VSS1320 @S9S_MB_2U_LIB.S9S_MB_2U(SCH_1):GND
EH61    GND VSS1319 @S9S_MB_2U_LIB.S9S_MB_2U(SCH_1):GND
EH55    GND VSS1315 @S9S_MB_2U_LIB.S9S_MB_2U(SCH_1):GND
EH42    GND VSS1312 @S9S_MB_2U_LIB.S9S_MB_2U(SCH_1):GND

SOCKET4677_AZIF0045P001C01CS-SA  I5  U1
 EH4    GND VSS1420 @S9S_MB_2U_LIB.S9S_MB_2U(SCH_1):GND
EH30    GND VSS1418 @S9S_MB_2U_LIB.S9S_MB_2U(SCH_1):GND
EH24    GND VSS1417 @S9S_MB_2U_LIB.S9S_MB_2U(SCH_1):GND
EH16    GND VSS1416 @S9S_MB_2U_LIB.S9S_MB_2U(SCH_1):GND
EG90    GND VSS1415 @S9S_MB_2U_LIB.S9S_MB_2U(SCH_1):GND
 EG9    GND VSS1414 @S9S_MB_2U_LIB.S9S_MB_2U(SCH_1):GND
EG88    GND VSS1413 @S9S_MB_2U_LIB.S9S_MB_2U(SCH_1):GND
EG86    GND VSS1412 @S9S_MB_2U_LIB.S9S_MB_2U(SCH_1):GND
EG84    GND VSS1411 @S9S_MB_2U_LIB.S9S_MB_2U(SCH_1):GND
EG82    GND VSS1410 @S9S_MB_2U_LIB.S9S_MB_2U(SCH_1):GND
EG39    GND VSS1408 @S9S_MB_2U_LIB.S9S_MB_2U(SCH_1):GND
EF87    GND VSS1407 @S9S_MB_2U_LIB.S9S_MB_2U(SCH_1):GND
EF85    GND VSS1406 @S9S_MB_2U_LIB.S9S_MB_2U(SCH_1):GND
 EF8    GND VSS1404 @S9S_MB_2U_LIB.S9S_MB_2U(SCH_1):GND
EF77    GND VSS1403 @S9S_MB_2U_LIB.S9S_MB_2U(SCH_1):GND
EF71    GND VSS1402 @S9S_MB_2U_LIB.S9S_MB_2U(SCH_1):GND
EF69    GND VSS1399 @S9S_MB_2U_LIB.S9S_MB_2U(SCH_1):GND
EF67    GND VSS1395 @S9S_MB_2U_LIB.S9S_MB_2U(SCH_1):GND
EF65    GND VSS1393 @S9S_MB_2U_LIB.S9S_MB_2U(SCH_1):GND
EF63    GND VSS1392 @S9S_MB_2U_LIB.S9S_MB_2U(SCH_1):GND
EF61    GND VSS1390 @S9S_MB_2U_LIB.S9S_MB_2U(SCH_1):GND
EF59    GND VSS1389 @S9S_MB_2U_LIB.S9S_MB_2U(SCH_1):GND
EF57    GND VSS1388 @S9S_MB_2U_LIB.S9S_MB_2U(SCH_1):GND
EF55    GND VSS1387 @S9S_MB_2U_LIB.S9S_MB_2U(SCH_1):GND
EF53    GND VSS1386 @S9S_MB_2U_LIB.S9S_MB_2U(SCH_1):GND
EF49    GND VSS1385 @S9S_MB_2U_LIB.S9S_MB_2U(SCH_1):GND
EF47    GND VSS1384 @S9S_MB_2U_LIB.S9S_MB_2U(SCH_1):GND
EF44    GND VSS1383 @S9S_MB_2U_LIB.S9S_MB_2U(SCH_1):GND
EF42    GND VSS1382 @S9S_MB_2U_LIB.S9S_MB_2U(SCH_1):GND
EF40    GND VSS1376 @S9S_MB_2U_LIB.S9S_MB_2U(SCH_1):GND
 EF4    GND VSS1374 @S9S_MB_2U_LIB.S9S_MB_2U(SCH_1):GND
EF38    GND VSS1373 @S9S_MB_2U_LIB.S9S_MB_2U(SCH_1):GND
EF36    GND VSS1370 @S9S_MB_2U_LIB.S9S_MB_2U(SCH_1):GND
EF34    GND VSS1367 @S9S_MB_2U_LIB.S9S_MB_2U(SCH_1):GND
EF32    GND VSS1365 @S9S_MB_2U_LIB.S9S_MB_2U(SCH_1):GND
EF30    GND VSS1364 @S9S_MB_2U_LIB.S9S_MB_2U(SCH_1):GND
EF28    GND VSS1363 @S9S_MB_2U_LIB.S9S_MB_2U(SCH_1):GND
EF26    GND VSS1362 @S9S_MB_2U_LIB.S9S_MB_2U(SCH_1):GND
EF24    GND VSS1361 @S9S_MB_2U_LIB.S9S_MB_2U(SCH_1):GND
EF22    GND VSS1360 @S9S_MB_2U_LIB.S9S_MB_2U(SCH_1):GND
EF20    GND VSS1358 @S9S_MB_2U_LIB.S9S_MB_2U(SCH_1):GND
 EF2    GND VSS1356 @S9S_MB_2U_LIB.S9S_MB_2U(SCH_1):GND
EF18    GND VSS1354 @S9S_MB_2U_LIB.S9S_MB_2U(SCH_1):GND
EF16    GND VSS1353 @S9S_MB_2U_LIB.S9S_MB_2U(SCH_1):GND
EF12    GND VSS1352 @S9S_MB_2U_LIB.S9S_MB_2U(SCH_1):GND
EE88    GND VSS1351 @S9S_MB_2U_LIB.S9S_MB_2U(SCH_1):GND
EE80    GND VSS1350 @S9S_MB_2U_LIB.S9S_MB_2U(SCH_1):GND
EE78    GND VSS1349 @S9S_MB_2U_LIB.S9S_MB_2U(SCH_1):GND
 ED8    GND VSS1348 @S9S_MB_2U_LIB.S9S_MB_2U(SCH_1):GND
ED49    GND VSS1346 @S9S_MB_2U_LIB.S9S_MB_2U(SCH_1):GND
 ED4    GND VSS1344 @S9S_MB_2U_LIB.S9S_MB_2U(SCH_1):GND
ED36    GND VSS1342 @S9S_MB_2U_LIB.S9S_MB_2U(SCH_1):GND
ED30    GND VSS1341 @S9S_MB_2U_LIB.S9S_MB_2U(SCH_1):GND
ED24    GND VSS1339 @S9S_MB_2U_LIB.S9S_MB_2U(SCH_1):GND
ED16    GND VSS1338 @S9S_MB_2U_LIB.S9S_MB_2U(SCH_1):GND
 EC9    GND VSS1337 @S9S_MB_2U_LIB.S9S_MB_2U(SCH_1):GND
EC88    GND VSS1336 @S9S_MB_2U_LIB.S9S_MB_2U(SCH_1):GND
EC84    GND VSS1335 @S9S_MB_2U_LIB.S9S_MB_2U(SCH_1):GND
EC82    GND VSS1333 @S9S_MB_2U_LIB.S9S_MB_2U(SCH_1):GND
EC74    GND VSS1332 @S9S_MB_2U_LIB.S9S_MB_2U(SCH_1):GND
EC72    GND VSS1330 @S9S_MB_2U_LIB.S9S_MB_2U(SCH_1):GND
EC66    GND VSS1329 @S9S_MB_2U_LIB.S9S_MB_2U(SCH_1):GND
EC56    GND VSS1327 @S9S_MB_2U_LIB.S9S_MB_2U(SCH_1):GND
EC50    GND VSS1326 @S9S_MB_2U_LIB.S9S_MB_2U(SCH_1):GND
EC48    GND VSS1324 @S9S_MB_2U_LIB.S9S_MB_2U(SCH_1):GND
EC43    GND VSS1323 @S9S_MB_2U_LIB.S9S_MB_2U(SCH_1):GND
EC41    GND VSS1321 @S9S_MB_2U_LIB.S9S_MB_2U(SCH_1):GND
 EH6    GND VSS1318 @S9S_MB_2U_LIB.S9S_MB_2U(SCH_1):GND
EC37    GND VSS1317 @S9S_MB_2U_LIB.S9S_MB_2U(SCH_1):GND
EC31    GND VSS1316 @S9S_MB_2U_LIB.S9S_MB_2U(SCH_1):GND
EC29    GND VSS1314 @S9S_MB_2U_LIB.S9S_MB_2U(SCH_1):GND
EC23    GND VSS1313 @S9S_MB_2U_LIB.S9S_MB_2U(SCH_1):GND
EC19    GND VSS1311 @S9S_MB_2U_LIB.S9S_MB_2U(SCH_1):GND
EC13    GND VSS1310 @S9S_MB_2U_LIB.S9S_MB_2U(SCH_1):GND
 EC1    GND VSS1309 @S9S_MB_2U_LIB.S9S_MB_2U(SCH_1):GND
EB87    GND VSS1308 @S9S_MB_2U_LIB.S9S_MB_2U(SCH_1):GND
EB83    GND VSS1307 @S9S_MB_2U_LIB.S9S_MB_2U(SCH_1):GND
 EB8    GND VSS1306 @S9S_MB_2U_LIB.S9S_MB_2U(SCH_1):GND
EH18    GND VSS1305 @S9S_MB_2U_LIB.S9S_MB_2U(SCH_1):GND
EB79    GND VSS1304 @S9S_MB_2U_LIB.S9S_MB_2U(SCH_1):GND
EH14    GND VSS1303 @S9S_MB_2U_LIB.S9S_MB_2U(SCH_1):GND
EH12    GND VSS1302 @S9S_MB_2U_LIB.S9S_MB_2U(SCH_1):GND
EB75    GND VSS1301 @S9S_MB_2U_LIB.S9S_MB_2U(SCH_1):GND
EB71    GND VSS1300 @S9S_MB_2U_LIB.S9S_MB_2U(SCH_1):GND
EB69    GND VSS1299 @S9S_MB_2U_LIB.S9S_MB_2U(SCH_1):GND
EB65    GND VSS1298 @S9S_MB_2U_LIB.S9S_MB_2U(SCH_1):GND
EB57    GND VSS1297 @S9S_MB_2U_LIB.S9S_MB_2U(SCH_1):GND
EB47    GND VSS1296 @S9S_MB_2U_LIB.S9S_MB_2U(SCH_1):GND
EB40    GND VSS1295 @S9S_MB_2U_LIB.S9S_MB_2U(SCH_1):GND
 EG7    GND VSS1294 @S9S_MB_2U_LIB.S9S_MB_2U(SCH_1):GND
EB38    GND VSS1293 @S9S_MB_2U_LIB.S9S_MB_2U(SCH_1):GND
EB32    GND VSS1292 @S9S_MB_2U_LIB.S9S_MB_2U(SCH_1):GND
EG52    GND VSS1291 @S9S_MB_2U_LIB.S9S_MB_2U(SCH_1):GND
 EG5    GND VSS1290 @S9S_MB_2U_LIB.S9S_MB_2U(SCH_1):GND
EB28    GND VSS1289 @S9S_MB_2U_LIB.S9S_MB_2U(SCH_1):GND
EB22    GND VSS1288 @S9S_MB_2U_LIB.S9S_MB_2U(SCH_1):GND
EB12    GND VSS1287 @S9S_MB_2U_LIB.S9S_MB_2U(SCH_1):GND
EA88    GND VSS1286 @S9S_MB_2U_LIB.S9S_MB_2U(SCH_1):GND
EA84    GND VSS1285 @S9S_MB_2U_LIB.S9S_MB_2U(SCH_1):GND
EG13    GND VSS1284 @S9S_MB_2U_LIB.S9S_MB_2U(SCH_1):GND
EF89    GND VSS1283 @S9S_MB_2U_LIB.S9S_MB_2U(SCH_1):GND
EA80    GND VSS1282 @S9S_MB_2U_LIB.S9S_MB_2U(SCH_1):GND
EA78    GND VSS1281 @S9S_MB_2U_LIB.S9S_MB_2U(SCH_1):GND
EA76    GND VSS1280 @S9S_MB_2U_LIB.S9S_MB_2U(SCH_1):GND
EA70    GND VSS1279 @S9S_MB_2U_LIB.S9S_MB_2U(SCH_1):GND
EA33    GND VSS1278 @S9S_MB_2U_LIB.S9S_MB_2U(SCH_1):GND
EF75    GND VSS1277 @S9S_MB_2U_LIB.S9S_MB_2U(SCH_1):GND
EF73    GND VSS1276 @S9S_MB_2U_LIB.S9S_MB_2U(SCH_1):GND
EA27    GND VSS1275 @S9S_MB_2U_LIB.S9S_MB_2U(SCH_1):GND
EA21    GND VSS1274 @S9S_MB_2U_LIB.S9S_MB_2U(SCH_1):GND
 DY8    GND VSS1270 @S9S_MB_2U_LIB.S9S_MB_2U(SCH_1):GND
DY77    GND VSS1269 @S9S_MB_2U_LIB.S9S_MB_2U(SCH_1):GND
DW88    GND VSS1267 @S9S_MB_2U_LIB.S9S_MB_2U(SCH_1):GND
DW84    GND VSS1266 @S9S_MB_2U_LIB.S9S_MB_2U(SCH_1):GND
EF51    GND VSS1265 @S9S_MB_2U_LIB.S9S_MB_2U(SCH_1):GND
DW82    GND VSS1264 @S9S_MB_2U_LIB.S9S_MB_2U(SCH_1):GND
DW80    GND VSS1263 @S9S_MB_2U_LIB.S9S_MB_2U(SCH_1):GND
DW76    GND VSS1262 @S9S_MB_2U_LIB.S9S_MB_2U(SCH_1):GND
DW74    GND VSS1261 @S9S_MB_2U_LIB.S9S_MB_2U(SCH_1):GND
DW72    GND VSS1260 @S9S_MB_2U_LIB.S9S_MB_2U(SCH_1):GND
DW70    GND VSS1259 @S9S_MB_2U_LIB.S9S_MB_2U(SCH_1):GND
DW68    GND VSS1258 @S9S_MB_2U_LIB.S9S_MB_2U(SCH_1):GND
DW66    GND VSS1257 @S9S_MB_2U_LIB.S9S_MB_2U(SCH_1):GND
EE52    GND VSS1237 @S9S_MB_2U_LIB.S9S_MB_2U(SCH_1):GND
EE39    GND VSS1235 @S9S_MB_2U_LIB.S9S_MB_2U(SCH_1):GND
EE17    GND VSS1232 @S9S_MB_2U_LIB.S9S_MB_2U(SCH_1):GND
ED73    GND VSS1225 @S9S_MB_2U_LIB.S9S_MB_2U(SCH_1):GND
ED67    GND VSS1224 @S9S_MB_2U_LIB.S9S_MB_2U(SCH_1):GND
ED61    GND VSS1223 @S9S_MB_2U_LIB.S9S_MB_2U(SCH_1):GND
ED55    GND VSS1220 @S9S_MB_2U_LIB.S9S_MB_2U(SCH_1):GND
ED42    GND VSS1217 @S9S_MB_2U_LIB.S9S_MB_2U(SCH_1):GND
ED18    GND VSS1210 @S9S_MB_2U_LIB.S9S_MB_2U(SCH_1):GND
ED12    GND VSS1208 @S9S_MB_2U_LIB.S9S_MB_2U(SCH_1):GND
EC68    GND VSS1200 @S9S_MB_2U_LIB.S9S_MB_2U(SCH_1):GND
EC62    GND VSS1198 @S9S_MB_2U_LIB.S9S_MB_2U(SCH_1):GND
EC60    GND VSS1197 @S9S_MB_2U_LIB.S9S_MB_2U(SCH_1):GND
EC54    GND VSS1195 @S9S_MB_2U_LIB.S9S_MB_2U(SCH_1):GND
 EC5    GND VSS1193 @S9S_MB_2U_LIB.S9S_MB_2U(SCH_1):GND
EC35    GND VSS1188 @S9S_MB_2U_LIB.S9S_MB_2U(SCH_1):GND
EC25    GND VSS1185 @S9S_MB_2U_LIB.S9S_MB_2U(SCH_1):GND
EB91    GND VSS1180 @S9S_MB_2U_LIB.S9S_MB_2U(SCH_1):GND
EB63    GND VSS1171 @S9S_MB_2U_LIB.S9S_MB_2U(SCH_1):GND
EB59    GND VSS1170 @S9S_MB_2U_LIB.S9S_MB_2U(SCH_1):GND
EB53    GND VSS1168 @S9S_MB_2U_LIB.S9S_MB_2U(SCH_1):GND
EB51    GND VSS1167 @S9S_MB_2U_LIB.S9S_MB_2U(SCH_1):GND
EB44    GND VSS1165 @S9S_MB_2U_LIB.S9S_MB_2U(SCH_1):GND
 EB4    GND VSS1163 @S9S_MB_2U_LIB.S9S_MB_2U(SCH_1):GND
EB34    GND VSS1161 @S9S_MB_2U_LIB.S9S_MB_2U(SCH_1):GND
EB26    GND VSS1158 @S9S_MB_2U_LIB.S9S_MB_2U(SCH_1):GND
EB20    GND VSS1156 @S9S_MB_2U_LIB.S9S_MB_2U(SCH_1):GND
EB16    GND VSS1155 @S9S_MB_2U_LIB.S9S_MB_2U(SCH_1):GND
EA64    GND VSS1146 @S9S_MB_2U_LIB.S9S_MB_2U(SCH_1):GND
EA58    GND VSS1145 @S9S_MB_2U_LIB.S9S_MB_2U(SCH_1):GND
EA52    GND VSS1144 @S9S_MB_2U_LIB.S9S_MB_2U(SCH_1):GND
EA45    GND VSS1142 @S9S_MB_2U_LIB.S9S_MB_2U(SCH_1):GND
EA39    GND VSS1141 @S9S_MB_2U_LIB.S9S_MB_2U(SCH_1):GND
DY42    GND VSS1116 @S9S_MB_2U_LIB.S9S_MB_2U(SCH_1):GND
 DY4    GND VSS1115 @S9S_MB_2U_LIB.S9S_MB_2U(SCH_1):GND
DY16    GND VSS1112 @S9S_MB_2U_LIB.S9S_MB_2U(SCH_1):GND
DY12    GND VSS1111 @S9S_MB_2U_LIB.S9S_MB_2U(SCH_1):GND

SOCKET4677_AZIF0045P001C01CS-SA  I8  U1
 DW9    GND VSS1268 @S9S_MB_2U_LIB.S9S_MB_2U(SCH_1):GND
DW64    GND VSS1256 @S9S_MB_2U_LIB.S9S_MB_2U(SCH_1):GND
DW62    GND VSS1255 @S9S_MB_2U_LIB.S9S_MB_2U(SCH_1):GND
DW58    GND VSS1254 @S9S_MB_2U_LIB.S9S_MB_2U(SCH_1):GND
DW56    GND VSS1253 @S9S_MB_2U_LIB.S9S_MB_2U(SCH_1):GND
DW54    GND VSS1252 @S9S_MB_2U_LIB.S9S_MB_2U(SCH_1):GND
DW52    GND VSS1251 @S9S_MB_2U_LIB.S9S_MB_2U(SCH_1):GND
DW50    GND VSS1250 @S9S_MB_2U_LIB.S9S_MB_2U(SCH_1):GND
 DW5    GND VSS1249 @S9S_MB_2U_LIB.S9S_MB_2U(SCH_1):GND
DW48    GND VSS1248 @S9S_MB_2U_LIB.S9S_MB_2U(SCH_1):GND
DW45    GND VSS1247 @S9S_MB_2U_LIB.S9S_MB_2U(SCH_1):GND
DW43    GND VSS1246 @S9S_MB_2U_LIB.S9S_MB_2U(SCH_1):GND
DW41    GND VSS1245 @S9S_MB_2U_LIB.S9S_MB_2U(SCH_1):GND
DW39    GND VSS1244 @S9S_MB_2U_LIB.S9S_MB_2U(SCH_1):GND
DW37    GND VSS1243 @S9S_MB_2U_LIB.S9S_MB_2U(SCH_1):GND
DW35    GND VSS1242 @S9S_MB_2U_LIB.S9S_MB_2U(SCH_1):GND
DW33    GND VSS1241 @S9S_MB_2U_LIB.S9S_MB_2U(SCH_1):GND
DW31    GND VSS1240 @S9S_MB_2U_LIB.S9S_MB_2U(SCH_1):GND
DW29    GND VSS1239 @S9S_MB_2U_LIB.S9S_MB_2U(SCH_1):GND
DW27    GND VSS1238 @S9S_MB_2U_LIB.S9S_MB_2U(SCH_1):GND
DW25    GND VSS1236 @S9S_MB_2U_LIB.S9S_MB_2U(SCH_1):GND
DW23    GND VSS1234 @S9S_MB_2U_LIB.S9S_MB_2U(SCH_1):GND
DW19    GND VSS1233 @S9S_MB_2U_LIB.S9S_MB_2U(SCH_1):GND
DW17    GND VSS1231 @S9S_MB_2U_LIB.S9S_MB_2U(SCH_1):GND
DW13    GND VSS1230 @S9S_MB_2U_LIB.S9S_MB_2U(SCH_1):GND
 DW1    GND VSS1229 @S9S_MB_2U_LIB.S9S_MB_2U(SCH_1):GND
DV91    GND VSS1228 @S9S_MB_2U_LIB.S9S_MB_2U(SCH_1):GND
DV87    GND VSS1227 @S9S_MB_2U_LIB.S9S_MB_2U(SCH_1):GND
DV83    GND VSS1226 @S9S_MB_2U_LIB.S9S_MB_2U(SCH_1):GND
DV81    GND VSS1222 @S9S_MB_2U_LIB.S9S_MB_2U(SCH_1):GND
 DV8    GND VSS1221 @S9S_MB_2U_LIB.S9S_MB_2U(SCH_1):GND
DV79    GND VSS1219 @S9S_MB_2U_LIB.S9S_MB_2U(SCH_1):GND
DV77    GND VSS1218 @S9S_MB_2U_LIB.S9S_MB_2U(SCH_1):GND
DU88    GND VSS1216 @S9S_MB_2U_LIB.S9S_MB_2U(SCH_1):GND
DU84    GND VSS1215 @S9S_MB_2U_LIB.S9S_MB_2U(SCH_1):GND
DU78    GND VSS1214 @S9S_MB_2U_LIB.S9S_MB_2U(SCH_1):GND
DU76    GND VSS1213 @S9S_MB_2U_LIB.S9S_MB_2U(SCH_1):GND
DU33    GND VSS1212 @S9S_MB_2U_LIB.S9S_MB_2U(SCH_1):GND
DU27    GND VSS1211 @S9S_MB_2U_LIB.S9S_MB_2U(SCH_1):GND
DU21    GND VSS1209 @S9S_MB_2U_LIB.S9S_MB_2U(SCH_1):GND
 DT8    GND VSS1207 @S9S_MB_2U_LIB.S9S_MB_2U(SCH_1):GND
DT75    GND VSS1206 @S9S_MB_2U_LIB.S9S_MB_2U(SCH_1):GND
DT71    GND VSS1205 @S9S_MB_2U_LIB.S9S_MB_2U(SCH_1):GND
DT69    GND VSS1204 @S9S_MB_2U_LIB.S9S_MB_2U(SCH_1):GND
DT65    GND VSS1203 @S9S_MB_2U_LIB.S9S_MB_2U(SCH_1):GND
DT57    GND VSS1202 @S9S_MB_2U_LIB.S9S_MB_2U(SCH_1):GND
DT47    GND VSS1201 @S9S_MB_2U_LIB.S9S_MB_2U(SCH_1):GND
DT40    GND VSS1199 @S9S_MB_2U_LIB.S9S_MB_2U(SCH_1):GND
DT38    GND VSS1196 @S9S_MB_2U_LIB.S9S_MB_2U(SCH_1):GND
DT34    GND VSS1194 @S9S_MB_2U_LIB.S9S_MB_2U(SCH_1):GND
DT32    GND VSS1192 @S9S_MB_2U_LIB.S9S_MB_2U(SCH_1):GND
DT28    GND VSS1191 @S9S_MB_2U_LIB.S9S_MB_2U(SCH_1):GND
DT22    GND VSS1190 @S9S_MB_2U_LIB.S9S_MB_2U(SCH_1):GND
DT12    GND VSS1189 @S9S_MB_2U_LIB.S9S_MB_2U(SCH_1):GND
 DR9    GND VSS1187 @S9S_MB_2U_LIB.S9S_MB_2U(SCH_1):GND
DR88    GND VSS1186 @S9S_MB_2U_LIB.S9S_MB_2U(SCH_1):GND
DR84    GND VSS1184 @S9S_MB_2U_LIB.S9S_MB_2U(SCH_1):GND
DR78    GND VSS1183 @S9S_MB_2U_LIB.S9S_MB_2U(SCH_1):GND
DR74    GND VSS1182 @S9S_MB_2U_LIB.S9S_MB_2U(SCH_1):GND
DR66    GND VSS1181 @S9S_MB_2U_LIB.S9S_MB_2U(SCH_1):GND
DR56    GND VSS1179 @S9S_MB_2U_LIB.S9S_MB_2U(SCH_1):GND
DR50    GND VSS1178 @S9S_MB_2U_LIB.S9S_MB_2U(SCH_1):GND
DR48    GND VSS1177 @S9S_MB_2U_LIB.S9S_MB_2U(SCH_1):GND
DR43    GND VSS1176 @S9S_MB_2U_LIB.S9S_MB_2U(SCH_1):GND
DR41    GND VSS1175 @S9S_MB_2U_LIB.S9S_MB_2U(SCH_1):GND
DR37    GND VSS1174 @S9S_MB_2U_LIB.S9S_MB_2U(SCH_1):GND
DR31    GND VSS1173 @S9S_MB_2U_LIB.S9S_MB_2U(SCH_1):GND
DR29    GND VSS1172 @S9S_MB_2U_LIB.S9S_MB_2U(SCH_1):GND
DR23    GND VSS1169 @S9S_MB_2U_LIB.S9S_MB_2U(SCH_1):GND
DR19    GND VSS1166 @S9S_MB_2U_LIB.S9S_MB_2U(SCH_1):GND
DR13    GND VSS1164 @S9S_MB_2U_LIB.S9S_MB_2U(SCH_1):GND
 DR1    GND VSS1162 @S9S_MB_2U_LIB.S9S_MB_2U(SCH_1):GND
DP87    GND VSS1160 @S9S_MB_2U_LIB.S9S_MB_2U(SCH_1):GND
DP81    GND VSS1159 @S9S_MB_2U_LIB.S9S_MB_2U(SCH_1):GND
 DP8    GND VSS1157 @S9S_MB_2U_LIB.S9S_MB_2U(SCH_1):GND
DP73    GND VSS1154 @S9S_MB_2U_LIB.S9S_MB_2U(SCH_1):GND
DP49    GND VSS1153 @S9S_MB_2U_LIB.S9S_MB_2U(SCH_1):GND
 DP4    GND VSS1152 @S9S_MB_2U_LIB.S9S_MB_2U(SCH_1):GND
DP36    GND VSS1151 @S9S_MB_2U_LIB.S9S_MB_2U(SCH_1):GND
DP30    GND VSS1150 @S9S_MB_2U_LIB.S9S_MB_2U(SCH_1):GND
DP16    GND VSS1149 @S9S_MB_2U_LIB.S9S_MB_2U(SCH_1):GND
DN88    GND VSS1148 @S9S_MB_2U_LIB.S9S_MB_2U(SCH_1):GND
DN84    GND VSS1147 @S9S_MB_2U_LIB.S9S_MB_2U(SCH_1):GND
DN78    GND VSS1143 @S9S_MB_2U_LIB.S9S_MB_2U(SCH_1):GND
 DM8    GND VSS1140 @S9S_MB_2U_LIB.S9S_MB_2U(SCH_1):GND
DM79    GND VSS1139 @S9S_MB_2U_LIB.S9S_MB_2U(SCH_1):GND
DM77    GND VSS1138 @S9S_MB_2U_LIB.S9S_MB_2U(SCH_1):GND
DM75    GND VSS1137 @S9S_MB_2U_LIB.S9S_MB_2U(SCH_1):GND
DM71    GND VSS1136 @S9S_MB_2U_LIB.S9S_MB_2U(SCH_1):GND
DM69    GND VSS1135 @S9S_MB_2U_LIB.S9S_MB_2U(SCH_1):GND
DM67    GND VSS1134 @S9S_MB_2U_LIB.S9S_MB_2U(SCH_1):GND
DM65    GND VSS1133 @S9S_MB_2U_LIB.S9S_MB_2U(SCH_1):GND
DM63    GND VSS1132 @S9S_MB_2U_LIB.S9S_MB_2U(SCH_1):GND
DM61    GND VSS1130 @S9S_MB_2U_LIB.S9S_MB_2U(SCH_1):GND
DM59    GND VSS1128 @S9S_MB_2U_LIB.S9S_MB_2U(SCH_1):GND
DM57    GND VSS1127 @S9S_MB_2U_LIB.S9S_MB_2U(SCH_1):GND
DM55    GND VSS1124 @S9S_MB_2U_LIB.S9S_MB_2U(SCH_1):GND
DM53    GND VSS1123 @S9S_MB_2U_LIB.S9S_MB_2U(SCH_1):GND
DM49    GND VSS1122 @S9S_MB_2U_LIB.S9S_MB_2U(SCH_1):GND
DM47    GND VSS1121 @S9S_MB_2U_LIB.S9S_MB_2U(SCH_1):GND
DM44    GND VSS1120 @S9S_MB_2U_LIB.S9S_MB_2U(SCH_1):GND
DM42    GND VSS1119 @S9S_MB_2U_LIB.S9S_MB_2U(SCH_1):GND
DM40    GND VSS1118 @S9S_MB_2U_LIB.S9S_MB_2U(SCH_1):GND
 DM4    GND VSS1117 @S9S_MB_2U_LIB.S9S_MB_2U(SCH_1):GND
DM38    GND VSS1114 @S9S_MB_2U_LIB.S9S_MB_2U(SCH_1):GND
DM36    GND VSS1113 @S9S_MB_2U_LIB.S9S_MB_2U(SCH_1):GND
DM34    GND VSS1110 @S9S_MB_2U_LIB.S9S_MB_2U(SCH_1):GND
DM32    GND VSS1109 @S9S_MB_2U_LIB.S9S_MB_2U(SCH_1):GND
DM30    GND VSS1108 @S9S_MB_2U_LIB.S9S_MB_2U(SCH_1):GND
DM28    GND VSS1107 @S9S_MB_2U_LIB.S9S_MB_2U(SCH_1):GND
DM26    GND VSS1106 @S9S_MB_2U_LIB.S9S_MB_2U(SCH_1):GND
DM24    GND VSS1105 @S9S_MB_2U_LIB.S9S_MB_2U(SCH_1):GND
DM22    GND VSS1104 @S9S_MB_2U_LIB.S9S_MB_2U(SCH_1):GND
DM20    GND VSS1103 @S9S_MB_2U_LIB.S9S_MB_2U(SCH_1):GND
DM18    GND VSS1102 @S9S_MB_2U_LIB.S9S_MB_2U(SCH_1):GND
DM16    GND VSS1101 @S9S_MB_2U_LIB.S9S_MB_2U(SCH_1):GND
DM12    GND VSS1100 @S9S_MB_2U_LIB.S9S_MB_2U(SCH_1):GND
DW60    GND VSS1097 @S9S_MB_2U_LIB.S9S_MB_2U(SCH_1):GND
DW21    GND VSS1077 @S9S_MB_2U_LIB.S9S_MB_2U(SCH_1):GND
DV42    GND VSS1064 @S9S_MB_2U_LIB.S9S_MB_2U(SCH_1):GND
 DV4    GND VSS1063 @S9S_MB_2U_LIB.S9S_MB_2U(SCH_1):GND
DV16    GND VSS1060 @S9S_MB_2U_LIB.S9S_MB_2U(SCH_1):GND
DV12    GND VSS1059 @S9S_MB_2U_LIB.S9S_MB_2U(SCH_1):GND
DU70    GND VSS1054 @S9S_MB_2U_LIB.S9S_MB_2U(SCH_1):GND
DU64    GND VSS1052 @S9S_MB_2U_LIB.S9S_MB_2U(SCH_1):GND
DU58    GND VSS1051 @S9S_MB_2U_LIB.S9S_MB_2U(SCH_1):GND
DU52    GND VSS1050 @S9S_MB_2U_LIB.S9S_MB_2U(SCH_1):GND
DU45    GND VSS1048 @S9S_MB_2U_LIB.S9S_MB_2U(SCH_1):GND
DU39    GND VSS1047 @S9S_MB_2U_LIB.S9S_MB_2U(SCH_1):GND
DT83    GND VSS1036 @S9S_MB_2U_LIB.S9S_MB_2U(SCH_1):GND
DT63    GND VSS1029 @S9S_MB_2U_LIB.S9S_MB_2U(SCH_1):GND
DT59    GND VSS1028 @S9S_MB_2U_LIB.S9S_MB_2U(SCH_1):GND
DT53    GND VSS1026 @S9S_MB_2U_LIB.S9S_MB_2U(SCH_1):GND
DT51    GND VSS1025 @S9S_MB_2U_LIB.S9S_MB_2U(SCH_1):GND
DT44    GND VSS1023 @S9S_MB_2U_LIB.S9S_MB_2U(SCH_1):GND
 DT4    GND VSS1021 @S9S_MB_2U_LIB.S9S_MB_2U(SCH_1):GND
DT26    GND VSS1016 @S9S_MB_2U_LIB.S9S_MB_2U(SCH_1):GND
DT20    GND VSS1014 @S9S_MB_2U_LIB.S9S_MB_2U(SCH_1):GND
DT16    GND VSS1013 @S9S_MB_2U_LIB.S9S_MB_2U(SCH_1):GND
DR72    GND VSS1006 @S9S_MB_2U_LIB.S9S_MB_2U(SCH_1):GND
DR68    GND VSS1005 @S9S_MB_2U_LIB.S9S_MB_2U(SCH_1):GND
DR62    GND VSS1003 @S9S_MB_2U_LIB.S9S_MB_2U(SCH_1):GND
DR60    GND VSS1002 @S9S_MB_2U_LIB.S9S_MB_2U(SCH_1):GND
DR54    GND VSS1000 @S9S_MB_2U_LIB.S9S_MB_2U(SCH_1):GND
 DR5    GND VSS998 @S9S_MB_2U_LIB.S9S_MB_2U(SCH_1):GND
DR35    GND VSS993 @S9S_MB_2U_LIB.S9S_MB_2U(SCH_1):GND
DR25    GND VSS990 @S9S_MB_2U_LIB.S9S_MB_2U(SCH_1):GND
DP91    GND VSS985 @S9S_MB_2U_LIB.S9S_MB_2U(SCH_1):GND
DP67    GND VSS980 @S9S_MB_2U_LIB.S9S_MB_2U(SCH_1):GND
DP61    GND VSS979 @S9S_MB_2U_LIB.S9S_MB_2U(SCH_1):GND
DP55    GND VSS976 @S9S_MB_2U_LIB.S9S_MB_2U(SCH_1):GND
DP42    GND VSS973 @S9S_MB_2U_LIB.S9S_MB_2U(SCH_1):GND
DP24    GND VSS969 @S9S_MB_2U_LIB.S9S_MB_2U(SCH_1):GND
DP18    GND VSS968 @S9S_MB_2U_LIB.S9S_MB_2U(SCH_1):GND
DP12    GND VSS966 @S9S_MB_2U_LIB.S9S_MB_2U(SCH_1):GND
DN52    GND VSS959 @S9S_MB_2U_LIB.S9S_MB_2U(SCH_1):GND
DN39    GND VSS957 @S9S_MB_2U_LIB.S9S_MB_2U(SCH_1):GND
DN17    GND VSS955 @S9S_MB_2U_LIB.S9S_MB_2U(SCH_1):GND
DM73    GND VSS945 @S9S_MB_2U_LIB.S9S_MB_2U(SCH_1):GND
DM51    GND VSS934 @S9S_MB_2U_LIB.S9S_MB_2U(SCH_1):GND


DRAWING: @S9S_MB_2U_LIB.S9S_MB_2U(SCH_1):PAGE71 

SOCKET4677_AZIF0045P001C01CS-SA  I2  U1
 DL9    GND VSS1099 @S9S_MB_2U_LIB.S9S_MB_2U(SCH_1):GND
DL88    GND VSS1098 @S9S_MB_2U_LIB.S9S_MB_2U(SCH_1):GND
DL84    GND VSS1096 @S9S_MB_2U_LIB.S9S_MB_2U(SCH_1):GND
DL39    GND VSS1095 @S9S_MB_2U_LIB.S9S_MB_2U(SCH_1):GND
DK91    GND VSS1094 @S9S_MB_2U_LIB.S9S_MB_2U(SCH_1):GND
DK87    GND VSS1093 @S9S_MB_2U_LIB.S9S_MB_2U(SCH_1):GND
DK83    GND VSS1092 @S9S_MB_2U_LIB.S9S_MB_2U(SCH_1):GND
DK81    GND VSS1091 @S9S_MB_2U_LIB.S9S_MB_2U(SCH_1):GND
 DK8    GND VSS1090 @S9S_MB_2U_LIB.S9S_MB_2U(SCH_1):GND
DK79    GND VSS1089 @S9S_MB_2U_LIB.S9S_MB_2U(SCH_1):GND
DK77    GND VSS1088 @S9S_MB_2U_LIB.S9S_MB_2U(SCH_1):GND
DK73    GND VSS1087 @S9S_MB_2U_LIB.S9S_MB_2U(SCH_1):GND
DK49    GND VSS1086 @S9S_MB_2U_LIB.S9S_MB_2U(SCH_1):GND
 DK4    GND VSS1085 @S9S_MB_2U_LIB.S9S_MB_2U(SCH_1):GND
DK36    GND VSS1084 @S9S_MB_2U_LIB.S9S_MB_2U(SCH_1):GND
DK30    GND VSS1083 @S9S_MB_2U_LIB.S9S_MB_2U(SCH_1):GND
DK16    GND VSS1082 @S9S_MB_2U_LIB.S9S_MB_2U(SCH_1):GND
DJ88    GND VSS1081 @S9S_MB_2U_LIB.S9S_MB_2U(SCH_1):GND
DJ84    GND VSS1080 @S9S_MB_2U_LIB.S9S_MB_2U(SCH_1):GND
DJ82    GND VSS1079 @S9S_MB_2U_LIB.S9S_MB_2U(SCH_1):GND
DJ80    GND VSS1078 @S9S_MB_2U_LIB.S9S_MB_2U(SCH_1):GND
DJ74    GND VSS1076 @S9S_MB_2U_LIB.S9S_MB_2U(SCH_1):GND
DJ72    GND VSS1075 @S9S_MB_2U_LIB.S9S_MB_2U(SCH_1):GND
DJ66    GND VSS1074 @S9S_MB_2U_LIB.S9S_MB_2U(SCH_1):GND
DJ60    GND VSS1073 @S9S_MB_2U_LIB.S9S_MB_2U(SCH_1):GND
DJ56    GND VSS1072 @S9S_MB_2U_LIB.S9S_MB_2U(SCH_1):GND
DJ50    GND VSS1071 @S9S_MB_2U_LIB.S9S_MB_2U(SCH_1):GND
DJ48    GND VSS1070 @S9S_MB_2U_LIB.S9S_MB_2U(SCH_1):GND
DJ43    GND VSS1069 @S9S_MB_2U_LIB.S9S_MB_2U(SCH_1):GND
DJ41    GND VSS1068 @S9S_MB_2U_LIB.S9S_MB_2U(SCH_1):GND
DJ37    GND VSS1067 @S9S_MB_2U_LIB.S9S_MB_2U(SCH_1):GND
DJ31    GND VSS1066 @S9S_MB_2U_LIB.S9S_MB_2U(SCH_1):GND
DJ29    GND VSS1065 @S9S_MB_2U_LIB.S9S_MB_2U(SCH_1):GND
DJ23    GND VSS1062 @S9S_MB_2U_LIB.S9S_MB_2U(SCH_1):GND
DJ19    GND VSS1061 @S9S_MB_2U_LIB.S9S_MB_2U(SCH_1):GND
DH85    GND VSS1058 @S9S_MB_2U_LIB.S9S_MB_2U(SCH_1):GND
 DH8    GND VSS1057 @S9S_MB_2U_LIB.S9S_MB_2U(SCH_1):GND
DH77    GND VSS1056 @S9S_MB_2U_LIB.S9S_MB_2U(SCH_1):GND
DH71    GND VSS1055 @S9S_MB_2U_LIB.S9S_MB_2U(SCH_1):GND
DH65    GND VSS1053 @S9S_MB_2U_LIB.S9S_MB_2U(SCH_1):GND
DH57    GND VSS1049 @S9S_MB_2U_LIB.S9S_MB_2U(SCH_1):GND
DH47    GND VSS1046 @S9S_MB_2U_LIB.S9S_MB_2U(SCH_1):GND
DH40    GND VSS1045 @S9S_MB_2U_LIB.S9S_MB_2U(SCH_1):GND
 DH4    GND VSS1044 @S9S_MB_2U_LIB.S9S_MB_2U(SCH_1):GND
DH38    GND VSS1043 @S9S_MB_2U_LIB.S9S_MB_2U(SCH_1):GND
DH32    GND VSS1042 @S9S_MB_2U_LIB.S9S_MB_2U(SCH_1):GND
DH28    GND VSS1041 @S9S_MB_2U_LIB.S9S_MB_2U(SCH_1):GND
DH22    GND VSS1040 @S9S_MB_2U_LIB.S9S_MB_2U(SCH_1):GND
DH12    GND VSS1039 @S9S_MB_2U_LIB.S9S_MB_2U(SCH_1):GND
 DG9    GND VSS1038 @S9S_MB_2U_LIB.S9S_MB_2U(SCH_1):GND
DG88    GND VSS1037 @S9S_MB_2U_LIB.S9S_MB_2U(SCH_1):GND
DG84    GND VSS1035 @S9S_MB_2U_LIB.S9S_MB_2U(SCH_1):GND
DG80    GND VSS1034 @S9S_MB_2U_LIB.S9S_MB_2U(SCH_1):GND
DG76    GND VSS1033 @S9S_MB_2U_LIB.S9S_MB_2U(SCH_1):GND
DG70    GND VSS1032 @S9S_MB_2U_LIB.S9S_MB_2U(SCH_1):GND
 DG5    GND VSS1031 @S9S_MB_2U_LIB.S9S_MB_2U(SCH_1):GND
DG45    GND VSS1030 @S9S_MB_2U_LIB.S9S_MB_2U(SCH_1):GND
DG39    GND VSS1027 @S9S_MB_2U_LIB.S9S_MB_2U(SCH_1):GND
DG33    GND VSS1024 @S9S_MB_2U_LIB.S9S_MB_2U(SCH_1):GND
DG27    GND VSS1022 @S9S_MB_2U_LIB.S9S_MB_2U(SCH_1):GND
DF87    GND VSS1020 @S9S_MB_2U_LIB.S9S_MB_2U(SCH_1):GND
 DF8    GND VSS1019 @S9S_MB_2U_LIB.S9S_MB_2U(SCH_1):GND
DF79    GND VSS1018 @S9S_MB_2U_LIB.S9S_MB_2U(SCH_1):GND
 DF4    GND VSS1017 @S9S_MB_2U_LIB.S9S_MB_2U(SCH_1):GND
DE88    GND VSS1015 @S9S_MB_2U_LIB.S9S_MB_2U(SCH_1):GND
DE84    GND VSS1012 @S9S_MB_2U_LIB.S9S_MB_2U(SCH_1):GND
DE82    GND VSS1011 @S9S_MB_2U_LIB.S9S_MB_2U(SCH_1):GND
DE76    GND VSS1010 @S9S_MB_2U_LIB.S9S_MB_2U(SCH_1):GND
DE74    GND VSS1009 @S9S_MB_2U_LIB.S9S_MB_2U(SCH_1):GND
DE72    GND VSS1008 @S9S_MB_2U_LIB.S9S_MB_2U(SCH_1):GND
DE68    GND VSS1007 @S9S_MB_2U_LIB.S9S_MB_2U(SCH_1):GND
DE66    GND VSS1004 @S9S_MB_2U_LIB.S9S_MB_2U(SCH_1):GND
DE64    GND VSS1001 @S9S_MB_2U_LIB.S9S_MB_2U(SCH_1):GND
DE62    GND VSS999 @S9S_MB_2U_LIB.S9S_MB_2U(SCH_1):GND
DE60    GND VSS997 @S9S_MB_2U_LIB.S9S_MB_2U(SCH_1):GND
DE58    GND VSS996 @S9S_MB_2U_LIB.S9S_MB_2U(SCH_1):GND
DE56    GND VSS995 @S9S_MB_2U_LIB.S9S_MB_2U(SCH_1):GND
DE54    GND VSS994 @S9S_MB_2U_LIB.S9S_MB_2U(SCH_1):GND
DE52    GND VSS992 @S9S_MB_2U_LIB.S9S_MB_2U(SCH_1):GND
DE50    GND VSS991 @S9S_MB_2U_LIB.S9S_MB_2U(SCH_1):GND
DE48    GND VSS989 @S9S_MB_2U_LIB.S9S_MB_2U(SCH_1):GND
DE45    GND VSS988 @S9S_MB_2U_LIB.S9S_MB_2U(SCH_1):GND
DE43    GND VSS987 @S9S_MB_2U_LIB.S9S_MB_2U(SCH_1):GND
DE41    GND VSS986 @S9S_MB_2U_LIB.S9S_MB_2U(SCH_1):GND
DE37    GND VSS984 @S9S_MB_2U_LIB.S9S_MB_2U(SCH_1):GND
DE35    GND VSS983 @S9S_MB_2U_LIB.S9S_MB_2U(SCH_1):GND
DE33    GND VSS982 @S9S_MB_2U_LIB.S9S_MB_2U(SCH_1):GND
DE31    GND VSS981 @S9S_MB_2U_LIB.S9S_MB_2U(SCH_1):GND
DE29    GND VSS978 @S9S_MB_2U_LIB.S9S_MB_2U(SCH_1):GND
DE27    GND VSS977 @S9S_MB_2U_LIB.S9S_MB_2U(SCH_1):GND
DE25    GND VSS975 @S9S_MB_2U_LIB.S9S_MB_2U(SCH_1):GND
DE23    GND VSS974 @S9S_MB_2U_LIB.S9S_MB_2U(SCH_1):GND
DE21    GND VSS972 @S9S_MB_2U_LIB.S9S_MB_2U(SCH_1):GND
DE19    GND VSS971 @S9S_MB_2U_LIB.S9S_MB_2U(SCH_1):GND
DE17    GND VSS970 @S9S_MB_2U_LIB.S9S_MB_2U(SCH_1):GND
 DD8    GND VSS967 @S9S_MB_2U_LIB.S9S_MB_2U(SCH_1):GND
DD79    GND VSS965 @S9S_MB_2U_LIB.S9S_MB_2U(SCH_1):GND
 DD4    GND VSS964 @S9S_MB_2U_LIB.S9S_MB_2U(SCH_1):GND
 DC9    GND VSS963 @S9S_MB_2U_LIB.S9S_MB_2U(SCH_1):GND
DC88    GND VSS962 @S9S_MB_2U_LIB.S9S_MB_2U(SCH_1):GND
DC84    GND VSS961 @S9S_MB_2U_LIB.S9S_MB_2U(SCH_1):GND
DC80    GND VSS960 @S9S_MB_2U_LIB.S9S_MB_2U(SCH_1):GND
DC78    GND VSS958 @S9S_MB_2U_LIB.S9S_MB_2U(SCH_1):GND
DC76    GND VSS956 @S9S_MB_2U_LIB.S9S_MB_2U(SCH_1):GND
DC70    GND VSS954 @S9S_MB_2U_LIB.S9S_MB_2U(SCH_1):GND
 DC5    GND VSS953 @S9S_MB_2U_LIB.S9S_MB_2U(SCH_1):GND
DC45    GND VSS952 @S9S_MB_2U_LIB.S9S_MB_2U(SCH_1):GND
DC39    GND VSS951 @S9S_MB_2U_LIB.S9S_MB_2U(SCH_1):GND
DC33    GND VSS950 @S9S_MB_2U_LIB.S9S_MB_2U(SCH_1):GND
DC27    GND VSS949 @S9S_MB_2U_LIB.S9S_MB_2U(SCH_1):GND
DL52    GND VSS909 @S9S_MB_2U_LIB.S9S_MB_2U(SCH_1):GND
 DL5    GND VSS908 @S9S_MB_2U_LIB.S9S_MB_2U(SCH_1):GND
DL17    GND VSS905 @S9S_MB_2U_LIB.S9S_MB_2U(SCH_1):GND
DL13    GND VSS904 @S9S_MB_2U_LIB.S9S_MB_2U(SCH_1):GND
 DL1    GND VSS903 @S9S_MB_2U_LIB.S9S_MB_2U(SCH_1):GND
DK67    GND VSS894 @S9S_MB_2U_LIB.S9S_MB_2U(SCH_1):GND
DK61    GND VSS893 @S9S_MB_2U_LIB.S9S_MB_2U(SCH_1):GND
DK55    GND VSS890 @S9S_MB_2U_LIB.S9S_MB_2U(SCH_1):GND
DK42    GND VSS887 @S9S_MB_2U_LIB.S9S_MB_2U(SCH_1):GND
DK24    GND VSS883 @S9S_MB_2U_LIB.S9S_MB_2U(SCH_1):GND
DK18    GND VSS882 @S9S_MB_2U_LIB.S9S_MB_2U(SCH_1):GND
DK12    GND VSS880 @S9S_MB_2U_LIB.S9S_MB_2U(SCH_1):GND
DJ68    GND VSS872 @S9S_MB_2U_LIB.S9S_MB_2U(SCH_1):GND
DJ62    GND VSS870 @S9S_MB_2U_LIB.S9S_MB_2U(SCH_1):GND
DJ54    GND VSS867 @S9S_MB_2U_LIB.S9S_MB_2U(SCH_1):GND
DJ35    GND VSS861 @S9S_MB_2U_LIB.S9S_MB_2U(SCH_1):GND
DJ25    GND VSS857 @S9S_MB_2U_LIB.S9S_MB_2U(SCH_1):GND
DH75    GND VSS849 @S9S_MB_2U_LIB.S9S_MB_2U(SCH_1):GND
DH69    GND VSS847 @S9S_MB_2U_LIB.S9S_MB_2U(SCH_1):GND
DH63    GND VSS845 @S9S_MB_2U_LIB.S9S_MB_2U(SCH_1):GND
DH59    GND VSS844 @S9S_MB_2U_LIB.S9S_MB_2U(SCH_1):GND
DH53    GND VSS842 @S9S_MB_2U_LIB.S9S_MB_2U(SCH_1):GND
DH51    GND VSS841 @S9S_MB_2U_LIB.S9S_MB_2U(SCH_1):GND
DH44    GND VSS839 @S9S_MB_2U_LIB.S9S_MB_2U(SCH_1):GND
DH34    GND VSS835 @S9S_MB_2U_LIB.S9S_MB_2U(SCH_1):GND
DH26    GND VSS832 @S9S_MB_2U_LIB.S9S_MB_2U(SCH_1):GND
DH20    GND VSS830 @S9S_MB_2U_LIB.S9S_MB_2U(SCH_1):GND
DH16    GND VSS829 @S9S_MB_2U_LIB.S9S_MB_2U(SCH_1):GND
DG64    GND VSS821 @S9S_MB_2U_LIB.S9S_MB_2U(SCH_1):GND
DG58    GND VSS820 @S9S_MB_2U_LIB.S9S_MB_2U(SCH_1):GND
DG52    GND VSS817 @S9S_MB_2U_LIB.S9S_MB_2U(SCH_1):GND
DG21    GND VSS809 @S9S_MB_2U_LIB.S9S_MB_2U(SCH_1):GND
DG13    GND VSS808 @S9S_MB_2U_LIB.S9S_MB_2U(SCH_1):GND
 DG1    GND VSS807 @S9S_MB_2U_LIB.S9S_MB_2U(SCH_1):GND
DF91    GND VSS806 @S9S_MB_2U_LIB.S9S_MB_2U(SCH_1):GND
DF49    GND VSS802 @S9S_MB_2U_LIB.S9S_MB_2U(SCH_1):GND
DF16    GND VSS799 @S9S_MB_2U_LIB.S9S_MB_2U(SCH_1):GND
DF12    GND VSS798 @S9S_MB_2U_LIB.S9S_MB_2U(SCH_1):GND
DE70    GND VSS791 @S9S_MB_2U_LIB.S9S_MB_2U(SCH_1):GND
DE39    GND VSS776 @S9S_MB_2U_LIB.S9S_MB_2U(SCH_1):GND
DD49    GND VSS753 @S9S_MB_2U_LIB.S9S_MB_2U(SCH_1):GND
DD16    GND VSS748 @S9S_MB_2U_LIB.S9S_MB_2U(SCH_1):GND
DD12    GND VSS747 @S9S_MB_2U_LIB.S9S_MB_2U(SCH_1):GND
DC64    GND VSS739 @S9S_MB_2U_LIB.S9S_MB_2U(SCH_1):GND
DC58    GND VSS738 @S9S_MB_2U_LIB.S9S_MB_2U(SCH_1):GND
DC52    GND VSS735 @S9S_MB_2U_LIB.S9S_MB_2U(SCH_1):GND
DC21    GND VSS726 @S9S_MB_2U_LIB.S9S_MB_2U(SCH_1):GND
DC13    GND VSS725 @S9S_MB_2U_LIB.S9S_MB_2U(SCH_1):GND
 DC1    GND VSS724 @S9S_MB_2U_LIB.S9S_MB_2U(SCH_1):GND
DB91    GND VSS723 @S9S_MB_2U_LIB.S9S_MB_2U(SCH_1):GND

SOCKET4677_AZIF0045P001C01CS-SA  I5  U1
DB87    GND VSS948 @S9S_MB_2U_LIB.S9S_MB_2U(SCH_1):GND
 DB8    GND VSS947 @S9S_MB_2U_LIB.S9S_MB_2U(SCH_1):GND
DB77    GND VSS946 @S9S_MB_2U_LIB.S9S_MB_2U(SCH_1):GND
DB71    GND VSS944 @S9S_MB_2U_LIB.S9S_MB_2U(SCH_1):GND
DB65    GND VSS943 @S9S_MB_2U_LIB.S9S_MB_2U(SCH_1):GND
DB57    GND VSS942 @S9S_MB_2U_LIB.S9S_MB_2U(SCH_1):GND
DB47    GND VSS941 @S9S_MB_2U_LIB.S9S_MB_2U(SCH_1):GND
DB40    GND VSS940 @S9S_MB_2U_LIB.S9S_MB_2U(SCH_1):GND
 DB4    GND VSS939 @S9S_MB_2U_LIB.S9S_MB_2U(SCH_1):GND
DB38    GND VSS938 @S9S_MB_2U_LIB.S9S_MB_2U(SCH_1):GND
DB32    GND VSS937 @S9S_MB_2U_LIB.S9S_MB_2U(SCH_1):GND
DB28    GND VSS936 @S9S_MB_2U_LIB.S9S_MB_2U(SCH_1):GND
DB22    GND VSS935 @S9S_MB_2U_LIB.S9S_MB_2U(SCH_1):GND
DB12    GND VSS933 @S9S_MB_2U_LIB.S9S_MB_2U(SCH_1):GND
DA88    GND VSS932 @S9S_MB_2U_LIB.S9S_MB_2U(SCH_1):GND
DA84    GND VSS931 @S9S_MB_2U_LIB.S9S_MB_2U(SCH_1):GND
DA82    GND VSS930 @S9S_MB_2U_LIB.S9S_MB_2U(SCH_1):GND
DA80    GND VSS929 @S9S_MB_2U_LIB.S9S_MB_2U(SCH_1):GND
DA74    GND VSS928 @S9S_MB_2U_LIB.S9S_MB_2U(SCH_1):GND
DA72    GND VSS927 @S9S_MB_2U_LIB.S9S_MB_2U(SCH_1):GND
DA66    GND VSS926 @S9S_MB_2U_LIB.S9S_MB_2U(SCH_1):GND
DA62    GND VSS925 @S9S_MB_2U_LIB.S9S_MB_2U(SCH_1):GND
DA60    GND VSS924 @S9S_MB_2U_LIB.S9S_MB_2U(SCH_1):GND
DA58    GND VSS923 @S9S_MB_2U_LIB.S9S_MB_2U(SCH_1):GND
DA56    GND VSS922 @S9S_MB_2U_LIB.S9S_MB_2U(SCH_1):GND
DA54    GND VSS921 @S9S_MB_2U_LIB.S9S_MB_2U(SCH_1):GND
DA50    GND VSS920 @S9S_MB_2U_LIB.S9S_MB_2U(SCH_1):GND
DA48    GND VSS919 @S9S_MB_2U_LIB.S9S_MB_2U(SCH_1):GND
DA41    GND VSS918 @S9S_MB_2U_LIB.S9S_MB_2U(SCH_1):GND
DA37    GND VSS917 @S9S_MB_2U_LIB.S9S_MB_2U(SCH_1):GND
DA35    GND VSS916 @S9S_MB_2U_LIB.S9S_MB_2U(SCH_1):GND
DA33    GND VSS915 @S9S_MB_2U_LIB.S9S_MB_2U(SCH_1):GND
DA31    GND VSS914 @S9S_MB_2U_LIB.S9S_MB_2U(SCH_1):GND
DA29    GND VSS913 @S9S_MB_2U_LIB.S9S_MB_2U(SCH_1):GND
DA25    GND VSS912 @S9S_MB_2U_LIB.S9S_MB_2U(SCH_1):GND
DA23    GND VSS911 @S9S_MB_2U_LIB.S9S_MB_2U(SCH_1):GND
DA19    GND VSS910 @S9S_MB_2U_LIB.S9S_MB_2U(SCH_1):GND
CY83    GND VSS863 @S9S_MB_2U_LIB.S9S_MB_2U(SCH_1):GND
CY81    GND VSS862 @S9S_MB_2U_LIB.S9S_MB_2U(SCH_1):GND
 CY8    GND VSS860 @S9S_MB_2U_LIB.S9S_MB_2U(SCH_1):GND
CY77    GND VSS859 @S9S_MB_2U_LIB.S9S_MB_2U(SCH_1):GND
CY73    GND VSS858 @S9S_MB_2U_LIB.S9S_MB_2U(SCH_1):GND
CY63    GND VSS856 @S9S_MB_2U_LIB.S9S_MB_2U(SCH_1):GND
CY30    GND VSS855 @S9S_MB_2U_LIB.S9S_MB_2U(SCH_1):GND
CY26    GND VSS854 @S9S_MB_2U_LIB.S9S_MB_2U(SCH_1):GND
CY18    GND VSS853 @S9S_MB_2U_LIB.S9S_MB_2U(SCH_1):GND
CY16    GND VSS852 @S9S_MB_2U_LIB.S9S_MB_2U(SCH_1):GND
CY12    GND VSS851 @S9S_MB_2U_LIB.S9S_MB_2U(SCH_1):GND
 CW9    GND VSS850 @S9S_MB_2U_LIB.S9S_MB_2U(SCH_1):GND
CW88    GND VSS848 @S9S_MB_2U_LIB.S9S_MB_2U(SCH_1):GND
CW84    GND VSS846 @S9S_MB_2U_LIB.S9S_MB_2U(SCH_1):GND
CW78    GND VSS843 @S9S_MB_2U_LIB.S9S_MB_2U(SCH_1):GND
CW72    GND VSS840 @S9S_MB_2U_LIB.S9S_MB_2U(SCH_1):GND
 CW5    GND VSS838 @S9S_MB_2U_LIB.S9S_MB_2U(SCH_1):GND
CW17    GND VSS837 @S9S_MB_2U_LIB.S9S_MB_2U(SCH_1):GND
CW13    GND VSS836 @S9S_MB_2U_LIB.S9S_MB_2U(SCH_1):GND
 CW1    GND VSS834 @S9S_MB_2U_LIB.S9S_MB_2U(SCH_1):GND
CV91    GND VSS833 @S9S_MB_2U_LIB.S9S_MB_2U(SCH_1):GND
CV87    GND VSS831 @S9S_MB_2U_LIB.S9S_MB_2U(SCH_1):GND
CV83    GND VSS828 @S9S_MB_2U_LIB.S9S_MB_2U(SCH_1):GND
 CV8    GND VSS827 @S9S_MB_2U_LIB.S9S_MB_2U(SCH_1):GND
CV75    GND VSS826 @S9S_MB_2U_LIB.S9S_MB_2U(SCH_1):GND
 CV4    GND VSS825 @S9S_MB_2U_LIB.S9S_MB_2U(SCH_1):GND
CV12    GND VSS824 @S9S_MB_2U_LIB.S9S_MB_2U(SCH_1):GND
CU88    GND VSS823 @S9S_MB_2U_LIB.S9S_MB_2U(SCH_1):GND
CU84    GND VSS822 @S9S_MB_2U_LIB.S9S_MB_2U(SCH_1):GND
CU68    GND VSS819 @S9S_MB_2U_LIB.S9S_MB_2U(SCH_1):GND
CU66    GND VSS818 @S9S_MB_2U_LIB.S9S_MB_2U(SCH_1):GND
CU60    GND VSS816 @S9S_MB_2U_LIB.S9S_MB_2U(SCH_1):GND
CU23    GND VSS815 @S9S_MB_2U_LIB.S9S_MB_2U(SCH_1):GND
CU21    GND VSS814 @S9S_MB_2U_LIB.S9S_MB_2U(SCH_1):GND
CU19    GND VSS813 @S9S_MB_2U_LIB.S9S_MB_2U(SCH_1):GND
CT81    GND VSS812 @S9S_MB_2U_LIB.S9S_MB_2U(SCH_1):GND
CT73    GND VSS811 @S9S_MB_2U_LIB.S9S_MB_2U(SCH_1):GND
CT69    GND VSS810 @S9S_MB_2U_LIB.S9S_MB_2U(SCH_1):GND
CT12    GND VSS805 @S9S_MB_2U_LIB.S9S_MB_2U(SCH_1):GND
CT10    GND VSS804 @S9S_MB_2U_LIB.S9S_MB_2U(SCH_1):GND
CR90    GND VSS803 @S9S_MB_2U_LIB.S9S_MB_2U(SCH_1):GND
 CR9    GND VSS801 @S9S_MB_2U_LIB.S9S_MB_2U(SCH_1):GND
CR88    GND VSS800 @S9S_MB_2U_LIB.S9S_MB_2U(SCH_1):GND
CR84    GND VSS797 @S9S_MB_2U_LIB.S9S_MB_2U(SCH_1):GND
CR64    GND VSS796 @S9S_MB_2U_LIB.S9S_MB_2U(SCH_1):GND
CR62    GND VSS795 @S9S_MB_2U_LIB.S9S_MB_2U(SCH_1):GND
 CR5    GND VSS794 @S9S_MB_2U_LIB.S9S_MB_2U(SCH_1):GND
CR17    GND VSS793 @S9S_MB_2U_LIB.S9S_MB_2U(SCH_1):GND
CR13    GND VSS792 @S9S_MB_2U_LIB.S9S_MB_2U(SCH_1):GND
CR11    GND VSS790 @S9S_MB_2U_LIB.S9S_MB_2U(SCH_1):GND
 CR1    GND VSS789 @S9S_MB_2U_LIB.S9S_MB_2U(SCH_1):GND
CP91    GND VSS788 @S9S_MB_2U_LIB.S9S_MB_2U(SCH_1):GND
CP87    GND VSS787 @S9S_MB_2U_LIB.S9S_MB_2U(SCH_1):GND
CP83    GND VSS786 @S9S_MB_2U_LIB.S9S_MB_2U(SCH_1):GND
 CP8    GND VSS785 @S9S_MB_2U_LIB.S9S_MB_2U(SCH_1):GND
CP77    GND VSS784 @S9S_MB_2U_LIB.S9S_MB_2U(SCH_1):GND
CP75    GND VSS783 @S9S_MB_2U_LIB.S9S_MB_2U(SCH_1):GND
 CP4    GND VSS782 @S9S_MB_2U_LIB.S9S_MB_2U(SCH_1):GND
CP18    GND VSS781 @S9S_MB_2U_LIB.S9S_MB_2U(SCH_1):GND
CP12    GND VSS780 @S9S_MB_2U_LIB.S9S_MB_2U(SCH_1):GND
CN86    GND VSS779 @S9S_MB_2U_LIB.S9S_MB_2U(SCH_1):GND
CN84    GND VSS778 @S9S_MB_2U_LIB.S9S_MB_2U(SCH_1):GND
CN74    GND VSS777 @S9S_MB_2U_LIB.S9S_MB_2U(SCH_1):GND
CN72    GND VSS775 @S9S_MB_2U_LIB.S9S_MB_2U(SCH_1):GND
CN70    GND VSS774 @S9S_MB_2U_LIB.S9S_MB_2U(SCH_1):GND
CN68    GND VSS773 @S9S_MB_2U_LIB.S9S_MB_2U(SCH_1):GND
CM85    GND VSS772 @S9S_MB_2U_LIB.S9S_MB_2U(SCH_1):GND
CM83    GND VSS771 @S9S_MB_2U_LIB.S9S_MB_2U(SCH_1):GND
CM81    GND VSS770 @S9S_MB_2U_LIB.S9S_MB_2U(SCH_1):GND
 CM8    GND VSS769 @S9S_MB_2U_LIB.S9S_MB_2U(SCH_1):GND
CM79    GND VSS768 @S9S_MB_2U_LIB.S9S_MB_2U(SCH_1):GND
CM67    GND VSS767 @S9S_MB_2U_LIB.S9S_MB_2U(SCH_1):GND
CM65    GND VSS766 @S9S_MB_2U_LIB.S9S_MB_2U(SCH_1):GND
CM61    GND VSS765 @S9S_MB_2U_LIB.S9S_MB_2U(SCH_1):GND
 CM4    GND VSS764 @S9S_MB_2U_LIB.S9S_MB_2U(SCH_1):GND
CM24    GND VSS763 @S9S_MB_2U_LIB.S9S_MB_2U(SCH_1):GND
CM20    GND VSS762 @S9S_MB_2U_LIB.S9S_MB_2U(SCH_1):GND
CM12    GND VSS761 @S9S_MB_2U_LIB.S9S_MB_2U(SCH_1):GND
 CL9    GND VSS760 @S9S_MB_2U_LIB.S9S_MB_2U(SCH_1):GND
CL82    GND VSS759 @S9S_MB_2U_LIB.S9S_MB_2U(SCH_1):GND
CL80    GND VSS758 @S9S_MB_2U_LIB.S9S_MB_2U(SCH_1):GND
CL78    GND VSS757 @S9S_MB_2U_LIB.S9S_MB_2U(SCH_1):GND
CL74    GND VSS756 @S9S_MB_2U_LIB.S9S_MB_2U(SCH_1):GND
CL62    GND VSS755 @S9S_MB_2U_LIB.S9S_MB_2U(SCH_1):GND
 CL5    GND VSS754 @S9S_MB_2U_LIB.S9S_MB_2U(SCH_1):GND
CL17    GND VSS752 @S9S_MB_2U_LIB.S9S_MB_2U(SCH_1):GND
CL13    GND VSS751 @S9S_MB_2U_LIB.S9S_MB_2U(SCH_1):GND
 CL1    GND VSS750 @S9S_MB_2U_LIB.S9S_MB_2U(SCH_1):GND
CK81    GND VSS749 @S9S_MB_2U_LIB.S9S_MB_2U(SCH_1):GND
CK69    GND VSS745 @S9S_MB_2U_LIB.S9S_MB_2U(SCH_1):GND
CK63    GND VSS744 @S9S_MB_2U_LIB.S9S_MB_2U(SCH_1):GND
DB75    GND VSS719 @S9S_MB_2U_LIB.S9S_MB_2U(SCH_1):GND
DB69    GND VSS717 @S9S_MB_2U_LIB.S9S_MB_2U(SCH_1):GND
DB63    GND VSS715 @S9S_MB_2U_LIB.S9S_MB_2U(SCH_1):GND
DB59    GND VSS714 @S9S_MB_2U_LIB.S9S_MB_2U(SCH_1):GND
DB53    GND VSS712 @S9S_MB_2U_LIB.S9S_MB_2U(SCH_1):GND
DB51    GND VSS711 @S9S_MB_2U_LIB.S9S_MB_2U(SCH_1):GND
DB44    GND VSS709 @S9S_MB_2U_LIB.S9S_MB_2U(SCH_1):GND
DB34    GND VSS705 @S9S_MB_2U_LIB.S9S_MB_2U(SCH_1):GND
DB26    GND VSS702 @S9S_MB_2U_LIB.S9S_MB_2U(SCH_1):GND
DB20    GND VSS700 @S9S_MB_2U_LIB.S9S_MB_2U(SCH_1):GND
DB16    GND VSS699 @S9S_MB_2U_LIB.S9S_MB_2U(SCH_1):GND
DA68    GND VSS690 @S9S_MB_2U_LIB.S9S_MB_2U(SCH_1):GND
DA43    GND VSS679 @S9S_MB_2U_LIB.S9S_MB_2U(SCH_1):GND
 CY4    GND VSS611 @S9S_MB_2U_LIB.S9S_MB_2U(SCH_1):GND
CW70    GND VSS595 @S9S_MB_2U_LIB.S9S_MB_2U(SCH_1):GND
CW33    GND VSS583 @S9S_MB_2U_LIB.S9S_MB_2U(SCH_1):GND
CV79    GND VSS571 @S9S_MB_2U_LIB.S9S_MB_2U(SCH_1):GND
CV26    GND VSS562 @S9S_MB_2U_LIB.S9S_MB_2U(SCH_1):GND
CV16    GND VSS558 @S9S_MB_2U_LIB.S9S_MB_2U(SCH_1):GND
CU78    GND VSS554 @S9S_MB_2U_LIB.S9S_MB_2U(SCH_1):GND
CU72    GND VSS553 @S9S_MB_2U_LIB.S9S_MB_2U(SCH_1):GND
CU25    GND VSS544 @S9S_MB_2U_LIB.S9S_MB_2U(SCH_1):GND
CT89    GND VSS537 @S9S_MB_2U_LIB.S9S_MB_2U(SCH_1):GND
 CT8    GND VSS534 @S9S_MB_2U_LIB.S9S_MB_2U(SCH_1):GND
 CT4    GND VSS526 @S9S_MB_2U_LIB.S9S_MB_2U(SCH_1):GND
CT16    GND VSS521 @S9S_MB_2U_LIB.S9S_MB_2U(SCH_1):GND
CR78    GND VSS514 @S9S_MB_2U_LIB.S9S_MB_2U(SCH_1):GND
CP79    GND VSS493 @S9S_MB_2U_LIB.S9S_MB_2U(SCH_1):GND
CP16    GND VSS478 @S9S_MB_2U_LIB.S9S_MB_2U(SCH_1):GND
CN76    GND VSS471 @S9S_MB_2U_LIB.S9S_MB_2U(SCH_1):GND
CM22    GND VSS438 @S9S_MB_2U_LIB.S9S_MB_2U(SCH_1):GND
CM16    GND VSS436 @S9S_MB_2U_LIB.S9S_MB_2U(SCH_1):GND

SOCKET4677_AZIF0045P001C01CS-SA  I8  U1
 CK8    GND VSS746 @S9S_MB_2U_LIB.S9S_MB_2U(SCH_1):GND
CK26    GND VSS743 @S9S_MB_2U_LIB.S9S_MB_2U(SCH_1):GND
CK20    GND VSS742 @S9S_MB_2U_LIB.S9S_MB_2U(SCH_1):GND
CK16    GND VSS741 @S9S_MB_2U_LIB.S9S_MB_2U(SCH_1):GND
CK12    GND VSS740 @S9S_MB_2U_LIB.S9S_MB_2U(SCH_1):GND
CJ80    GND VSS737 @S9S_MB_2U_LIB.S9S_MB_2U(SCH_1):GND
CJ60    GND VSS736 @S9S_MB_2U_LIB.S9S_MB_2U(SCH_1):GND
CH89    GND VSS734 @S9S_MB_2U_LIB.S9S_MB_2U(SCH_1):GND
CH87    GND VSS733 @S9S_MB_2U_LIB.S9S_MB_2U(SCH_1):GND
CH85    GND VSS732 @S9S_MB_2U_LIB.S9S_MB_2U(SCH_1):GND
CH83    GND VSS731 @S9S_MB_2U_LIB.S9S_MB_2U(SCH_1):GND
 CH8    GND VSS730 @S9S_MB_2U_LIB.S9S_MB_2U(SCH_1):GND
CH79    GND VSS729 @S9S_MB_2U_LIB.S9S_MB_2U(SCH_1):GND
CH73    GND VSS728 @S9S_MB_2U_LIB.S9S_MB_2U(SCH_1):GND
CH67    GND VSS727 @S9S_MB_2U_LIB.S9S_MB_2U(SCH_1):GND
 CH4    GND VSS722 @S9S_MB_2U_LIB.S9S_MB_2U(SCH_1):GND
CH20    GND VSS721 @S9S_MB_2U_LIB.S9S_MB_2U(SCH_1):GND
CH16    GND VSS720 @S9S_MB_2U_LIB.S9S_MB_2U(SCH_1):GND
CH12    GND VSS718 @S9S_MB_2U_LIB.S9S_MB_2U(SCH_1):GND
 CG9    GND VSS716 @S9S_MB_2U_LIB.S9S_MB_2U(SCH_1):GND
CG78    GND VSS713 @S9S_MB_2U_LIB.S9S_MB_2U(SCH_1):GND
CG74    GND VSS710 @S9S_MB_2U_LIB.S9S_MB_2U(SCH_1):GND
CG72    GND VSS708 @S9S_MB_2U_LIB.S9S_MB_2U(SCH_1):GND
CG70    GND VSS707 @S9S_MB_2U_LIB.S9S_MB_2U(SCH_1):GND
CG64    GND VSS706 @S9S_MB_2U_LIB.S9S_MB_2U(SCH_1):GND
CG62    GND VSS704 @S9S_MB_2U_LIB.S9S_MB_2U(SCH_1):GND
 CG5    GND VSS703 @S9S_MB_2U_LIB.S9S_MB_2U(SCH_1):GND
CG25    GND VSS701 @S9S_MB_2U_LIB.S9S_MB_2U(SCH_1):GND
CG23    GND VSS698 @S9S_MB_2U_LIB.S9S_MB_2U(SCH_1):GND
CG21    GND VSS697 @S9S_MB_2U_LIB.S9S_MB_2U(SCH_1):GND
CG17    GND VSS696 @S9S_MB_2U_LIB.S9S_MB_2U(SCH_1):GND
CG13    GND VSS695 @S9S_MB_2U_LIB.S9S_MB_2U(SCH_1):GND
 CG1    GND VSS694 @S9S_MB_2U_LIB.S9S_MB_2U(SCH_1):GND
 CF8    GND VSS693 @S9S_MB_2U_LIB.S9S_MB_2U(SCH_1):GND
CF71    GND VSS692 @S9S_MB_2U_LIB.S9S_MB_2U(SCH_1):GND
CF69    GND VSS691 @S9S_MB_2U_LIB.S9S_MB_2U(SCH_1):GND
 CF4    GND VSS689 @S9S_MB_2U_LIB.S9S_MB_2U(SCH_1):GND
CF20    GND VSS688 @S9S_MB_2U_LIB.S9S_MB_2U(SCH_1):GND
CF16    GND VSS687 @S9S_MB_2U_LIB.S9S_MB_2U(SCH_1):GND
CF12    GND VSS686 @S9S_MB_2U_LIB.S9S_MB_2U(SCH_1):GND
CE78    GND VSS685 @S9S_MB_2U_LIB.S9S_MB_2U(SCH_1):GND
CE76    GND VSS684 @S9S_MB_2U_LIB.S9S_MB_2U(SCH_1):GND
CE72    GND VSS683 @S9S_MB_2U_LIB.S9S_MB_2U(SCH_1):GND
CE66    GND VSS682 @S9S_MB_2U_LIB.S9S_MB_2U(SCH_1):GND
CE60    GND VSS681 @S9S_MB_2U_LIB.S9S_MB_2U(SCH_1):GND
 CE3    GND VSS680 @S9S_MB_2U_LIB.S9S_MB_2U(SCH_1):GND
 CD8    GND VSS678 @S9S_MB_2U_LIB.S9S_MB_2U(SCH_1):GND
CD77    GND VSS677 @S9S_MB_2U_LIB.S9S_MB_2U(SCH_1):GND
CD75    GND VSS676 @S9S_MB_2U_LIB.S9S_MB_2U(SCH_1):GND
CD61    GND VSS675 @S9S_MB_2U_LIB.S9S_MB_2U(SCH_1):GND
 CD4    GND VSS674 @S9S_MB_2U_LIB.S9S_MB_2U(SCH_1):GND
CD20    GND VSS673 @S9S_MB_2U_LIB.S9S_MB_2U(SCH_1):GND
CD16    GND VSS672 @S9S_MB_2U_LIB.S9S_MB_2U(SCH_1):GND
CD12    GND VSS671 @S9S_MB_2U_LIB.S9S_MB_2U(SCH_1):GND
 CC9    GND VSS670 @S9S_MB_2U_LIB.S9S_MB_2U(SCH_1):GND
CC74    GND VSS669 @S9S_MB_2U_LIB.S9S_MB_2U(SCH_1):GND
CC72    GND VSS668 @S9S_MB_2U_LIB.S9S_MB_2U(SCH_1):GND
CC70    GND VSS667 @S9S_MB_2U_LIB.S9S_MB_2U(SCH_1):GND
CC62    GND VSS666 @S9S_MB_2U_LIB.S9S_MB_2U(SCH_1):GND
 CC5    GND VSS665 @S9S_MB_2U_LIB.S9S_MB_2U(SCH_1):GND
CC31    GND VSS664 @S9S_MB_2U_LIB.S9S_MB_2U(SCH_1):GND
CC17    GND VSS661 @S9S_MB_2U_LIB.S9S_MB_2U(SCH_1):GND
CC13    GND VSS660 @S9S_MB_2U_LIB.S9S_MB_2U(SCH_1):GND
CB89    GND VSS656 @S9S_MB_2U_LIB.S9S_MB_2U(SCH_1):GND
CB87    GND VSS655 @S9S_MB_2U_LIB.S9S_MB_2U(SCH_1):GND
CB85    GND VSS654 @S9S_MB_2U_LIB.S9S_MB_2U(SCH_1):GND
CB83    GND VSS653 @S9S_MB_2U_LIB.S9S_MB_2U(SCH_1):GND
CB81    GND VSS652 @S9S_MB_2U_LIB.S9S_MB_2U(SCH_1):GND
 CB8    GND VSS651 @S9S_MB_2U_LIB.S9S_MB_2U(SCH_1):GND
CB79    GND VSS650 @S9S_MB_2U_LIB.S9S_MB_2U(SCH_1):GND
CB73    GND VSS649 @S9S_MB_2U_LIB.S9S_MB_2U(SCH_1):GND
CB71    GND VSS648 @S9S_MB_2U_LIB.S9S_MB_2U(SCH_1):GND
CB69    GND VSS647 @S9S_MB_2U_LIB.S9S_MB_2U(SCH_1):GND
CB67    GND VSS646 @S9S_MB_2U_LIB.S9S_MB_2U(SCH_1):GND
CB65    GND VSS645 @S9S_MB_2U_LIB.S9S_MB_2U(SCH_1):GND
CB63    GND VSS644 @S9S_MB_2U_LIB.S9S_MB_2U(SCH_1):GND
CB59    GND VSS643 @S9S_MB_2U_LIB.S9S_MB_2U(SCH_1):GND
CB57    GND VSS642 @S9S_MB_2U_LIB.S9S_MB_2U(SCH_1):GND
CB55    GND VSS641 @S9S_MB_2U_LIB.S9S_MB_2U(SCH_1):GND
CB53    GND VSS640 @S9S_MB_2U_LIB.S9S_MB_2U(SCH_1):GND
CB51    GND VSS639 @S9S_MB_2U_LIB.S9S_MB_2U(SCH_1):GND
CB49    GND VSS638 @S9S_MB_2U_LIB.S9S_MB_2U(SCH_1):GND
CB47    GND VSS637 @S9S_MB_2U_LIB.S9S_MB_2U(SCH_1):GND
CB44    GND VSS636 @S9S_MB_2U_LIB.S9S_MB_2U(SCH_1):GND
CB42    GND VSS635 @S9S_MB_2U_LIB.S9S_MB_2U(SCH_1):GND
CB40    GND VSS634 @S9S_MB_2U_LIB.S9S_MB_2U(SCH_1):GND
 CB4    GND VSS633 @S9S_MB_2U_LIB.S9S_MB_2U(SCH_1):GND
CB38    GND VSS632 @S9S_MB_2U_LIB.S9S_MB_2U(SCH_1):GND
CB36    GND VSS631 @S9S_MB_2U_LIB.S9S_MB_2U(SCH_1):GND
CB34    GND VSS630 @S9S_MB_2U_LIB.S9S_MB_2U(SCH_1):GND
CB32    GND VSS629 @S9S_MB_2U_LIB.S9S_MB_2U(SCH_1):GND
CB28    GND VSS628 @S9S_MB_2U_LIB.S9S_MB_2U(SCH_1):GND
CB26    GND VSS627 @S9S_MB_2U_LIB.S9S_MB_2U(SCH_1):GND
CB24    GND VSS626 @S9S_MB_2U_LIB.S9S_MB_2U(SCH_1):GND
CB22    GND VSS625 @S9S_MB_2U_LIB.S9S_MB_2U(SCH_1):GND
CB20    GND VSS624 @S9S_MB_2U_LIB.S9S_MB_2U(SCH_1):GND
CB16    GND VSS623 @S9S_MB_2U_LIB.S9S_MB_2U(SCH_1):GND
CB12    GND VSS622 @S9S_MB_2U_LIB.S9S_MB_2U(SCH_1):GND
CA31    GND VSS621 @S9S_MB_2U_LIB.S9S_MB_2U(SCH_1):GND
 CA3    GND VSS620 @S9S_MB_2U_LIB.S9S_MB_2U(SCH_1):GND
 BY8    GND VSS608 @S9S_MB_2U_LIB.S9S_MB_2U(SCH_1):GND
 BY4    GND VSS607 @S9S_MB_2U_LIB.S9S_MB_2U(SCH_1):GND
BY20    GND VSS606 @S9S_MB_2U_LIB.S9S_MB_2U(SCH_1):GND
BY16    GND VSS605 @S9S_MB_2U_LIB.S9S_MB_2U(SCH_1):GND
BY12    GND VSS604 @S9S_MB_2U_LIB.S9S_MB_2U(SCH_1):GND
 BW9    GND VSS603 @S9S_MB_2U_LIB.S9S_MB_2U(SCH_1):GND
 BW5    GND VSS602 @S9S_MB_2U_LIB.S9S_MB_2U(SCH_1):GND
BW31    GND VSS601 @S9S_MB_2U_LIB.S9S_MB_2U(SCH_1):GND
 BW3    GND VSS600 @S9S_MB_2U_LIB.S9S_MB_2U(SCH_1):GND
BW29    GND VSS599 @S9S_MB_2U_LIB.S9S_MB_2U(SCH_1):GND
BW27    GND VSS598 @S9S_MB_2U_LIB.S9S_MB_2U(SCH_1):GND
BW17    GND VSS597 @S9S_MB_2U_LIB.S9S_MB_2U(SCH_1):GND
BW13    GND VSS596 @S9S_MB_2U_LIB.S9S_MB_2U(SCH_1):GND
 BV8    GND VSS594 @S9S_MB_2U_LIB.S9S_MB_2U(SCH_1):GND
 BV6    GND VSS593 @S9S_MB_2U_LIB.S9S_MB_2U(SCH_1):GND
 BV4    GND VSS592 @S9S_MB_2U_LIB.S9S_MB_2U(SCH_1):GND
BV20    GND VSS591 @S9S_MB_2U_LIB.S9S_MB_2U(SCH_1):GND
 BV2    GND VSS590 @S9S_MB_2U_LIB.S9S_MB_2U(SCH_1):GND
BV18    GND VSS589 @S9S_MB_2U_LIB.S9S_MB_2U(SCH_1):GND
BV16    GND VSS588 @S9S_MB_2U_LIB.S9S_MB_2U(SCH_1):GND
BV12    GND VSS587 @S9S_MB_2U_LIB.S9S_MB_2U(SCH_1):GND
 BU7    GND VSS586 @S9S_MB_2U_LIB.S9S_MB_2U(SCH_1):GND
BU31    GND VSS585 @S9S_MB_2U_LIB.S9S_MB_2U(SCH_1):GND
BU25    GND VSS584 @S9S_MB_2U_LIB.S9S_MB_2U(SCH_1):GND
BU23    GND VSS582 @S9S_MB_2U_LIB.S9S_MB_2U(SCH_1):GND
BU21    GND VSS581 @S9S_MB_2U_LIB.S9S_MB_2U(SCH_1):GND
BU19    GND VSS580 @S9S_MB_2U_LIB.S9S_MB_2U(SCH_1):GND
BU15    GND VSS579 @S9S_MB_2U_LIB.S9S_MB_2U(SCH_1):GND
 BT8    GND VSS578 @S9S_MB_2U_LIB.S9S_MB_2U(SCH_1):GND
 BT4    GND VSS577 @S9S_MB_2U_LIB.S9S_MB_2U(SCH_1):GND
BT20    GND VSS576 @S9S_MB_2U_LIB.S9S_MB_2U(SCH_1):GND
BT16    GND VSS575 @S9S_MB_2U_LIB.S9S_MB_2U(SCH_1):GND
BT12    GND VSS574 @S9S_MB_2U_LIB.S9S_MB_2U(SCH_1):GND
BR90    GND VSS573 @S9S_MB_2U_LIB.S9S_MB_2U(SCH_1):GND
BR88    GND VSS570 @S9S_MB_2U_LIB.S9S_MB_2U(SCH_1):GND
BR86    GND VSS569 @S9S_MB_2U_LIB.S9S_MB_2U(SCH_1):GND
BR84    GND VSS568 @S9S_MB_2U_LIB.S9S_MB_2U(SCH_1):GND
BR82    GND VSS567 @S9S_MB_2U_LIB.S9S_MB_2U(SCH_1):GND
BR80    GND VSS566 @S9S_MB_2U_LIB.S9S_MB_2U(SCH_1):GND
BR76    GND VSS565 @S9S_MB_2U_LIB.S9S_MB_2U(SCH_1):GND
BR74    GND VSS564 @S9S_MB_2U_LIB.S9S_MB_2U(SCH_1):GND
BR72    GND VSS563 @S9S_MB_2U_LIB.S9S_MB_2U(SCH_1):GND
BR70    GND VSS561 @S9S_MB_2U_LIB.S9S_MB_2U(SCH_1):GND
BR68    GND VSS560 @S9S_MB_2U_LIB.S9S_MB_2U(SCH_1):GND
BR66    GND VSS559 @S9S_MB_2U_LIB.S9S_MB_2U(SCH_1):GND
BR64    GND VSS557 @S9S_MB_2U_LIB.S9S_MB_2U(SCH_1):GND
BR58    GND VSS556 @S9S_MB_2U_LIB.S9S_MB_2U(SCH_1):GND
BR56    GND VSS555 @S9S_MB_2U_LIB.S9S_MB_2U(SCH_1):GND
BR54    GND VSS552 @S9S_MB_2U_LIB.S9S_MB_2U(SCH_1):GND
BR52    GND VSS551 @S9S_MB_2U_LIB.S9S_MB_2U(SCH_1):GND
BR50    GND VSS550 @S9S_MB_2U_LIB.S9S_MB_2U(SCH_1):GND
BR48    GND VSS549 @S9S_MB_2U_LIB.S9S_MB_2U(SCH_1):GND
BR45    GND VSS548 @S9S_MB_2U_LIB.S9S_MB_2U(SCH_1):GND
BR43    GND VSS547 @S9S_MB_2U_LIB.S9S_MB_2U(SCH_1):GND
BR41    GND VSS546 @S9S_MB_2U_LIB.S9S_MB_2U(SCH_1):GND
BR39    GND VSS545 @S9S_MB_2U_LIB.S9S_MB_2U(SCH_1):GND
BR37    GND VSS543 @S9S_MB_2U_LIB.S9S_MB_2U(SCH_1):GND
BR35    GND VSS542 @S9S_MB_2U_LIB.S9S_MB_2U(SCH_1):GND
 CK4    GND VSS396 @S9S_MB_2U_LIB.S9S_MB_2U(SCH_1):GND
CJ76    GND VSS383 @S9S_MB_2U_LIB.S9S_MB_2U(SCH_1):GND


DRAWING: @S9S_MB_2U_LIB.S9S_MB_2U(SCH_1):PAGE72 

SOCKET4677_AZIF0045P001C01CS-SA  I2  U1
 BR9    GND VSS572 @S9S_MB_2U_LIB.S9S_MB_2U(SCH_1):GND
BR33    GND VSS541 @S9S_MB_2U_LIB.S9S_MB_2U(SCH_1):GND
BR31    GND VSS540 @S9S_MB_2U_LIB.S9S_MB_2U(SCH_1):GND
BR29    GND VSS539 @S9S_MB_2U_LIB.S9S_MB_2U(SCH_1):GND
BR27    GND VSS538 @S9S_MB_2U_LIB.S9S_MB_2U(SCH_1):GND
BR17    GND VSS536 @S9S_MB_2U_LIB.S9S_MB_2U(SCH_1):GND
BR13    GND VSS535 @S9S_MB_2U_LIB.S9S_MB_2U(SCH_1):GND
 BP8    GND VSS533 @S9S_MB_2U_LIB.S9S_MB_2U(SCH_1):GND
BP77    GND VSS532 @S9S_MB_2U_LIB.S9S_MB_2U(SCH_1):GND
BP75    GND VSS531 @S9S_MB_2U_LIB.S9S_MB_2U(SCH_1):GND
BP73    GND VSS530 @S9S_MB_2U_LIB.S9S_MB_2U(SCH_1):GND
BP71    GND VSS529 @S9S_MB_2U_LIB.S9S_MB_2U(SCH_1):GND
BP63    GND VSS528 @S9S_MB_2U_LIB.S9S_MB_2U(SCH_1):GND
 BP4    GND VSS527 @S9S_MB_2U_LIB.S9S_MB_2U(SCH_1):GND
BP20    GND VSS525 @S9S_MB_2U_LIB.S9S_MB_2U(SCH_1):GND
 BP2    GND VSS524 @S9S_MB_2U_LIB.S9S_MB_2U(SCH_1):GND
BP16    GND VSS523 @S9S_MB_2U_LIB.S9S_MB_2U(SCH_1):GND
BP12    GND VSS522 @S9S_MB_2U_LIB.S9S_MB_2U(SCH_1):GND
BN70    GND VSS520 @S9S_MB_2U_LIB.S9S_MB_2U(SCH_1):GND
BN62    GND VSS519 @S9S_MB_2U_LIB.S9S_MB_2U(SCH_1):GND
BN31    GND VSS518 @S9S_MB_2U_LIB.S9S_MB_2U(SCH_1):GND
 BM8    GND VSS517 @S9S_MB_2U_LIB.S9S_MB_2U(SCH_1):GND
BM77    GND VSS516 @S9S_MB_2U_LIB.S9S_MB_2U(SCH_1):GND
BM73    GND VSS515 @S9S_MB_2U_LIB.S9S_MB_2U(SCH_1):GND
BM61    GND VSS513 @S9S_MB_2U_LIB.S9S_MB_2U(SCH_1):GND
 BM4    GND VSS512 @S9S_MB_2U_LIB.S9S_MB_2U(SCH_1):GND
BM26    GND VSS511 @S9S_MB_2U_LIB.S9S_MB_2U(SCH_1):GND
BM24    GND VSS510 @S9S_MB_2U_LIB.S9S_MB_2U(SCH_1):GND
BM22    GND VSS509 @S9S_MB_2U_LIB.S9S_MB_2U(SCH_1):GND
BM20    GND VSS508 @S9S_MB_2U_LIB.S9S_MB_2U(SCH_1):GND
BM16    GND VSS507 @S9S_MB_2U_LIB.S9S_MB_2U(SCH_1):GND
BM12    GND VSS506 @S9S_MB_2U_LIB.S9S_MB_2U(SCH_1):GND
 BL9    GND VSS505 @S9S_MB_2U_LIB.S9S_MB_2U(SCH_1):GND
BL78    GND VSS504 @S9S_MB_2U_LIB.S9S_MB_2U(SCH_1):GND
BL72    GND VSS503 @S9S_MB_2U_LIB.S9S_MB_2U(SCH_1):GND
BL70    GND VSS502 @S9S_MB_2U_LIB.S9S_MB_2U(SCH_1):GND
BL68    GND VSS501 @S9S_MB_2U_LIB.S9S_MB_2U(SCH_1):GND
 BL5    GND VSS500 @S9S_MB_2U_LIB.S9S_MB_2U(SCH_1):GND
BL17    GND VSS499 @S9S_MB_2U_LIB.S9S_MB_2U(SCH_1):GND
BL13    GND VSS498 @S9S_MB_2U_LIB.S9S_MB_2U(SCH_1):GND
 BL1    GND VSS497 @S9S_MB_2U_LIB.S9S_MB_2U(SCH_1):GND
 BK8    GND VSS496 @S9S_MB_2U_LIB.S9S_MB_2U(SCH_1):GND
BK79    GND VSS495 @S9S_MB_2U_LIB.S9S_MB_2U(SCH_1):GND
BK75    GND VSS494 @S9S_MB_2U_LIB.S9S_MB_2U(SCH_1):GND
BK71    GND VSS492 @S9S_MB_2U_LIB.S9S_MB_2U(SCH_1):GND
BK65    GND VSS491 @S9S_MB_2U_LIB.S9S_MB_2U(SCH_1):GND
 BK4    GND VSS490 @S9S_MB_2U_LIB.S9S_MB_2U(SCH_1):GND
BK20    GND VSS489 @S9S_MB_2U_LIB.S9S_MB_2U(SCH_1):GND
BK16    GND VSS488 @S9S_MB_2U_LIB.S9S_MB_2U(SCH_1):GND
BK12    GND VSS487 @S9S_MB_2U_LIB.S9S_MB_2U(SCH_1):GND
BJ90    GND VSS486 @S9S_MB_2U_LIB.S9S_MB_2U(SCH_1):GND
BJ88    GND VSS485 @S9S_MB_2U_LIB.S9S_MB_2U(SCH_1):GND
BJ86    GND VSS484 @S9S_MB_2U_LIB.S9S_MB_2U(SCH_1):GND
BJ84    GND VSS483 @S9S_MB_2U_LIB.S9S_MB_2U(SCH_1):GND
BJ82    GND VSS482 @S9S_MB_2U_LIB.S9S_MB_2U(SCH_1):GND
BJ80    GND VSS481 @S9S_MB_2U_LIB.S9S_MB_2U(SCH_1):GND
BJ68    GND VSS480 @S9S_MB_2U_LIB.S9S_MB_2U(SCH_1):GND
BJ62    GND VSS479 @S9S_MB_2U_LIB.S9S_MB_2U(SCH_1):GND
BH83    GND VSS477 @S9S_MB_2U_LIB.S9S_MB_2U(SCH_1):GND
BH81    GND VSS476 @S9S_MB_2U_LIB.S9S_MB_2U(SCH_1):GND
 BH8    GND VSS475 @S9S_MB_2U_LIB.S9S_MB_2U(SCH_1):GND
BH77    GND VSS474 @S9S_MB_2U_LIB.S9S_MB_2U(SCH_1):GND
BH73    GND VSS473 @S9S_MB_2U_LIB.S9S_MB_2U(SCH_1):GND
BH67    GND VSS472 @S9S_MB_2U_LIB.S9S_MB_2U(SCH_1):GND
 BH4    GND VSS470 @S9S_MB_2U_LIB.S9S_MB_2U(SCH_1):GND
BH20    GND VSS469 @S9S_MB_2U_LIB.S9S_MB_2U(SCH_1):GND
BH16    GND VSS468 @S9S_MB_2U_LIB.S9S_MB_2U(SCH_1):GND
BH12    GND VSS467 @S9S_MB_2U_LIB.S9S_MB_2U(SCH_1):GND
 BG9    GND VSS466 @S9S_MB_2U_LIB.S9S_MB_2U(SCH_1):GND
BG70    GND VSS465 @S9S_MB_2U_LIB.S9S_MB_2U(SCH_1):GND
 BG5    GND VSS464 @S9S_MB_2U_LIB.S9S_MB_2U(SCH_1):GND
BG25    GND VSS463 @S9S_MB_2U_LIB.S9S_MB_2U(SCH_1):GND
BG23    GND VSS462 @S9S_MB_2U_LIB.S9S_MB_2U(SCH_1):GND
BG21    GND VSS461 @S9S_MB_2U_LIB.S9S_MB_2U(SCH_1):GND
BG17    GND VSS460 @S9S_MB_2U_LIB.S9S_MB_2U(SCH_1):GND
BG13    GND VSS459 @S9S_MB_2U_LIB.S9S_MB_2U(SCH_1):GND
 BG1    GND VSS458 @S9S_MB_2U_LIB.S9S_MB_2U(SCH_1):GND
BF83    GND VSS457 @S9S_MB_2U_LIB.S9S_MB_2U(SCH_1):GND
 BF8    GND VSS456 @S9S_MB_2U_LIB.S9S_MB_2U(SCH_1):GND
BF79    GND VSS455 @S9S_MB_2U_LIB.S9S_MB_2U(SCH_1):GND
BF75    GND VSS454 @S9S_MB_2U_LIB.S9S_MB_2U(SCH_1):GND
BF73    GND VSS453 @S9S_MB_2U_LIB.S9S_MB_2U(SCH_1):GND
BF63    GND VSS452 @S9S_MB_2U_LIB.S9S_MB_2U(SCH_1):GND
BF61    GND VSS451 @S9S_MB_2U_LIB.S9S_MB_2U(SCH_1):GND
 BF4    GND VSS450 @S9S_MB_2U_LIB.S9S_MB_2U(SCH_1):GND
BF20    GND VSS449 @S9S_MB_2U_LIB.S9S_MB_2U(SCH_1):GND
BF16    GND VSS448 @S9S_MB_2U_LIB.S9S_MB_2U(SCH_1):GND
BF12    GND VSS447 @S9S_MB_2U_LIB.S9S_MB_2U(SCH_1):GND
BE84    GND VSS446 @S9S_MB_2U_LIB.S9S_MB_2U(SCH_1):GND
BE78    GND VSS445 @S9S_MB_2U_LIB.S9S_MB_2U(SCH_1):GND
BE76    GND VSS444 @S9S_MB_2U_LIB.S9S_MB_2U(SCH_1):GND
BE74    GND VSS443 @S9S_MB_2U_LIB.S9S_MB_2U(SCH_1):GND
BE68    GND VSS442 @S9S_MB_2U_LIB.S9S_MB_2U(SCH_1):GND
BE66    GND VSS441 @S9S_MB_2U_LIB.S9S_MB_2U(SCH_1):GND
BE64    GND VSS440 @S9S_MB_2U_LIB.S9S_MB_2U(SCH_1):GND
BD89    GND VSS439 @S9S_MB_2U_LIB.S9S_MB_2U(SCH_1):GND
BD85    GND VSS437 @S9S_MB_2U_LIB.S9S_MB_2U(SCH_1):GND
BD81    GND VSS435 @S9S_MB_2U_LIB.S9S_MB_2U(SCH_1):GND
 BD8    GND VSS434 @S9S_MB_2U_LIB.S9S_MB_2U(SCH_1):GND
 BD4    GND VSS433 @S9S_MB_2U_LIB.S9S_MB_2U(SCH_1):GND
BD20    GND VSS432 @S9S_MB_2U_LIB.S9S_MB_2U(SCH_1):GND
BD16    GND VSS431 @S9S_MB_2U_LIB.S9S_MB_2U(SCH_1):GND
BD12    GND VSS430 @S9S_MB_2U_LIB.S9S_MB_2U(SCH_1):GND
 BC9    GND VSS429 @S9S_MB_2U_LIB.S9S_MB_2U(SCH_1):GND
BC88    GND VSS428 @S9S_MB_2U_LIB.S9S_MB_2U(SCH_1):GND
BC86    GND VSS427 @S9S_MB_2U_LIB.S9S_MB_2U(SCH_1):GND
BC84    GND VSS426 @S9S_MB_2U_LIB.S9S_MB_2U(SCH_1):GND
BC78    GND VSS425 @S9S_MB_2U_LIB.S9S_MB_2U(SCH_1):GND
BC76    GND VSS424 @S9S_MB_2U_LIB.S9S_MB_2U(SCH_1):GND
BC72    GND VSS423 @S9S_MB_2U_LIB.S9S_MB_2U(SCH_1):GND
BC66    GND VSS422 @S9S_MB_2U_LIB.S9S_MB_2U(SCH_1):GND
BC62    GND VSS421 @S9S_MB_2U_LIB.S9S_MB_2U(SCH_1):GND
 BC5    GND VSS420 @S9S_MB_2U_LIB.S9S_MB_2U(SCH_1):GND
BC17    GND VSS419 @S9S_MB_2U_LIB.S9S_MB_2U(SCH_1):GND
BC13    GND VSS418 @S9S_MB_2U_LIB.S9S_MB_2U(SCH_1):GND
 BC1    GND VSS417 @S9S_MB_2U_LIB.S9S_MB_2U(SCH_1):GND
BB91    GND VSS416 @S9S_MB_2U_LIB.S9S_MB_2U(SCH_1):GND
BB87    GND VSS415 @S9S_MB_2U_LIB.S9S_MB_2U(SCH_1):GND
BB83    GND VSS414 @S9S_MB_2U_LIB.S9S_MB_2U(SCH_1):GND
 BB8    GND VSS413 @S9S_MB_2U_LIB.S9S_MB_2U(SCH_1):GND
BB79    GND VSS412 @S9S_MB_2U_LIB.S9S_MB_2U(SCH_1):GND
BB77    GND VSS411 @S9S_MB_2U_LIB.S9S_MB_2U(SCH_1):GND
BB71    GND VSS410 @S9S_MB_2U_LIB.S9S_MB_2U(SCH_1):GND
BB69    GND VSS409 @S9S_MB_2U_LIB.S9S_MB_2U(SCH_1):GND
BB63    GND VSS408 @S9S_MB_2U_LIB.S9S_MB_2U(SCH_1):GND
 BB4    GND VSS407 @S9S_MB_2U_LIB.S9S_MB_2U(SCH_1):GND
BB26    GND VSS406 @S9S_MB_2U_LIB.S9S_MB_2U(SCH_1):GND
BB24    GND VSS405 @S9S_MB_2U_LIB.S9S_MB_2U(SCH_1):GND
BB22    GND VSS404 @S9S_MB_2U_LIB.S9S_MB_2U(SCH_1):GND
BB20    GND VSS403 @S9S_MB_2U_LIB.S9S_MB_2U(SCH_1):GND
BB16    GND VSS402 @S9S_MB_2U_LIB.S9S_MB_2U(SCH_1):GND
BB12    GND VSS401 @S9S_MB_2U_LIB.S9S_MB_2U(SCH_1):GND
BB10    GND VSS400 @S9S_MB_2U_LIB.S9S_MB_2U(SCH_1):GND
BA88    GND VSS399 @S9S_MB_2U_LIB.S9S_MB_2U(SCH_1):GND
BA84    GND VSS398 @S9S_MB_2U_LIB.S9S_MB_2U(SCH_1):GND
BA74    GND VSS397 @S9S_MB_2U_LIB.S9S_MB_2U(SCH_1):GND
BA64    GND VSS395 @S9S_MB_2U_LIB.S9S_MB_2U(SCH_1):GND
BA60    GND VSS394 @S9S_MB_2U_LIB.S9S_MB_2U(SCH_1):GND
BA17    GND VSS393 @S9S_MB_2U_LIB.S9S_MB_2U(SCH_1):GND
AY83    GND VSS377 @S9S_MB_2U_LIB.S9S_MB_2U(SCH_1):GND
AY81    GND VSS376 @S9S_MB_2U_LIB.S9S_MB_2U(SCH_1):GND
 AY8    GND VSS375 @S9S_MB_2U_LIB.S9S_MB_2U(SCH_1):GND
AY79    GND VSS374 @S9S_MB_2U_LIB.S9S_MB_2U(SCH_1):GND
AY77    GND VSS373 @S9S_MB_2U_LIB.S9S_MB_2U(SCH_1):GND
AY71    GND VSS372 @S9S_MB_2U_LIB.S9S_MB_2U(SCH_1):GND
 AY4    GND VSS371 @S9S_MB_2U_LIB.S9S_MB_2U(SCH_1):GND
AY16    GND VSS370 @S9S_MB_2U_LIB.S9S_MB_2U(SCH_1):GND
AY12    GND VSS369 @S9S_MB_2U_LIB.S9S_MB_2U(SCH_1):GND
AW88    GND VSS367 @S9S_MB_2U_LIB.S9S_MB_2U(SCH_1):GND
AW84    GND VSS366 @S9S_MB_2U_LIB.S9S_MB_2U(SCH_1):GND
AW82    GND VSS365 @S9S_MB_2U_LIB.S9S_MB_2U(SCH_1):GND
AW80    GND VSS364 @S9S_MB_2U_LIB.S9S_MB_2U(SCH_1):GND
AW72    GND VSS363 @S9S_MB_2U_LIB.S9S_MB_2U(SCH_1):GND
AW68    GND VSS362 @S9S_MB_2U_LIB.S9S_MB_2U(SCH_1):GND
AW66    GND VSS361 @S9S_MB_2U_LIB.S9S_MB_2U(SCH_1):GND
AW62    GND VSS360 @S9S_MB_2U_LIB.S9S_MB_2U(SCH_1):GND
AW25    GND VSS358 @S9S_MB_2U_LIB.S9S_MB_2U(SCH_1):GND
AW23    GND VSS357 @S9S_MB_2U_LIB.S9S_MB_2U(SCH_1):GND
AW21    GND VSS356 @S9S_MB_2U_LIB.S9S_MB_2U(SCH_1):GND
 BR5    GND   VSS0 @S9S_MB_2U_LIB.S9S_MB_2U(SCH_1):GND

SOCKET4677_AZIF0045P001C01CS-SA  I5  U1
 AW9    GND VSS368 @S9S_MB_2U_LIB.S9S_MB_2U(SCH_1):GND
 AW5    GND VSS359 @S9S_MB_2U_LIB.S9S_MB_2U(SCH_1):GND
AW13    GND VSS355 @S9S_MB_2U_LIB.S9S_MB_2U(SCH_1):GND
 AW1    GND VSS354 @S9S_MB_2U_LIB.S9S_MB_2U(SCH_1):GND
AV91    GND VSS353 @S9S_MB_2U_LIB.S9S_MB_2U(SCH_1):GND
AV87    GND VSS352 @S9S_MB_2U_LIB.S9S_MB_2U(SCH_1):GND
 AV8    GND VSS351 @S9S_MB_2U_LIB.S9S_MB_2U(SCH_1):GND
AV77    GND VSS350 @S9S_MB_2U_LIB.S9S_MB_2U(SCH_1):GND
 AV4    GND VSS349 @S9S_MB_2U_LIB.S9S_MB_2U(SCH_1):GND
AV16    GND VSS348 @S9S_MB_2U_LIB.S9S_MB_2U(SCH_1):GND
AV12    GND VSS347 @S9S_MB_2U_LIB.S9S_MB_2U(SCH_1):GND
AU88    GND VSS346 @S9S_MB_2U_LIB.S9S_MB_2U(SCH_1):GND
AU84    GND VSS345 @S9S_MB_2U_LIB.S9S_MB_2U(SCH_1):GND
AU80    GND VSS344 @S9S_MB_2U_LIB.S9S_MB_2U(SCH_1):GND
AU76    GND VSS343 @S9S_MB_2U_LIB.S9S_MB_2U(SCH_1):GND
AU74    GND VSS342 @S9S_MB_2U_LIB.S9S_MB_2U(SCH_1):GND
AU72    GND VSS341 @S9S_MB_2U_LIB.S9S_MB_2U(SCH_1):GND
AU70    GND VSS340 @S9S_MB_2U_LIB.S9S_MB_2U(SCH_1):GND
AU48    GND VSS339 @S9S_MB_2U_LIB.S9S_MB_2U(SCH_1):GND
AU45    GND VSS338 @S9S_MB_2U_LIB.S9S_MB_2U(SCH_1):GND
AU41    GND VSS337 @S9S_MB_2U_LIB.S9S_MB_2U(SCH_1):GND
AU39    GND VSS336 @S9S_MB_2U_LIB.S9S_MB_2U(SCH_1):GND
AU37    GND VSS335 @S9S_MB_2U_LIB.S9S_MB_2U(SCH_1):GND
AU31    GND VSS334 @S9S_MB_2U_LIB.S9S_MB_2U(SCH_1):GND
AU27    GND VSS333 @S9S_MB_2U_LIB.S9S_MB_2U(SCH_1):GND
 AT8    GND VSS332 @S9S_MB_2U_LIB.S9S_MB_2U(SCH_1):GND
AT79    GND VSS331 @S9S_MB_2U_LIB.S9S_MB_2U(SCH_1):GND
AT77    GND VSS330 @S9S_MB_2U_LIB.S9S_MB_2U(SCH_1):GND
AT75    GND VSS329 @S9S_MB_2U_LIB.S9S_MB_2U(SCH_1):GND
AT71    GND VSS328 @S9S_MB_2U_LIB.S9S_MB_2U(SCH_1):GND
AT69    GND VSS327 @S9S_MB_2U_LIB.S9S_MB_2U(SCH_1):GND
AT65    GND VSS326 @S9S_MB_2U_LIB.S9S_MB_2U(SCH_1):GND
AT63    GND VSS325 @S9S_MB_2U_LIB.S9S_MB_2U(SCH_1):GND
AT59    GND VSS324 @S9S_MB_2U_LIB.S9S_MB_2U(SCH_1):GND
AT57    GND VSS323 @S9S_MB_2U_LIB.S9S_MB_2U(SCH_1):GND
AT53    GND VSS322 @S9S_MB_2U_LIB.S9S_MB_2U(SCH_1):GND
AT51    GND VSS321 @S9S_MB_2U_LIB.S9S_MB_2U(SCH_1):GND
AT44    GND VSS320 @S9S_MB_2U_LIB.S9S_MB_2U(SCH_1):GND
AT40    GND VSS319 @S9S_MB_2U_LIB.S9S_MB_2U(SCH_1):GND
 AT4    GND VSS318 @S9S_MB_2U_LIB.S9S_MB_2U(SCH_1):GND
AT38    GND VSS317 @S9S_MB_2U_LIB.S9S_MB_2U(SCH_1):GND
AT34    GND VSS316 @S9S_MB_2U_LIB.S9S_MB_2U(SCH_1):GND
AT32    GND VSS315 @S9S_MB_2U_LIB.S9S_MB_2U(SCH_1):GND
AT28    GND VSS314 @S9S_MB_2U_LIB.S9S_MB_2U(SCH_1):GND
AT26    GND VSS313 @S9S_MB_2U_LIB.S9S_MB_2U(SCH_1):GND
AT22    GND VSS312 @S9S_MB_2U_LIB.S9S_MB_2U(SCH_1):GND
AT20    GND VSS311 @S9S_MB_2U_LIB.S9S_MB_2U(SCH_1):GND
AT16    GND VSS310 @S9S_MB_2U_LIB.S9S_MB_2U(SCH_1):GND
AT12    GND VSS309 @S9S_MB_2U_LIB.S9S_MB_2U(SCH_1):GND
 AR9    GND VSS308 @S9S_MB_2U_LIB.S9S_MB_2U(SCH_1):GND
AR88    GND VSS307 @S9S_MB_2U_LIB.S9S_MB_2U(SCH_1):GND
AR84    GND VSS306 @S9S_MB_2U_LIB.S9S_MB_2U(SCH_1):GND
AR82    GND VSS305 @S9S_MB_2U_LIB.S9S_MB_2U(SCH_1):GND
AR78    GND VSS304 @S9S_MB_2U_LIB.S9S_MB_2U(SCH_1):GND
AR74    GND VSS303 @S9S_MB_2U_LIB.S9S_MB_2U(SCH_1):GND
AR72    GND VSS302 @S9S_MB_2U_LIB.S9S_MB_2U(SCH_1):GND
AR68    GND VSS301 @S9S_MB_2U_LIB.S9S_MB_2U(SCH_1):GND
AR66    GND VSS300 @S9S_MB_2U_LIB.S9S_MB_2U(SCH_1):GND
AR62    GND VSS299 @S9S_MB_2U_LIB.S9S_MB_2U(SCH_1):GND
AR60    GND VSS298 @S9S_MB_2U_LIB.S9S_MB_2U(SCH_1):GND
AR56    GND VSS297 @S9S_MB_2U_LIB.S9S_MB_2U(SCH_1):GND
AR54    GND VSS296 @S9S_MB_2U_LIB.S9S_MB_2U(SCH_1):GND
AR50    GND VSS295 @S9S_MB_2U_LIB.S9S_MB_2U(SCH_1):GND
 AR5    GND VSS294 @S9S_MB_2U_LIB.S9S_MB_2U(SCH_1):GND
AR48    GND VSS293 @S9S_MB_2U_LIB.S9S_MB_2U(SCH_1):GND
AR43    GND VSS292 @S9S_MB_2U_LIB.S9S_MB_2U(SCH_1):GND
AR41    GND VSS291 @S9S_MB_2U_LIB.S9S_MB_2U(SCH_1):GND
AR37    GND VSS290 @S9S_MB_2U_LIB.S9S_MB_2U(SCH_1):GND
AR35    GND VSS289 @S9S_MB_2U_LIB.S9S_MB_2U(SCH_1):GND
AR31    GND VSS288 @S9S_MB_2U_LIB.S9S_MB_2U(SCH_1):GND
AR29    GND VSS287 @S9S_MB_2U_LIB.S9S_MB_2U(SCH_1):GND
AR25    GND VSS286 @S9S_MB_2U_LIB.S9S_MB_2U(SCH_1):GND
AR23    GND VSS285 @S9S_MB_2U_LIB.S9S_MB_2U(SCH_1):GND
AR19    GND VSS284 @S9S_MB_2U_LIB.S9S_MB_2U(SCH_1):GND
AR13    GND VSS283 @S9S_MB_2U_LIB.S9S_MB_2U(SCH_1):GND
 AR1    GND VSS282 @S9S_MB_2U_LIB.S9S_MB_2U(SCH_1):GND
AP91    GND VSS281 @S9S_MB_2U_LIB.S9S_MB_2U(SCH_1):GND
AP87    GND VSS280 @S9S_MB_2U_LIB.S9S_MB_2U(SCH_1):GND
AP83    GND VSS279 @S9S_MB_2U_LIB.S9S_MB_2U(SCH_1):GND
 AP8    GND VSS278 @S9S_MB_2U_LIB.S9S_MB_2U(SCH_1):GND
AP79    GND VSS277 @S9S_MB_2U_LIB.S9S_MB_2U(SCH_1):GND
AP73    GND VSS276 @S9S_MB_2U_LIB.S9S_MB_2U(SCH_1):GND
AP67    GND VSS275 @S9S_MB_2U_LIB.S9S_MB_2U(SCH_1):GND
AP61    GND VSS274 @S9S_MB_2U_LIB.S9S_MB_2U(SCH_1):GND
AP55    GND VSS273 @S9S_MB_2U_LIB.S9S_MB_2U(SCH_1):GND
AP49    GND VSS272 @S9S_MB_2U_LIB.S9S_MB_2U(SCH_1):GND
AP42    GND VSS271 @S9S_MB_2U_LIB.S9S_MB_2U(SCH_1):GND
 AP4    GND VSS270 @S9S_MB_2U_LIB.S9S_MB_2U(SCH_1):GND
AP36    GND VSS269 @S9S_MB_2U_LIB.S9S_MB_2U(SCH_1):GND
AP30    GND VSS268 @S9S_MB_2U_LIB.S9S_MB_2U(SCH_1):GND
AP24    GND VSS267 @S9S_MB_2U_LIB.S9S_MB_2U(SCH_1):GND
AP18    GND VSS266 @S9S_MB_2U_LIB.S9S_MB_2U(SCH_1):GND
AP16    GND VSS265 @S9S_MB_2U_LIB.S9S_MB_2U(SCH_1):GND
AP12    GND VSS264 @S9S_MB_2U_LIB.S9S_MB_2U(SCH_1):GND
AN88    GND VSS263 @S9S_MB_2U_LIB.S9S_MB_2U(SCH_1):GND
AN84    GND VSS262 @S9S_MB_2U_LIB.S9S_MB_2U(SCH_1):GND
AN52    GND VSS261 @S9S_MB_2U_LIB.S9S_MB_2U(SCH_1):GND
 AM8    GND VSS260 @S9S_MB_2U_LIB.S9S_MB_2U(SCH_1):GND
AM77    GND VSS259 @S9S_MB_2U_LIB.S9S_MB_2U(SCH_1):GND
AM75    GND VSS258 @S9S_MB_2U_LIB.S9S_MB_2U(SCH_1):GND
AM73    GND VSS257 @S9S_MB_2U_LIB.S9S_MB_2U(SCH_1):GND
AM71    GND VSS256 @S9S_MB_2U_LIB.S9S_MB_2U(SCH_1):GND
AM69    GND VSS255 @S9S_MB_2U_LIB.S9S_MB_2U(SCH_1):GND
AM67    GND VSS254 @S9S_MB_2U_LIB.S9S_MB_2U(SCH_1):GND
AM65    GND VSS253 @S9S_MB_2U_LIB.S9S_MB_2U(SCH_1):GND
AM63    GND VSS252 @S9S_MB_2U_LIB.S9S_MB_2U(SCH_1):GND
AM61    GND VSS251 @S9S_MB_2U_LIB.S9S_MB_2U(SCH_1):GND
AM59    GND VSS250 @S9S_MB_2U_LIB.S9S_MB_2U(SCH_1):GND
AM57    GND VSS249 @S9S_MB_2U_LIB.S9S_MB_2U(SCH_1):GND
AM55    GND VSS248 @S9S_MB_2U_LIB.S9S_MB_2U(SCH_1):GND
AM53    GND VSS247 @S9S_MB_2U_LIB.S9S_MB_2U(SCH_1):GND
AM51    GND VSS246 @S9S_MB_2U_LIB.S9S_MB_2U(SCH_1):GND
AM49    GND VSS245 @S9S_MB_2U_LIB.S9S_MB_2U(SCH_1):GND
AM47    GND VSS244 @S9S_MB_2U_LIB.S9S_MB_2U(SCH_1):GND
AM44    GND VSS243 @S9S_MB_2U_LIB.S9S_MB_2U(SCH_1):GND
AM42    GND VSS242 @S9S_MB_2U_LIB.S9S_MB_2U(SCH_1):GND
AM40    GND VSS241 @S9S_MB_2U_LIB.S9S_MB_2U(SCH_1):GND
 AM4    GND VSS240 @S9S_MB_2U_LIB.S9S_MB_2U(SCH_1):GND
AM38    GND VSS239 @S9S_MB_2U_LIB.S9S_MB_2U(SCH_1):GND
AM36    GND VSS238 @S9S_MB_2U_LIB.S9S_MB_2U(SCH_1):GND
AM34    GND VSS237 @S9S_MB_2U_LIB.S9S_MB_2U(SCH_1):GND
AM32    GND VSS236 @S9S_MB_2U_LIB.S9S_MB_2U(SCH_1):GND
AM30    GND VSS235 @S9S_MB_2U_LIB.S9S_MB_2U(SCH_1):GND
AM28    GND VSS234 @S9S_MB_2U_LIB.S9S_MB_2U(SCH_1):GND
AM26    GND VSS233 @S9S_MB_2U_LIB.S9S_MB_2U(SCH_1):GND
AM24    GND VSS232 @S9S_MB_2U_LIB.S9S_MB_2U(SCH_1):GND
AM22    GND VSS231 @S9S_MB_2U_LIB.S9S_MB_2U(SCH_1):GND
AM20    GND VSS230 @S9S_MB_2U_LIB.S9S_MB_2U(SCH_1):GND
AM18    GND VSS229 @S9S_MB_2U_LIB.S9S_MB_2U(SCH_1):GND
AM16    GND VSS228 @S9S_MB_2U_LIB.S9S_MB_2U(SCH_1):GND
AM12    GND VSS227 @S9S_MB_2U_LIB.S9S_MB_2U(SCH_1):GND
 AL9    GND VSS226 @S9S_MB_2U_LIB.S9S_MB_2U(SCH_1):GND
AL88    GND VSS225 @S9S_MB_2U_LIB.S9S_MB_2U(SCH_1):GND
AL84    GND VSS224 @S9S_MB_2U_LIB.S9S_MB_2U(SCH_1):GND
AL82    GND VSS223 @S9S_MB_2U_LIB.S9S_MB_2U(SCH_1):GND
AL80    GND VSS222 @S9S_MB_2U_LIB.S9S_MB_2U(SCH_1):GND
AL52    GND VSS221 @S9S_MB_2U_LIB.S9S_MB_2U(SCH_1):GND
 AL5    GND VSS220 @S9S_MB_2U_LIB.S9S_MB_2U(SCH_1):GND
AL17    GND VSS219 @S9S_MB_2U_LIB.S9S_MB_2U(SCH_1):GND
AL13    GND VSS218 @S9S_MB_2U_LIB.S9S_MB_2U(SCH_1):GND
 AL1    GND VSS217 @S9S_MB_2U_LIB.S9S_MB_2U(SCH_1):GND
AK91    GND VSS216 @S9S_MB_2U_LIB.S9S_MB_2U(SCH_1):GND
AK87    GND VSS215 @S9S_MB_2U_LIB.S9S_MB_2U(SCH_1):GND
AK83    GND VSS214 @S9S_MB_2U_LIB.S9S_MB_2U(SCH_1):GND
AK81    GND VSS213 @S9S_MB_2U_LIB.S9S_MB_2U(SCH_1):GND
 AK8    GND VSS212 @S9S_MB_2U_LIB.S9S_MB_2U(SCH_1):GND
AK79    GND VSS211 @S9S_MB_2U_LIB.S9S_MB_2U(SCH_1):GND
AK73    GND VSS210 @S9S_MB_2U_LIB.S9S_MB_2U(SCH_1):GND
AK67    GND VSS209 @S9S_MB_2U_LIB.S9S_MB_2U(SCH_1):GND
AK61    GND VSS208 @S9S_MB_2U_LIB.S9S_MB_2U(SCH_1):GND
AK55    GND VSS207 @S9S_MB_2U_LIB.S9S_MB_2U(SCH_1):GND
AK49    GND VSS206 @S9S_MB_2U_LIB.S9S_MB_2U(SCH_1):GND
AK42    GND VSS205 @S9S_MB_2U_LIB.S9S_MB_2U(SCH_1):GND
 AK4    GND VSS204 @S9S_MB_2U_LIB.S9S_MB_2U(SCH_1):GND
AK36    GND VSS203 @S9S_MB_2U_LIB.S9S_MB_2U(SCH_1):GND
AK30    GND VSS202 @S9S_MB_2U_LIB.S9S_MB_2U(SCH_1):GND
AK24    GND VSS201 @S9S_MB_2U_LIB.S9S_MB_2U(SCH_1):GND
AK18    GND VSS200 @S9S_MB_2U_LIB.S9S_MB_2U(SCH_1):GND
AK16    GND VSS199 @S9S_MB_2U_LIB.S9S_MB_2U(SCH_1):GND
AK12    GND VSS198 @S9S_MB_2U_LIB.S9S_MB_2U(SCH_1):GND

SOCKET4677_AZIF0045P001C01CS-SA  I8  U1
AJ88    GND VSS197 @S9S_MB_2U_LIB.S9S_MB_2U(SCH_1):GND
AJ84    GND VSS196 @S9S_MB_2U_LIB.S9S_MB_2U(SCH_1):GND
AJ78    GND VSS195 @S9S_MB_2U_LIB.S9S_MB_2U(SCH_1):GND
AJ74    GND VSS194 @S9S_MB_2U_LIB.S9S_MB_2U(SCH_1):GND
AJ72    GND VSS193 @S9S_MB_2U_LIB.S9S_MB_2U(SCH_1):GND
AJ68    GND VSS192 @S9S_MB_2U_LIB.S9S_MB_2U(SCH_1):GND
AJ66    GND VSS191 @S9S_MB_2U_LIB.S9S_MB_2U(SCH_1):GND
AJ62    GND VSS190 @S9S_MB_2U_LIB.S9S_MB_2U(SCH_1):GND
AJ60    GND VSS189 @S9S_MB_2U_LIB.S9S_MB_2U(SCH_1):GND
AJ56    GND VSS188 @S9S_MB_2U_LIB.S9S_MB_2U(SCH_1):GND
AJ54    GND VSS187 @S9S_MB_2U_LIB.S9S_MB_2U(SCH_1):GND
AJ50    GND VSS186 @S9S_MB_2U_LIB.S9S_MB_2U(SCH_1):GND
AJ48    GND VSS185 @S9S_MB_2U_LIB.S9S_MB_2U(SCH_1):GND
AJ43    GND VSS184 @S9S_MB_2U_LIB.S9S_MB_2U(SCH_1):GND
AJ41    GND VSS183 @S9S_MB_2U_LIB.S9S_MB_2U(SCH_1):GND
AJ37    GND VSS182 @S9S_MB_2U_LIB.S9S_MB_2U(SCH_1):GND
AJ35    GND VSS181 @S9S_MB_2U_LIB.S9S_MB_2U(SCH_1):GND
AJ31    GND VSS180 @S9S_MB_2U_LIB.S9S_MB_2U(SCH_1):GND
AJ29    GND VSS179 @S9S_MB_2U_LIB.S9S_MB_2U(SCH_1):GND
AJ25    GND VSS178 @S9S_MB_2U_LIB.S9S_MB_2U(SCH_1):GND
AJ23    GND VSS177 @S9S_MB_2U_LIB.S9S_MB_2U(SCH_1):GND
AJ19    GND VSS176 @S9S_MB_2U_LIB.S9S_MB_2U(SCH_1):GND
AH83    GND VSS175 @S9S_MB_2U_LIB.S9S_MB_2U(SCH_1):GND
 AH8    GND VSS174 @S9S_MB_2U_LIB.S9S_MB_2U(SCH_1):GND
AH79    GND VSS173 @S9S_MB_2U_LIB.S9S_MB_2U(SCH_1):GND
AH77    GND VSS172 @S9S_MB_2U_LIB.S9S_MB_2U(SCH_1):GND
AH75    GND VSS171 @S9S_MB_2U_LIB.S9S_MB_2U(SCH_1):GND
AH71    GND VSS170 @S9S_MB_2U_LIB.S9S_MB_2U(SCH_1):GND
AH69    GND VSS169 @S9S_MB_2U_LIB.S9S_MB_2U(SCH_1):GND
AH65    GND VSS168 @S9S_MB_2U_LIB.S9S_MB_2U(SCH_1):GND
AH63    GND VSS167 @S9S_MB_2U_LIB.S9S_MB_2U(SCH_1):GND
AH59    GND VSS166 @S9S_MB_2U_LIB.S9S_MB_2U(SCH_1):GND
AH57    GND VSS165 @S9S_MB_2U_LIB.S9S_MB_2U(SCH_1):GND
AH53    GND VSS164 @S9S_MB_2U_LIB.S9S_MB_2U(SCH_1):GND
AH51    GND VSS163 @S9S_MB_2U_LIB.S9S_MB_2U(SCH_1):GND
AH47    GND VSS162 @S9S_MB_2U_LIB.S9S_MB_2U(SCH_1):GND
AH44    GND VSS161 @S9S_MB_2U_LIB.S9S_MB_2U(SCH_1):GND
AH40    GND VSS160 @S9S_MB_2U_LIB.S9S_MB_2U(SCH_1):GND
 AH4    GND VSS159 @S9S_MB_2U_LIB.S9S_MB_2U(SCH_1):GND
AH38    GND VSS158 @S9S_MB_2U_LIB.S9S_MB_2U(SCH_1):GND
AH34    GND VSS157 @S9S_MB_2U_LIB.S9S_MB_2U(SCH_1):GND
AH32    GND VSS156 @S9S_MB_2U_LIB.S9S_MB_2U(SCH_1):GND
AH28    GND VSS155 @S9S_MB_2U_LIB.S9S_MB_2U(SCH_1):GND
AH26    GND VSS154 @S9S_MB_2U_LIB.S9S_MB_2U(SCH_1):GND
AH22    GND VSS153 @S9S_MB_2U_LIB.S9S_MB_2U(SCH_1):GND
AH20    GND VSS152 @S9S_MB_2U_LIB.S9S_MB_2U(SCH_1):GND
AH16    GND VSS151 @S9S_MB_2U_LIB.S9S_MB_2U(SCH_1):GND
AH12    GND VSS150 @S9S_MB_2U_LIB.S9S_MB_2U(SCH_1):GND
 AG9    GND VSS149 @S9S_MB_2U_LIB.S9S_MB_2U(SCH_1):GND
AG88    GND VSS148 @S9S_MB_2U_LIB.S9S_MB_2U(SCH_1):GND
AG84    GND VSS147 @S9S_MB_2U_LIB.S9S_MB_2U(SCH_1):GND
AG76    GND VSS146 @S9S_MB_2U_LIB.S9S_MB_2U(SCH_1):GND
AG70    GND VSS145 @S9S_MB_2U_LIB.S9S_MB_2U(SCH_1):GND
AG64    GND VSS144 @S9S_MB_2U_LIB.S9S_MB_2U(SCH_1):GND
AG58    GND VSS143 @S9S_MB_2U_LIB.S9S_MB_2U(SCH_1):GND
AG52    GND VSS142 @S9S_MB_2U_LIB.S9S_MB_2U(SCH_1):GND
 AG5    GND VSS141 @S9S_MB_2U_LIB.S9S_MB_2U(SCH_1):GND
AG45    GND VSS140 @S9S_MB_2U_LIB.S9S_MB_2U(SCH_1):GND
AG39    GND VSS139 @S9S_MB_2U_LIB.S9S_MB_2U(SCH_1):GND
AG33    GND VSS138 @S9S_MB_2U_LIB.S9S_MB_2U(SCH_1):GND
AG27    GND VSS137 @S9S_MB_2U_LIB.S9S_MB_2U(SCH_1):GND
AG21    GND VSS136 @S9S_MB_2U_LIB.S9S_MB_2U(SCH_1):GND
AG13    GND VSS135 @S9S_MB_2U_LIB.S9S_MB_2U(SCH_1):GND
 AG1    GND VSS134 @S9S_MB_2U_LIB.S9S_MB_2U(SCH_1):GND
AF91    GND VSS133 @S9S_MB_2U_LIB.S9S_MB_2U(SCH_1):GND
AF87    GND VSS132 @S9S_MB_2U_LIB.S9S_MB_2U(SCH_1):GND
AF81    GND VSS131 @S9S_MB_2U_LIB.S9S_MB_2U(SCH_1):GND
 AF8    GND VSS130 @S9S_MB_2U_LIB.S9S_MB_2U(SCH_1):GND
AF42    GND VSS129 @S9S_MB_2U_LIB.S9S_MB_2U(SCH_1):GND
 AF4    GND VSS128 @S9S_MB_2U_LIB.S9S_MB_2U(SCH_1):GND
AF16    GND VSS127 @S9S_MB_2U_LIB.S9S_MB_2U(SCH_1):GND
AF12    GND VSS126 @S9S_MB_2U_LIB.S9S_MB_2U(SCH_1):GND
AE88    GND VSS125 @S9S_MB_2U_LIB.S9S_MB_2U(SCH_1):GND
AE84    GND VSS124 @S9S_MB_2U_LIB.S9S_MB_2U(SCH_1):GND
AE78    GND VSS123 @S9S_MB_2U_LIB.S9S_MB_2U(SCH_1):GND
AE76    GND VSS122 @S9S_MB_2U_LIB.S9S_MB_2U(SCH_1):GND
AE74    GND VSS121 @S9S_MB_2U_LIB.S9S_MB_2U(SCH_1):GND
AE72    GND VSS120 @S9S_MB_2U_LIB.S9S_MB_2U(SCH_1):GND
AE70    GND VSS119 @S9S_MB_2U_LIB.S9S_MB_2U(SCH_1):GND
AE68    GND VSS118 @S9S_MB_2U_LIB.S9S_MB_2U(SCH_1):GND
AE66    GND VSS117 @S9S_MB_2U_LIB.S9S_MB_2U(SCH_1):GND
AE64    GND VSS116 @S9S_MB_2U_LIB.S9S_MB_2U(SCH_1):GND
AE62    GND VSS115 @S9S_MB_2U_LIB.S9S_MB_2U(SCH_1):GND
AE60    GND VSS114 @S9S_MB_2U_LIB.S9S_MB_2U(SCH_1):GND
AE58    GND VSS113 @S9S_MB_2U_LIB.S9S_MB_2U(SCH_1):GND
AE56    GND VSS112 @S9S_MB_2U_LIB.S9S_MB_2U(SCH_1):GND
AE54    GND VSS111 @S9S_MB_2U_LIB.S9S_MB_2U(SCH_1):GND
AE52    GND VSS110 @S9S_MB_2U_LIB.S9S_MB_2U(SCH_1):GND
AE50    GND VSS109 @S9S_MB_2U_LIB.S9S_MB_2U(SCH_1):GND
AE48    GND VSS108 @S9S_MB_2U_LIB.S9S_MB_2U(SCH_1):GND
AE45    GND VSS107 @S9S_MB_2U_LIB.S9S_MB_2U(SCH_1):GND
AE43    GND VSS106 @S9S_MB_2U_LIB.S9S_MB_2U(SCH_1):GND
AE41    GND VSS105 @S9S_MB_2U_LIB.S9S_MB_2U(SCH_1):GND
AE39    GND VSS104 @S9S_MB_2U_LIB.S9S_MB_2U(SCH_1):GND
AE37    GND VSS103 @S9S_MB_2U_LIB.S9S_MB_2U(SCH_1):GND
AE35    GND VSS102 @S9S_MB_2U_LIB.S9S_MB_2U(SCH_1):GND
AE33    GND VSS101 @S9S_MB_2U_LIB.S9S_MB_2U(SCH_1):GND
AE31    GND VSS100 @S9S_MB_2U_LIB.S9S_MB_2U(SCH_1):GND
AE29    GND  VSS99 @S9S_MB_2U_LIB.S9S_MB_2U(SCH_1):GND
AE27    GND  VSS98 @S9S_MB_2U_LIB.S9S_MB_2U(SCH_1):GND
AE25    GND  VSS97 @S9S_MB_2U_LIB.S9S_MB_2U(SCH_1):GND
AE23    GND  VSS96 @S9S_MB_2U_LIB.S9S_MB_2U(SCH_1):GND
AE21    GND  VSS95 @S9S_MB_2U_LIB.S9S_MB_2U(SCH_1):GND
AE19    GND  VSS94 @S9S_MB_2U_LIB.S9S_MB_2U(SCH_1):GND
AE17    GND  VSS93 @S9S_MB_2U_LIB.S9S_MB_2U(SCH_1):GND
AD83    GND  VSS92 @S9S_MB_2U_LIB.S9S_MB_2U(SCH_1):GND
 AD8    GND  VSS91 @S9S_MB_2U_LIB.S9S_MB_2U(SCH_1):GND
AD79    GND  VSS90 @S9S_MB_2U_LIB.S9S_MB_2U(SCH_1):GND
AD42    GND  VSS89 @S9S_MB_2U_LIB.S9S_MB_2U(SCH_1):GND
 AD4    GND  VSS88 @S9S_MB_2U_LIB.S9S_MB_2U(SCH_1):GND
AD16    GND  VSS87 @S9S_MB_2U_LIB.S9S_MB_2U(SCH_1):GND
AD12    GND  VSS86 @S9S_MB_2U_LIB.S9S_MB_2U(SCH_1):GND
 AC9    GND  VSS85 @S9S_MB_2U_LIB.S9S_MB_2U(SCH_1):GND
AC88    GND  VSS84 @S9S_MB_2U_LIB.S9S_MB_2U(SCH_1):GND
AC84    GND  VSS83 @S9S_MB_2U_LIB.S9S_MB_2U(SCH_1):GND
AC76    GND  VSS82 @S9S_MB_2U_LIB.S9S_MB_2U(SCH_1):GND
AC70    GND  VSS81 @S9S_MB_2U_LIB.S9S_MB_2U(SCH_1):GND
AC64    GND  VSS80 @S9S_MB_2U_LIB.S9S_MB_2U(SCH_1):GND
AC58    GND  VSS79 @S9S_MB_2U_LIB.S9S_MB_2U(SCH_1):GND
AC52    GND  VSS78 @S9S_MB_2U_LIB.S9S_MB_2U(SCH_1):GND
 AC5    GND  VSS77 @S9S_MB_2U_LIB.S9S_MB_2U(SCH_1):GND
AC45    GND  VSS76 @S9S_MB_2U_LIB.S9S_MB_2U(SCH_1):GND
AC39    GND  VSS75 @S9S_MB_2U_LIB.S9S_MB_2U(SCH_1):GND
AC33    GND  VSS74 @S9S_MB_2U_LIB.S9S_MB_2U(SCH_1):GND
AC27    GND  VSS73 @S9S_MB_2U_LIB.S9S_MB_2U(SCH_1):GND
AC21    GND  VSS72 @S9S_MB_2U_LIB.S9S_MB_2U(SCH_1):GND
AC13    GND  VSS71 @S9S_MB_2U_LIB.S9S_MB_2U(SCH_1):GND
 AC1    GND  VSS70 @S9S_MB_2U_LIB.S9S_MB_2U(SCH_1):GND
AB91    GND  VSS69 @S9S_MB_2U_LIB.S9S_MB_2U(SCH_1):GND
AB87    GND  VSS68 @S9S_MB_2U_LIB.S9S_MB_2U(SCH_1):GND
AB83    GND  VSS67 @S9S_MB_2U_LIB.S9S_MB_2U(SCH_1):GND
AB81    GND  VSS66 @S9S_MB_2U_LIB.S9S_MB_2U(SCH_1):GND
 AB8    GND  VSS65 @S9S_MB_2U_LIB.S9S_MB_2U(SCH_1):GND
AB79    GND  VSS64 @S9S_MB_2U_LIB.S9S_MB_2U(SCH_1):GND
AB77    GND  VSS63 @S9S_MB_2U_LIB.S9S_MB_2U(SCH_1):GND
AB75    GND  VSS62 @S9S_MB_2U_LIB.S9S_MB_2U(SCH_1):GND
AB71    GND  VSS61 @S9S_MB_2U_LIB.S9S_MB_2U(SCH_1):GND
AB69    GND  VSS60 @S9S_MB_2U_LIB.S9S_MB_2U(SCH_1):GND
AB65    GND  VSS59 @S9S_MB_2U_LIB.S9S_MB_2U(SCH_1):GND
AB63    GND  VSS58 @S9S_MB_2U_LIB.S9S_MB_2U(SCH_1):GND
AB59    GND  VSS57 @S9S_MB_2U_LIB.S9S_MB_2U(SCH_1):GND
AB57    GND  VSS56 @S9S_MB_2U_LIB.S9S_MB_2U(SCH_1):GND
AB53    GND  VSS55 @S9S_MB_2U_LIB.S9S_MB_2U(SCH_1):GND
AB51    GND  VSS54 @S9S_MB_2U_LIB.S9S_MB_2U(SCH_1):GND
AB47    GND  VSS53 @S9S_MB_2U_LIB.S9S_MB_2U(SCH_1):GND
AB44    GND  VSS52 @S9S_MB_2U_LIB.S9S_MB_2U(SCH_1):GND
AB40    GND  VSS51 @S9S_MB_2U_LIB.S9S_MB_2U(SCH_1):GND
 AB4    GND  VSS50 @S9S_MB_2U_LIB.S9S_MB_2U(SCH_1):GND
AB38    GND  VSS49 @S9S_MB_2U_LIB.S9S_MB_2U(SCH_1):GND
AB34    GND  VSS48 @S9S_MB_2U_LIB.S9S_MB_2U(SCH_1):GND
AB32    GND  VSS47 @S9S_MB_2U_LIB.S9S_MB_2U(SCH_1):GND
AB28    GND  VSS46 @S9S_MB_2U_LIB.S9S_MB_2U(SCH_1):GND
AB26    GND  VSS45 @S9S_MB_2U_LIB.S9S_MB_2U(SCH_1):GND
AB22    GND  VSS44 @S9S_MB_2U_LIB.S9S_MB_2U(SCH_1):GND
AB20    GND  VSS43 @S9S_MB_2U_LIB.S9S_MB_2U(SCH_1):GND
AB16    GND  VSS42 @S9S_MB_2U_LIB.S9S_MB_2U(SCH_1):GND
AB12    GND  VSS41 @S9S_MB_2U_LIB.S9S_MB_2U(SCH_1):GND
AA88    GND  VSS40 @S9S_MB_2U_LIB.S9S_MB_2U(SCH_1):GND
AA84    GND  VSS39 @S9S_MB_2U_LIB.S9S_MB_2U(SCH_1):GND
AA82    GND  VSS38 @S9S_MB_2U_LIB.S9S_MB_2U(SCH_1):GND


DRAWING: @S9S_MB_2U_LIB.S9S_MB_2U(SCH_1):PAGE73 

SOCKET4677_AZIF0045P001C01CS-SA  I2  U1
 Y73    GND VSS1833 @S9S_MB_2U_LIB.S9S_MB_2U(SCH_1):GND
  Y8    GND VSS1832 @S9S_MB_2U_LIB.S9S_MB_2U(SCH_1):GND
 Y55    GND VSS1831 @S9S_MB_2U_LIB.S9S_MB_2U(SCH_1):GND
 Y49    GND VSS1830 @S9S_MB_2U_LIB.S9S_MB_2U(SCH_1):GND
 Y67    GND VSS1829 @S9S_MB_2U_LIB.S9S_MB_2U(SCH_1):GND
 Y61    GND VSS1828 @S9S_MB_2U_LIB.S9S_MB_2U(SCH_1):GND
 Y42    GND VSS1827 @S9S_MB_2U_LIB.S9S_MB_2U(SCH_1):GND
  Y4    GND VSS1826 @S9S_MB_2U_LIB.S9S_MB_2U(SCH_1):GND
 Y36    GND VSS1825 @S9S_MB_2U_LIB.S9S_MB_2U(SCH_1):GND
 Y30    GND VSS1824 @S9S_MB_2U_LIB.S9S_MB_2U(SCH_1):GND
 Y24    GND VSS1823 @S9S_MB_2U_LIB.S9S_MB_2U(SCH_1):GND
 Y18    GND VSS1822 @S9S_MB_2U_LIB.S9S_MB_2U(SCH_1):GND
 Y16    GND VSS1821 @S9S_MB_2U_LIB.S9S_MB_2U(SCH_1):GND
 Y12    GND VSS1820 @S9S_MB_2U_LIB.S9S_MB_2U(SCH_1):GND
  W9    GND VSS1819 @S9S_MB_2U_LIB.S9S_MB_2U(SCH_1):GND
 W88    GND VSS1818 @S9S_MB_2U_LIB.S9S_MB_2U(SCH_1):GND
 W84    GND VSS1817 @S9S_MB_2U_LIB.S9S_MB_2U(SCH_1):GND
 W39    GND VSS1816 @S9S_MB_2U_LIB.S9S_MB_2U(SCH_1):GND
 W52    GND VSS1815 @S9S_MB_2U_LIB.S9S_MB_2U(SCH_1):GND
  W5    GND VSS1814 @S9S_MB_2U_LIB.S9S_MB_2U(SCH_1):GND
 V87    GND VSS1813 @S9S_MB_2U_LIB.S9S_MB_2U(SCH_1):GND
  V8    GND VSS1812 @S9S_MB_2U_LIB.S9S_MB_2U(SCH_1):GND
 V79    GND VSS1811 @S9S_MB_2U_LIB.S9S_MB_2U(SCH_1):GND
 V77    GND VSS1810 @S9S_MB_2U_LIB.S9S_MB_2U(SCH_1):GND
 W13    GND VSS1809 @S9S_MB_2U_LIB.S9S_MB_2U(SCH_1):GND
  W1    GND VSS1808 @S9S_MB_2U_LIB.S9S_MB_2U(SCH_1):GND
 V91    GND VSS1807 @S9S_MB_2U_LIB.S9S_MB_2U(SCH_1):GND
 V75    GND VSS1806 @S9S_MB_2U_LIB.S9S_MB_2U(SCH_1):GND
 V69    GND VSS1805 @S9S_MB_2U_LIB.S9S_MB_2U(SCH_1):GND
 V67    GND VSS1804 @S9S_MB_2U_LIB.S9S_MB_2U(SCH_1):GND
 V65    GND VSS1803 @S9S_MB_2U_LIB.S9S_MB_2U(SCH_1):GND
 V63    GND VSS1802 @S9S_MB_2U_LIB.S9S_MB_2U(SCH_1):GND
 V73    GND VSS1801 @S9S_MB_2U_LIB.S9S_MB_2U(SCH_1):GND
 V71    GND VSS1800 @S9S_MB_2U_LIB.S9S_MB_2U(SCH_1):GND
 V61    GND VSS1799 @S9S_MB_2U_LIB.S9S_MB_2U(SCH_1):GND
 V59    GND VSS1798 @S9S_MB_2U_LIB.S9S_MB_2U(SCH_1):GND
 V57    GND VSS1797 @S9S_MB_2U_LIB.S9S_MB_2U(SCH_1):GND
 V55    GND VSS1796 @S9S_MB_2U_LIB.S9S_MB_2U(SCH_1):GND
 V53    GND VSS1795 @S9S_MB_2U_LIB.S9S_MB_2U(SCH_1):GND
 V51    GND VSS1794 @S9S_MB_2U_LIB.S9S_MB_2U(SCH_1):GND
 V47    GND VSS1793 @S9S_MB_2U_LIB.S9S_MB_2U(SCH_1):GND
 V44    GND VSS1792 @S9S_MB_2U_LIB.S9S_MB_2U(SCH_1):GND
 V42    GND VSS1791 @S9S_MB_2U_LIB.S9S_MB_2U(SCH_1):GND
 V40    GND VSS1790 @S9S_MB_2U_LIB.S9S_MB_2U(SCH_1):GND
 V49    GND VSS1789 @S9S_MB_2U_LIB.S9S_MB_2U(SCH_1):GND
  V4    GND VSS1788 @S9S_MB_2U_LIB.S9S_MB_2U(SCH_1):GND
 V38    GND VSS1787 @S9S_MB_2U_LIB.S9S_MB_2U(SCH_1):GND
 V36    GND VSS1786 @S9S_MB_2U_LIB.S9S_MB_2U(SCH_1):GND
 V34    GND VSS1785 @S9S_MB_2U_LIB.S9S_MB_2U(SCH_1):GND
 V32    GND VSS1784 @S9S_MB_2U_LIB.S9S_MB_2U(SCH_1):GND
 V30    GND VSS1783 @S9S_MB_2U_LIB.S9S_MB_2U(SCH_1):GND
 V28    GND VSS1782 @S9S_MB_2U_LIB.S9S_MB_2U(SCH_1):GND
 V26    GND VSS1781 @S9S_MB_2U_LIB.S9S_MB_2U(SCH_1):GND
 V24    GND VSS1780 @S9S_MB_2U_LIB.S9S_MB_2U(SCH_1):GND
 V22    GND VSS1779 @S9S_MB_2U_LIB.S9S_MB_2U(SCH_1):GND
 V20    GND VSS1778 @S9S_MB_2U_LIB.S9S_MB_2U(SCH_1):GND
 V18    GND VSS1777 @S9S_MB_2U_LIB.S9S_MB_2U(SCH_1):GND
 V16    GND VSS1776 @S9S_MB_2U_LIB.S9S_MB_2U(SCH_1):GND
 V12    GND VSS1775 @S9S_MB_2U_LIB.S9S_MB_2U(SCH_1):GND
 U88    GND VSS1774 @S9S_MB_2U_LIB.S9S_MB_2U(SCH_1):GND
 U84    GND VSS1773 @S9S_MB_2U_LIB.S9S_MB_2U(SCH_1):GND
 U82    GND VSS1772 @S9S_MB_2U_LIB.S9S_MB_2U(SCH_1):GND
 U39    GND VSS1771 @S9S_MB_2U_LIB.S9S_MB_2U(SCH_1):GND
 T83    GND VSS1770 @S9S_MB_2U_LIB.S9S_MB_2U(SCH_1):GND
  T8    GND VSS1769 @S9S_MB_2U_LIB.S9S_MB_2U(SCH_1):GND
 T79    GND VSS1768 @S9S_MB_2U_LIB.S9S_MB_2U(SCH_1):GND
 T73    GND VSS1767 @S9S_MB_2U_LIB.S9S_MB_2U(SCH_1):GND
 U52    GND VSS1766 @S9S_MB_2U_LIB.S9S_MB_2U(SCH_1):GND
 T67    GND VSS1765 @S9S_MB_2U_LIB.S9S_MB_2U(SCH_1):GND
 T61    GND VSS1764 @S9S_MB_2U_LIB.S9S_MB_2U(SCH_1):GND
 T42    GND VSS1763 @S9S_MB_2U_LIB.S9S_MB_2U(SCH_1):GND
  T4    GND VSS1762 @S9S_MB_2U_LIB.S9S_MB_2U(SCH_1):GND
 T30    GND VSS1761 @S9S_MB_2U_LIB.S9S_MB_2U(SCH_1):GND
 T24    GND VSS1760 @S9S_MB_2U_LIB.S9S_MB_2U(SCH_1):GND
  R9    GND VSS1759 @S9S_MB_2U_LIB.S9S_MB_2U(SCH_1):GND
 R88    GND VSS1758 @S9S_MB_2U_LIB.S9S_MB_2U(SCH_1):GND
 R84    GND VSS1757 @S9S_MB_2U_LIB.S9S_MB_2U(SCH_1):GND
 R78    GND VSS1756 @S9S_MB_2U_LIB.S9S_MB_2U(SCH_1):GND
 R74    GND VSS1755 @S9S_MB_2U_LIB.S9S_MB_2U(SCH_1):GND
 R72    GND VSS1754 @S9S_MB_2U_LIB.S9S_MB_2U(SCH_1):GND
 R68    GND VSS1753 @S9S_MB_2U_LIB.S9S_MB_2U(SCH_1):GND
 R62    GND VSS1752 @S9S_MB_2U_LIB.S9S_MB_2U(SCH_1):GND
 R56    GND VSS1751 @S9S_MB_2U_LIB.S9S_MB_2U(SCH_1):GND
 T55    GND VSS1750 @S9S_MB_2U_LIB.S9S_MB_2U(SCH_1):GND
 T49    GND VSS1749 @S9S_MB_2U_LIB.S9S_MB_2U(SCH_1):GND
 R54    GND VSS1748 @S9S_MB_2U_LIB.S9S_MB_2U(SCH_1):GND
 R50    GND VSS1747 @S9S_MB_2U_LIB.S9S_MB_2U(SCH_1):GND
 T36    GND VSS1746 @S9S_MB_2U_LIB.S9S_MB_2U(SCH_1):GND
  R5    GND VSS1745 @S9S_MB_2U_LIB.S9S_MB_2U(SCH_1):GND
 R43    GND VSS1744 @S9S_MB_2U_LIB.S9S_MB_2U(SCH_1):GND
 R41    GND VSS1743 @S9S_MB_2U_LIB.S9S_MB_2U(SCH_1):GND
 R37    GND VSS1742 @S9S_MB_2U_LIB.S9S_MB_2U(SCH_1):GND
 T18    GND VSS1741 @S9S_MB_2U_LIB.S9S_MB_2U(SCH_1):GND
 T16    GND VSS1740 @S9S_MB_2U_LIB.S9S_MB_2U(SCH_1):GND
 T12    GND VSS1739 @S9S_MB_2U_LIB.S9S_MB_2U(SCH_1):GND
 R35    GND VSS1738 @S9S_MB_2U_LIB.S9S_MB_2U(SCH_1):GND
 R31    GND VSS1737 @S9S_MB_2U_LIB.S9S_MB_2U(SCH_1):GND
 R29    GND VSS1736 @S9S_MB_2U_LIB.S9S_MB_2U(SCH_1):GND
 R25    GND VSS1735 @S9S_MB_2U_LIB.S9S_MB_2U(SCH_1):GND
 R17    GND VSS1734 @S9S_MB_2U_LIB.S9S_MB_2U(SCH_1):GND
 R13    GND VSS1733 @S9S_MB_2U_LIB.S9S_MB_2U(SCH_1):GND
 P91    GND VSS1732 @S9S_MB_2U_LIB.S9S_MB_2U(SCH_1):GND
 P87    GND VSS1731 @S9S_MB_2U_LIB.S9S_MB_2U(SCH_1):GND
 R66    GND VSS1730 @S9S_MB_2U_LIB.S9S_MB_2U(SCH_1):GND
  P8    GND VSS1729 @S9S_MB_2U_LIB.S9S_MB_2U(SCH_1):GND
 R60    GND VSS1728 @S9S_MB_2U_LIB.S9S_MB_2U(SCH_1):GND
 P77    GND VSS1727 @S9S_MB_2U_LIB.S9S_MB_2U(SCH_1):GND
 P75    GND VSS1726 @S9S_MB_2U_LIB.S9S_MB_2U(SCH_1):GND
 P69    GND VSS1725 @S9S_MB_2U_LIB.S9S_MB_2U(SCH_1):GND
 P65    GND VSS1724 @S9S_MB_2U_LIB.S9S_MB_2U(SCH_1):GND
 R48    GND VSS1723 @S9S_MB_2U_LIB.S9S_MB_2U(SCH_1):GND
 P63    GND VSS1722 @S9S_MB_2U_LIB.S9S_MB_2U(SCH_1):GND
 P59    GND VSS1721 @S9S_MB_2U_LIB.S9S_MB_2U(SCH_1):GND
 P53    GND VSS1720 @S9S_MB_2U_LIB.S9S_MB_2U(SCH_1):GND
 P47    GND VSS1719 @S9S_MB_2U_LIB.S9S_MB_2U(SCH_1):GND
 P44    GND VSS1718 @S9S_MB_2U_LIB.S9S_MB_2U(SCH_1):GND
 P40    GND VSS1717 @S9S_MB_2U_LIB.S9S_MB_2U(SCH_1):GND
  P4    GND VSS1716 @S9S_MB_2U_LIB.S9S_MB_2U(SCH_1):GND
 R23    GND VSS1715 @S9S_MB_2U_LIB.S9S_MB_2U(SCH_1):GND
 R19    GND VSS1714 @S9S_MB_2U_LIB.S9S_MB_2U(SCH_1):GND
 P38    GND VSS1713 @S9S_MB_2U_LIB.S9S_MB_2U(SCH_1):GND
 P34    GND VSS1712 @S9S_MB_2U_LIB.S9S_MB_2U(SCH_1):GND
  R1    GND VSS1711 @S9S_MB_2U_LIB.S9S_MB_2U(SCH_1):GND
 P28    GND VSS1710 @S9S_MB_2U_LIB.S9S_MB_2U(SCH_1):GND
 P26    GND VSS1709 @S9S_MB_2U_LIB.S9S_MB_2U(SCH_1):GND
 P22    GND VSS1708 @S9S_MB_2U_LIB.S9S_MB_2U(SCH_1):GND
 P20    GND VSS1707 @S9S_MB_2U_LIB.S9S_MB_2U(SCH_1):GND
 P16    GND VSS1706 @S9S_MB_2U_LIB.S9S_MB_2U(SCH_1):GND
 P12    GND VSS1705 @S9S_MB_2U_LIB.S9S_MB_2U(SCH_1):GND
 P71    GND VSS1704 @S9S_MB_2U_LIB.S9S_MB_2U(SCH_1):GND
 N88    GND VSS1703 @S9S_MB_2U_LIB.S9S_MB_2U(SCH_1):GND
 N84    GND VSS1702 @S9S_MB_2U_LIB.S9S_MB_2U(SCH_1):GND
 N82    GND VSS1701 @S9S_MB_2U_LIB.S9S_MB_2U(SCH_1):GND
 N80    GND VSS1700 @S9S_MB_2U_LIB.S9S_MB_2U(SCH_1):GND
 P57    GND VSS1699 @S9S_MB_2U_LIB.S9S_MB_2U(SCH_1):GND
 N78    GND VSS1698 @S9S_MB_2U_LIB.S9S_MB_2U(SCH_1):GND
 P51    GND VSS1697 @S9S_MB_2U_LIB.S9S_MB_2U(SCH_1):GND
 N76    GND VSS1696 @S9S_MB_2U_LIB.S9S_MB_2U(SCH_1):GND
 P32    GND VSS1690 @S9S_MB_2U_LIB.S9S_MB_2U(SCH_1):GND
AA80    GND  VSS37 @S9S_MB_2U_LIB.S9S_MB_2U(SCH_1):GND
AA78    GND  VSS36 @S9S_MB_2U_LIB.S9S_MB_2U(SCH_1):GND
AA74    GND  VSS35 @S9S_MB_2U_LIB.S9S_MB_2U(SCH_1):GND
AA72    GND  VSS34 @S9S_MB_2U_LIB.S9S_MB_2U(SCH_1):GND
AA68    GND  VSS33 @S9S_MB_2U_LIB.S9S_MB_2U(SCH_1):GND
AA66    GND  VSS32 @S9S_MB_2U_LIB.S9S_MB_2U(SCH_1):GND
AA62    GND  VSS31 @S9S_MB_2U_LIB.S9S_MB_2U(SCH_1):GND
AA60    GND  VSS30 @S9S_MB_2U_LIB.S9S_MB_2U(SCH_1):GND
AA56    GND  VSS29 @S9S_MB_2U_LIB.S9S_MB_2U(SCH_1):GND
AA54    GND  VSS28 @S9S_MB_2U_LIB.S9S_MB_2U(SCH_1):GND
AA50    GND  VSS27 @S9S_MB_2U_LIB.S9S_MB_2U(SCH_1):GND
AA48    GND  VSS26 @S9S_MB_2U_LIB.S9S_MB_2U(SCH_1):GND
AA43    GND  VSS25 @S9S_MB_2U_LIB.S9S_MB_2U(SCH_1):GND
AA41    GND  VSS24 @S9S_MB_2U_LIB.S9S_MB_2U(SCH_1):GND
AA37    GND  VSS23 @S9S_MB_2U_LIB.S9S_MB_2U(SCH_1):GND
AA35    GND  VSS22 @S9S_MB_2U_LIB.S9S_MB_2U(SCH_1):GND
AA31    GND  VSS21 @S9S_MB_2U_LIB.S9S_MB_2U(SCH_1):GND
AA29    GND  VSS20 @S9S_MB_2U_LIB.S9S_MB_2U(SCH_1):GND
AA25    GND  VSS19 @S9S_MB_2U_LIB.S9S_MB_2U(SCH_1):GND
AA23    GND  VSS18 @S9S_MB_2U_LIB.S9S_MB_2U(SCH_1):GND
AA19    GND  VSS17 @S9S_MB_2U_LIB.S9S_MB_2U(SCH_1):GND

SOCKET4677_AZIF0045P001C01CS-SA  I5  U1
 N70    GND VSS1695 @S9S_MB_2U_LIB.S9S_MB_2U(SCH_1):GND
 N58    GND VSS1694 @S9S_MB_2U_LIB.S9S_MB_2U(SCH_1):GND
 N52    GND VSS1693 @S9S_MB_2U_LIB.S9S_MB_2U(SCH_1):GND
 N45    GND VSS1692 @S9S_MB_2U_LIB.S9S_MB_2U(SCH_1):GND
 N33    GND VSS1691 @S9S_MB_2U_LIB.S9S_MB_2U(SCH_1):GND
 N27    GND VSS1689 @S9S_MB_2U_LIB.S9S_MB_2U(SCH_1):GND
 N15    GND VSS1688 @S9S_MB_2U_LIB.S9S_MB_2U(SCH_1):GND
 M83    GND VSS1687 @S9S_MB_2U_LIB.S9S_MB_2U(SCH_1):GND
 M81    GND VSS1686 @S9S_MB_2U_LIB.S9S_MB_2U(SCH_1):GND
 L78    GND VSS1685 @S9S_MB_2U_LIB.S9S_MB_2U(SCH_1):GND
 L76    GND VSS1684 @S9S_MB_2U_LIB.S9S_MB_2U(SCH_1):GND
 L74    GND VSS1683 @S9S_MB_2U_LIB.S9S_MB_2U(SCH_1):GND
 L72    GND VSS1682 @S9S_MB_2U_LIB.S9S_MB_2U(SCH_1):GND
 L68    GND VSS1681 @S9S_MB_2U_LIB.S9S_MB_2U(SCH_1):GND
 L66    GND VSS1680 @S9S_MB_2U_LIB.S9S_MB_2U(SCH_1):GND
 L64    GND VSS1679 @S9S_MB_2U_LIB.S9S_MB_2U(SCH_1):GND
 L62    GND VSS1678 @S9S_MB_2U_LIB.S9S_MB_2U(SCH_1):GND
 L60    GND VSS1677 @S9S_MB_2U_LIB.S9S_MB_2U(SCH_1):GND
 L56    GND VSS1676 @S9S_MB_2U_LIB.S9S_MB_2U(SCH_1):GND
 N64    GND VSS1675 @S9S_MB_2U_LIB.S9S_MB_2U(SCH_1):GND
 L54    GND VSS1674 @S9S_MB_2U_LIB.S9S_MB_2U(SCH_1):GND
 L52    GND VSS1673 @S9S_MB_2U_LIB.S9S_MB_2U(SCH_1):GND
 L50    GND VSS1672 @S9S_MB_2U_LIB.S9S_MB_2U(SCH_1):GND
  L5    GND VSS1671 @S9S_MB_2U_LIB.S9S_MB_2U(SCH_1):GND
 L48    GND VSS1670 @S9S_MB_2U_LIB.S9S_MB_2U(SCH_1):GND
 N39    GND VSS1669 @S9S_MB_2U_LIB.S9S_MB_2U(SCH_1):GND
 L45    GND VSS1668 @S9S_MB_2U_LIB.S9S_MB_2U(SCH_1):GND
 L43    GND VSS1667 @S9S_MB_2U_LIB.S9S_MB_2U(SCH_1):GND
 L41    GND VSS1666 @S9S_MB_2U_LIB.S9S_MB_2U(SCH_1):GND
 L39    GND VSS1665 @S9S_MB_2U_LIB.S9S_MB_2U(SCH_1):GND
 N21    GND VSS1664 @S9S_MB_2U_LIB.S9S_MB_2U(SCH_1):GND
 L37    GND VSS1663 @S9S_MB_2U_LIB.S9S_MB_2U(SCH_1):GND
 L35    GND VSS1662 @S9S_MB_2U_LIB.S9S_MB_2U(SCH_1):GND
 L33    GND VSS1661 @S9S_MB_2U_LIB.S9S_MB_2U(SCH_1):GND
 L31    GND VSS1660 @S9S_MB_2U_LIB.S9S_MB_2U(SCH_1):GND
 L29    GND VSS1659 @S9S_MB_2U_LIB.S9S_MB_2U(SCH_1):GND
 L27    GND VSS1658 @S9S_MB_2U_LIB.S9S_MB_2U(SCH_1):GND
  M8    GND VSS1657 @S9S_MB_2U_LIB.S9S_MB_2U(SCH_1):GND
 L25    GND VSS1656 @S9S_MB_2U_LIB.S9S_MB_2U(SCH_1):GND
 L23    GND VSS1655 @S9S_MB_2U_LIB.S9S_MB_2U(SCH_1):GND
 M49    GND VSS1654 @S9S_MB_2U_LIB.S9S_MB_2U(SCH_1):GND
 M42    GND VSS1653 @S9S_MB_2U_LIB.S9S_MB_2U(SCH_1):GND
  M4    GND VSS1652 @S9S_MB_2U_LIB.S9S_MB_2U(SCH_1):GND
 L21    GND VSS1651 @S9S_MB_2U_LIB.S9S_MB_2U(SCH_1):GND
 L17    GND VSS1650 @S9S_MB_2U_LIB.S9S_MB_2U(SCH_1):GND
 M12    GND VSS1649 @S9S_MB_2U_LIB.S9S_MB_2U(SCH_1):GND
 L90    GND VSS1648 @S9S_MB_2U_LIB.S9S_MB_2U(SCH_1):GND
  L9    GND VSS1647 @S9S_MB_2U_LIB.S9S_MB_2U(SCH_1):GND
 L88    GND VSS1646 @S9S_MB_2U_LIB.S9S_MB_2U(SCH_1):GND
 L15    GND VSS1645 @S9S_MB_2U_LIB.S9S_MB_2U(SCH_1):GND
 L13    GND VSS1644 @S9S_MB_2U_LIB.S9S_MB_2U(SCH_1):GND
 K85    GND VSS1643 @S9S_MB_2U_LIB.S9S_MB_2U(SCH_1):GND
 K83    GND VSS1642 @S9S_MB_2U_LIB.S9S_MB_2U(SCH_1):GND
  K8    GND VSS1641 @S9S_MB_2U_LIB.S9S_MB_2U(SCH_1):GND
 L70    GND VSS1640 @S9S_MB_2U_LIB.S9S_MB_2U(SCH_1):GND
 K77    GND VSS1639 @S9S_MB_2U_LIB.S9S_MB_2U(SCH_1):GND
 J86    GND VSS1638 @S9S_MB_2U_LIB.S9S_MB_2U(SCH_1):GND
 J84    GND VSS1637 @S9S_MB_2U_LIB.S9S_MB_2U(SCH_1):GND
 J78    GND VSS1636 @S9S_MB_2U_LIB.S9S_MB_2U(SCH_1):GND
 J76    GND VSS1635 @S9S_MB_2U_LIB.S9S_MB_2U(SCH_1):GND
 L58    GND VSS1634 @S9S_MB_2U_LIB.S9S_MB_2U(SCH_1):GND
 J58    GND VSS1633 @S9S_MB_2U_LIB.S9S_MB_2U(SCH_1):GND
 J52    GND VSS1632 @S9S_MB_2U_LIB.S9S_MB_2U(SCH_1):GND
 J45    GND VSS1631 @S9S_MB_2U_LIB.S9S_MB_2U(SCH_1):GND
 J33    GND VSS1630 @S9S_MB_2U_LIB.S9S_MB_2U(SCH_1):GND
 J27    GND VSS1629 @S9S_MB_2U_LIB.S9S_MB_2U(SCH_1):GND
 J15    GND VSS1628 @S9S_MB_2U_LIB.S9S_MB_2U(SCH_1):GND
 H81    GND VSS1627 @S9S_MB_2U_LIB.S9S_MB_2U(SCH_1):GND
  H8    GND VSS1626 @S9S_MB_2U_LIB.S9S_MB_2U(SCH_1):GND
 H79    GND VSS1625 @S9S_MB_2U_LIB.S9S_MB_2U(SCH_1):GND
 H71    GND VSS1624 @S9S_MB_2U_LIB.S9S_MB_2U(SCH_1):GND
 H69    GND VSS1623 @S9S_MB_2U_LIB.S9S_MB_2U(SCH_1):GND
 H63    GND VSS1622 @S9S_MB_2U_LIB.S9S_MB_2U(SCH_1):GND
  H6    GND VSS1621 @S9S_MB_2U_LIB.S9S_MB_2U(SCH_1):GND
 H59    GND VSS1620 @S9S_MB_2U_LIB.S9S_MB_2U(SCH_1):GND
 H53    GND VSS1619 @S9S_MB_2U_LIB.S9S_MB_2U(SCH_1):GND
 H47    GND VSS1618 @S9S_MB_2U_LIB.S9S_MB_2U(SCH_1):GND
 H44    GND VSS1617 @S9S_MB_2U_LIB.S9S_MB_2U(SCH_1):GND
 H40    GND VSS1616 @S9S_MB_2U_LIB.S9S_MB_2U(SCH_1):GND
  H4    GND VSS1615 @S9S_MB_2U_LIB.S9S_MB_2U(SCH_1):GND
 L19    GND VSS1614 @S9S_MB_2U_LIB.S9S_MB_2U(SCH_1):GND
 H38    GND VSS1613 @S9S_MB_2U_LIB.S9S_MB_2U(SCH_1):GND
 H34    GND VSS1612 @S9S_MB_2U_LIB.S9S_MB_2U(SCH_1):GND
 H32    GND VSS1611 @S9S_MB_2U_LIB.S9S_MB_2U(SCH_1):GND
 H28    GND VSS1610 @S9S_MB_2U_LIB.S9S_MB_2U(SCH_1):GND
 H26    GND VSS1609 @S9S_MB_2U_LIB.S9S_MB_2U(SCH_1):GND
 H22    GND VSS1608 @S9S_MB_2U_LIB.S9S_MB_2U(SCH_1):GND
 H20    GND VSS1607 @S9S_MB_2U_LIB.S9S_MB_2U(SCH_1):GND
 H16    GND VSS1606 @S9S_MB_2U_LIB.S9S_MB_2U(SCH_1):GND
 H10    GND VSS1605 @S9S_MB_2U_LIB.S9S_MB_2U(SCH_1):GND
 G90    GND VSS1604 @S9S_MB_2U_LIB.S9S_MB_2U(SCH_1):GND
 K49    GND VSS1603 @S9S_MB_2U_LIB.S9S_MB_2U(SCH_1):GND
 K42    GND VSS1602 @S9S_MB_2U_LIB.S9S_MB_2U(SCH_1):GND
 G88    GND VSS1601 @S9S_MB_2U_LIB.S9S_MB_2U(SCH_1):GND
 G84    GND VSS1600 @S9S_MB_2U_LIB.S9S_MB_2U(SCH_1):GND
  K2    GND VSS1599 @S9S_MB_2U_LIB.S9S_MB_2U(SCH_1):GND
 K14    GND VSS1598 @S9S_MB_2U_LIB.S9S_MB_2U(SCH_1):GND
 K12    GND VSS1597 @S9S_MB_2U_LIB.S9S_MB_2U(SCH_1):GND
  J9    GND VSS1596 @S9S_MB_2U_LIB.S9S_MB_2U(SCH_1):GND
 J88    GND VSS1595 @S9S_MB_2U_LIB.S9S_MB_2U(SCH_1):GND
 G72    GND VSS1594 @S9S_MB_2U_LIB.S9S_MB_2U(SCH_1):GND
 G62    GND VSS1593 @S9S_MB_2U_LIB.S9S_MB_2U(SCH_1):GND
 G56    GND VSS1592 @S9S_MB_2U_LIB.S9S_MB_2U(SCH_1):GND
 G54    GND VSS1591 @S9S_MB_2U_LIB.S9S_MB_2U(SCH_1):GND
 G50    GND VSS1590 @S9S_MB_2U_LIB.S9S_MB_2U(SCH_1):GND
 J70    GND VSS1589 @S9S_MB_2U_LIB.S9S_MB_2U(SCH_1):GND
 G43    GND VSS1588 @S9S_MB_2U_LIB.S9S_MB_2U(SCH_1):GND
 J64    GND VSS1587 @S9S_MB_2U_LIB.S9S_MB_2U(SCH_1):GND
 G41    GND VSS1586 @S9S_MB_2U_LIB.S9S_MB_2U(SCH_1):GND
 G37    GND VSS1585 @S9S_MB_2U_LIB.S9S_MB_2U(SCH_1):GND
 G31    GND VSS1584 @S9S_MB_2U_LIB.S9S_MB_2U(SCH_1):GND
 G29    GND VSS1583 @S9S_MB_2U_LIB.S9S_MB_2U(SCH_1):GND
  J5    GND VSS1582 @S9S_MB_2U_LIB.S9S_MB_2U(SCH_1):GND
 G23    GND VSS1581 @S9S_MB_2U_LIB.S9S_MB_2U(SCH_1):GND
 J39    GND VSS1580 @S9S_MB_2U_LIB.S9S_MB_2U(SCH_1):GND
 G19    GND VSS1579 @S9S_MB_2U_LIB.S9S_MB_2U(SCH_1):GND
 G13    GND VSS1578 @S9S_MB_2U_LIB.S9S_MB_2U(SCH_1):GND
 F89    GND VSS1577 @S9S_MB_2U_LIB.S9S_MB_2U(SCH_1):GND
 F83    GND VSS1576 @S9S_MB_2U_LIB.S9S_MB_2U(SCH_1):GND
 J21    GND VSS1575 @S9S_MB_2U_LIB.S9S_MB_2U(SCH_1):GND
 F49    GND VSS1574 @S9S_MB_2U_LIB.S9S_MB_2U(SCH_1):GND
  F4    GND VSS1573 @S9S_MB_2U_LIB.S9S_MB_2U(SCH_1):GND
 F36    GND VSS1572 @S9S_MB_2U_LIB.S9S_MB_2U(SCH_1):GND
 F30    GND VSS1571 @S9S_MB_2U_LIB.S9S_MB_2U(SCH_1):GND
 F24    GND VSS1570 @S9S_MB_2U_LIB.S9S_MB_2U(SCH_1):GND
 H75    GND VSS1567 @S9S_MB_2U_LIB.S9S_MB_2U(SCH_1):GND
 H65    GND VSS1564 @S9S_MB_2U_LIB.S9S_MB_2U(SCH_1):GND
 H57    GND VSS1560 @S9S_MB_2U_LIB.S9S_MB_2U(SCH_1):GND
 H51    GND VSS1558 @S9S_MB_2U_LIB.S9S_MB_2U(SCH_1):GND
  H2    GND VSS1546 @S9S_MB_2U_LIB.S9S_MB_2U(SCH_1):GND
 H14    GND VSS1544 @S9S_MB_2U_LIB.S9S_MB_2U(SCH_1):GND
 G74    GND VSS1538 @S9S_MB_2U_LIB.S9S_MB_2U(SCH_1):GND
  G7    GND VSS1536 @S9S_MB_2U_LIB.S9S_MB_2U(SCH_1):GND
 G68    GND VSS1535 @S9S_MB_2U_LIB.S9S_MB_2U(SCH_1):GND
 G66    GND VSS1534 @S9S_MB_2U_LIB.S9S_MB_2U(SCH_1):GND
 G60    GND VSS1532 @S9S_MB_2U_LIB.S9S_MB_2U(SCH_1):GND
 G48    GND VSS1527 @S9S_MB_2U_LIB.S9S_MB_2U(SCH_1):GND
 G35    GND VSS1523 @S9S_MB_2U_LIB.S9S_MB_2U(SCH_1):GND
  G3    GND VSS1521 @S9S_MB_2U_LIB.S9S_MB_2U(SCH_1):GND
 G25    GND VSS1519 @S9S_MB_2U_LIB.S9S_MB_2U(SCH_1):GND
 G17    GND VSS1516 @S9S_MB_2U_LIB.S9S_MB_2U(SCH_1):GND
 G11    GND VSS1514 @S9S_MB_2U_LIB.S9S_MB_2U(SCH_1):GND
 F79    GND VSS1511 @S9S_MB_2U_LIB.S9S_MB_2U(SCH_1):GND
 F73    GND VSS1510 @S9S_MB_2U_LIB.S9S_MB_2U(SCH_1):GND
 F67    GND VSS1509 @S9S_MB_2U_LIB.S9S_MB_2U(SCH_1):GND
 F61    GND VSS1508 @S9S_MB_2U_LIB.S9S_MB_2U(SCH_1):GND
  F6    GND VSS1507 @S9S_MB_2U_LIB.S9S_MB_2U(SCH_1):GND
 F55    GND VSS1504 @S9S_MB_2U_LIB.S9S_MB_2U(SCH_1):GND
 F42    GND VSS1502 @S9S_MB_2U_LIB.S9S_MB_2U(SCH_1):GND
 F18    GND VSS1495 @S9S_MB_2U_LIB.S9S_MB_2U(SCH_1):GND
 F12    GND VSS1494 @S9S_MB_2U_LIB.S9S_MB_2U(SCH_1):GND
 E86    GND VSS1273 @S9S_MB_2U_LIB.S9S_MB_2U(SCH_1):GND
 E76    GND VSS1272 @S9S_MB_2U_LIB.S9S_MB_2U(SCH_1):GND
 E78    GND VSS1131 @S9S_MB_2U_LIB.S9S_MB_2U(SCH_1):GND
 E74    GND VSS1129 @S9S_MB_2U_LIB.S9S_MB_2U(SCH_1):GND
 E52    GND VSS1126 @S9S_MB_2U_LIB.S9S_MB_2U(SCH_1):GND

SOCKET4677_AZIF0045P001C01CS-SA  I8  U1
 E39    GND VSS1271 @S9S_MB_2U_LIB.S9S_MB_2U(SCH_1):GND
  E5    GND VSS1125 @S9S_MB_2U_LIB.S9S_MB_2U(SCH_1):GND
 D83    GND VSS907 @S9S_MB_2U_LIB.S9S_MB_2U(SCH_1):GND
 D81    GND VSS906 @S9S_MB_2U_LIB.S9S_MB_2U(SCH_1):GND
 D71    GND VSS902 @S9S_MB_2U_LIB.S9S_MB_2U(SCH_1):GND
 D69    GND VSS901 @S9S_MB_2U_LIB.S9S_MB_2U(SCH_1):GND
 D61    GND VSS900 @S9S_MB_2U_LIB.S9S_MB_2U(SCH_1):GND
  D6    GND VSS899 @S9S_MB_2U_LIB.S9S_MB_2U(SCH_1):GND
 D59    GND VSS898 @S9S_MB_2U_LIB.S9S_MB_2U(SCH_1):GND
 D57    GND VSS897 @S9S_MB_2U_LIB.S9S_MB_2U(SCH_1):GND
 D55    GND VSS896 @S9S_MB_2U_LIB.S9S_MB_2U(SCH_1):GND
 D53    GND VSS895 @S9S_MB_2U_LIB.S9S_MB_2U(SCH_1):GND
 D51    GND VSS892 @S9S_MB_2U_LIB.S9S_MB_2U(SCH_1):GND
 D49    GND VSS891 @S9S_MB_2U_LIB.S9S_MB_2U(SCH_1):GND
 D47    GND VSS889 @S9S_MB_2U_LIB.S9S_MB_2U(SCH_1):GND
 D44    GND VSS888 @S9S_MB_2U_LIB.S9S_MB_2U(SCH_1):GND
 D42    GND VSS886 @S9S_MB_2U_LIB.S9S_MB_2U(SCH_1):GND
 D40    GND VSS885 @S9S_MB_2U_LIB.S9S_MB_2U(SCH_1):GND
 D38    GND VSS884 @S9S_MB_2U_LIB.S9S_MB_2U(SCH_1):GND
 D36    GND VSS881 @S9S_MB_2U_LIB.S9S_MB_2U(SCH_1):GND
 D34    GND VSS879 @S9S_MB_2U_LIB.S9S_MB_2U(SCH_1):GND
 D32    GND VSS878 @S9S_MB_2U_LIB.S9S_MB_2U(SCH_1):GND
 D30    GND VSS877 @S9S_MB_2U_LIB.S9S_MB_2U(SCH_1):GND
 D28    GND VSS876 @S9S_MB_2U_LIB.S9S_MB_2U(SCH_1):GND
 D26    GND VSS875 @S9S_MB_2U_LIB.S9S_MB_2U(SCH_1):GND
 D24    GND VSS874 @S9S_MB_2U_LIB.S9S_MB_2U(SCH_1):GND
 D22    GND VSS873 @S9S_MB_2U_LIB.S9S_MB_2U(SCH_1):GND
 D20    GND VSS871 @S9S_MB_2U_LIB.S9S_MB_2U(SCH_1):GND
 D18    GND VSS869 @S9S_MB_2U_LIB.S9S_MB_2U(SCH_1):GND
 D16    GND VSS868 @S9S_MB_2U_LIB.S9S_MB_2U(SCH_1):GND
 D14    GND VSS866 @S9S_MB_2U_LIB.S9S_MB_2U(SCH_1):GND
 D12    GND VSS865 @S9S_MB_2U_LIB.S9S_MB_2U(SCH_1):GND
 D10    GND VSS864 @S9S_MB_2U_LIB.S9S_MB_2U(SCH_1):GND
  D8    GND VSS663 @S9S_MB_2U_LIB.S9S_MB_2U(SCH_1):GND
 D79    GND VSS662 @S9S_MB_2U_LIB.S9S_MB_2U(SCH_1):GND
 D67    GND VSS659 @S9S_MB_2U_LIB.S9S_MB_2U(SCH_1):GND
 D65    GND VSS658 @S9S_MB_2U_LIB.S9S_MB_2U(SCH_1):GND
 D63    GND VSS657 @S9S_MB_2U_LIB.S9S_MB_2U(SCH_1):GND
 C86    GND VSS619 @S9S_MB_2U_LIB.S9S_MB_2U(SCH_1):GND
 C82    GND VSS618 @S9S_MB_2U_LIB.S9S_MB_2U(SCH_1):GND
 C80    GND VSS617 @S9S_MB_2U_LIB.S9S_MB_2U(SCH_1):GND
 C78    GND VSS616 @S9S_MB_2U_LIB.S9S_MB_2U(SCH_1):GND
 C74    GND VSS615 @S9S_MB_2U_LIB.S9S_MB_2U(SCH_1):GND
 C72    GND VSS614 @S9S_MB_2U_LIB.S9S_MB_2U(SCH_1):GND
 C52    GND VSS613 @S9S_MB_2U_LIB.S9S_MB_2U(SCH_1):GND
  C5    GND VSS612 @S9S_MB_2U_LIB.S9S_MB_2U(SCH_1):GND
 C45    GND VSS610 @S9S_MB_2U_LIB.S9S_MB_2U(SCH_1):GND
 C39    GND VSS609 @S9S_MB_2U_LIB.S9S_MB_2U(SCH_1):GND
 B87    GND VSS392 @S9S_MB_2U_LIB.S9S_MB_2U(SCH_1):GND
 B83    GND VSS391 @S9S_MB_2U_LIB.S9S_MB_2U(SCH_1):GND
 B75    GND VSS390 @S9S_MB_2U_LIB.S9S_MB_2U(SCH_1):GND
 B67    GND VSS389 @S9S_MB_2U_LIB.S9S_MB_2U(SCH_1):GND
 B61    GND VSS388 @S9S_MB_2U_LIB.S9S_MB_2U(SCH_1):GND
  B6    GND VSS387 @S9S_MB_2U_LIB.S9S_MB_2U(SCH_1):GND
 B55    GND VSS386 @S9S_MB_2U_LIB.S9S_MB_2U(SCH_1):GND
 B49    GND VSS385 @S9S_MB_2U_LIB.S9S_MB_2U(SCH_1):GND
 B42    GND VSS384 @S9S_MB_2U_LIB.S9S_MB_2U(SCH_1):GND
 B36    GND VSS382 @S9S_MB_2U_LIB.S9S_MB_2U(SCH_1):GND
 B30    GND VSS381 @S9S_MB_2U_LIB.S9S_MB_2U(SCH_1):GND
 B24    GND VSS380 @S9S_MB_2U_LIB.S9S_MB_2U(SCH_1):GND
 B18    GND VSS379 @S9S_MB_2U_LIB.S9S_MB_2U(SCH_1):GND
 B12    GND VSS378 @S9S_MB_2U_LIB.S9S_MB_2U(SCH_1):GND
 A62    GND  VSS16 @S9S_MB_2U_LIB.S9S_MB_2U(SCH_1):GND
 A60    GND  VSS15 @S9S_MB_2U_LIB.S9S_MB_2U(SCH_1):GND
 A56    GND  VSS14 @S9S_MB_2U_LIB.S9S_MB_2U(SCH_1):GND
 A54    GND  VSS13 @S9S_MB_2U_LIB.S9S_MB_2U(SCH_1):GND
 A50    GND  VSS12 @S9S_MB_2U_LIB.S9S_MB_2U(SCH_1):GND
 A41    GND  VSS11 @S9S_MB_2U_LIB.S9S_MB_2U(SCH_1):GND
 A37    GND  VSS10 @S9S_MB_2U_LIB.S9S_MB_2U(SCH_1):GND
 A35    GND   VSS9 @S9S_MB_2U_LIB.S9S_MB_2U(SCH_1):GND
 A31    GND   VSS8 @S9S_MB_2U_LIB.S9S_MB_2U(SCH_1):GND
 A29    GND   VSS7 @S9S_MB_2U_LIB.S9S_MB_2U(SCH_1):GND
 A25    GND   VSS6 @S9S_MB_2U_LIB.S9S_MB_2U(SCH_1):GND
 A23    GND   VSS5 @S9S_MB_2U_LIB.S9S_MB_2U(SCH_1):GND
 A19    GND   VSS4 @S9S_MB_2U_LIB.S9S_MB_2U(SCH_1):GND
 A17    GND   VSS3 @S9S_MB_2U_LIB.S9S_MB_2U(SCH_1):GND
 A13    GND   VSS2 @S9S_MB_2U_LIB.S9S_MB_2U(SCH_1):GND
 A11    GND   VSS1 @S9S_MB_2U_LIB.S9S_MB_2U(SCH_1):GND


DRAWING: @S9S_MB_2U_LIB.S9S_MB_2U(SCH_1):PAGE74 

Q_CAP_C0402-22UF,4V,20%,X6S,CHA  I7  C407
   1 PVCCFA_EHV_FIVRA_CPU0      A @S9S_MB_2U_LIB.S9S_MB_2U(SCH_1):PVCCFA_EHV_FIVRA_CPU0
   2    GND      B @S9S_MB_2U_LIB.S9S_MB_2U(SCH_1):GND

Q_CAP_C0402-22UF,4V,20%,X6S,CHA  I8  C409
   1 PVCCFA_EHV_FIVRA_CPU0      A @S9S_MB_2U_LIB.S9S_MB_2U(SCH_1):PVCCFA_EHV_FIVRA_CPU0
   2    GND      B @S9S_MB_2U_LIB.S9S_MB_2U(SCH_1):GND

Q_CAP_C0402-22UF,4V,20%,X6S,CHA  I9  C411
   1 PVCCFA_EHV_FIVRA_CPU0      A @S9S_MB_2U_LIB.S9S_MB_2U(SCH_1):PVCCFA_EHV_FIVRA_CPU0
   2    GND      B @S9S_MB_2U_LIB.S9S_MB_2U(SCH_1):GND

Q_CAP_C0402-22UF,4V,20%,X6S,CHA  I10  C413
   1 PVCCFA_EHV_FIVRA_CPU0      A @S9S_MB_2U_LIB.S9S_MB_2U(SCH_1):PVCCFA_EHV_FIVRA_CPU0
   2    GND      B @S9S_MB_2U_LIB.S9S_MB_2U(SCH_1):GND

Q_CAP_C0805-47UF,4V,20%,X6S,CHA  I13  C101
   1 PVCCIN_CPU0      A @S9S_MB_2U_LIB.S9S_MB_2U(SCH_1):PVCCIN_CPU0
   2    GND      B @S9S_MB_2U_LIB.S9S_MB_2U(SCH_1):GND

Q_CAP_C0402-10UF,6.3V,20%,X6S,B  I15  C969
   1 PVCCIN_CPU0      A @S9S_MB_2U_LIB.S9S_MB_2U(SCH_1):PVCCIN_CPU0
   2    GND      B @S9S_MB_2U_LIB.S9S_MB_2U(SCH_1):GND

Q_CAP_C0402-22UF,4V,20%,X6S,CHA  I17  C401
   1 PVCCD_HV_CPU0      A @S9S_MB_2U_LIB.S9S_MB_2U(SCH_1):PVCCD_HV_CPU0
   2    GND      B @S9S_MB_2U_LIB.S9S_MB_2U(SCH_1):GND

Q_CAP_C0805-47UF,4V,20%,X6S,CHA  I18  C212
   1 PVCCIN_CPU0      A @S9S_MB_2U_LIB.S9S_MB_2U(SCH_1):PVCCIN_CPU0
   2    GND      B @S9S_MB_2U_LIB.S9S_MB_2U(SCH_1):GND

Q_CAP_C0402-22UF,4V,20%,X6S,CHA  I19  C403
   1 PVCCD_HV_CPU0      A @S9S_MB_2U_LIB.S9S_MB_2U(SCH_1):PVCCD_HV_CPU0
   2    GND      B @S9S_MB_2U_LIB.S9S_MB_2U(SCH_1):GND

Q_CAP_C0805-47UF,4V,20%,X6S,CHA  I20  C213
   1 PVCCIN_CPU0      A @S9S_MB_2U_LIB.S9S_MB_2U(SCH_1):PVCCIN_CPU0
   2    GND      B @S9S_MB_2U_LIB.S9S_MB_2U(SCH_1):GND

Q_CAP_C0402-10UF,6.3V,20%,X6S,B  I21  C973
   1 PVCCIN_CPU0      A @S9S_MB_2U_LIB.S9S_MB_2U(SCH_1):PVCCIN_CPU0
   2    GND      B @S9S_MB_2U_LIB.S9S_MB_2U(SCH_1):GND

Q_CAP_C0402-10UF,6.3V,20%,X6S,B  I22  C977
   1 PVCCIN_CPU0      A @S9S_MB_2U_LIB.S9S_MB_2U(SCH_1):PVCCIN_CPU0
   2    GND      B @S9S_MB_2U_LIB.S9S_MB_2U(SCH_1):GND

Q_CAP_C0402-10UF,6.3V,20%,X6S,B  I23  C968
   1 PVCCIN_CPU0      A @S9S_MB_2U_LIB.S9S_MB_2U(SCH_1):PVCCIN_CPU0
   2    GND      B @S9S_MB_2U_LIB.S9S_MB_2U(SCH_1):GND

Q_CAP_C0402-10UF,6.3V,20%,X6S,B  I29  C976
   1 PVCCIN_CPU0      A @S9S_MB_2U_LIB.S9S_MB_2U(SCH_1):PVCCIN_CPU0
   2    GND      B @S9S_MB_2U_LIB.S9S_MB_2U(SCH_1):GND

Q_CAP_C0402-10UF,6.3V,20%,X6S,B  I30  C971
   1 PVCCIN_CPU0      A @S9S_MB_2U_LIB.S9S_MB_2U(SCH_1):PVCCIN_CPU0
   2    GND      B @S9S_MB_2U_LIB.S9S_MB_2U(SCH_1):GND

Q_CAP_C0402-10UF,6.3V,20%,X6S,B  I32  C975
   1 PVCCIN_CPU0      A @S9S_MB_2U_LIB.S9S_MB_2U(SCH_1):PVCCIN_CPU0
   2    GND      B @S9S_MB_2U_LIB.S9S_MB_2U(SCH_1):GND

Q_CAP_C0402-10UF,6.3V,20%,X6S,B  I33  C974
   1 PVCCIN_CPU0      A @S9S_MB_2U_LIB.S9S_MB_2U(SCH_1):PVCCIN_CPU0
   2    GND      B @S9S_MB_2U_LIB.S9S_MB_2U(SCH_1):GND

Q_CAP_C0805-47UF,4V,20%,X6S,CHA  I35  C214
   1 PVCCIN_CPU0      A @S9S_MB_2U_LIB.S9S_MB_2U(SCH_1):PVCCIN_CPU0
   2    GND      B @S9S_MB_2U_LIB.S9S_MB_2U(SCH_1):GND

Q_CAP_C0805-47UF,4V,20%,X6S,CHA  I36  C215
   1 PVCCIN_CPU0      A @S9S_MB_2U_LIB.S9S_MB_2U(SCH_1):PVCCIN_CPU0
   2    GND      B @S9S_MB_2U_LIB.S9S_MB_2U(SCH_1):GND

Q_CAP_C0402-10UF,6.3V,20%,X6S,B  I37  C981
   1 PVCCIN_CPU0      A @S9S_MB_2U_LIB.S9S_MB_2U(SCH_1):PVCCIN_CPU0
   2    GND      B @S9S_MB_2U_LIB.S9S_MB_2U(SCH_1):GND

Q_CAP_C0402-10UF,6.3V,20%,X6S,B  I38  C985
   1 PVCCIN_CPU0      A @S9S_MB_2U_LIB.S9S_MB_2U(SCH_1):PVCCIN_CPU0
   2    GND      B @S9S_MB_2U_LIB.S9S_MB_2U(SCH_1):GND

Q_CAP_C0805-47UF,4V,20%,X6S,CHA  I40  C216
   1 PVCCIN_CPU0      A @S9S_MB_2U_LIB.S9S_MB_2U(SCH_1):PVCCIN_CPU0
   2    GND      B @S9S_MB_2U_LIB.S9S_MB_2U(SCH_1):GND

Q_CAP_C0402-22UF,4V,20%,X6S,CHA  I41  C410
   1 PVCCINFAON_CPU0      A @S9S_MB_2U_LIB.S9S_MB_2U(SCH_1):PVCCINFAON_CPU0
   2    GND      B @S9S_MB_2U_LIB.S9S_MB_2U(SCH_1):GND

Q_CAP_C0402-22UF,4V,20%,X6S,CHA  I42  C412
   1 PVCCINFAON_CPU0      A @S9S_MB_2U_LIB.S9S_MB_2U(SCH_1):PVCCINFAON_CPU0
   2    GND      B @S9S_MB_2U_LIB.S9S_MB_2U(SCH_1):GND

Q_CAP_C0805-47UF,4V,20%,X6S,CHA  I44  C218
   1 PVCCIN_CPU0      A @S9S_MB_2U_LIB.S9S_MB_2U(SCH_1):PVCCIN_CPU0
   2    GND      B @S9S_MB_2U_LIB.S9S_MB_2U(SCH_1):GND

Q_CAP_C0402-10UF,6.3V,20%,X6S,B  I46  C993
   1 PVCCIN_CPU0      A @S9S_MB_2U_LIB.S9S_MB_2U(SCH_1):PVCCIN_CPU0
   2    GND      B @S9S_MB_2U_LIB.S9S_MB_2U(SCH_1):GND

Q_CAP_C0402-10UF,6.3V,20%,X6S,B  I47  C997
   1 PVCCIN_CPU0      A @S9S_MB_2U_LIB.S9S_MB_2U(SCH_1):PVCCIN_CPU0
   2    GND      B @S9S_MB_2U_LIB.S9S_MB_2U(SCH_1):GND

Q_CAP_C0402-10UF,6.3V,20%,X6S,B  I48  C980
   1 PVCCIN_CPU0      A @S9S_MB_2U_LIB.S9S_MB_2U(SCH_1):PVCCIN_CPU0
   2    GND      B @S9S_MB_2U_LIB.S9S_MB_2U(SCH_1):GND

Q_CAP_C0402-10UF,6.3V,20%,X6S,B  I49  C984
   1 PVCCIN_CPU0      A @S9S_MB_2U_LIB.S9S_MB_2U(SCH_1):PVCCIN_CPU0
   2    GND      B @S9S_MB_2U_LIB.S9S_MB_2U(SCH_1):GND

Q_CAP_C0402-10UF,6.3V,20%,X6S,B  I50  C979
   1 PVCCIN_CPU0      A @S9S_MB_2U_LIB.S9S_MB_2U(SCH_1):PVCCIN_CPU0
   2    GND      B @S9S_MB_2U_LIB.S9S_MB_2U(SCH_1):GND

Q_CAP_C0402-10UF,6.3V,20%,X6S,B  I51  C978
   1 PVCCIN_CPU0      A @S9S_MB_2U_LIB.S9S_MB_2U(SCH_1):PVCCIN_CPU0
   2    GND      B @S9S_MB_2U_LIB.S9S_MB_2U(SCH_1):GND

Q_CAP_C0402-10UF,6.3V,20%,X6S,B  I52  C983
   1 PVCCIN_CPU0      A @S9S_MB_2U_LIB.S9S_MB_2U(SCH_1):PVCCIN_CPU0
   2    GND      B @S9S_MB_2U_LIB.S9S_MB_2U(SCH_1):GND

Q_CAP_C0402-10UF,6.3V,20%,X6S,B  I53  C982
   1 PVCCIN_CPU0      A @S9S_MB_2U_LIB.S9S_MB_2U(SCH_1):PVCCIN_CPU0
   2    GND      B @S9S_MB_2U_LIB.S9S_MB_2U(SCH_1):GND

Q_CAP_C0402-10UF,6.3V,20%,X6S,B  I54  C988
   1 PVCCIN_CPU0      A @S9S_MB_2U_LIB.S9S_MB_2U(SCH_1):PVCCIN_CPU0
   2    GND      B @S9S_MB_2U_LIB.S9S_MB_2U(SCH_1):GND

Q_CAP_C0402-10UF,6.3V,20%,X6S,B  I56  C996
   1 PVCCIN_CPU0      A @S9S_MB_2U_LIB.S9S_MB_2U(SCH_1):PVCCIN_CPU0
   2    GND      B @S9S_MB_2U_LIB.S9S_MB_2U(SCH_1):GND

Q_CAP_C0402-10UF,6.3V,20%,X6S,B  I58  C986
   1 PVCCIN_CPU0      A @S9S_MB_2U_LIB.S9S_MB_2U(SCH_1):PVCCIN_CPU0
   2    GND      B @S9S_MB_2U_LIB.S9S_MB_2U(SCH_1):GND

Q_CAP_C0402-10UF,6.3V,20%,X6S,B  I59  C991
   1 PVCCIN_CPU0      A @S9S_MB_2U_LIB.S9S_MB_2U(SCH_1):PVCCIN_CPU0
   2    GND      B @S9S_MB_2U_LIB.S9S_MB_2U(SCH_1):GND

Q_CAP_C0402-10UF,6.3V,20%,X6S,B  I60  C990
   1 PVCCIN_CPU0      A @S9S_MB_2U_LIB.S9S_MB_2U(SCH_1):PVCCIN_CPU0
   2    GND      B @S9S_MB_2U_LIB.S9S_MB_2U(SCH_1):GND

Q_CAP_C0402-10UF,6.3V,20%,X6S,B  I61  C995
   1 PVCCIN_CPU0      A @S9S_MB_2U_LIB.S9S_MB_2U(SCH_1):PVCCIN_CPU0
   2    GND      B @S9S_MB_2U_LIB.S9S_MB_2U(SCH_1):GND

Q_CAP_C0402-22UF,4V,20%,X6S,CHA  I64  C415
   1 PVCCFA_EHV_FIVRA_CPU0      A @S9S_MB_2U_LIB.S9S_MB_2U(SCH_1):PVCCFA_EHV_FIVRA_CPU0
   2    GND      B @S9S_MB_2U_LIB.S9S_MB_2U(SCH_1):GND

Q_CAP_C0402-22UF,4V,20%,X6S,CHA  I65  C417
   1 PVCCFA_EHV_FIVRA_CPU0      A @S9S_MB_2U_LIB.S9S_MB_2U(SCH_1):PVCCFA_EHV_FIVRA_CPU0
   2    GND      B @S9S_MB_2U_LIB.S9S_MB_2U(SCH_1):GND

Q_CAP_C0402-22UF,4V,20%,X6S,CHA  I68  C418
   1 PVCCFA_EHV_FIVRA_CPU0      A @S9S_MB_2U_LIB.S9S_MB_2U(SCH_1):PVCCFA_EHV_FIVRA_CPU0
   2    GND      B @S9S_MB_2U_LIB.S9S_MB_2U(SCH_1):GND

Q_CAP_C0402-22UF,4V,20%,X6S,CHA  I70  C414
   1 PVCCINFAON_CPU0      A @S9S_MB_2U_LIB.S9S_MB_2U(SCH_1):PVCCINFAON_CPU0
   2    GND      B @S9S_MB_2U_LIB.S9S_MB_2U(SCH_1):GND

Q_CAP_C0805-47UF,4V,20%,X6S,CHA  I71  C219
   1 PVCCIN_CPU0      A @S9S_MB_2U_LIB.S9S_MB_2U(SCH_1):PVCCIN_CPU0
   2    GND      B @S9S_MB_2U_LIB.S9S_MB_2U(SCH_1):GND

Q_CAP_C0402-22UF,4V,20%,X6S,CHA  I72  C416
   1 PVCCINFAON_CPU0      A @S9S_MB_2U_LIB.S9S_MB_2U(SCH_1):PVCCINFAON_CPU0
   2    GND      B @S9S_MB_2U_LIB.S9S_MB_2U(SCH_1):GND

Q_CAP_C0805-47UF,4V,20%,X6S,CHA  I74  C220
   1 PVCCIN_CPU0      A @S9S_MB_2U_LIB.S9S_MB_2U(SCH_1):PVCCIN_CPU0
   2    GND      B @S9S_MB_2U_LIB.S9S_MB_2U(SCH_1):GND

Q_CAP_C0402-10UF,6.3V,20%,X6S,B  I75  C1001
   1 PVCCIN_CPU0      A @S9S_MB_2U_LIB.S9S_MB_2U(SCH_1):PVCCIN_CPU0
   2    GND      B @S9S_MB_2U_LIB.S9S_MB_2U(SCH_1):GND

Q_CAP_C0402-10UF,6.3V,20%,X6S,B  I77  C1005
   1 PVCCIN_CPU0      A @S9S_MB_2U_LIB.S9S_MB_2U(SCH_1):PVCCIN_CPU0
   2    GND      B @S9S_MB_2U_LIB.S9S_MB_2U(SCH_1):GND

Q_CAP_C0402-22UF,4V,20%,X6S,CHA  I78  C1009
   1 PVCCIN_CPU0      A @S9S_MB_2U_LIB.S9S_MB_2U(SCH_1):PVCCIN_CPU0
   2    GND      B @S9S_MB_2U_LIB.S9S_MB_2U(SCH_1):GND

Q_CAP_C0402-22UF,4V,20%,X6S,CHA  I80  C1013
   1 PVCCIN_CPU0      A @S9S_MB_2U_LIB.S9S_MB_2U(SCH_1):PVCCIN_CPU0
   2    GND      B @S9S_MB_2U_LIB.S9S_MB_2U(SCH_1):GND

Q_CAP_C0402-10UF,6.3V,20%,X6S,B  I81  C1000
   1 PVCCIN_CPU0      A @S9S_MB_2U_LIB.S9S_MB_2U(SCH_1):PVCCIN_CPU0
   2    GND      B @S9S_MB_2U_LIB.S9S_MB_2U(SCH_1):GND

Q_CAP_C0402-10UF,6.3V,20%,X6S,B  I85  C999
   1 PVCCIN_CPU0      A @S9S_MB_2U_LIB.S9S_MB_2U(SCH_1):PVCCIN_CPU0
   2    GND      B @S9S_MB_2U_LIB.S9S_MB_2U(SCH_1):GND

Q_CAP_C0402-10UF,6.3V,20%,X6S,B  I86  C998
   1 PVCCIN_CPU0      A @S9S_MB_2U_LIB.S9S_MB_2U(SCH_1):PVCCIN_CPU0
   2    GND      B @S9S_MB_2U_LIB.S9S_MB_2U(SCH_1):GND

Q_CAP_C0402-10UF,6.3V,20%,X6S,B  I87  C1003
   1 PVCCIN_CPU0      A @S9S_MB_2U_LIB.S9S_MB_2U(SCH_1):PVCCIN_CPU0
   2    GND      B @S9S_MB_2U_LIB.S9S_MB_2U(SCH_1):GND

Q_CAP_C0402-10UF,6.3V,20%,X6S,B  I89  C1002
   1 PVCCIN_CPU0      A @S9S_MB_2U_LIB.S9S_MB_2U(SCH_1):PVCCIN_CPU0
   2    GND      B @S9S_MB_2U_LIB.S9S_MB_2U(SCH_1):GND

Q_CAP_C0402-22UF,4V,20%,X6S,CHA  I90  C1008
   1 PVCCIN_CPU0      A @S9S_MB_2U_LIB.S9S_MB_2U(SCH_1):PVCCIN_CPU0
   2    GND      B @S9S_MB_2U_LIB.S9S_MB_2U(SCH_1):GND

Q_CAP_C0402-22UF,4V,20%,X6S,CHA  I92  C1012
   1 PVCCIN_CPU0      A @S9S_MB_2U_LIB.S9S_MB_2U(SCH_1):PVCCIN_CPU0
   2    GND      B @S9S_MB_2U_LIB.S9S_MB_2U(SCH_1):GND

Q_CAP_C0402-22UF,4V,20%,X6S,CHA  I93  C1007
   1 PVCCIN_CPU0      A @S9S_MB_2U_LIB.S9S_MB_2U(SCH_1):PVCCIN_CPU0
   2    GND      B @S9S_MB_2U_LIB.S9S_MB_2U(SCH_1):GND

Q_CAP_C0402-22UF,4V,20%,X6S,CHA  I95  C1006
   1 PVCCIN_CPU0      A @S9S_MB_2U_LIB.S9S_MB_2U(SCH_1):PVCCIN_CPU0
   2    GND      B @S9S_MB_2U_LIB.S9S_MB_2U(SCH_1):GND

Q_CAP_C0402-22UF,4V,20%,X6S,CHA  I96  C1011
   1 PVCCIN_CPU0      A @S9S_MB_2U_LIB.S9S_MB_2U(SCH_1):PVCCIN_CPU0
   2    GND      B @S9S_MB_2U_LIB.S9S_MB_2U(SCH_1):GND

Q_CAP_C0402-22UF,4V,20%,X6S,CHA  I97  C1010
   1 PVCCIN_CPU0      A @S9S_MB_2U_LIB.S9S_MB_2U(SCH_1):PVCCIN_CPU0
   2    GND      B @S9S_MB_2U_LIB.S9S_MB_2U(SCH_1):GND

Q_CAP_C0402-22UF,4V,20%,X6S,CHA  I98  C419
   1 PVCCFA_EHV_CPU0      A @S9S_MB_2U_LIB.S9S_MB_2U(SCH_1):PVCCFA_EHV_CPU0
   2    GND      B @S9S_MB_2U_LIB.S9S_MB_2U(SCH_1):GND

Q_CAP_C0402-22UF,4V,20%,X6S,CHA  I102  C590
   1 PVNN_MAIN_CPU0      A @S9S_MB_2U_LIB.S9S_MB_2U(SCH_1):PVNN_MAIN_CPU0
   2    GND      B @S9S_MB_2U_LIB.S9S_MB_2U(SCH_1):GND

Q_CAP_C0402-22UF,4V,20%,X6S,CHA  I103  C421
   1 PVCCFA_EHV_CPU0      A @S9S_MB_2U_LIB.S9S_MB_2U(SCH_1):PVCCFA_EHV_CPU0
   2    GND      B @S9S_MB_2U_LIB.S9S_MB_2U(SCH_1):GND

Q_CAP_C0402-22UF,4V,20%,X6S,CHA  I105  C1017
   1 PVCCIN_CPU0      A @S9S_MB_2U_LIB.S9S_MB_2U(SCH_1):PVCCIN_CPU0
   2    GND      B @S9S_MB_2U_LIB.S9S_MB_2U(SCH_1):GND

Q_CAP_C0402-22UF,4V,20%,X6S,CHA  I111  C1016
   1 PVCCIN_CPU0      A @S9S_MB_2U_LIB.S9S_MB_2U(SCH_1):PVCCIN_CPU0
   2    GND      B @S9S_MB_2U_LIB.S9S_MB_2U(SCH_1):GND

Q_CAP_C0402-22UF,4V,20%,X6S,CHA  I112  C1020
   1 PVCCIN_CPU0      A @S9S_MB_2U_LIB.S9S_MB_2U(SCH_1):PVCCIN_CPU0
   2    GND      B @S9S_MB_2U_LIB.S9S_MB_2U(SCH_1):GND

Q_CAP_C0402-22UF,4V,20%,X6S,CHA  I113  C1015
   1 PVCCIN_CPU0      A @S9S_MB_2U_LIB.S9S_MB_2U(SCH_1):PVCCIN_CPU0
   2    GND      B @S9S_MB_2U_LIB.S9S_MB_2U(SCH_1):GND

Q_CAP_C0402-22UF,4V,20%,X6S,CHA  I114  C1014
   1 PVCCIN_CPU0      A @S9S_MB_2U_LIB.S9S_MB_2U(SCH_1):PVCCIN_CPU0
   2    GND      B @S9S_MB_2U_LIB.S9S_MB_2U(SCH_1):GND

Q_CAP_C0402-22UF,4V,20%,X6S,CHA  I115  C1019
   1 PVCCIN_CPU0      A @S9S_MB_2U_LIB.S9S_MB_2U(SCH_1):PVCCIN_CPU0
   2    GND      B @S9S_MB_2U_LIB.S9S_MB_2U(SCH_1):GND

Q_CAP_C0402-22UF,4V,20%,X6S,CHA  I131  C1036
   1 PVCCIN_CPU0      A @S9S_MB_2U_LIB.S9S_MB_2U(SCH_1):PVCCIN_CPU0
   2    GND      B @S9S_MB_2U_LIB.S9S_MB_2U(SCH_1):GND

Q_CAP_C0402-22UF,4V,20%,X6S,CHA  I132  C1040
   1 PVCCIN_CPU0      A @S9S_MB_2U_LIB.S9S_MB_2U(SCH_1):PVCCIN_CPU0
   2    GND      B @S9S_MB_2U_LIB.S9S_MB_2U(SCH_1):GND

Q_CAP_C0402-22UF,4V,20%,X6S,CHA  I133  C1035
   1 PVCCIN_CPU0      A @S9S_MB_2U_LIB.S9S_MB_2U(SCH_1):PVCCIN_CPU0
   2    GND      B @S9S_MB_2U_LIB.S9S_MB_2U(SCH_1):GND

Q_CAP_C0402-22UF,4V,20%,X6S,CHA  I134  C1034
   1 PVCCIN_CPU0      A @S9S_MB_2U_LIB.S9S_MB_2U(SCH_1):PVCCIN_CPU0
   2    GND      B @S9S_MB_2U_LIB.S9S_MB_2U(SCH_1):GND

Q_CAP_C0402-22UF,4V,20%,X6S,CHA  I135  C1039
   1 PVCCIN_CPU0      A @S9S_MB_2U_LIB.S9S_MB_2U(SCH_1):PVCCIN_CPU0
   2    GND      B @S9S_MB_2U_LIB.S9S_MB_2U(SCH_1):GND

Q_CAP_C0402-22UF,4V,20%,X6S,CHA  I137  C1038
   1 PVCCIN_CPU0      A @S9S_MB_2U_LIB.S9S_MB_2U(SCH_1):PVCCIN_CPU0
   2    GND      B @S9S_MB_2U_LIB.S9S_MB_2U(SCH_1):GND

Q_CAP_C0402-22UF,4V,20%,X6S,CHA  I139  C1044
   1 PVCCIN_CPU0      A @S9S_MB_2U_LIB.S9S_MB_2U(SCH_1):PVCCIN_CPU0
   2    GND      B @S9S_MB_2U_LIB.S9S_MB_2U(SCH_1):GND

Q_CAP_C0402-22UF,4V,20%,X6S,CHA  I141  C1043
   1 PVCCIN_CPU0      A @S9S_MB_2U_LIB.S9S_MB_2U(SCH_1):PVCCIN_CPU0
   2    GND      B @S9S_MB_2U_LIB.S9S_MB_2U(SCH_1):GND

Q_CAP_C0402-22UF,4V,20%,X6S,CHA  I142  C408
   1 PVCCINFAON_CPU0      A @S9S_MB_2U_LIB.S9S_MB_2U(SCH_1):PVCCINFAON_CPU0
   2    GND      B @S9S_MB_2U_LIB.S9S_MB_2U(SCH_1):GND

Q_CAP_C0402-22UF,4V,20%,X6S,CHA  I1  C400
   1 PVCCFA_EHV_FIVRA_CPU0      A @S9S_MB_2U_LIB.S9S_MB_2U(SCH_1):PVCCFA_EHV_FIVRA_CPU0
   2    GND      B @S9S_MB_2U_LIB.S9S_MB_2U(SCH_1):GND

Q_CAP_C0402-22UF,4V,20%,X6S,CHA  I3  C402
   1 PVCCFA_EHV_FIVRA_CPU0      A @S9S_MB_2U_LIB.S9S_MB_2U(SCH_1):PVCCFA_EHV_FIVRA_CPU0
   2    GND      B @S9S_MB_2U_LIB.S9S_MB_2U(SCH_1):GND

Q_CAP_C0402-22UF,4V,20%,X6S,CHA  I4  C404
   1 PVCCFA_EHV_FIVRA_CPU0      A @S9S_MB_2U_LIB.S9S_MB_2U(SCH_1):PVCCFA_EHV_FIVRA_CPU0
   2    GND      B @S9S_MB_2U_LIB.S9S_MB_2U(SCH_1):GND

Q_CAP_C0402-22UF,4V,20%,X6S,CHA  I5  C406
   1 PVCCFA_EHV_FIVRA_CPU0      A @S9S_MB_2U_LIB.S9S_MB_2U(SCH_1):PVCCFA_EHV_FIVRA_CPU0
   2    GND      B @S9S_MB_2U_LIB.S9S_MB_2U(SCH_1):GND

Q_CAP_C0402-22UF,4V,20%,X6S,CHA  I11  C399
   1 PVCCD_HV_CPU0      A @S9S_MB_2U_LIB.S9S_MB_2U(SCH_1):PVCCD_HV_CPU0
   2    GND      B @S9S_MB_2U_LIB.S9S_MB_2U(SCH_1):GND

Q_CAP_C0402-10UF,6.3V,20%,X6S,B  I25  C967
   1 PVCCIN_CPU0      A @S9S_MB_2U_LIB.S9S_MB_2U(SCH_1):PVCCIN_CPU0
   2    GND      B @S9S_MB_2U_LIB.S9S_MB_2U(SCH_1):GND

Q_CAP_C0402-10UF,6.3V,20%,X6S,B  I27  C966
   1 PVCCIN_CPU0      A @S9S_MB_2U_LIB.S9S_MB_2U(SCH_1):PVCCIN_CPU0
   2    GND      B @S9S_MB_2U_LIB.S9S_MB_2U(SCH_1):GND

Q_CAP_C0402-10UF,6.3V,20%,X6S,B  I28  C972
   1 PVCCIN_CPU0      A @S9S_MB_2U_LIB.S9S_MB_2U(SCH_1):PVCCIN_CPU0
   2    GND      B @S9S_MB_2U_LIB.S9S_MB_2U(SCH_1):GND

Q_CAP_C0402-10UF,6.3V,20%,X6S,B  I31  C970
   1 PVCCIN_CPU0      A @S9S_MB_2U_LIB.S9S_MB_2U(SCH_1):PVCCIN_CPU0
   2    GND      B @S9S_MB_2U_LIB.S9S_MB_2U(SCH_1):GND

Q_CAP_C0402-22UF,4V,20%,X6S,CHA  I34  C405
   1 PVCCD_HV_CPU0      A @S9S_MB_2U_LIB.S9S_MB_2U(SCH_1):PVCCD_HV_CPU0
   2    GND      B @S9S_MB_2U_LIB.S9S_MB_2U(SCH_1):GND

Q_CAP_C0805-47UF,4V,20%,X6S,CHA  I43  C217
   1 PVCCIN_CPU0      A @S9S_MB_2U_LIB.S9S_MB_2U(SCH_1):PVCCIN_CPU0
   2    GND      B @S9S_MB_2U_LIB.S9S_MB_2U(SCH_1):GND

Q_CAP_C0402-10UF,6.3V,20%,X6S,B  I45  C989
   1 PVCCIN_CPU0      A @S9S_MB_2U_LIB.S9S_MB_2U(SCH_1):PVCCIN_CPU0
   2    GND      B @S9S_MB_2U_LIB.S9S_MB_2U(SCH_1):GND

Q_CAP_C0402-10UF,6.3V,20%,X6S,B  I55  C992
   1 PVCCIN_CPU0      A @S9S_MB_2U_LIB.S9S_MB_2U(SCH_1):PVCCIN_CPU0
   2    GND      B @S9S_MB_2U_LIB.S9S_MB_2U(SCH_1):GND

Q_CAP_C0402-10UF,6.3V,20%,X6S,B  I57  C987
   1 PVCCIN_CPU0      A @S9S_MB_2U_LIB.S9S_MB_2U(SCH_1):PVCCIN_CPU0
   2    GND      B @S9S_MB_2U_LIB.S9S_MB_2U(SCH_1):GND

Q_CAP_C0402-10UF,6.3V,20%,X6S,B  I62  C994
   1 PVCCIN_CPU0      A @S9S_MB_2U_LIB.S9S_MB_2U(SCH_1):PVCCIN_CPU0
   2    GND      B @S9S_MB_2U_LIB.S9S_MB_2U(SCH_1):GND

Q_CAP_C0402-10UF,6.3V,20%,X6S,B  I83  C1004
   1 PVCCIN_CPU0      A @S9S_MB_2U_LIB.S9S_MB_2U(SCH_1):PVCCIN_CPU0
   2    GND      B @S9S_MB_2U_LIB.S9S_MB_2U(SCH_1):GND

Q_CAP_C0402-22UF,4V,20%,X6S,CHA  I100  C420
   1 PVCCFA_EHV_CPU0      A @S9S_MB_2U_LIB.S9S_MB_2U(SCH_1):PVCCFA_EHV_CPU0
   2    GND      B @S9S_MB_2U_LIB.S9S_MB_2U(SCH_1):GND

Q_CAP_C0402-22UF,4V,20%,X6S,CHA  I106  C1021
   1 PVCCIN_CPU0      A @S9S_MB_2U_LIB.S9S_MB_2U(SCH_1):PVCCIN_CPU0
   2    GND      B @S9S_MB_2U_LIB.S9S_MB_2U(SCH_1):GND

Q_CAP_C0402-22UF,4V,20%,X6S,CHA  I107  C422
   1 PVCCFA_EHV_CPU0      A @S9S_MB_2U_LIB.S9S_MB_2U(SCH_1):PVCCFA_EHV_CPU0
   2    GND      B @S9S_MB_2U_LIB.S9S_MB_2U(SCH_1):GND

Q_CAP_C0402-22UF,4V,20%,X6S,CHA  I108  C1025
   1 PVCCIN_CPU0      A @S9S_MB_2U_LIB.S9S_MB_2U(SCH_1):PVCCIN_CPU0
   2    GND      B @S9S_MB_2U_LIB.S9S_MB_2U(SCH_1):GND

Q_CAP_C0402-22UF,4V,20%,X6S,CHA  I109  C1029
   1 PVCCIN_CPU0      A @S9S_MB_2U_LIB.S9S_MB_2U(SCH_1):PVCCIN_CPU0
   2    GND      B @S9S_MB_2U_LIB.S9S_MB_2U(SCH_1):GND

Q_CAP_C0402-22UF,4V,20%,X6S,CHA  I110  C1033
   1 PVCCIN_CPU0      A @S9S_MB_2U_LIB.S9S_MB_2U(SCH_1):PVCCIN_CPU0
   2    GND      B @S9S_MB_2U_LIB.S9S_MB_2U(SCH_1):GND

Q_CAP_C0402-22UF,4V,20%,X6S,CHA  I116  C1018
   1 PVCCIN_CPU0      A @S9S_MB_2U_LIB.S9S_MB_2U(SCH_1):PVCCIN_CPU0
   2    GND      B @S9S_MB_2U_LIB.S9S_MB_2U(SCH_1):GND

Q_CAP_C0402-22UF,4V,20%,X6S,CHA  I117  C1024
   1 PVCCIN_CPU0      A @S9S_MB_2U_LIB.S9S_MB_2U(SCH_1):PVCCIN_CPU0
   2    GND      B @S9S_MB_2U_LIB.S9S_MB_2U(SCH_1):GND

Q_CAP_C0402-22UF,4V,20%,X6S,CHA  I118  C1028
   1 PVCCIN_CPU0      A @S9S_MB_2U_LIB.S9S_MB_2U(SCH_1):PVCCIN_CPU0
   2    GND      B @S9S_MB_2U_LIB.S9S_MB_2U(SCH_1):GND

Q_CAP_C0402-22UF,4V,20%,X6S,CHA  I119  C1032
   1 PVCCIN_CPU0      A @S9S_MB_2U_LIB.S9S_MB_2U(SCH_1):PVCCIN_CPU0
   2    GND      B @S9S_MB_2U_LIB.S9S_MB_2U(SCH_1):GND

Q_CAP_C0402-22UF,4V,20%,X6S,CHA  I120  C1023
   1 PVCCIN_CPU0      A @S9S_MB_2U_LIB.S9S_MB_2U(SCH_1):PVCCIN_CPU0
   2    GND      B @S9S_MB_2U_LIB.S9S_MB_2U(SCH_1):GND

Q_CAP_C0402-22UF,4V,20%,X6S,CHA  I121  C1027
   1 PVCCIN_CPU0      A @S9S_MB_2U_LIB.S9S_MB_2U(SCH_1):PVCCIN_CPU0
   2    GND      B @S9S_MB_2U_LIB.S9S_MB_2U(SCH_1):GND

Q_CAP_C0402-22UF,4V,20%,X6S,CHA  I122  C1022
   1 PVCCIN_CPU0      A @S9S_MB_2U_LIB.S9S_MB_2U(SCH_1):PVCCIN_CPU0
   2    GND      B @S9S_MB_2U_LIB.S9S_MB_2U(SCH_1):GND

Q_CAP_C0402-22UF,4V,20%,X6S,CHA  I123  C1026
   1 PVCCIN_CPU0      A @S9S_MB_2U_LIB.S9S_MB_2U(SCH_1):PVCCIN_CPU0
   2    GND      B @S9S_MB_2U_LIB.S9S_MB_2U(SCH_1):GND

Q_CAP_C0402-22UF,4V,20%,X6S,CHA  I124  C1031
   1 PVCCIN_CPU0      A @S9S_MB_2U_LIB.S9S_MB_2U(SCH_1):PVCCIN_CPU0
   2    GND      B @S9S_MB_2U_LIB.S9S_MB_2U(SCH_1):GND

Q_CAP_C0402-22UF,4V,20%,X6S,CHA  I125  C1030
   1 PVCCIN_CPU0      A @S9S_MB_2U_LIB.S9S_MB_2U(SCH_1):PVCCIN_CPU0
   2    GND      B @S9S_MB_2U_LIB.S9S_MB_2U(SCH_1):GND

Q_CAP_C0402-22UF,4V,20%,X6S,CHA  I127  C1037
   1 PVCCIN_CPU0      A @S9S_MB_2U_LIB.S9S_MB_2U(SCH_1):PVCCIN_CPU0
   2    GND      B @S9S_MB_2U_LIB.S9S_MB_2U(SCH_1):GND

Q_CAP_C0402-22UF,4V,20%,X6S,CHA  I128  C1041
   1 PVCCIN_CPU0      A @S9S_MB_2U_LIB.S9S_MB_2U(SCH_1):PVCCIN_CPU0
   2    GND      B @S9S_MB_2U_LIB.S9S_MB_2U(SCH_1):GND

Q_CAP_C0402-22UF,4V,20%,X6S,CHA  I130  C1045
   1 PVCCIN_CPU0      A @S9S_MB_2U_LIB.S9S_MB_2U(SCH_1):PVCCIN_CPU0
   2    GND      B @S9S_MB_2U_LIB.S9S_MB_2U(SCH_1):GND


DRAWING: @S9S_MB_2U_LIB.S9S_MB_2U(SCH_1):PAGE75 

Q_CAP_C0805-47UF,4V,20%,X6S,CHA  I1  C493
   1 PVCCFA_EHV_FIVRA_CPU0      A @S9S_MB_2U_LIB.S9S_MB_2U(SCH_1):PVCCFA_EHV_FIVRA_CPU0
   2    GND      B @S9S_MB_2U_LIB.S9S_MB_2U(SCH_1):GND

Q_CAP_C0805-47UF,4V,20%,X6S,CHA  I3  C497
   1 PVCCFA_EHV_FIVRA_CPU0      A @S9S_MB_2U_LIB.S9S_MB_2U(SCH_1):PVCCFA_EHV_FIVRA_CPU0
   2    GND      B @S9S_MB_2U_LIB.S9S_MB_2U(SCH_1):GND

Q_CAP_C0805-47UF,4V,20%,X6S,CHA  I4  C501
   1 PVCCFA_EHV_FIVRA_CPU0      A @S9S_MB_2U_LIB.S9S_MB_2U(SCH_1):PVCCFA_EHV_FIVRA_CPU0
   2    GND      B @S9S_MB_2U_LIB.S9S_MB_2U(SCH_1):GND

Q_CAP_C0603-47UF,2.5V,20%,X6S,A  I14  C532
   1 PVCCINFAON_CPU0      A @S9S_MB_2U_LIB.S9S_MB_2U(SCH_1):PVCCINFAON_CPU0
   2    GND      B @S9S_MB_2U_LIB.S9S_MB_2U(SCH_1):GND

Q_CAP_C0805-47UF,4V,20%,X6S,CHA  I25  C359
   1 PVCCIN_CPU0      A @S9S_MB_2U_LIB.S9S_MB_2U(SCH_1):PVCCIN_CPU0
   2    GND      B @S9S_MB_2U_LIB.S9S_MB_2U(SCH_1):GND

Q_CAP_C0805-47UF,4V,20%,X6S,CHA  I26  C362
   1 PVCCIN_CPU0      A @S9S_MB_2U_LIB.S9S_MB_2U(SCH_1):PVCCIN_CPU0
   2    GND      B @S9S_MB_2U_LIB.S9S_MB_2U(SCH_1):GND

Q_CAP_C0805-47UF,4V,20%,X6S,CHA  I27  C358
   1 PVCCIN_CPU0      A @S9S_MB_2U_LIB.S9S_MB_2U(SCH_1):PVCCIN_CPU0
   2    GND      B @S9S_MB_2U_LIB.S9S_MB_2U(SCH_1):GND

Q_CAP_C0805-47UF,4V,20%,X6S,CHA  I28  C361
   1 PVCCIN_CPU0      A @S9S_MB_2U_LIB.S9S_MB_2U(SCH_1):PVCCIN_CPU0
   2    GND      B @S9S_MB_2U_LIB.S9S_MB_2U(SCH_1):GND

Q_CAP_C0805-47UF,4V,20%,X6S,CHA  I33  C368
   1 PVCCIN_CPU0      A @S9S_MB_2U_LIB.S9S_MB_2U(SCH_1):PVCCIN_CPU0
   2    GND      B @S9S_MB_2U_LIB.S9S_MB_2U(SCH_1):GND

Q_CAP_C0805-47UF,4V,20%,X6S,CHA  I43  C1396
   1 PVPP_HBM_CPU0      A @S9S_MB_2U_LIB.S9S_MB_2U(SCH_1):PVPP_HBM_CPU0
   2    GND      B @S9S_MB_2U_LIB.S9S_MB_2U(SCH_1):GND

Q_CAP_C0805-47UF,4V,20%,X6S,CHA  I44  C1397
   1 PVPP_HBM_CPU0      A @S9S_MB_2U_LIB.S9S_MB_2U(SCH_1):PVPP_HBM_CPU0
   2    GND      B @S9S_MB_2U_LIB.S9S_MB_2U(SCH_1):GND

Q_CAP_C0805-47UF,4V,20%,X6S,CHA  I49  C391
   1 PVCCIN_CPU0      A @S9S_MB_2U_LIB.S9S_MB_2U(SCH_1):PVCCIN_CPU0
   2    GND      B @S9S_MB_2U_LIB.S9S_MB_2U(SCH_1):GND

Q_CAP_C0805-47UF,4V,20%,X6S,CHA  I50  C379
   1 PVCCIN_CPU0      A @S9S_MB_2U_LIB.S9S_MB_2U(SCH_1):PVCCIN_CPU0
   2    GND      B @S9S_MB_2U_LIB.S9S_MB_2U(SCH_1):GND

Q_CAP_C0805-47UF,4V,20%,X6S,CHA  I52  C393
   1 PVCCIN_CPU0      A @S9S_MB_2U_LIB.S9S_MB_2U(SCH_1):PVCCIN_CPU0
   2    GND      B @S9S_MB_2U_LIB.S9S_MB_2U(SCH_1):GND

Q_CAP_C0805-47UF,4V,20%,X6S,CHA  I54  C360
   1 PVCCIN_CPU0      A @S9S_MB_2U_LIB.S9S_MB_2U(SCH_1):PVCCIN_CPU0
   2    GND      B @S9S_MB_2U_LIB.S9S_MB_2U(SCH_1):GND

Q_CAP_C0805-47UF,4V,20%,X6S,CHA  I67  C381
   1 PVCCIN_CPU0      A @S9S_MB_2U_LIB.S9S_MB_2U(SCH_1):PVCCIN_CPU0
   2    GND      B @S9S_MB_2U_LIB.S9S_MB_2U(SCH_1):GND

Q_CAP_C0805-47UF,4V,20%,X6S,CHA  I6  C505
   1 PVCCFA_EHV_FIVRA_CPU0      A @S9S_MB_2U_LIB.S9S_MB_2U(SCH_1):PVCCFA_EHV_FIVRA_CPU0
   2    GND      B @S9S_MB_2U_LIB.S9S_MB_2U(SCH_1):GND

Q_CAP_C0603-47UF,2.5V,20%,X6S,A  I8  C509
   1 PVCCFA_EHV_FIVRA_CPU0      A @S9S_MB_2U_LIB.S9S_MB_2U(SCH_1):PVCCFA_EHV_FIVRA_CPU0
   2    GND      B @S9S_MB_2U_LIB.S9S_MB_2U(SCH_1):GND

Q_CAP_C0805-47UF,4V,20%,X6S,CHA  I9  C522
   1 PVCCINFAON_CPU0      A @S9S_MB_2U_LIB.S9S_MB_2U(SCH_1):PVCCINFAON_CPU0
   2    GND      B @S9S_MB_2U_LIB.S9S_MB_2U(SCH_1):GND

Q_CAP_C0805-47UF,4V,20%,X6S,CHA  I11  C492
   1 PVCCFA_EHV_CPU0      A @S9S_MB_2U_LIB.S9S_MB_2U(SCH_1):PVCCFA_EHV_CPU0
   2    GND      B @S9S_MB_2U_LIB.S9S_MB_2U(SCH_1):GND

Q_CAP_C0805-47UF,4V,20%,X6S,CHA  I13  C491
   1 PVCCD_HV_CPU0      A @S9S_MB_2U_LIB.S9S_MB_2U(SCH_1):PVCCD_HV_CPU0
   2    GND      B @S9S_MB_2U_LIB.S9S_MB_2U(SCH_1):GND

Q_CAP_C0805-47UF,4V,20%,X6S,CHA  I16  C496
   1 PVCCFA_EHV_CPU0      A @S9S_MB_2U_LIB.S9S_MB_2U(SCH_1):PVCCFA_EHV_CPU0
   2    GND      B @S9S_MB_2U_LIB.S9S_MB_2U(SCH_1):GND

Q_CAP_C0603-47UF,2.5V,20%,X6S,A  I17  C533
   1 PVCCINFAON_CPU0      A @S9S_MB_2U_LIB.S9S_MB_2U(SCH_1):PVCCINFAON_CPU0
   2    GND      B @S9S_MB_2U_LIB.S9S_MB_2U(SCH_1):GND

Q_CAP_C0805-47UF,4V,20%,X6S,CHA  I18  C495
   1 PVCCD_HV_CPU0      A @S9S_MB_2U_LIB.S9S_MB_2U(SCH_1):PVCCD_HV_CPU0
   2    GND      B @S9S_MB_2U_LIB.S9S_MB_2U(SCH_1):GND

Q_CAP_C0805-47UF,4V,20%,X6S,CHA  I19  C515
   1 PVCCD_HV_CPU0      A @S9S_MB_2U_LIB.S9S_MB_2U(SCH_1):PVCCD_HV_CPU0
   2    GND      B @S9S_MB_2U_LIB.S9S_MB_2U(SCH_1):GND

Q_CAP_C0805-47UF,4V,20%,X6S,CHA  I21  C356
   1 PVCCIN_CPU0      A @S9S_MB_2U_LIB.S9S_MB_2U(SCH_1):PVCCIN_CPU0
   2    GND      B @S9S_MB_2U_LIB.S9S_MB_2U(SCH_1):GND

Q_CAP_C0805-47UF,4V,20%,X6S,CHA  I23  C355
   1 PVCCIN_CPU0      A @S9S_MB_2U_LIB.S9S_MB_2U(SCH_1):PVCCIN_CPU0
   2    GND      B @S9S_MB_2U_LIB.S9S_MB_2U(SCH_1):GND

Q_CAP_C0402-22UF,4V,20%,X6S,CHA  I29  C534
   1 PVCCINFAON_CPU0      A @S9S_MB_2U_LIB.S9S_MB_2U(SCH_1):PVCCINFAON_CPU0
   2    GND      B @S9S_MB_2U_LIB.S9S_MB_2U(SCH_1):GND

Q_CAP_C0805-47UF,4V,20%,X6S,CHA  I31  C518
   1 PVCCD_HV_CPU0      A @S9S_MB_2U_LIB.S9S_MB_2U(SCH_1):PVCCD_HV_CPU0
   2    GND      B @S9S_MB_2U_LIB.S9S_MB_2U(SCH_1):GND

Q_CAP_C0805-47UF,4V,20%,X6S,CHA  I32  C365
   1 PVCCIN_CPU0      A @S9S_MB_2U_LIB.S9S_MB_2U(SCH_1):PVCCIN_CPU0
   2    GND      B @S9S_MB_2U_LIB.S9S_MB_2U(SCH_1):GND

Q_CAP_C0805-47UF,4V,20%,X6S,CHA  I34  C364
   1 PVCCIN_CPU0      A @S9S_MB_2U_LIB.S9S_MB_2U(SCH_1):PVCCIN_CPU0
   2    GND      B @S9S_MB_2U_LIB.S9S_MB_2U(SCH_1):GND

Q_CAP_C0805-47UF,4V,20%,X6S,CHA  I35  C367
   1 PVCCIN_CPU0      A @S9S_MB_2U_LIB.S9S_MB_2U(SCH_1):PVCCIN_CPU0
   2    GND      B @S9S_MB_2U_LIB.S9S_MB_2U(SCH_1):GND

Q_CAP_C0805-47UF,4V,20%,X6S,CHA  I36  C371
   1 PVCCIN_CPU0      A @S9S_MB_2U_LIB.S9S_MB_2U(SCH_1):PVCCIN_CPU0
   2    GND      B @S9S_MB_2U_LIB.S9S_MB_2U(SCH_1):GND

Q_CAP_C0805-47UF,4V,20%,X6S,CHA  I37  C397
   1 PVCCIN_CPU0      A @S9S_MB_2U_LIB.S9S_MB_2U(SCH_1):PVCCIN_CPU0
   2    GND      B @S9S_MB_2U_LIB.S9S_MB_2U(SCH_1):GND

Q_CAP_C0805-47UF,4V,20%,X6S,CHA  I38  C357
   1 PVCCIN_CPU0      A @S9S_MB_2U_LIB.S9S_MB_2U(SCH_1):PVCCIN_CPU0
   2    GND      B @S9S_MB_2U_LIB.S9S_MB_2U(SCH_1):GND

Q_CAP_C0805-47UF,4V,20%,X6S,CHA  I39  C370
   1 PVCCIN_CPU0      A @S9S_MB_2U_LIB.S9S_MB_2U(SCH_1):PVCCIN_CPU0
   2    GND      B @S9S_MB_2U_LIB.S9S_MB_2U(SCH_1):GND

Q_CAP_C0805-47UF,4V,20%,X6S,CHA  I40  C373
   1 PVCCIN_CPU0      A @S9S_MB_2U_LIB.S9S_MB_2U(SCH_1):PVCCIN_CPU0
   2    GND      B @S9S_MB_2U_LIB.S9S_MB_2U(SCH_1):GND

Q_CAP_C0805-47UF,4V,20%,X6S,CHA  I41  C376
   1 PVCCIN_CPU0      A @S9S_MB_2U_LIB.S9S_MB_2U(SCH_1):PVCCIN_CPU0
   2    GND      B @S9S_MB_2U_LIB.S9S_MB_2U(SCH_1):GND

Q_CAP_C0805-47UF,4V,20%,X6S,CHA  I46  C395
   1 PVNN_MAIN_CPU0      A @S9S_MB_2U_LIB.S9S_MB_2U(SCH_1):PVNN_MAIN_CPU0
   2    GND      B @S9S_MB_2U_LIB.S9S_MB_2U(SCH_1):GND

Q_CAP_C0603-47UF,2.5V,20%,X6S,A  I47  C1405
   1 PVNN_MAIN_CPU0      A @S9S_MB_2U_LIB.S9S_MB_2U(SCH_1):PVNN_MAIN_CPU0
   2    GND      B @S9S_MB_2U_LIB.S9S_MB_2U(SCH_1):GND

Q_CAP_C0805-47UF,4V,20%,X6S,CHA  I48  C389
   1 PVCCIN_CPU0      A @S9S_MB_2U_LIB.S9S_MB_2U(SCH_1):PVCCIN_CPU0
   2    GND      B @S9S_MB_2U_LIB.S9S_MB_2U(SCH_1):GND

Q_CAP_C0805-47UF,4V,20%,X6S,CHA  I51  C382
   1 PVCCIN_CPU0      A @S9S_MB_2U_LIB.S9S_MB_2U(SCH_1):PVCCIN_CPU0
   2    GND      B @S9S_MB_2U_LIB.S9S_MB_2U(SCH_1):GND

Q_CAP_C0805-47UF,4V,20%,X6S,CHA  I55  C385
   1 PVCCIN_CPU0      A @S9S_MB_2U_LIB.S9S_MB_2U(SCH_1):PVCCIN_CPU0
   2    GND      B @S9S_MB_2U_LIB.S9S_MB_2U(SCH_1):GND

Q_CAP_C0805-47UF,4V,20%,X6S,CHA  I56  C387
   1 PVCCIN_CPU0      A @S9S_MB_2U_LIB.S9S_MB_2U(SCH_1):PVCCIN_CPU0
   2    GND      B @S9S_MB_2U_LIB.S9S_MB_2U(SCH_1):GND

Q_CAP_C0805-47UF,4V,20%,X6S,CHA  I58  C1398
   1 PVPP_HBM_CPU0      A @S9S_MB_2U_LIB.S9S_MB_2U(SCH_1):PVPP_HBM_CPU0
   2    GND      B @S9S_MB_2U_LIB.S9S_MB_2U(SCH_1):GND

Q_CAP_C0201-0.22UF,6.3V,10%,X6A  I59  C1436
   1 PVPP_HBM_CPU0      A @S9S_MB_2U_LIB.S9S_MB_2U(SCH_1):PVPP_HBM_CPU0
   2    GND      B @S9S_MB_2U_LIB.S9S_MB_2U(SCH_1):GND

Q_CAP_C0603-47UF,2.5V,20%,X6S,A  I61  C1406
   1 PVNN_MAIN_CPU0      A @S9S_MB_2U_LIB.S9S_MB_2U(SCH_1):PVNN_MAIN_CPU0
   2    GND      B @S9S_MB_2U_LIB.S9S_MB_2U(SCH_1):GND

Q_CAP_C0603-47UF,2.5V,20%,X6S,A  I62  C1407
   1 PVNN_MAIN_CPU0      A @S9S_MB_2U_LIB.S9S_MB_2U(SCH_1):PVNN_MAIN_CPU0
   2    GND      B @S9S_MB_2U_LIB.S9S_MB_2U(SCH_1):GND

Q_CAP_C0805-47UF,4V,20%,X6S,CHA  I64  C363
   1 PVCCIN_CPU0      A @S9S_MB_2U_LIB.S9S_MB_2U(SCH_1):PVCCIN_CPU0
   2    GND      B @S9S_MB_2U_LIB.S9S_MB_2U(SCH_1):GND

Q_CAP_C0805-47UF,4V,20%,X6S,CHA  I68  C527
   1 PVCCIN_CPU0      A @S9S_MB_2U_LIB.S9S_MB_2U(SCH_1):PVCCIN_CPU0
   2    GND      B @S9S_MB_2U_LIB.S9S_MB_2U(SCH_1):GND


DRAWING: @S9S_MB_2U_LIB.S9S_MB_2U(SCH_1):PAGE76 

Q_CAP_C0805-47UF,4V,20%,X6S,CHA  I1  C494
   1 PVCCFA_EHV_FIVRA_CPU0      A @S9S_MB_2U_LIB.S9S_MB_2U(SCH_1):PVCCFA_EHV_FIVRA_CPU0
   2    GND      B @S9S_MB_2U_LIB.S9S_MB_2U(SCH_1):GND

Q_CAP_C0805-47UF,4V,20%,X6S,CHA  I6  C528
   1 PVCCINFAON_CPU0      A @S9S_MB_2U_LIB.S9S_MB_2U(SCH_1):PVCCINFAON_CPU0
   2    GND      B @S9S_MB_2U_LIB.S9S_MB_2U(SCH_1):GND

Q_CAP_C0805-47UF,4V,20%,X6S,CHA  I7  C530
   1 PVCCINFAON_CPU0      A @S9S_MB_2U_LIB.S9S_MB_2U(SCH_1):PVCCINFAON_CPU0
   2    GND      B @S9S_MB_2U_LIB.S9S_MB_2U(SCH_1):GND

Q_CAP_C0805-47UF,4V,20%,X6S,CHA  I13  C1399
   1 PVNN_MAIN_CPU0      A @S9S_MB_2U_LIB.S9S_MB_2U(SCH_1):PVNN_MAIN_CPU0
   2    GND      B @S9S_MB_2U_LIB.S9S_MB_2U(SCH_1):GND

Q_CAP_C0805-47UF,4V,20%,X6S,CHA  I18  C499
   1 PVCCD_HV_CPU0      A @S9S_MB_2U_LIB.S9S_MB_2U(SCH_1):PVCCD_HV_CPU0
   2    GND      B @S9S_MB_2U_LIB.S9S_MB_2U(SCH_1):GND

Q_CAP_C0805-47UF,4V,20%,X6S,CHA  I20  C503
   1 PVCCD_HV_CPU0      A @S9S_MB_2U_LIB.S9S_MB_2U(SCH_1):PVCCD_HV_CPU0
   2    GND      B @S9S_MB_2U_LIB.S9S_MB_2U(SCH_1):GND

Q_CAP_C0805-47UF,4V,20%,X6S,CHA  I27  C510
   1 PVCCFA_EHV_FIVRA_CPU0      A @S9S_MB_2U_LIB.S9S_MB_2U(SCH_1):PVCCFA_EHV_FIVRA_CPU0
   2    GND      B @S9S_MB_2U_LIB.S9S_MB_2U(SCH_1):GND

Q_CAP_C0805-47UF,4V,20%,X6S,CHA  I28  C514
   1 PVCCFA_EHV_FIVRA_CPU0      A @S9S_MB_2U_LIB.S9S_MB_2U(SCH_1):PVCCFA_EHV_FIVRA_CPU0
   2    GND      B @S9S_MB_2U_LIB.S9S_MB_2U(SCH_1):GND

Q_CAP_C0805-47UF,4V,20%,X6S,CHA  I29  C517
   1 PVCCFA_EHV_FIVRA_CPU0      A @S9S_MB_2U_LIB.S9S_MB_2U(SCH_1):PVCCFA_EHV_FIVRA_CPU0
   2    GND      B @S9S_MB_2U_LIB.S9S_MB_2U(SCH_1):GND

Q_CAP_C0805-47UF,4V,20%,X6S,CHA  I31  C531
   1 PVCCINFAON_CPU0      A @S9S_MB_2U_LIB.S9S_MB_2U(SCH_1):PVCCINFAON_CPU0
   2    GND      B @S9S_MB_2U_LIB.S9S_MB_2U(SCH_1):GND

Q_CAP_C0805-47UF,4V,20%,X6S,CHA  I41  C529
   1 PVCCFA_EHV_FIVRA_CPU0      A @S9S_MB_2U_LIB.S9S_MB_2U(SCH_1):PVCCFA_EHV_FIVRA_CPU0
   2    GND      B @S9S_MB_2U_LIB.S9S_MB_2U(SCH_1):GND

Q_CAP_C0805-47UF,4V,20%,X6S,CHA  I46  C396
   1 PVCCIN_CPU0      A @S9S_MB_2U_LIB.S9S_MB_2U(SCH_1):PVCCIN_CPU0
   2    GND      B @S9S_MB_2U_LIB.S9S_MB_2U(SCH_1):GND

Q_CAP_C0805-47UF,4V,20%,X6S,CHA  I47  C398
   1 PVCCIN_CPU0      A @S9S_MB_2U_LIB.S9S_MB_2U(SCH_1):PVCCIN_CPU0
   2    GND      B @S9S_MB_2U_LIB.S9S_MB_2U(SCH_1):GND

Q_CAP_C0805-47UF,4V,20%,X6S,CHA  I2  C498
   1 PVCCFA_EHV_FIVRA_CPU0      A @S9S_MB_2U_LIB.S9S_MB_2U(SCH_1):PVCCFA_EHV_FIVRA_CPU0
   2    GND      B @S9S_MB_2U_LIB.S9S_MB_2U(SCH_1):GND

Q_CAP_C0805-47UF,4V,20%,X6S,CHA  I3  C502
   1 PVCCFA_EHV_FIVRA_CPU0      A @S9S_MB_2U_LIB.S9S_MB_2U(SCH_1):PVCCFA_EHV_FIVRA_CPU0
   2    GND      B @S9S_MB_2U_LIB.S9S_MB_2U(SCH_1):GND

Q_CAP_C0805-47UF,4V,20%,X6S,CHA  I5  C525
   1 PVCCINFAON_CPU0      A @S9S_MB_2U_LIB.S9S_MB_2U(SCH_1):PVCCINFAON_CPU0
   2    GND      B @S9S_MB_2U_LIB.S9S_MB_2U(SCH_1):GND

Q_CAP_C0805-47UF,4V,20%,X6S,CHA  I9  C500
   1 PVCCFA_EHV_CPU0      A @S9S_MB_2U_LIB.S9S_MB_2U(SCH_1):PVCCFA_EHV_CPU0
   2    GND      B @S9S_MB_2U_LIB.S9S_MB_2U(SCH_1):GND

Q_CAP_C0805-47UF,4V,20%,X6S,CHA  I10  C504
   1 PVCCFA_EHV_CPU0      A @S9S_MB_2U_LIB.S9S_MB_2U(SCH_1):PVCCFA_EHV_CPU0
   2    GND      B @S9S_MB_2U_LIB.S9S_MB_2U(SCH_1):GND

Q_CAP_C0805-47UF,4V,20%,X6S,CHA  I11  C508
   1 PVCCFA_EHV_CPU0      A @S9S_MB_2U_LIB.S9S_MB_2U(SCH_1):PVCCFA_EHV_CPU0
   2    GND      B @S9S_MB_2U_LIB.S9S_MB_2U(SCH_1):GND

Q_CAP_C0805-47UF,4V,20%,X6S,CHA  I14  C1400
   1 PVNN_MAIN_CPU0      A @S9S_MB_2U_LIB.S9S_MB_2U(SCH_1):PVNN_MAIN_CPU0
   2    GND      B @S9S_MB_2U_LIB.S9S_MB_2U(SCH_1):GND

Q_CAP_C0402-22UF,4V,20%,X6S,CHA  I16  C1362
   1 PVNN_MAIN_CPU0      A @S9S_MB_2U_LIB.S9S_MB_2U(SCH_1):PVNN_MAIN_CPU0
   2    GND      B @S9S_MB_2U_LIB.S9S_MB_2U(SCH_1):GND

Q_CAP_C0805-47UF,4V,20%,X6S,CHA  I21  C507
   1 PVCCD_HV_CPU0      A @S9S_MB_2U_LIB.S9S_MB_2U(SCH_1):PVCCD_HV_CPU0
   2    GND      B @S9S_MB_2U_LIB.S9S_MB_2U(SCH_1):GND

Q_CAP_C0805-47UF,4V,20%,X6S,CHA  I22  C386
   1 PVCCIN_CPU0      A @S9S_MB_2U_LIB.S9S_MB_2U(SCH_1):PVCCIN_CPU0
   2    GND      B @S9S_MB_2U_LIB.S9S_MB_2U(SCH_1):GND

Q_CAP_C0805-47UF,4V,20%,X6S,CHA  I23  C388
   1 PVCCIN_CPU0      A @S9S_MB_2U_LIB.S9S_MB_2U(SCH_1):PVCCIN_CPU0
   2    GND      B @S9S_MB_2U_LIB.S9S_MB_2U(SCH_1):GND

Q_CAP_C0805-47UF,4V,20%,X6S,CHA  I25  C390
   1 PVCCIN_CPU0      A @S9S_MB_2U_LIB.S9S_MB_2U(SCH_1):PVCCIN_CPU0
   2    GND      B @S9S_MB_2U_LIB.S9S_MB_2U(SCH_1):GND

Q_CAP_C0805-47UF,4V,20%,X6S,CHA  I26  C506
   1 PVCCFA_EHV_FIVRA_CPU0      A @S9S_MB_2U_LIB.S9S_MB_2U(SCH_1):PVCCFA_EHV_FIVRA_CPU0
   2    GND      B @S9S_MB_2U_LIB.S9S_MB_2U(SCH_1):GND

Q_CAP_C0805-47UF,4V,20%,X6S,CHA  I32  C512
   1 PVCCFA_EHV_CPU0      A @S9S_MB_2U_LIB.S9S_MB_2U(SCH_1):PVCCFA_EHV_CPU0
   2    GND      B @S9S_MB_2U_LIB.S9S_MB_2U(SCH_1):GND

Q_CAP_C0603-47UF,2.5V,20%,X6S,A  I33  C516
   1 PVCCFA_EHV_CPU0      A @S9S_MB_2U_LIB.S9S_MB_2U(SCH_1):PVCCFA_EHV_CPU0
   2    GND      B @S9S_MB_2U_LIB.S9S_MB_2U(SCH_1):GND

Q_CAP_C0603-47UF,2.5V,20%,X6S,A  I35  C519
   1 PVCCFA_EHV_CPU0      A @S9S_MB_2U_LIB.S9S_MB_2U(SCH_1):PVCCFA_EHV_CPU0
   2    GND      B @S9S_MB_2U_LIB.S9S_MB_2U(SCH_1):GND

Q_CAP_C0805-47UF,4V,20%,X6S,CHA  I36  C520
   1 PVCCFA_EHV_FIVRA_CPU0      A @S9S_MB_2U_LIB.S9S_MB_2U(SCH_1):PVCCFA_EHV_FIVRA_CPU0
   2    GND      B @S9S_MB_2U_LIB.S9S_MB_2U(SCH_1):GND

Q_CAP_C0805-47UF,4V,20%,X6S,CHA  I37  C521
   1 PVCCFA_EHV_FIVRA_CPU0      A @S9S_MB_2U_LIB.S9S_MB_2U(SCH_1):PVCCFA_EHV_FIVRA_CPU0
   2    GND      B @S9S_MB_2U_LIB.S9S_MB_2U(SCH_1):GND

Q_CAP_C0805-47UF,4V,20%,X6S,CHA  I38  C523
   1 PVCCFA_EHV_FIVRA_CPU0      A @S9S_MB_2U_LIB.S9S_MB_2U(SCH_1):PVCCFA_EHV_FIVRA_CPU0
   2    GND      B @S9S_MB_2U_LIB.S9S_MB_2U(SCH_1):GND

Q_CAP_C0805-47UF,4V,20%,X6S,CHA  I39  C526
   1 PVCCFA_EHV_FIVRA_CPU0      A @S9S_MB_2U_LIB.S9S_MB_2U(SCH_1):PVCCFA_EHV_FIVRA_CPU0
   2    GND      B @S9S_MB_2U_LIB.S9S_MB_2U(SCH_1):GND

Q_CAP_C0805-47UF,4V,20%,X6S,CHA  I43  C511
   1 PVCCD_HV_CPU0      A @S9S_MB_2U_LIB.S9S_MB_2U(SCH_1):PVCCD_HV_CPU0
   2    GND      B @S9S_MB_2U_LIB.S9S_MB_2U(SCH_1):GND

Q_CAP_C0805-47UF,4V,20%,X6S,CHA  I44  C392
   1 PVCCIN_CPU0      A @S9S_MB_2U_LIB.S9S_MB_2U(SCH_1):PVCCIN_CPU0
   2    GND      B @S9S_MB_2U_LIB.S9S_MB_2U(SCH_1):GND

Q_CAP_C0805-47UF,4V,20%,X6S,CHA  I45  C394
   1 PVCCIN_CPU0      A @S9S_MB_2U_LIB.S9S_MB_2U(SCH_1):PVCCIN_CPU0
   2    GND      B @S9S_MB_2U_LIB.S9S_MB_2U(SCH_1):GND

Q_CAP_C0805-47UF,4V,20%,X6S,CHA  I48  C366
   1 PVCCIN_CPU0      A @S9S_MB_2U_LIB.S9S_MB_2U(SCH_1):PVCCIN_CPU0
   2    GND      B @S9S_MB_2U_LIB.S9S_MB_2U(SCH_1):GND

Q_CAP_C0805-47UF,4V,20%,X6S,CHA  I49  C369
   1 PVCCIN_CPU0      A @S9S_MB_2U_LIB.S9S_MB_2U(SCH_1):PVCCIN_CPU0
   2    GND      B @S9S_MB_2U_LIB.S9S_MB_2U(SCH_1):GND

Q_CAP_C0805-47UF,4V,20%,X6S,CHA  I50  C372
   1 PVCCIN_CPU0      A @S9S_MB_2U_LIB.S9S_MB_2U(SCH_1):PVCCIN_CPU0
   2    GND      B @S9S_MB_2U_LIB.S9S_MB_2U(SCH_1):GND

Q_CAP_C0805-47UF,4V,20%,X6S,CHA  I51  C374
   1 PVCCIN_CPU0      A @S9S_MB_2U_LIB.S9S_MB_2U(SCH_1):PVCCIN_CPU0
   2    GND      B @S9S_MB_2U_LIB.S9S_MB_2U(SCH_1):GND

Q_CAP_C0805-47UF,4V,20%,X6S,CHA  I52  C377
   1 PVCCIN_CPU0      A @S9S_MB_2U_LIB.S9S_MB_2U(SCH_1):PVCCIN_CPU0
   2    GND      B @S9S_MB_2U_LIB.S9S_MB_2U(SCH_1):GND

Q_CAP_C0805-47UF,4V,20%,X6S,CHA  I53  C380
   1 PVCCIN_CPU0      A @S9S_MB_2U_LIB.S9S_MB_2U(SCH_1):PVCCIN_CPU0
   2    GND      B @S9S_MB_2U_LIB.S9S_MB_2U(SCH_1):GND

Q_CAP_C0805-47UF,4V,20%,X6S,CHA  I54  C383
   1 PVCCIN_CPU0      A @S9S_MB_2U_LIB.S9S_MB_2U(SCH_1):PVCCIN_CPU0
   2    GND      B @S9S_MB_2U_LIB.S9S_MB_2U(SCH_1):GND


DRAWING: @S9S_MB_2U_LIB.S9S_MB_2U(SCH_1):PAGE77 

Q_CAP_C0402-22UF,4V,20%,X6S,CHA  I1  C424
   1 PVCCFA_EHV_FIVRA_CPU1      A @S9S_MB_2U_LIB.S9S_MB_2U(SCH_1):PVCCFA_EHV_FIVRA_CPU1
   2    GND      B @S9S_MB_2U_LIB.S9S_MB_2U(SCH_1):GND

Q_CAP_C0402-22UF,4V,20%,X6S,CHA  I4  C428
   1 PVCCFA_EHV_FIVRA_CPU1      A @S9S_MB_2U_LIB.S9S_MB_2U(SCH_1):PVCCFA_EHV_FIVRA_CPU1
   2    GND      B @S9S_MB_2U_LIB.S9S_MB_2U(SCH_1):GND

Q_CAP_C0402-22UF,4V,20%,X6S,CHA  I5  C430
   1 PVCCFA_EHV_FIVRA_CPU1      A @S9S_MB_2U_LIB.S9S_MB_2U(SCH_1):PVCCFA_EHV_FIVRA_CPU1
   2    GND      B @S9S_MB_2U_LIB.S9S_MB_2U(SCH_1):GND

Q_CAP_C0402-22UF,4V,20%,X6S,CHA  I7  C423
   1 PVCCD_HV_CPU1      A @S9S_MB_2U_LIB.S9S_MB_2U(SCH_1):PVCCD_HV_CPU1
   2    GND      B @S9S_MB_2U_LIB.S9S_MB_2U(SCH_1):GND

Q_CAP_C0402-22UF,4V,20%,X6S,CHA  I8  C425
   1 PVCCD_HV_CPU1      A @S9S_MB_2U_LIB.S9S_MB_2U(SCH_1):PVCCD_HV_CPU1
   2    GND      B @S9S_MB_2U_LIB.S9S_MB_2U(SCH_1):GND

Q_CAP_C0805-47UF,4V,20%,X6S,CHA  I10  C225
   1 PVCCIN_CPU1      A @S9S_MB_2U_LIB.S9S_MB_2U(SCH_1):PVCCIN_CPU1
   2    GND      B @S9S_MB_2U_LIB.S9S_MB_2U(SCH_1):GND

Q_CAP_C0805-47UF,4V,20%,X6S,CHA  I11  C230
   1 PVCCIN_CPU1      A @S9S_MB_2U_LIB.S9S_MB_2U(SCH_1):PVCCIN_CPU1
   2    GND      B @S9S_MB_2U_LIB.S9S_MB_2U(SCH_1):GND

Q_CAP_C0402-10UF,6.3V,20%,X6S,B  I13  C224
   1 PVCCIN_CPU1      A @S9S_MB_2U_LIB.S9S_MB_2U(SCH_1):PVCCIN_CPU1
   2    GND      B @S9S_MB_2U_LIB.S9S_MB_2U(SCH_1):GND

Q_CAP_C0402-22UF,4V,20%,X6S,CHA  I15  C427
   1 PVCCD_HV_CPU1      A @S9S_MB_2U_LIB.S9S_MB_2U(SCH_1):PVCCD_HV_CPU1
   2    GND      B @S9S_MB_2U_LIB.S9S_MB_2U(SCH_1):GND

Q_CAP_C0402-22UF,4V,20%,X6S,CHA  I17  C429
   1 PVCCD_HV_CPU1      A @S9S_MB_2U_LIB.S9S_MB_2U(SCH_1):PVCCD_HV_CPU1
   2    GND      B @S9S_MB_2U_LIB.S9S_MB_2U(SCH_1):GND

Q_CAP_C0805-47UF,4V,20%,X6S,CHA  I18  C240
   1 PVCCIN_CPU1      A @S9S_MB_2U_LIB.S9S_MB_2U(SCH_1):PVCCIN_CPU1
   2    GND      B @S9S_MB_2U_LIB.S9S_MB_2U(SCH_1):GND

Q_CAP_C0402-10UF,6.3V,20%,X6S,B  I19  C234
   1 PVCCIN_CPU1      A @S9S_MB_2U_LIB.S9S_MB_2U(SCH_1):PVCCIN_CPU1
   2    GND      B @S9S_MB_2U_LIB.S9S_MB_2U(SCH_1):GND

Q_CAP_C0402-10UF,6.3V,20%,X6S,B  I20  C239
   1 PVCCIN_CPU1      A @S9S_MB_2U_LIB.S9S_MB_2U(SCH_1):PVCCIN_CPU1
   2    GND      B @S9S_MB_2U_LIB.S9S_MB_2U(SCH_1):GND

Q_CAP_C0402-10UF,6.3V,20%,X6S,B  I22  C223
   1 PVCCIN_CPU1      A @S9S_MB_2U_LIB.S9S_MB_2U(SCH_1):PVCCIN_CPU1
   2    GND      B @S9S_MB_2U_LIB.S9S_MB_2U(SCH_1):GND

Q_CAP_C0402-10UF,6.3V,20%,X6S,B  I23  C228
   1 PVCCIN_CPU1      A @S9S_MB_2U_LIB.S9S_MB_2U(SCH_1):PVCCIN_CPU1
   2    GND      B @S9S_MB_2U_LIB.S9S_MB_2U(SCH_1):GND

Q_CAP_C0402-10UF,6.3V,20%,X6S,B  I25  C222
   1 PVCCIN_CPU1      A @S9S_MB_2U_LIB.S9S_MB_2U(SCH_1):PVCCIN_CPU1
   2    GND      B @S9S_MB_2U_LIB.S9S_MB_2U(SCH_1):GND

Q_CAP_C0402-10UF,6.3V,20%,X6S,B  I28  C221
   1 PVCCIN_CPU1      A @S9S_MB_2U_LIB.S9S_MB_2U(SCH_1):PVCCIN_CPU1
   2    GND      B @S9S_MB_2U_LIB.S9S_MB_2U(SCH_1):GND

Q_CAP_C0402-10UF,6.3V,20%,X6S,B  I29  C226
   1 PVCCIN_CPU1      A @S9S_MB_2U_LIB.S9S_MB_2U(SCH_1):PVCCIN_CPU1
   2    GND      B @S9S_MB_2U_LIB.S9S_MB_2U(SCH_1):GND

Q_CAP_C0402-10UF,6.3V,20%,X6S,B  I30  C233
   1 PVCCIN_CPU1      A @S9S_MB_2U_LIB.S9S_MB_2U(SCH_1):PVCCIN_CPU1
   2    GND      B @S9S_MB_2U_LIB.S9S_MB_2U(SCH_1):GND

Q_CAP_C0402-10UF,6.3V,20%,X6S,B  I31  C238
   1 PVCCIN_CPU1      A @S9S_MB_2U_LIB.S9S_MB_2U(SCH_1):PVCCIN_CPU1
   2    GND      B @S9S_MB_2U_LIB.S9S_MB_2U(SCH_1):GND

Q_CAP_C0402-10UF,6.3V,20%,X6S,B  I32  C232
   1 PVCCIN_CPU1      A @S9S_MB_2U_LIB.S9S_MB_2U(SCH_1):PVCCIN_CPU1
   2    GND      B @S9S_MB_2U_LIB.S9S_MB_2U(SCH_1):GND

Q_CAP_C0402-10UF,6.3V,20%,X6S,B  I33  C231
   1 PVCCIN_CPU1      A @S9S_MB_2U_LIB.S9S_MB_2U(SCH_1):PVCCIN_CPU1
   2    GND      B @S9S_MB_2U_LIB.S9S_MB_2U(SCH_1):GND

Q_CAP_C0402-10UF,6.3V,20%,X6S,B  I34  C237
   1 PVCCIN_CPU1      A @S9S_MB_2U_LIB.S9S_MB_2U(SCH_1):PVCCIN_CPU1
   2    GND      B @S9S_MB_2U_LIB.S9S_MB_2U(SCH_1):GND

Q_CAP_C0402-10UF,6.3V,20%,X6S,B  I35  C236
   1 PVCCIN_CPU1      A @S9S_MB_2U_LIB.S9S_MB_2U(SCH_1):PVCCIN_CPU1
   2    GND      B @S9S_MB_2U_LIB.S9S_MB_2U(SCH_1):GND

Q_CAP_C0402-22UF,4V,20%,X6S,CHA  I37  C431
   1 PVCCFA_EHV_FIVRA_CPU1      A @S9S_MB_2U_LIB.S9S_MB_2U(SCH_1):PVCCFA_EHV_FIVRA_CPU1
   2    GND      B @S9S_MB_2U_LIB.S9S_MB_2U(SCH_1):GND

Q_CAP_C0402-22UF,4V,20%,X6S,CHA  I38  C433
   1 PVCCFA_EHV_FIVRA_CPU1      A @S9S_MB_2U_LIB.S9S_MB_2U(SCH_1):PVCCFA_EHV_FIVRA_CPU1
   2    GND      B @S9S_MB_2U_LIB.S9S_MB_2U(SCH_1):GND

Q_CAP_C0402-22UF,4V,20%,X6S,CHA  I39  C435
   1 PVCCFA_EHV_FIVRA_CPU1      A @S9S_MB_2U_LIB.S9S_MB_2U(SCH_1):PVCCFA_EHV_FIVRA_CPU1
   2    GND      B @S9S_MB_2U_LIB.S9S_MB_2U(SCH_1):GND

Q_CAP_C0805-47UF,4V,20%,X6S,CHA  I41  C245
   1 PVCCIN_CPU1      A @S9S_MB_2U_LIB.S9S_MB_2U(SCH_1):PVCCIN_CPU1
   2    GND      B @S9S_MB_2U_LIB.S9S_MB_2U(SCH_1):GND

Q_CAP_C0402-22UF,4V,20%,X6S,CHA  I42  C432
   1 PVCCINFAON_CPU1      A @S9S_MB_2U_LIB.S9S_MB_2U(SCH_1):PVCCINFAON_CPU1
   2    GND      B @S9S_MB_2U_LIB.S9S_MB_2U(SCH_1):GND

Q_CAP_C0805-47UF,4V,20%,X6S,CHA  I44  C250
   1 PVCCIN_CPU1      A @S9S_MB_2U_LIB.S9S_MB_2U(SCH_1):PVCCIN_CPU1
   2    GND      B @S9S_MB_2U_LIB.S9S_MB_2U(SCH_1):GND

Q_CAP_C0402-10UF,6.3V,20%,X6S,B  I45  C244
   1 PVCCIN_CPU1      A @S9S_MB_2U_LIB.S9S_MB_2U(SCH_1):PVCCIN_CPU1
   2    GND      B @S9S_MB_2U_LIB.S9S_MB_2U(SCH_1):GND

Q_CAP_C0402-10UF,6.3V,20%,X6S,B  I46  C249
   1 PVCCIN_CPU1      A @S9S_MB_2U_LIB.S9S_MB_2U(SCH_1):PVCCIN_CPU1
   2    GND      B @S9S_MB_2U_LIB.S9S_MB_2U(SCH_1):GND

Q_CAP_C0402-22UF,4V,20%,X6S,CHA  I47  C434
   1 PVCCINFAON_CPU1      A @S9S_MB_2U_LIB.S9S_MB_2U(SCH_1):PVCCINFAON_CPU1
   2    GND      B @S9S_MB_2U_LIB.S9S_MB_2U(SCH_1):GND

Q_CAP_C0805-47UF,4V,20%,X6S,CHA  I48  C255
   1 PVCCIN_CPU1      A @S9S_MB_2U_LIB.S9S_MB_2U(SCH_1):PVCCIN_CPU1
   2    GND      B @S9S_MB_2U_LIB.S9S_MB_2U(SCH_1):GND

Q_CAP_C0402-22UF,4V,20%,X6S,CHA  I49  C436
   1 PVCCINFAON_CPU1      A @S9S_MB_2U_LIB.S9S_MB_2U(SCH_1):PVCCINFAON_CPU1
   2    GND      B @S9S_MB_2U_LIB.S9S_MB_2U(SCH_1):GND

Q_CAP_C0805-47UF,4V,20%,X6S,CHA  I50  C260
   1 PVCCIN_CPU1      A @S9S_MB_2U_LIB.S9S_MB_2U(SCH_1):PVCCIN_CPU1
   2    GND      B @S9S_MB_2U_LIB.S9S_MB_2U(SCH_1):GND

Q_CAP_C0402-10UF,6.3V,20%,X6S,B  I51  C254
   1 PVCCIN_CPU1      A @S9S_MB_2U_LIB.S9S_MB_2U(SCH_1):PVCCIN_CPU1
   2    GND      B @S9S_MB_2U_LIB.S9S_MB_2U(SCH_1):GND

Q_CAP_C0402-10UF,6.3V,20%,X6S,B  I52  C259
   1 PVCCIN_CPU1      A @S9S_MB_2U_LIB.S9S_MB_2U(SCH_1):PVCCIN_CPU1
   2    GND      B @S9S_MB_2U_LIB.S9S_MB_2U(SCH_1):GND

Q_CAP_C0402-22UF,4V,20%,X6S,CHA  I53  C439
   1 PVCCFA_EHV_FIVRA_CPU1      A @S9S_MB_2U_LIB.S9S_MB_2U(SCH_1):PVCCFA_EHV_FIVRA_CPU1
   2    GND      B @S9S_MB_2U_LIB.S9S_MB_2U(SCH_1):GND

Q_CAP_C0402-22UF,4V,20%,X6S,CHA  I55  C441
   1 PVCCFA_EHV_FIVRA_CPU1      A @S9S_MB_2U_LIB.S9S_MB_2U(SCH_1):PVCCFA_EHV_FIVRA_CPU1
   2    GND      B @S9S_MB_2U_LIB.S9S_MB_2U(SCH_1):GND

Q_CAP_C0402-22UF,4V,20%,X6S,CHA  I57  C442
   1 PVCCFA_EHV_FIVRA_CPU1      A @S9S_MB_2U_LIB.S9S_MB_2U(SCH_1):PVCCFA_EHV_FIVRA_CPU1
   2    GND      B @S9S_MB_2U_LIB.S9S_MB_2U(SCH_1):GND

Q_CAP_C0402-22UF,4V,20%,X6S,CHA  I58  C438
   1 PVCCINFAON_CPU1      A @S9S_MB_2U_LIB.S9S_MB_2U(SCH_1):PVCCINFAON_CPU1
   2    GND      B @S9S_MB_2U_LIB.S9S_MB_2U(SCH_1):GND

Q_CAP_C0805-47UF,4V,20%,X6S,CHA  I59  C265
   1 PVCCIN_CPU1      A @S9S_MB_2U_LIB.S9S_MB_2U(SCH_1):PVCCIN_CPU1
   2    GND      B @S9S_MB_2U_LIB.S9S_MB_2U(SCH_1):GND

Q_CAP_C0402-22UF,4V,20%,X6S,CHA  I61  C440
   1 PVCCINFAON_CPU1      A @S9S_MB_2U_LIB.S9S_MB_2U(SCH_1):PVCCINFAON_CPU1
   2    GND      B @S9S_MB_2U_LIB.S9S_MB_2U(SCH_1):GND

Q_CAP_C0805-47UF,4V,20%,X6S,CHA  I62  C270
   1 PVCCIN_CPU1      A @S9S_MB_2U_LIB.S9S_MB_2U(SCH_1):PVCCIN_CPU1
   2    GND      B @S9S_MB_2U_LIB.S9S_MB_2U(SCH_1):GND

Q_CAP_C0402-10UF,6.3V,20%,X6S,B  I63  C264
   1 PVCCIN_CPU1      A @S9S_MB_2U_LIB.S9S_MB_2U(SCH_1):PVCCIN_CPU1
   2    GND      B @S9S_MB_2U_LIB.S9S_MB_2U(SCH_1):GND

Q_CAP_C0402-22UF,4V,20%,X6S,CHA  I66  C274
   1 PVCCIN_CPU1      A @S9S_MB_2U_LIB.S9S_MB_2U(SCH_1):PVCCIN_CPU1
   2    GND      B @S9S_MB_2U_LIB.S9S_MB_2U(SCH_1):GND

Q_CAP_C0402-22UF,4V,20%,X6S,CHA  I71  C278
   1 PVCCIN_CPU1      A @S9S_MB_2U_LIB.S9S_MB_2U(SCH_1):PVCCIN_CPU1
   2    GND      B @S9S_MB_2U_LIB.S9S_MB_2U(SCH_1):GND

Q_CAP_C0402-22UF,4V,20%,X6S,CHA  I73  C282
   1 PVCCIN_CPU1      A @S9S_MB_2U_LIB.S9S_MB_2U(SCH_1):PVCCIN_CPU1
   2    GND      B @S9S_MB_2U_LIB.S9S_MB_2U(SCH_1):GND

Q_CAP_C0402-10UF,6.3V,20%,X6S,B  I75  C248
   1 PVCCIN_CPU1      A @S9S_MB_2U_LIB.S9S_MB_2U(SCH_1):PVCCIN_CPU1
   2    GND      B @S9S_MB_2U_LIB.S9S_MB_2U(SCH_1):GND

Q_CAP_C0402-10UF,6.3V,20%,X6S,B  I76  C242
   1 PVCCIN_CPU1      A @S9S_MB_2U_LIB.S9S_MB_2U(SCH_1):PVCCIN_CPU1
   2    GND      B @S9S_MB_2U_LIB.S9S_MB_2U(SCH_1):GND

Q_CAP_C0402-10UF,6.3V,20%,X6S,B  I78  C247
   1 PVCCIN_CPU1      A @S9S_MB_2U_LIB.S9S_MB_2U(SCH_1):PVCCIN_CPU1
   2    GND      B @S9S_MB_2U_LIB.S9S_MB_2U(SCH_1):GND

Q_CAP_C0402-10UF,6.3V,20%,X6S,B  I79  C246
   1 PVCCIN_CPU1      A @S9S_MB_2U_LIB.S9S_MB_2U(SCH_1):PVCCIN_CPU1
   2    GND      B @S9S_MB_2U_LIB.S9S_MB_2U(SCH_1):GND

Q_CAP_C0402-10UF,6.3V,20%,X6S,B  I81  C258
   1 PVCCIN_CPU1      A @S9S_MB_2U_LIB.S9S_MB_2U(SCH_1):PVCCIN_CPU1
   2    GND      B @S9S_MB_2U_LIB.S9S_MB_2U(SCH_1):GND

Q_CAP_C0402-10UF,6.3V,20%,X6S,B  I83  C251
   1 PVCCIN_CPU1      A @S9S_MB_2U_LIB.S9S_MB_2U(SCH_1):PVCCIN_CPU1
   2    GND      B @S9S_MB_2U_LIB.S9S_MB_2U(SCH_1):GND

Q_CAP_C0402-10UF,6.3V,20%,X6S,B  I84  C257
   1 PVCCIN_CPU1      A @S9S_MB_2U_LIB.S9S_MB_2U(SCH_1):PVCCIN_CPU1
   2    GND      B @S9S_MB_2U_LIB.S9S_MB_2U(SCH_1):GND

Q_CAP_C0402-10UF,6.3V,20%,X6S,B  I86  C263
   1 PVCCIN_CPU1      A @S9S_MB_2U_LIB.S9S_MB_2U(SCH_1):PVCCIN_CPU1
   2    GND      B @S9S_MB_2U_LIB.S9S_MB_2U(SCH_1):GND

Q_CAP_C0402-10UF,6.3V,20%,X6S,B  I88  C268
   1 PVCCIN_CPU1      A @S9S_MB_2U_LIB.S9S_MB_2U(SCH_1):PVCCIN_CPU1
   2    GND      B @S9S_MB_2U_LIB.S9S_MB_2U(SCH_1):GND

Q_CAP_C0402-10UF,6.3V,20%,X6S,B  I93  C262
   1 PVCCIN_CPU1      A @S9S_MB_2U_LIB.S9S_MB_2U(SCH_1):PVCCIN_CPU1
   2    GND      B @S9S_MB_2U_LIB.S9S_MB_2U(SCH_1):GND

Q_CAP_C0402-10UF,6.3V,20%,X6S,B  I95  C261
   1 PVCCIN_CPU1      A @S9S_MB_2U_LIB.S9S_MB_2U(SCH_1):PVCCIN_CPU1
   2    GND      B @S9S_MB_2U_LIB.S9S_MB_2U(SCH_1):GND

Q_CAP_C0402-22UF,4V,20%,X6S,CHA  I98  C272
   1 PVCCIN_CPU1      A @S9S_MB_2U_LIB.S9S_MB_2U(SCH_1):PVCCIN_CPU1
   2    GND      B @S9S_MB_2U_LIB.S9S_MB_2U(SCH_1):GND

Q_CAP_C0402-22UF,4V,20%,X6S,CHA  I100  C271
   1 PVCCIN_CPU1      A @S9S_MB_2U_LIB.S9S_MB_2U(SCH_1):PVCCIN_CPU1
   2    GND      B @S9S_MB_2U_LIB.S9S_MB_2U(SCH_1):GND

Q_CAP_C0402-22UF,4V,20%,X6S,CHA  I101  C277
   1 PVCCIN_CPU1      A @S9S_MB_2U_LIB.S9S_MB_2U(SCH_1):PVCCIN_CPU1
   2    GND      B @S9S_MB_2U_LIB.S9S_MB_2U(SCH_1):GND

Q_CAP_C0402-22UF,4V,20%,X6S,CHA  I102  C281
   1 PVCCIN_CPU1      A @S9S_MB_2U_LIB.S9S_MB_2U(SCH_1):PVCCIN_CPU1
   2    GND      B @S9S_MB_2U_LIB.S9S_MB_2U(SCH_1):GND

Q_CAP_C0402-22UF,4V,20%,X6S,CHA  I103  C276
   1 PVCCIN_CPU1      A @S9S_MB_2U_LIB.S9S_MB_2U(SCH_1):PVCCIN_CPU1
   2    GND      B @S9S_MB_2U_LIB.S9S_MB_2U(SCH_1):GND

Q_CAP_C0402-22UF,4V,20%,X6S,CHA  I104  C275
   1 PVCCIN_CPU1      A @S9S_MB_2U_LIB.S9S_MB_2U(SCH_1):PVCCIN_CPU1
   2    GND      B @S9S_MB_2U_LIB.S9S_MB_2U(SCH_1):GND

Q_CAP_C0402-22UF,4V,20%,X6S,CHA  I105  C280
   1 PVCCIN_CPU1      A @S9S_MB_2U_LIB.S9S_MB_2U(SCH_1):PVCCIN_CPU1
   2    GND      B @S9S_MB_2U_LIB.S9S_MB_2U(SCH_1):GND

Q_CAP_C0402-22UF,4V,20%,X6S,CHA  I106  C279
   1 PVCCIN_CPU1      A @S9S_MB_2U_LIB.S9S_MB_2U(SCH_1):PVCCIN_CPU1
   2    GND      B @S9S_MB_2U_LIB.S9S_MB_2U(SCH_1):GND

Q_CAP_C0402-22UF,4V,20%,X6S,CHA  I109  C444
   1 PVCCFA_EHV_CPU1      A @S9S_MB_2U_LIB.S9S_MB_2U(SCH_1):PVCCFA_EHV_CPU1
   2    GND      B @S9S_MB_2U_LIB.S9S_MB_2U(SCH_1):GND

Q_CAP_C0402-22UF,4V,20%,X6S,CHA  I110  C445
   1 PVCCFA_EHV_CPU1      A @S9S_MB_2U_LIB.S9S_MB_2U(SCH_1):PVCCFA_EHV_CPU1
   2    GND      B @S9S_MB_2U_LIB.S9S_MB_2U(SCH_1):GND

Q_CAP_C0402-22UF,4V,20%,X6S,CHA  I111  C286
   1 PVCCIN_CPU1      A @S9S_MB_2U_LIB.S9S_MB_2U(SCH_1):PVCCIN_CPU1
   2    GND      B @S9S_MB_2U_LIB.S9S_MB_2U(SCH_1):GND

Q_CAP_C0402-22UF,4V,20%,X6S,CHA  I112  C290
   1 PVCCIN_CPU1      A @S9S_MB_2U_LIB.S9S_MB_2U(SCH_1):PVCCIN_CPU1
   2    GND      B @S9S_MB_2U_LIB.S9S_MB_2U(SCH_1):GND

Q_CAP_C0402-22UF,4V,20%,X6S,CHA  I113  C446
   1 PVCCFA_EHV_CPU1      A @S9S_MB_2U_LIB.S9S_MB_2U(SCH_1):PVCCFA_EHV_CPU1
   2    GND      B @S9S_MB_2U_LIB.S9S_MB_2U(SCH_1):GND

Q_CAP_C0402-22UF,4V,20%,X6S,CHA  I114  C294
   1 PVCCIN_CPU1      A @S9S_MB_2U_LIB.S9S_MB_2U(SCH_1):PVCCIN_CPU1
   2    GND      B @S9S_MB_2U_LIB.S9S_MB_2U(SCH_1):GND

Q_CAP_C0402-22UF,4V,20%,X6S,CHA  I115  C298
   1 PVCCIN_CPU1      A @S9S_MB_2U_LIB.S9S_MB_2U(SCH_1):PVCCIN_CPU1
   2    GND      B @S9S_MB_2U_LIB.S9S_MB_2U(SCH_1):GND

Q_CAP_C0402-22UF,4V,20%,X6S,CHA  I117  C302
   1 PVCCIN_CPU1      A @S9S_MB_2U_LIB.S9S_MB_2U(SCH_1):PVCCIN_CPU1
   2    GND      B @S9S_MB_2U_LIB.S9S_MB_2U(SCH_1):GND

Q_CAP_C0402-22UF,4V,20%,X6S,CHA  I118  C306
   1 PVCCIN_CPU1      A @S9S_MB_2U_LIB.S9S_MB_2U(SCH_1):PVCCIN_CPU1
   2    GND      B @S9S_MB_2U_LIB.S9S_MB_2U(SCH_1):GND

Q_CAP_C0402-22UF,4V,20%,X6S,CHA  I119  C285
   1 PVCCIN_CPU1      A @S9S_MB_2U_LIB.S9S_MB_2U(SCH_1):PVCCIN_CPU1
   2    GND      B @S9S_MB_2U_LIB.S9S_MB_2U(SCH_1):GND

Q_CAP_C0402-22UF,4V,20%,X6S,CHA  I120  C289
   1 PVCCIN_CPU1      A @S9S_MB_2U_LIB.S9S_MB_2U(SCH_1):PVCCIN_CPU1
   2    GND      B @S9S_MB_2U_LIB.S9S_MB_2U(SCH_1):GND

Q_CAP_C0402-22UF,4V,20%,X6S,CHA  I121  C284
   1 PVCCIN_CPU1      A @S9S_MB_2U_LIB.S9S_MB_2U(SCH_1):PVCCIN_CPU1
   2    GND      B @S9S_MB_2U_LIB.S9S_MB_2U(SCH_1):GND

Q_CAP_C0402-22UF,4V,20%,X6S,CHA  I122  C283
   1 PVCCIN_CPU1      A @S9S_MB_2U_LIB.S9S_MB_2U(SCH_1):PVCCIN_CPU1
   2    GND      B @S9S_MB_2U_LIB.S9S_MB_2U(SCH_1):GND

Q_CAP_C0402-22UF,4V,20%,X6S,CHA  I123  C288
   1 PVCCIN_CPU1      A @S9S_MB_2U_LIB.S9S_MB_2U(SCH_1):PVCCIN_CPU1
   2    GND      B @S9S_MB_2U_LIB.S9S_MB_2U(SCH_1):GND

Q_CAP_C0402-22UF,4V,20%,X6S,CHA  I125  C293
   1 PVCCIN_CPU1      A @S9S_MB_2U_LIB.S9S_MB_2U(SCH_1):PVCCIN_CPU1
   2    GND      B @S9S_MB_2U_LIB.S9S_MB_2U(SCH_1):GND

Q_CAP_C0402-22UF,4V,20%,X6S,CHA  I126  C297
   1 PVCCIN_CPU1      A @S9S_MB_2U_LIB.S9S_MB_2U(SCH_1):PVCCIN_CPU1
   2    GND      B @S9S_MB_2U_LIB.S9S_MB_2U(SCH_1):GND

Q_CAP_C0402-22UF,4V,20%,X6S,CHA  I129  C296
   1 PVCCIN_CPU1      A @S9S_MB_2U_LIB.S9S_MB_2U(SCH_1):PVCCIN_CPU1
   2    GND      B @S9S_MB_2U_LIB.S9S_MB_2U(SCH_1):GND

Q_CAP_C0402-22UF,4V,20%,X6S,CHA  I130  C295
   1 PVCCIN_CPU1      A @S9S_MB_2U_LIB.S9S_MB_2U(SCH_1):PVCCIN_CPU1
   2    GND      B @S9S_MB_2U_LIB.S9S_MB_2U(SCH_1):GND

Q_CAP_C0402-22UF,4V,20%,X6S,CHA  I131  C299
   1 PVCCIN_CPU1      A @S9S_MB_2U_LIB.S9S_MB_2U(SCH_1):PVCCIN_CPU1
   2    GND      B @S9S_MB_2U_LIB.S9S_MB_2U(SCH_1):GND

Q_CAP_C0402-22UF,4V,20%,X6S,CHA  I132  C300
   1 PVCCIN_CPU1      A @S9S_MB_2U_LIB.S9S_MB_2U(SCH_1):PVCCIN_CPU1
   2    GND      B @S9S_MB_2U_LIB.S9S_MB_2U(SCH_1):GND

Q_CAP_C0402-22UF,4V,20%,X6S,CHA  I133  C301
   1 PVCCIN_CPU1      A @S9S_MB_2U_LIB.S9S_MB_2U(SCH_1):PVCCIN_CPU1
   2    GND      B @S9S_MB_2U_LIB.S9S_MB_2U(SCH_1):GND

Q_CAP_C0402-22UF,4V,20%,X6S,CHA  I134  C305
   1 PVCCIN_CPU1      A @S9S_MB_2U_LIB.S9S_MB_2U(SCH_1):PVCCIN_CPU1
   2    GND      B @S9S_MB_2U_LIB.S9S_MB_2U(SCH_1):GND

Q_CAP_C0402-22UF,4V,20%,X6S,CHA  I136  C309
   1 PVCCIN_CPU1      A @S9S_MB_2U_LIB.S9S_MB_2U(SCH_1):PVCCIN_CPU1
   2    GND      B @S9S_MB_2U_LIB.S9S_MB_2U(SCH_1):GND

Q_CAP_C0402-22UF,4V,20%,X6S,CHA  I138  C304
   1 PVCCIN_CPU1      A @S9S_MB_2U_LIB.S9S_MB_2U(SCH_1):PVCCIN_CPU1
   2    GND      B @S9S_MB_2U_LIB.S9S_MB_2U(SCH_1):GND

Q_CAP_C0402-22UF,4V,20%,X6S,CHA  I140  C308
   1 PVCCIN_CPU1      A @S9S_MB_2U_LIB.S9S_MB_2U(SCH_1):PVCCIN_CPU1
   2    GND      B @S9S_MB_2U_LIB.S9S_MB_2U(SCH_1):GND

Q_CAP_C0402-22UF,4V,20%,X6S,CHA  I2  C426
   1 PVCCFA_EHV_FIVRA_CPU1      A @S9S_MB_2U_LIB.S9S_MB_2U(SCH_1):PVCCFA_EHV_FIVRA_CPU1
   2    GND      B @S9S_MB_2U_LIB.S9S_MB_2U(SCH_1):GND

Q_CAP_C0402-10UF,6.3V,20%,X6S,B  I14  C229
   1 PVCCIN_CPU1      A @S9S_MB_2U_LIB.S9S_MB_2U(SCH_1):PVCCIN_CPU1
   2    GND      B @S9S_MB_2U_LIB.S9S_MB_2U(SCH_1):GND

Q_CAP_C0805-47UF,4V,20%,X6S,CHA  I16  C235
   1 PVCCIN_CPU1      A @S9S_MB_2U_LIB.S9S_MB_2U(SCH_1):PVCCIN_CPU1
   2    GND      B @S9S_MB_2U_LIB.S9S_MB_2U(SCH_1):GND

Q_CAP_C0402-10UF,6.3V,20%,X6S,B  I26  C227
   1 PVCCIN_CPU1      A @S9S_MB_2U_LIB.S9S_MB_2U(SCH_1):PVCCIN_CPU1
   2    GND      B @S9S_MB_2U_LIB.S9S_MB_2U(SCH_1):GND

Q_CAP_C0402-22UF,4V,20%,X6S,CHA  I40  C437
   1 PVCCFA_EHV_FIVRA_CPU1      A @S9S_MB_2U_LIB.S9S_MB_2U(SCH_1):PVCCFA_EHV_FIVRA_CPU1
   2    GND      B @S9S_MB_2U_LIB.S9S_MB_2U(SCH_1):GND

Q_CAP_C0402-10UF,6.3V,20%,X6S,B  I64  C269
   1 PVCCIN_CPU1      A @S9S_MB_2U_LIB.S9S_MB_2U(SCH_1):PVCCIN_CPU1
   2    GND      B @S9S_MB_2U_LIB.S9S_MB_2U(SCH_1):GND

Q_CAP_C0402-22UF,4V,20%,X6S,CHA  I67  C443
   1 PVCCFA_EHV_CPU1      A @S9S_MB_2U_LIB.S9S_MB_2U(SCH_1):PVCCFA_EHV_CPU1
   2    GND      B @S9S_MB_2U_LIB.S9S_MB_2U(SCH_1):GND

Q_CAP_C0402-22UF,4V,20%,X6S,CHA  I70  C310
   1 PVNN_MAIN_CPU1      A @S9S_MB_2U_LIB.S9S_MB_2U(SCH_1):PVNN_MAIN_CPU1
   2    GND      B @S9S_MB_2U_LIB.S9S_MB_2U(SCH_1):GND

Q_CAP_C0402-10UF,6.3V,20%,X6S,B  I74  C243
   1 PVCCIN_CPU1      A @S9S_MB_2U_LIB.S9S_MB_2U(SCH_1):PVCCIN_CPU1
   2    GND      B @S9S_MB_2U_LIB.S9S_MB_2U(SCH_1):GND

Q_CAP_C0402-10UF,6.3V,20%,X6S,B  I77  C241
   1 PVCCIN_CPU1      A @S9S_MB_2U_LIB.S9S_MB_2U(SCH_1):PVCCIN_CPU1
   2    GND      B @S9S_MB_2U_LIB.S9S_MB_2U(SCH_1):GND

Q_CAP_C0402-10UF,6.3V,20%,X6S,B  I80  C253
   1 PVCCIN_CPU1      A @S9S_MB_2U_LIB.S9S_MB_2U(SCH_1):PVCCIN_CPU1
   2    GND      B @S9S_MB_2U_LIB.S9S_MB_2U(SCH_1):GND

Q_CAP_C0402-10UF,6.3V,20%,X6S,B  I82  C252
   1 PVCCIN_CPU1      A @S9S_MB_2U_LIB.S9S_MB_2U(SCH_1):PVCCIN_CPU1
   2    GND      B @S9S_MB_2U_LIB.S9S_MB_2U(SCH_1):GND

Q_CAP_C0402-10UF,6.3V,20%,X6S,B  I85  C256
   1 PVCCIN_CPU1      A @S9S_MB_2U_LIB.S9S_MB_2U(SCH_1):PVCCIN_CPU1
   2    GND      B @S9S_MB_2U_LIB.S9S_MB_2U(SCH_1):GND

Q_CAP_C0402-22UF,4V,20%,X6S,CHA  I91  C273
   1 PVCCIN_CPU1      A @S9S_MB_2U_LIB.S9S_MB_2U(SCH_1):PVCCIN_CPU1
   2    GND      B @S9S_MB_2U_LIB.S9S_MB_2U(SCH_1):GND

Q_CAP_C0402-10UF,6.3V,20%,X6S,B  I94  C267
   1 PVCCIN_CPU1      A @S9S_MB_2U_LIB.S9S_MB_2U(SCH_1):PVCCIN_CPU1
   2    GND      B @S9S_MB_2U_LIB.S9S_MB_2U(SCH_1):GND

Q_CAP_C0402-10UF,6.3V,20%,X6S,B  I97  C266
   1 PVCCIN_CPU1      A @S9S_MB_2U_LIB.S9S_MB_2U(SCH_1):PVCCIN_CPU1
   2    GND      B @S9S_MB_2U_LIB.S9S_MB_2U(SCH_1):GND

Q_CAP_C0402-22UF,4V,20%,X6S,CHA  I124  C287
   1 PVCCIN_CPU1      A @S9S_MB_2U_LIB.S9S_MB_2U(SCH_1):PVCCIN_CPU1
   2    GND      B @S9S_MB_2U_LIB.S9S_MB_2U(SCH_1):GND

Q_CAP_C0402-22UF,4V,20%,X6S,CHA  I127  C292
   1 PVCCIN_CPU1      A @S9S_MB_2U_LIB.S9S_MB_2U(SCH_1):PVCCIN_CPU1
   2    GND      B @S9S_MB_2U_LIB.S9S_MB_2U(SCH_1):GND

Q_CAP_C0402-22UF,4V,20%,X6S,CHA  I128  C291
   1 PVCCIN_CPU1      A @S9S_MB_2U_LIB.S9S_MB_2U(SCH_1):PVCCIN_CPU1
   2    GND      B @S9S_MB_2U_LIB.S9S_MB_2U(SCH_1):GND

Q_CAP_C0402-22UF,4V,20%,X6S,CHA  I139  C303
   1 PVCCIN_CPU1      A @S9S_MB_2U_LIB.S9S_MB_2U(SCH_1):PVCCIN_CPU1
   2    GND      B @S9S_MB_2U_LIB.S9S_MB_2U(SCH_1):GND

Q_CAP_C0402-22UF,4V,20%,X6S,CHA  I142  C307
   1 PVCCIN_CPU1      A @S9S_MB_2U_LIB.S9S_MB_2U(SCH_1):PVCCIN_CPU1
   2    GND      B @S9S_MB_2U_LIB.S9S_MB_2U(SCH_1):GND


DRAWING: @S9S_MB_2U_LIB.S9S_MB_2U(SCH_1):PAGE78 

Q_CAP_C0805-47UF,4V,20%,X6S,CHA  I3  C453
   1 PVCCFA_EHV_FIVRA_CPU1      A @S9S_MB_2U_LIB.S9S_MB_2U(SCH_1):PVCCFA_EHV_FIVRA_CPU1
   2    GND      B @S9S_MB_2U_LIB.S9S_MB_2U(SCH_1):GND

Q_CAP_C0805-47UF,4V,20%,X6S,CHA  I5  C461
   1 PVCCFA_EHV_FIVRA_CPU1      A @S9S_MB_2U_LIB.S9S_MB_2U(SCH_1):PVCCFA_EHV_FIVRA_CPU1
   2    GND      B @S9S_MB_2U_LIB.S9S_MB_2U(SCH_1):GND

Q_CAP_C0603-47UF,2.5V,20%,X6S,A  I7  C465
   1 PVCCFA_EHV_FIVRA_CPU1      A @S9S_MB_2U_LIB.S9S_MB_2U(SCH_1):PVCCFA_EHV_FIVRA_CPU1
   2    GND      B @S9S_MB_2U_LIB.S9S_MB_2U(SCH_1):GND

Q_CAP_C0402-22UF,4V,20%,X6S,CHA  I23  C490
   1 PVCCINFAON_CPU1      A @S9S_MB_2U_LIB.S9S_MB_2U(SCH_1):PVCCINFAON_CPU1
   2    GND      B @S9S_MB_2U_LIB.S9S_MB_2U(SCH_1):GND

Q_CAP_C0805-47UF,4V,20%,X6S,CHA  I24  C451
   1 PVCCD_HV_CPU1      A @S9S_MB_2U_LIB.S9S_MB_2U(SCH_1):PVCCD_HV_CPU1
   2    GND      B @S9S_MB_2U_LIB.S9S_MB_2U(SCH_1):GND

Q_CAP_C0805-47UF,4V,20%,X6S,CHA  I27  C318
   1 PVCCIN_CPU1      A @S9S_MB_2U_LIB.S9S_MB_2U(SCH_1):PVCCIN_CPU1
   2    GND      B @S9S_MB_2U_LIB.S9S_MB_2U(SCH_1):GND

Q_CAP_C0805-47UF,4V,20%,X6S,CHA  I29  C474
   1 PVCCD_HV_CPU1      A @S9S_MB_2U_LIB.S9S_MB_2U(SCH_1):PVCCD_HV_CPU1
   2    GND      B @S9S_MB_2U_LIB.S9S_MB_2U(SCH_1):GND

Q_CAP_C0805-47UF,4V,20%,X6S,CHA  I32  C327
   1 PVCCIN_CPU1      A @S9S_MB_2U_LIB.S9S_MB_2U(SCH_1):PVCCIN_CPU1
   2    GND      B @S9S_MB_2U_LIB.S9S_MB_2U(SCH_1):GND

Q_CAP_C0805-47UF,4V,20%,X6S,CHA  I35  C336
   1 PVCCIN_CPU1      A @S9S_MB_2U_LIB.S9S_MB_2U(SCH_1):PVCCIN_CPU1
   2    GND      B @S9S_MB_2U_LIB.S9S_MB_2U(SCH_1):GND

Q_CAP_C0805-47UF,4V,20%,X6S,CHA  I37  C314
   1 PVCCIN_CPU1      A @S9S_MB_2U_LIB.S9S_MB_2U(SCH_1):PVCCIN_CPU1
   2    GND      B @S9S_MB_2U_LIB.S9S_MB_2U(SCH_1):GND

Q_CAP_C0805-47UF,4V,20%,X6S,CHA  I39  C320
   1 PVCCIN_CPU1      A @S9S_MB_2U_LIB.S9S_MB_2U(SCH_1):PVCCIN_CPU1
   2    GND      B @S9S_MB_2U_LIB.S9S_MB_2U(SCH_1):GND

Q_CAP_C0805-47UF,4V,20%,X6S,CHA  I40  C323
   1 PVCCIN_CPU1      A @S9S_MB_2U_LIB.S9S_MB_2U(SCH_1):PVCCIN_CPU1
   2    GND      B @S9S_MB_2U_LIB.S9S_MB_2U(SCH_1):GND

Q_CAP_C0805-47UF,4V,20%,X6S,CHA  I41  C326
   1 PVCCIN_CPU1      A @S9S_MB_2U_LIB.S9S_MB_2U(SCH_1):PVCCIN_CPU1
   2    GND      B @S9S_MB_2U_LIB.S9S_MB_2U(SCH_1):GND

Q_CAP_C0603-47UF,2.5V,20%,X6S,A  I52  C1391
   1 PVNN_MAIN_CPU1      A @S9S_MB_2U_LIB.S9S_MB_2U(SCH_1):PVNN_MAIN_CPU1
   2    GND      B @S9S_MB_2U_LIB.S9S_MB_2U(SCH_1):GND

Q_CAP_C0805-47UF,4V,20%,X6S,CHA  I58  C313
   1 PVCCIN_CPU1      A @S9S_MB_2U_LIB.S9S_MB_2U(SCH_1):PVCCIN_CPU1
   2    GND      B @S9S_MB_2U_LIB.S9S_MB_2U(SCH_1):GND

Q_CAP_C0805-47UF,4V,20%,X6S,CHA  I60  C316
   1 PVCCIN_CPU1      A @S9S_MB_2U_LIB.S9S_MB_2U(SCH_1):PVCCIN_CPU1
   2    GND      B @S9S_MB_2U_LIB.S9S_MB_2U(SCH_1):GND

Q_CAP_C0805-47UF,4V,20%,X6S,CHA  I65  C353
   1 PVCCIN_CPU1      A @S9S_MB_2U_LIB.S9S_MB_2U(SCH_1):PVCCIN_CPU1
   2    GND      B @S9S_MB_2U_LIB.S9S_MB_2U(SCH_1):GND

Q_CAP_C0805-47UF,4V,20%,X6S,CHA  I66  C337
   1 PVCCIN_CPU1      A @S9S_MB_2U_LIB.S9S_MB_2U(SCH_1):PVCCIN_CPU1
   2    GND      B @S9S_MB_2U_LIB.S9S_MB_2U(SCH_1):GND

Q_CAP_C0805-47UF,4V,20%,X6S,CHA  I68  C483
   1 PVCCIN_CPU1      A @S9S_MB_2U_LIB.S9S_MB_2U(SCH_1):PVCCIN_CPU1
   2    GND      B @S9S_MB_2U_LIB.S9S_MB_2U(SCH_1):GND

Q_CAP_C0805-47UF,4V,20%,X6S,CHA  I1  C449
   1 PVCCFA_EHV_FIVRA_CPU1      A @S9S_MB_2U_LIB.S9S_MB_2U(SCH_1):PVCCFA_EHV_FIVRA_CPU1
   2    GND      B @S9S_MB_2U_LIB.S9S_MB_2U(SCH_1):GND

Q_CAP_C0805-47UF,4V,20%,X6S,CHA  I4  C457
   1 PVCCFA_EHV_FIVRA_CPU1      A @S9S_MB_2U_LIB.S9S_MB_2U(SCH_1):PVCCFA_EHV_FIVRA_CPU1
   2    GND      B @S9S_MB_2U_LIB.S9S_MB_2U(SCH_1):GND

Q_CAP_C0805-47UF,4V,20%,X6S,CHA  I8  C478
   1 PVCCINFAON_CPU1      A @S9S_MB_2U_LIB.S9S_MB_2U(SCH_1):PVCCINFAON_CPU1
   2    GND      B @S9S_MB_2U_LIB.S9S_MB_2U(SCH_1):GND

Q_CAP_C0805-47UF,4V,20%,X6S,CHA  I10  C448
   1 PVCCFA_EHV_CPU1      A @S9S_MB_2U_LIB.S9S_MB_2U(SCH_1):PVCCFA_EHV_CPU1
   2    GND      B @S9S_MB_2U_LIB.S9S_MB_2U(SCH_1):GND

Q_CAP_C0805-47UF,4V,20%,X6S,CHA  I12  C447
   1 PVCCD_HV_CPU1      A @S9S_MB_2U_LIB.S9S_MB_2U(SCH_1):PVCCD_HV_CPU1
   2    GND      B @S9S_MB_2U_LIB.S9S_MB_2U(SCH_1):GND

Q_CAP_C0805-47UF,4V,20%,X6S,CHA  I14  C312
   1 PVCCIN_CPU1      A @S9S_MB_2U_LIB.S9S_MB_2U(SCH_1):PVCCIN_CPU1
   2    GND      B @S9S_MB_2U_LIB.S9S_MB_2U(SCH_1):GND

Q_CAP_C0805-47UF,4V,20%,X6S,CHA  I16  C311
   1 PVCCIN_CPU1      A @S9S_MB_2U_LIB.S9S_MB_2U(SCH_1):PVCCIN_CPU1
   2    GND      B @S9S_MB_2U_LIB.S9S_MB_2U(SCH_1):GND

Q_CAP_C0603-47UF,2.5V,20%,X6S,A  I18  C488
   1 PVCCINFAON_CPU1      A @S9S_MB_2U_LIB.S9S_MB_2U(SCH_1):PVCCINFAON_CPU1
   2    GND      B @S9S_MB_2U_LIB.S9S_MB_2U(SCH_1):GND

Q_CAP_C0603-47UF,2.5V,20%,X6S,A  I19  C489
   1 PVCCINFAON_CPU1      A @S9S_MB_2U_LIB.S9S_MB_2U(SCH_1):PVCCINFAON_CPU1
   2    GND      B @S9S_MB_2U_LIB.S9S_MB_2U(SCH_1):GND

Q_CAP_C0805-47UF,4V,20%,X6S,CHA  I21  C452
   1 PVCCFA_EHV_CPU1      A @S9S_MB_2U_LIB.S9S_MB_2U(SCH_1):PVCCFA_EHV_CPU1
   2    GND      B @S9S_MB_2U_LIB.S9S_MB_2U(SCH_1):GND

Q_CAP_C0805-47UF,4V,20%,X6S,CHA  I25  C471
   1 PVCCD_HV_CPU1      A @S9S_MB_2U_LIB.S9S_MB_2U(SCH_1):PVCCD_HV_CPU1
   2    GND      B @S9S_MB_2U_LIB.S9S_MB_2U(SCH_1):GND

Q_CAP_C0805-47UF,4V,20%,X6S,CHA  I26  C315
   1 PVCCIN_CPU1      A @S9S_MB_2U_LIB.S9S_MB_2U(SCH_1):PVCCIN_CPU1
   2    GND      B @S9S_MB_2U_LIB.S9S_MB_2U(SCH_1):GND

Q_CAP_C0805-47UF,4V,20%,X6S,CHA  I30  C321
   1 PVCCIN_CPU1      A @S9S_MB_2U_LIB.S9S_MB_2U(SCH_1):PVCCIN_CPU1
   2    GND      B @S9S_MB_2U_LIB.S9S_MB_2U(SCH_1):GND

Q_CAP_C0805-47UF,4V,20%,X6S,CHA  I31  C324
   1 PVCCIN_CPU1      A @S9S_MB_2U_LIB.S9S_MB_2U(SCH_1):PVCCIN_CPU1
   2    GND      B @S9S_MB_2U_LIB.S9S_MB_2U(SCH_1):GND

Q_CAP_C0805-47UF,4V,20%,X6S,CHA  I33  C330
   1 PVCCIN_CPU1      A @S9S_MB_2U_LIB.S9S_MB_2U(SCH_1):PVCCIN_CPU1
   2    GND      B @S9S_MB_2U_LIB.S9S_MB_2U(SCH_1):GND

Q_CAP_C0805-47UF,4V,20%,X6S,CHA  I34  C333
   1 PVCCIN_CPU1      A @S9S_MB_2U_LIB.S9S_MB_2U(SCH_1):PVCCIN_CPU1
   2    GND      B @S9S_MB_2U_LIB.S9S_MB_2U(SCH_1):GND

Q_CAP_C0805-47UF,4V,20%,X6S,CHA  I36  C339
   1 PVCCIN_CPU1      A @S9S_MB_2U_LIB.S9S_MB_2U(SCH_1):PVCCIN_CPU1
   2    GND      B @S9S_MB_2U_LIB.S9S_MB_2U(SCH_1):GND

Q_CAP_C0805-47UF,4V,20%,X6S,CHA  I38  C317
   1 PVCCIN_CPU1      A @S9S_MB_2U_LIB.S9S_MB_2U(SCH_1):PVCCIN_CPU1
   2    GND      B @S9S_MB_2U_LIB.S9S_MB_2U(SCH_1):GND

Q_CAP_C0805-47UF,4V,20%,X6S,CHA  I42  C329
   1 PVCCIN_CPU1      A @S9S_MB_2U_LIB.S9S_MB_2U(SCH_1):PVCCIN_CPU1
   2    GND      B @S9S_MB_2U_LIB.S9S_MB_2U(SCH_1):GND

Q_CAP_C0805-47UF,4V,20%,X6S,CHA  I43  C332
   1 PVCCIN_CPU1      A @S9S_MB_2U_LIB.S9S_MB_2U(SCH_1):PVCCIN_CPU1
   2    GND      B @S9S_MB_2U_LIB.S9S_MB_2U(SCH_1):GND

Q_CAP_C0805-47UF,4V,20%,X6S,CHA  I44  C335
   1 PVCCIN_CPU1      A @S9S_MB_2U_LIB.S9S_MB_2U(SCH_1):PVCCIN_CPU1
   2    GND      B @S9S_MB_2U_LIB.S9S_MB_2U(SCH_1):GND

Q_CAP_C0805-47UF,4V,20%,X6S,CHA  I45  C338
   1 PVCCIN_CPU1      A @S9S_MB_2U_LIB.S9S_MB_2U(SCH_1):PVCCIN_CPU1
   2    GND      B @S9S_MB_2U_LIB.S9S_MB_2U(SCH_1):GND

Q_CAP_C0805-47UF,4V,20%,X6S,CHA  I46  C1388
   1 PVPP_HBM_CPU1      A @S9S_MB_2U_LIB.S9S_MB_2U(SCH_1):PVPP_HBM_CPU1
   2    GND      B @S9S_MB_2U_LIB.S9S_MB_2U(SCH_1):GND

Q_CAP_C0805-47UF,4V,20%,X6S,CHA  I48  C1390
   1 PVPP_HBM_CPU1      A @S9S_MB_2U_LIB.S9S_MB_2U(SCH_1):PVPP_HBM_CPU1
   2    GND      B @S9S_MB_2U_LIB.S9S_MB_2U(SCH_1):GND

Q_CAP_C0805-47UF,4V,20%,X6S,CHA  I49  C1387
   1 PVNN_MAIN_CPU1      A @S9S_MB_2U_LIB.S9S_MB_2U(SCH_1):PVNN_MAIN_CPU1
   2    GND      B @S9S_MB_2U_LIB.S9S_MB_2U(SCH_1):GND

Q_CAP_C0603-47UF,2.5V,20%,X6S,A  I51  C1389
   1 PVNN_MAIN_CPU1      A @S9S_MB_2U_LIB.S9S_MB_2U(SCH_1):PVNN_MAIN_CPU1
   2    GND      B @S9S_MB_2U_LIB.S9S_MB_2U(SCH_1):GND

Q_CAP_C0805-47UF,4V,20%,X6S,CHA  I53  C1392
   1 PVPP_HBM_CPU1      A @S9S_MB_2U_LIB.S9S_MB_2U(SCH_1):PVPP_HBM_CPU1
   2    GND      B @S9S_MB_2U_LIB.S9S_MB_2U(SCH_1):GND

Q_CAP_C0201-0.22UF,6.3V,10%,X6A  I55  C1437
   1 PVPP_HBM_CPU1      A @S9S_MB_2U_LIB.S9S_MB_2U(SCH_1):PVPP_HBM_CPU1
   2    GND      B @S9S_MB_2U_LIB.S9S_MB_2U(SCH_1):GND

Q_CAP_C0603-47UF,2.5V,20%,X6S,A  I57  C1393
   1 PVNN_MAIN_CPU1      A @S9S_MB_2U_LIB.S9S_MB_2U(SCH_1):PVNN_MAIN_CPU1
   2    GND      B @S9S_MB_2U_LIB.S9S_MB_2U(SCH_1):GND

Q_CAP_C0805-47UF,4V,20%,X6S,CHA  I63  C349
   1 PVCCIN_CPU1      A @S9S_MB_2U_LIB.S9S_MB_2U(SCH_1):PVCCIN_CPU1
   2    GND      B @S9S_MB_2U_LIB.S9S_MB_2U(SCH_1):GND

Q_CAP_C0805-47UF,4V,20%,X6S,CHA  I64  C351
   1 PVCCIN_CPU1      A @S9S_MB_2U_LIB.S9S_MB_2U(SCH_1):PVCCIN_CPU1
   2    GND      B @S9S_MB_2U_LIB.S9S_MB_2U(SCH_1):GND


DRAWING: @S9S_MB_2U_LIB.S9S_MB_2U(SCH_1):PAGE79 

Q_CAP_C0805-47UF,4V,20%,X6S,CHA  I1  C450
   1 PVCCFA_EHV_FIVRA_CPU1      A @S9S_MB_2U_LIB.S9S_MB_2U(SCH_1):PVCCFA_EHV_FIVRA_CPU1
   2    GND      B @S9S_MB_2U_LIB.S9S_MB_2U(SCH_1):GND

Q_CAP_C0805-47UF,4V,20%,X6S,CHA  I3  C454
   1 PVCCFA_EHV_FIVRA_CPU1      A @S9S_MB_2U_LIB.S9S_MB_2U(SCH_1):PVCCFA_EHV_FIVRA_CPU1
   2    GND      B @S9S_MB_2U_LIB.S9S_MB_2U(SCH_1):GND

Q_CAP_C0805-47UF,4V,20%,X6S,CHA  I4  C458
   1 PVCCFA_EHV_FIVRA_CPU1      A @S9S_MB_2U_LIB.S9S_MB_2U(SCH_1):PVCCFA_EHV_FIVRA_CPU1
   2    GND      B @S9S_MB_2U_LIB.S9S_MB_2U(SCH_1):GND

Q_CAP_C0805-47UF,4V,20%,X6S,CHA  I5  C462
   1 PVCCFA_EHV_FIVRA_CPU1      A @S9S_MB_2U_LIB.S9S_MB_2U(SCH_1):PVCCFA_EHV_FIVRA_CPU1
   2    GND      B @S9S_MB_2U_LIB.S9S_MB_2U(SCH_1):GND

Q_CAP_C0805-47UF,4V,20%,X6S,CHA  I7  C466
   1 PVCCFA_EHV_FIVRA_CPU1      A @S9S_MB_2U_LIB.S9S_MB_2U(SCH_1):PVCCFA_EHV_FIVRA_CPU1
   2    GND      B @S9S_MB_2U_LIB.S9S_MB_2U(SCH_1):GND

Q_CAP_C0805-47UF,4V,20%,X6S,CHA  I8  C470
   1 PVCCFA_EHV_FIVRA_CPU1      A @S9S_MB_2U_LIB.S9S_MB_2U(SCH_1):PVCCFA_EHV_FIVRA_CPU1
   2    GND      B @S9S_MB_2U_LIB.S9S_MB_2U(SCH_1):GND

Q_CAP_C0805-47UF,4V,20%,X6S,CHA  I9  C473
   1 PVCCFA_EHV_FIVRA_CPU1      A @S9S_MB_2U_LIB.S9S_MB_2U(SCH_1):PVCCFA_EHV_FIVRA_CPU1
   2    GND      B @S9S_MB_2U_LIB.S9S_MB_2U(SCH_1):GND

Q_CAP_C0805-47UF,4V,20%,X6S,CHA  I10  C487
   1 PVCCINFAON_CPU1      A @S9S_MB_2U_LIB.S9S_MB_2U(SCH_1):PVCCINFAON_CPU1
   2    GND      B @S9S_MB_2U_LIB.S9S_MB_2U(SCH_1):GND

Q_CAP_C0805-47UF,4V,20%,X6S,CHA  I11  C486
   1 PVCCINFAON_CPU1      A @S9S_MB_2U_LIB.S9S_MB_2U(SCH_1):PVCCINFAON_CPU1
   2    GND      B @S9S_MB_2U_LIB.S9S_MB_2U(SCH_1):GND

Q_CAP_C0805-47UF,4V,20%,X6S,CHA  I12  C484
   1 PVCCINFAON_CPU1      A @S9S_MB_2U_LIB.S9S_MB_2U(SCH_1):PVCCINFAON_CPU1
   2    GND      B @S9S_MB_2U_LIB.S9S_MB_2U(SCH_1):GND

Q_CAP_C0805-47UF,4V,20%,X6S,CHA  I13  C481
   1 PVCCINFAON_CPU1      A @S9S_MB_2U_LIB.S9S_MB_2U(SCH_1):PVCCINFAON_CPU1
   2    GND      B @S9S_MB_2U_LIB.S9S_MB_2U(SCH_1):GND

Q_CAP_C0805-47UF,4V,20%,X6S,CHA  I15  C456
   1 PVCCFA_EHV_CPU1      A @S9S_MB_2U_LIB.S9S_MB_2U(SCH_1):PVCCFA_EHV_CPU1
   2    GND      B @S9S_MB_2U_LIB.S9S_MB_2U(SCH_1):GND

Q_CAP_C0805-47UF,4V,20%,X6S,CHA  I16  C460
   1 PVCCFA_EHV_CPU1      A @S9S_MB_2U_LIB.S9S_MB_2U(SCH_1):PVCCFA_EHV_CPU1
   2    GND      B @S9S_MB_2U_LIB.S9S_MB_2U(SCH_1):GND

Q_CAP_C0805-47UF,4V,20%,X6S,CHA  I17  C464
   1 PVCCFA_EHV_CPU1      A @S9S_MB_2U_LIB.S9S_MB_2U(SCH_1):PVCCFA_EHV_CPU1
   2    GND      B @S9S_MB_2U_LIB.S9S_MB_2U(SCH_1):GND

Q_CAP_C0805-47UF,4V,20%,X6S,CHA  I19  C455
   1 PVCCD_HV_CPU1      A @S9S_MB_2U_LIB.S9S_MB_2U(SCH_1):PVCCD_HV_CPU1
   2    GND      B @S9S_MB_2U_LIB.S9S_MB_2U(SCH_1):GND

Q_CAP_C0805-47UF,4V,20%,X6S,CHA  I20  C459
   1 PVCCD_HV_CPU1      A @S9S_MB_2U_LIB.S9S_MB_2U(SCH_1):PVCCD_HV_CPU1
   2    GND      B @S9S_MB_2U_LIB.S9S_MB_2U(SCH_1):GND

Q_CAP_C0805-47UF,4V,20%,X6S,CHA  I21  C463
   1 PVCCD_HV_CPU1      A @S9S_MB_2U_LIB.S9S_MB_2U(SCH_1):PVCCD_HV_CPU1
   2    GND      B @S9S_MB_2U_LIB.S9S_MB_2U(SCH_1):GND

Q_CAP_C0805-47UF,4V,20%,X6S,CHA  I23  C342
   1 PVCCIN_CPU1      A @S9S_MB_2U_LIB.S9S_MB_2U(SCH_1):PVCCIN_CPU1
   2    GND      B @S9S_MB_2U_LIB.S9S_MB_2U(SCH_1):GND

Q_CAP_C0805-47UF,4V,20%,X6S,CHA  I24  C344
   1 PVCCIN_CPU1      A @S9S_MB_2U_LIB.S9S_MB_2U(SCH_1):PVCCIN_CPU1
   2    GND      B @S9S_MB_2U_LIB.S9S_MB_2U(SCH_1):GND

Q_CAP_C0805-47UF,4V,20%,X6S,CHA  I25  C346
   1 PVCCIN_CPU1      A @S9S_MB_2U_LIB.S9S_MB_2U(SCH_1):PVCCIN_CPU1
   2    GND      B @S9S_MB_2U_LIB.S9S_MB_2U(SCH_1):GND

Q_CAP_C0805-47UF,4V,20%,X6S,CHA  I26  C468
   1 PVCCFA_EHV_CPU1      A @S9S_MB_2U_LIB.S9S_MB_2U(SCH_1):PVCCFA_EHV_CPU1
   2    GND      B @S9S_MB_2U_LIB.S9S_MB_2U(SCH_1):GND

Q_CAP_C0603-47UF,2.5V,20%,X6S,A  I27  C472
   1 PVCCFA_EHV_CPU1      A @S9S_MB_2U_LIB.S9S_MB_2U(SCH_1):PVCCFA_EHV_CPU1
   2    GND      B @S9S_MB_2U_LIB.S9S_MB_2U(SCH_1):GND

Q_CAP_C0603-47UF,2.5V,20%,X6S,A  I29  C475
   1 PVCCFA_EHV_CPU1      A @S9S_MB_2U_LIB.S9S_MB_2U(SCH_1):PVCCFA_EHV_CPU1
   2    GND      B @S9S_MB_2U_LIB.S9S_MB_2U(SCH_1):GND

Q_CAP_C0805-47UF,4V,20%,X6S,CHA  I31  C467
   1 PVCCD_HV_CPU1      A @S9S_MB_2U_LIB.S9S_MB_2U(SCH_1):PVCCD_HV_CPU1
   2    GND      B @S9S_MB_2U_LIB.S9S_MB_2U(SCH_1):GND

Q_CAP_C0805-47UF,4V,20%,X6S,CHA  I32  C348
   1 PVCCIN_CPU1      A @S9S_MB_2U_LIB.S9S_MB_2U(SCH_1):PVCCIN_CPU1
   2    GND      B @S9S_MB_2U_LIB.S9S_MB_2U(SCH_1):GND

Q_CAP_C0805-47UF,4V,20%,X6S,CHA  I33  C350
   1 PVCCIN_CPU1      A @S9S_MB_2U_LIB.S9S_MB_2U(SCH_1):PVCCIN_CPU1
   2    GND      B @S9S_MB_2U_LIB.S9S_MB_2U(SCH_1):GND

Q_CAP_C0805-47UF,4V,20%,X6S,CHA  I34  C352
   1 PVCCIN_CPU1      A @S9S_MB_2U_LIB.S9S_MB_2U(SCH_1):PVCCIN_CPU1
   2    GND      B @S9S_MB_2U_LIB.S9S_MB_2U(SCH_1):GND

Q_CAP_C0805-47UF,4V,20%,X6S,CHA  I35  C354
   1 PVCCIN_CPU1      A @S9S_MB_2U_LIB.S9S_MB_2U(SCH_1):PVCCIN_CPU1
   2    GND      B @S9S_MB_2U_LIB.S9S_MB_2U(SCH_1):GND

Q_CAP_C0805-47UF,4V,20%,X6S,CHA  I37  C476
   1 PVCCFA_EHV_FIVRA_CPU1      A @S9S_MB_2U_LIB.S9S_MB_2U(SCH_1):PVCCFA_EHV_FIVRA_CPU1
   2    GND      B @S9S_MB_2U_LIB.S9S_MB_2U(SCH_1):GND

Q_CAP_C0805-47UF,4V,20%,X6S,CHA  I38  C477
   1 PVCCFA_EHV_FIVRA_CPU1      A @S9S_MB_2U_LIB.S9S_MB_2U(SCH_1):PVCCFA_EHV_FIVRA_CPU1
   2    GND      B @S9S_MB_2U_LIB.S9S_MB_2U(SCH_1):GND

Q_CAP_C0805-47UF,4V,20%,X6S,CHA  I39  C479
   1 PVCCFA_EHV_FIVRA_CPU1      A @S9S_MB_2U_LIB.S9S_MB_2U(SCH_1):PVCCFA_EHV_FIVRA_CPU1
   2    GND      B @S9S_MB_2U_LIB.S9S_MB_2U(SCH_1):GND

Q_CAP_C0805-47UF,4V,20%,X6S,CHA  I41  C482
   1 PVCCFA_EHV_FIVRA_CPU1      A @S9S_MB_2U_LIB.S9S_MB_2U(SCH_1):PVCCFA_EHV_FIVRA_CPU1
   2    GND      B @S9S_MB_2U_LIB.S9S_MB_2U(SCH_1):GND

Q_CAP_C0805-47UF,4V,20%,X6S,CHA  I42  C485
   1 PVCCFA_EHV_FIVRA_CPU1      A @S9S_MB_2U_LIB.S9S_MB_2U(SCH_1):PVCCFA_EHV_FIVRA_CPU1
   2    GND      B @S9S_MB_2U_LIB.S9S_MB_2U(SCH_1):GND

Q_CAP_C0805-47UF,4V,20%,X6S,CHA  I43  C1403
   1 PVNN_MAIN_CPU1      A @S9S_MB_2U_LIB.S9S_MB_2U(SCH_1):PVNN_MAIN_CPU1
   2    GND      B @S9S_MB_2U_LIB.S9S_MB_2U(SCH_1):GND

Q_CAP_C0805-47UF,4V,20%,X6S,CHA  I44  C1404
   1 PVNN_MAIN_CPU1      A @S9S_MB_2U_LIB.S9S_MB_2U(SCH_1):PVNN_MAIN_CPU1
   2    GND      B @S9S_MB_2U_LIB.S9S_MB_2U(SCH_1):GND

Q_CAP_C0805-47UF,4V,20%,X6S,CHA  I46  C322
   1 PVCCIN_CPU1      A @S9S_MB_2U_LIB.S9S_MB_2U(SCH_1):PVCCIN_CPU1
   2    GND      B @S9S_MB_2U_LIB.S9S_MB_2U(SCH_1):GND

Q_CAP_C0805-47UF,4V,20%,X6S,CHA  I47  C325
   1 PVCCIN_CPU1      A @S9S_MB_2U_LIB.S9S_MB_2U(SCH_1):PVCCIN_CPU1
   2    GND      B @S9S_MB_2U_LIB.S9S_MB_2U(SCH_1):GND

Q_CAP_C0402-22UF,4V,20%,X6S,CHA  I49  C1353
   1 PVNN_MAIN_CPU1      A @S9S_MB_2U_LIB.S9S_MB_2U(SCH_1):PVNN_MAIN_CPU1
   2    GND      B @S9S_MB_2U_LIB.S9S_MB_2U(SCH_1):GND

Q_CAP_C0805-47UF,4V,20%,X6S,CHA  I50  C328
   1 PVCCIN_CPU1      A @S9S_MB_2U_LIB.S9S_MB_2U(SCH_1):PVCCIN_CPU1
   2    GND      B @S9S_MB_2U_LIB.S9S_MB_2U(SCH_1):GND

Q_CAP_C0805-47UF,4V,20%,X6S,CHA  I51  C341
   1 PVCCIN_CPU1      A @S9S_MB_2U_LIB.S9S_MB_2U(SCH_1):PVCCIN_CPU1
   2    GND      B @S9S_MB_2U_LIB.S9S_MB_2U(SCH_1):GND

Q_CAP_C0805-47UF,4V,20%,X6S,CHA  I52  C343
   1 PVCCIN_CPU1      A @S9S_MB_2U_LIB.S9S_MB_2U(SCH_1):PVCCIN_CPU1
   2    GND      B @S9S_MB_2U_LIB.S9S_MB_2U(SCH_1):GND

Q_CAP_C0805-47UF,4V,20%,X6S,CHA  I53  C345
   1 PVCCIN_CPU1      A @S9S_MB_2U_LIB.S9S_MB_2U(SCH_1):PVCCIN_CPU1
   2    GND      B @S9S_MB_2U_LIB.S9S_MB_2U(SCH_1):GND

Q_CAP_C0805-47UF,4V,20%,X6S,CHA  I55  C347
   1 PVCCIN_CPU1      A @S9S_MB_2U_LIB.S9S_MB_2U(SCH_1):PVCCIN_CPU1
   2    GND      B @S9S_MB_2U_LIB.S9S_MB_2U(SCH_1):GND


DRAWING: @S9S_MB_2U_LIB.S9S_MB_2U(SCH_1):PAGE80 

Q_RES_0402LF-10K,1%,1/16W,CHIPA  I8  R319
   1 P3V3_AUX      A @S9S_MB_2U_LIB.S9S_MB_2U(SCH_1):P3V3_AUX
   2 PU_S3M_CPU0_CPLD_STATUS      B @S9S_MB_2U_LIB.S9S_MB_2U(SCH_1):PU_S3M_CPU0_CPLD_STATUS

Q_CAP_C0402-22UF,4V,20%,X6S,CHA  I9  C1364
   1 PVNN_MAIN_CPU0      A @S9S_MB_2U_LIB.S9S_MB_2U(SCH_1):PVNN_MAIN_CPU0
   2    GND      B @S9S_MB_2U_LIB.S9S_MB_2U(SCH_1):GND

Q_CAP_C0402-22UF,4V,20%,X6S,CHA  I20  C1365
   1 PVNN_MAIN_CPU1      A @S9S_MB_2U_LIB.S9S_MB_2U(SCH_1):PVNN_MAIN_CPU1
   2    GND      B @S9S_MB_2U_LIB.S9S_MB_2U(SCH_1):GND

Q_CAP_C0402-22UF,4V,20%,X6S,CHA  I28  C1366
   1 PVNN_MAIN_CPU1      A @S9S_MB_2U_LIB.S9S_MB_2U(SCH_1):PVNN_MAIN_CPU1
   2    GND      B @S9S_MB_2U_LIB.S9S_MB_2U(SCH_1):GND

Q_RES_0402LF-1.5K,1%,1/16W,CHIA  I1  R1216
   1 P3V3_AUX      A @S9S_MB_2U_LIB.S9S_MB_2U(SCH_1):P3V3_AUX
   2 FM_S3M_CPU0_CPLD_CRC_ERROR      B @S9S_MB_2U_LIB.S9S_MB_2U(SCH_1):FM_S3M_CPU0_CPLD_CRC_ERROR

Q_RES_0402LF-10K,1%,1/16W,CHIPA  I2  R321
   1 P3V3_AUX      A @S9S_MB_2U_LIB.S9S_MB_2U(SCH_1):P3V3_AUX
   2 FM_S3M_CPU0_CPLD_CONFIG_N      B @S9S_MB_2U_LIB.S9S_MB_2U(SCH_1):FM_S3M_CPU0_CPLD_CONFIG_N

Q_CAP_C0402-22UF,4V,20%,X6S,CHA  I5  C1363
   1 PVNN_MAIN_CPU0      A @S9S_MB_2U_LIB.S9S_MB_2U(SCH_1):PVNN_MAIN_CPU0
   2    GND      B @S9S_MB_2U_LIB.S9S_MB_2U(SCH_1):GND

Q_RES_0402LF-10K,1%,1/16W,CHIPA  I7  R320
   1 P3V3_AUX      A @S9S_MB_2U_LIB.S9S_MB_2U(SCH_1):P3V3_AUX
   2 PU_S3M_CPU0_CPLD_CONFD      B @S9S_MB_2U_LIB.S9S_MB_2U(SCH_1):PU_S3M_CPU0_CPLD_CONFD

Q_RES_1206LF-0,,1/2W,CHIP,CS00A  I12  R324
   1 PVNN_MAIN_CPU0      A @S9S_MB_2U_LIB.S9S_MB_2U(SCH_1):PVNN_MAIN_CPU0
   2 PVNN_TERM_CPU0      B @S9S_MB_2U_LIB.S9S_MB_2U(SCH_1):PVNN_TERM_CPU0

Q_RES_1206LF-0,,1/2W,EMPTY,CS0A  I13  R323
   1 PVCCINFAON_CPU0      A @S9S_MB_2U_LIB.S9S_MB_2U(SCH_1):PVCCINFAON_CPU0
   2 PVNN_TERM_CPU0      B @S9S_MB_2U_LIB.S9S_MB_2U(SCH_1):PVNN_TERM_CPU0

Q_RES_0402LF-1.5K,1%,1/16W,CHIA  I22  R1217
   1 P3V3_AUX      A @S9S_MB_2U_LIB.S9S_MB_2U(SCH_1):P3V3_AUX
   2 FM_S3M_CPU1_CPLD_CRC_ERROR      B @S9S_MB_2U_LIB.S9S_MB_2U(SCH_1):FM_S3M_CPU1_CPLD_CRC_ERROR

Q_RES_0402LF-10K,1%,1/16W,CHIPA  I25  R327
   1 P3V3_AUX      A @S9S_MB_2U_LIB.S9S_MB_2U(SCH_1):P3V3_AUX
   2 FM_S3M_CPU1_CPLD_CONFIG_N      B @S9S_MB_2U_LIB.S9S_MB_2U(SCH_1):FM_S3M_CPU1_CPLD_CONFIG_N

Q_RES_0402LF-10K,1%,1/16W,CHIPA  I26  R326
   1 P3V3_AUX      A @S9S_MB_2U_LIB.S9S_MB_2U(SCH_1):P3V3_AUX
   2 PU_S3M_CPU1_CPLD_CONFD      B @S9S_MB_2U_LIB.S9S_MB_2U(SCH_1):PU_S3M_CPU1_CPLD_CONFD

Q_RES_0402LF-10K,1%,1/16W,CHIPA  I27  R325
   1 P3V3_AUX      A @S9S_MB_2U_LIB.S9S_MB_2U(SCH_1):P3V3_AUX
   2 PU_S3M_CPU1_CPLD_STATUS      B @S9S_MB_2U_LIB.S9S_MB_2U(SCH_1):PU_S3M_CPU1_CPLD_STATUS

Q_RES_1206LF-0,,1/2W,CHIP,CS00A  I34  R330
   1 PVNN_MAIN_CPU1      A @S9S_MB_2U_LIB.S9S_MB_2U(SCH_1):PVNN_MAIN_CPU1
   2 PVNN_TERM_CPU1      B @S9S_MB_2U_LIB.S9S_MB_2U(SCH_1):PVNN_TERM_CPU1

Q_RES_1206LF-0,,1/2W,EMPTY,CS0A  I35  R329
   1 PVCCINFAON_CPU1      A @S9S_MB_2U_LIB.S9S_MB_2U(SCH_1):PVCCINFAON_CPU1
   2 PVNN_TERM_CPU1      B @S9S_MB_2U_LIB.S9S_MB_2U(SCH_1):PVNN_TERM_CPU1


DRAWING: @S9S_MB_2U_LIB.S9S_MB_2U(SCH_1):PAGE82 

Q_CAP_C0805-10UF,16V,10%,X6S,CA  I188  C3
   1 P12V_S3_AUX_CPU0_NVDIMM      A @S9S_MB_2U_LIB.S9S_MB_2U(SCH_1):P12V_S3_AUX_CPU0_NVDIMM
   2    GND      B @S9S_MB_2U_LIB.S9S_MB_2U(SCH_1):GND

Q_CAP_C0805-10UF,16V,10%,X6S,CA  I190  C4
   1 P12V_S3_AUX_CPU0_NVDIMM      A @S9S_MB_2U_LIB.S9S_MB_2U(SCH_1):P12V_S3_AUX_CPU0_NVDIMM
   2    GND      B @S9S_MB_2U_LIB.S9S_MB_2U(SCH_1):GND

Q_CAP_C0402-2.2UF,6.3V,20%,X6SA  I192  C2
   1 P3V3_AUX      A @S9S_MB_2U_LIB.S9S_MB_2U(SCH_1):P3V3_AUX
   2    GND      B @S9S_MB_2U_LIB.S9S_MB_2U(SCH_1):GND

Q_RES_0402LF-10K,1%,1/16W,CHIPA  I196  R26
   1 PD_CHA_CPU0_DIMM1_SAA      A @S9S_MB_2U_LIB.S9S_MB_2U(SCH_1):PD_CHA_CPU0_DIMM1_SAA
   2    GND      B @S9S_MB_2U_LIB.S9S_MB_2U(SCH_1):GND

SCONN288_ADR50017P130CC-SCONN2A  I198  J1
   3 P3V3_AUX VIN_MGMT @S9S_MB_2U_LIB.S9S_MB_2U(SCH_1):P3V3_AUX
   2 TP_CHA_CPU0_DIMM1_FRU_0   RFU0 @S9S_MB_2U_LIB.S9S_MB_2U(SCH_1):TP_CHA_CPU0_DIMM1_FRU_0
 144 TP_CHA_CPU0_DIMM1_FRU_1   RFU1 @S9S_MB_2U_LIB.S9S_MB_2U(SCH_1):TP_CHA_CPU0_DIMM1_FRU_1
 149 TP_CHA_CPU0_DIMM1_FRU_2   RFU2 @S9S_MB_2U_LIB.S9S_MB_2U(SCH_1):TP_CHA_CPU0_DIMM1_FRU_2
 150 TP_CHA_CPU0_DIMM1_FRU_3   RFU3 @S9S_MB_2U_LIB.S9S_MB_2U(SCH_1):TP_CHA_CPU0_DIMM1_FRU_3
 220 TP_CHA_CPU0_DIMM1_FRU_4   RFU4 @S9S_MB_2U_LIB.S9S_MB_2U(SCH_1):TP_CHA_CPU0_DIMM1_FRU_4
 231 TP_CHA_CPU0_DIMM1_FRU_5   RFU5 @S9S_MB_2U_LIB.S9S_MB_2U(SCH_1):TP_CHA_CPU0_DIMM1_FRU_5
 232 TP_CHA_CPU0_DIMM1_FRU_6   RFU6 @S9S_MB_2U_LIB.S9S_MB_2U(SCH_1):TP_CHA_CPU0_DIMM1_FRU_6
 207 RST_M_AB_CPU0_FPGA_N RESET_N @S9S_MB_2U_LIB.S9S_MB_2U(SCH_1):RST_M_AB_CPU0_FPGA_N
 147 PWRGD_CHA_CPU0_DIMM1 PWR_GOOD||FAIL_N @S9S_MB_2U_LIB.S9S_MB_2U(SCH_1):PWRGD_CHA_CPU0_DIMM1
 227 M_A_CPU0_SB_PAR  PAR_B @S9S_MB_2U_LIB.S9S_MB_2U(SCH_1):M_A_CPU0_SB_PAR
  74 M_A_CPU0_SA_PAR  PAR_A @S9S_MB_2U_LIB.S9S_MB_2U(SCH_1):M_A_CPU0_SA_PAR
  87 M_A_CPU0_SB_RSP<0> LBS||RSP_B_N @S9S_MB_2U_LIB.S9S_MB_2U(SCH_1):M_A_CPU0_SB_RSP(0)
  86 M_A_CPU0_SA_RSP<0> LBD||RSP_A_N @S9S_MB_2U_LIB.S9S_MB_2U(SCH_1):M_A_CPU0_SA_RSP(0)
   5 I3C_SPD_DDRABCD_CPU0_LVC1_SDA   HSDA @S9S_MB_2U_LIB.S9S_MB_2U(SCH_1):I3C_SPD_DDRABCD_CPU0_LVC1_SDA
   4 I3C_SPD_DDRABCD_CPU0_LVC1_SCL_R   HSCL @S9S_MB_2U_LIB.S9S_MB_2U(SCH_1):I3C_SPD_DDRABCD_CPU0_LVC1_SCL_R1
 148 PD_CHA_CPU0_DIMM1_SAA    HSA @S9S_MB_2U_LIB.S9S_MB_2U(SCH_1):PD_CHA_CPU0_DIMM1_SAA
 100 M_A_CPU0_SB_DQ<0>  DQ0_B @S9S_MB_2U_LIB.S9S_MB_2U(SCH_1):M_A_CPU0_SB_DQ(0)
 102 M_A_CPU0_SB_DQ<1>  DQ1_B @S9S_MB_2U_LIB.S9S_MB_2U(SCH_1):M_A_CPU0_SB_DQ(1)
 245 M_A_CPU0_SB_DQ<2>  DQ2_B @S9S_MB_2U_LIB.S9S_MB_2U(SCH_1):M_A_CPU0_SB_DQ(2)
 247 M_A_CPU0_SB_DQ<3>  DQ3_B @S9S_MB_2U_LIB.S9S_MB_2U(SCH_1):M_A_CPU0_SB_DQ(3)
 107 M_A_CPU0_SB_DQ<4>  DQ4_B @S9S_MB_2U_LIB.S9S_MB_2U(SCH_1):M_A_CPU0_SB_DQ(4)
 109 M_A_CPU0_SB_DQ<5>  DQ5_B @S9S_MB_2U_LIB.S9S_MB_2U(SCH_1):M_A_CPU0_SB_DQ(5)
 252 M_A_CPU0_SB_DQ<6>  DQ6_B @S9S_MB_2U_LIB.S9S_MB_2U(SCH_1):M_A_CPU0_SB_DQ(6)
 254 M_A_CPU0_SB_DQ<7>  DQ7_B @S9S_MB_2U_LIB.S9S_MB_2U(SCH_1):M_A_CPU0_SB_DQ(7)
 111 M_A_CPU0_SB_DQ<8>  DQ8_B @S9S_MB_2U_LIB.S9S_MB_2U(SCH_1):M_A_CPU0_SB_DQ(8)
 113 M_A_CPU0_SB_DQ<9>  DQ9_B @S9S_MB_2U_LIB.S9S_MB_2U(SCH_1):M_A_CPU0_SB_DQ(9)
 256 M_A_CPU0_SB_DQ<10> DQ10_B @S9S_MB_2U_LIB.S9S_MB_2U(SCH_1):M_A_CPU0_SB_DQ(10)
 258 M_A_CPU0_SB_DQ<11> DQ11_B @S9S_MB_2U_LIB.S9S_MB_2U(SCH_1):M_A_CPU0_SB_DQ(11)
 118 M_A_CPU0_SB_DQ<12> DQ12_B @S9S_MB_2U_LIB.S9S_MB_2U(SCH_1):M_A_CPU0_SB_DQ(12)
 120 M_A_CPU0_SB_DQ<13> DQ13_B @S9S_MB_2U_LIB.S9S_MB_2U(SCH_1):M_A_CPU0_SB_DQ(13)
 263 M_A_CPU0_SB_DQ<14> DQ14_B @S9S_MB_2U_LIB.S9S_MB_2U(SCH_1):M_A_CPU0_SB_DQ(14)
 265 M_A_CPU0_SB_DQ<15> DQ15_B @S9S_MB_2U_LIB.S9S_MB_2U(SCH_1):M_A_CPU0_SB_DQ(15)
 122 M_A_CPU0_SB_DQ<16> DQ16_B @S9S_MB_2U_LIB.S9S_MB_2U(SCH_1):M_A_CPU0_SB_DQ(16)
 124 M_A_CPU0_SB_DQ<17> DQ17_B @S9S_MB_2U_LIB.S9S_MB_2U(SCH_1):M_A_CPU0_SB_DQ(17)
 267 M_A_CPU0_SB_DQ<18> DQ18_B @S9S_MB_2U_LIB.S9S_MB_2U(SCH_1):M_A_CPU0_SB_DQ(18)
 269 M_A_CPU0_SB_DQ<19> DQ19_B @S9S_MB_2U_LIB.S9S_MB_2U(SCH_1):M_A_CPU0_SB_DQ(19)
 129 M_A_CPU0_SB_DQ<20> DQ20_B @S9S_MB_2U_LIB.S9S_MB_2U(SCH_1):M_A_CPU0_SB_DQ(20)
 131 M_A_CPU0_SB_DQ<21> DQ21_B @S9S_MB_2U_LIB.S9S_MB_2U(SCH_1):M_A_CPU0_SB_DQ(21)
 274 M_A_CPU0_SB_DQ<22> DQ22_B @S9S_MB_2U_LIB.S9S_MB_2U(SCH_1):M_A_CPU0_SB_DQ(22)
 276 M_A_CPU0_SB_DQ<23> DQ23_B @S9S_MB_2U_LIB.S9S_MB_2U(SCH_1):M_A_CPU0_SB_DQ(23)
 133 M_A_CPU0_SB_DQ<24> DQ24_B @S9S_MB_2U_LIB.S9S_MB_2U(SCH_1):M_A_CPU0_SB_DQ(24)
 135 M_A_CPU0_SB_DQ<25> DQ25_B @S9S_MB_2U_LIB.S9S_MB_2U(SCH_1):M_A_CPU0_SB_DQ(25)
 278 M_A_CPU0_SB_DQ<26> DQ26_B @S9S_MB_2U_LIB.S9S_MB_2U(SCH_1):M_A_CPU0_SB_DQ(26)
 280 M_A_CPU0_SB_DQ<27> DQ27_B @S9S_MB_2U_LIB.S9S_MB_2U(SCH_1):M_A_CPU0_SB_DQ(27)
 140 M_A_CPU0_SB_DQ<28> DQ28_B @S9S_MB_2U_LIB.S9S_MB_2U(SCH_1):M_A_CPU0_SB_DQ(28)
 142 M_A_CPU0_SB_DQ<29> DQ29_B @S9S_MB_2U_LIB.S9S_MB_2U(SCH_1):M_A_CPU0_SB_DQ(29)
 285 M_A_CPU0_SB_DQ<30> DQ30_B @S9S_MB_2U_LIB.S9S_MB_2U(SCH_1):M_A_CPU0_SB_DQ(30)
 287 M_A_CPU0_SB_DQ<31> DQ31_B @S9S_MB_2U_LIB.S9S_MB_2U(SCH_1):M_A_CPU0_SB_DQ(31)
   7 M_A_CPU0_SA_DQ<0>  DQ0_A @S9S_MB_2U_LIB.S9S_MB_2U(SCH_1):M_A_CPU0_SA_DQ(0)
   9 M_A_CPU0_SA_DQ<1>  DQ1_A @S9S_MB_2U_LIB.S9S_MB_2U(SCH_1):M_A_CPU0_SA_DQ(1)
 152 M_A_CPU0_SA_DQ<2>  DQ2_A @S9S_MB_2U_LIB.S9S_MB_2U(SCH_1):M_A_CPU0_SA_DQ(2)
 154 M_A_CPU0_SA_DQ<3>  DQ3_A @S9S_MB_2U_LIB.S9S_MB_2U(SCH_1):M_A_CPU0_SA_DQ(3)
  14 M_A_CPU0_SA_DQ<4>  DQ4_A @S9S_MB_2U_LIB.S9S_MB_2U(SCH_1):M_A_CPU0_SA_DQ(4)
  16 M_A_CPU0_SA_DQ<5>  DQ5_A @S9S_MB_2U_LIB.S9S_MB_2U(SCH_1):M_A_CPU0_SA_DQ(5)
 159 M_A_CPU0_SA_DQ<6>  DQ6_A @S9S_MB_2U_LIB.S9S_MB_2U(SCH_1):M_A_CPU0_SA_DQ(6)
 161 M_A_CPU0_SA_DQ<7>  DQ7_A @S9S_MB_2U_LIB.S9S_MB_2U(SCH_1):M_A_CPU0_SA_DQ(7)
  18 M_A_CPU0_SA_DQ<8>  DQ8_A @S9S_MB_2U_LIB.S9S_MB_2U(SCH_1):M_A_CPU0_SA_DQ(8)
  20 M_A_CPU0_SA_DQ<9>  DQ9_A @S9S_MB_2U_LIB.S9S_MB_2U(SCH_1):M_A_CPU0_SA_DQ(9)
 163 M_A_CPU0_SA_DQ<10> DQ10_A @S9S_MB_2U_LIB.S9S_MB_2U(SCH_1):M_A_CPU0_SA_DQ(10)
 165 M_A_CPU0_SA_DQ<11> DQ11_A @S9S_MB_2U_LIB.S9S_MB_2U(SCH_1):M_A_CPU0_SA_DQ(11)
  25 M_A_CPU0_SA_DQ<12> DQ12_A @S9S_MB_2U_LIB.S9S_MB_2U(SCH_1):M_A_CPU0_SA_DQ(12)
  27 M_A_CPU0_SA_DQ<13> DQ13_A @S9S_MB_2U_LIB.S9S_MB_2U(SCH_1):M_A_CPU0_SA_DQ(13)
 170 M_A_CPU0_SA_DQ<14> DQ14_A @S9S_MB_2U_LIB.S9S_MB_2U(SCH_1):M_A_CPU0_SA_DQ(14)
 172 M_A_CPU0_SA_DQ<15> DQ15_A @S9S_MB_2U_LIB.S9S_MB_2U(SCH_1):M_A_CPU0_SA_DQ(15)
  29 M_A_CPU0_SA_DQ<16> DQ16_A @S9S_MB_2U_LIB.S9S_MB_2U(SCH_1):M_A_CPU0_SA_DQ(16)
  31 M_A_CPU0_SA_DQ<17> DQ17_A @S9S_MB_2U_LIB.S9S_MB_2U(SCH_1):M_A_CPU0_SA_DQ(17)
 174 M_A_CPU0_SA_DQ<18> DQ18_A @S9S_MB_2U_LIB.S9S_MB_2U(SCH_1):M_A_CPU0_SA_DQ(18)
 176 M_A_CPU0_SA_DQ<19> DQ19_A @S9S_MB_2U_LIB.S9S_MB_2U(SCH_1):M_A_CPU0_SA_DQ(19)
  36 M_A_CPU0_SA_DQ<20> DQ20_A @S9S_MB_2U_LIB.S9S_MB_2U(SCH_1):M_A_CPU0_SA_DQ(20)
  38 M_A_CPU0_SA_DQ<21> DQ21_A @S9S_MB_2U_LIB.S9S_MB_2U(SCH_1):M_A_CPU0_SA_DQ(21)
 181 M_A_CPU0_SA_DQ<22> DQ22_A @S9S_MB_2U_LIB.S9S_MB_2U(SCH_1):M_A_CPU0_SA_DQ(22)
 183 M_A_CPU0_SA_DQ<23> DQ23_A @S9S_MB_2U_LIB.S9S_MB_2U(SCH_1):M_A_CPU0_SA_DQ(23)
  40 M_A_CPU0_SA_DQ<24> DQ24_A @S9S_MB_2U_LIB.S9S_MB_2U(SCH_1):M_A_CPU0_SA_DQ(24)
  42 M_A_CPU0_SA_DQ<25> DQ25_A @S9S_MB_2U_LIB.S9S_MB_2U(SCH_1):M_A_CPU0_SA_DQ(25)
 185 M_A_CPU0_SA_DQ<26> DQ26_A @S9S_MB_2U_LIB.S9S_MB_2U(SCH_1):M_A_CPU0_SA_DQ(26)
 187 M_A_CPU0_SA_DQ<27> DQ27_A @S9S_MB_2U_LIB.S9S_MB_2U(SCH_1):M_A_CPU0_SA_DQ(27)
  47 M_A_CPU0_SA_DQ<28> DQ28_A @S9S_MB_2U_LIB.S9S_MB_2U(SCH_1):M_A_CPU0_SA_DQ(28)
  49 M_A_CPU0_SA_DQ<29> DQ29_A @S9S_MB_2U_LIB.S9S_MB_2U(SCH_1):M_A_CPU0_SA_DQ(29)
 192 M_A_CPU0_SA_DQ<30> DQ30_A @S9S_MB_2U_LIB.S9S_MB_2U(SCH_1):M_A_CPU0_SA_DQ(30)
 229 M_A_CPU0_SB_CS_N<1> CS1_B_N @S9S_MB_2U_LIB.S9S_MB_2U(SCH_1):M_A_CPU0_SB_CS_N(1)
 209 M_A_CPU0_SA_CS_N<1> CS1_A_N @S9S_MB_2U_LIB.S9S_MB_2U(SCH_1):M_A_CPU0_SA_CS_N(1)
  84 M_A_CPU0_SB_CS_N<0> CS0_B_N @S9S_MB_2U_LIB.S9S_MB_2U(SCH_1):M_A_CPU0_SB_CS_N(0)
  64 M_A_CPU0_SA_CS_N<0> CS0_A_N @S9S_MB_2U_LIB.S9S_MB_2U(SCH_1):M_A_CPU0_SA_CS_N(0)
 217 M_A_CPU0_CLK_DP<0>   CK_T @S9S_MB_2U_LIB.S9S_MB_2U(SCH_1):M_A_CPU0_CLK_DP(0)
 218 M_A_CPU0_CLK_DN<0>   CK_C @S9S_MB_2U_LIB.S9S_MB_2U(SCH_1):M_A_CPU0_CLK_DN(0)
  96 M_A_CPU0_SB_CB<0>  CB0_B @S9S_MB_2U_LIB.S9S_MB_2U(SCH_1):M_A_CPU0_SB_CB(0)
  98 M_A_CPU0_SB_CB<1>  CB1_B @S9S_MB_2U_LIB.S9S_MB_2U(SCH_1):M_A_CPU0_SB_CB(1)
 241 M_A_CPU0_SB_CB<2>  CB2_B @S9S_MB_2U_LIB.S9S_MB_2U(SCH_1):M_A_CPU0_SB_CB(2)
 243 M_A_CPU0_SB_CB<3>  CB3_B @S9S_MB_2U_LIB.S9S_MB_2U(SCH_1):M_A_CPU0_SB_CB(3)
  89 M_A_CPU0_SB_CB<4>  CB4_B @S9S_MB_2U_LIB.S9S_MB_2U(SCH_1):M_A_CPU0_SB_CB(4)
  91 M_A_CPU0_SB_CB<5>  CB5_B @S9S_MB_2U_LIB.S9S_MB_2U(SCH_1):M_A_CPU0_SB_CB(5)
 234 M_A_CPU0_SB_CB<6>  CB6_B @S9S_MB_2U_LIB.S9S_MB_2U(SCH_1):M_A_CPU0_SB_CB(6)
  51 M_A_CPU0_SA_CB<0>  CB0_A @S9S_MB_2U_LIB.S9S_MB_2U(SCH_1):M_A_CPU0_SA_CB(0)
 196 M_A_CPU0_SA_CB<2>  CB2_A @S9S_MB_2U_LIB.S9S_MB_2U(SCH_1):M_A_CPU0_SA_CB(2)
 198 M_A_CPU0_SA_CB<3>  CB3_A @S9S_MB_2U_LIB.S9S_MB_2U(SCH_1):M_A_CPU0_SA_CB(3)
  60 M_A_CPU0_SA_CB<5>  CB5_A @S9S_MB_2U_LIB.S9S_MB_2U(SCH_1):M_A_CPU0_SA_CB(5)
 203 M_A_CPU0_SA_CB<6>  CB6_A @S9S_MB_2U_LIB.S9S_MB_2U(SCH_1):M_A_CPU0_SA_CB(6)
  82 M_A_CPU0_SB_CA<6>  CA6_B @S9S_MB_2U_LIB.S9S_MB_2U(SCH_1):M_A_CPU0_SB_CA(6)
  72 M_A_CPU0_SA_CA<6>  CA6_A @S9S_MB_2U_LIB.S9S_MB_2U(SCH_1):M_A_CPU0_SA_CA(6)
 225 M_A_CPU0_SB_CA<5>  CA5_B @S9S_MB_2U_LIB.S9S_MB_2U(SCH_1):M_A_CPU0_SB_CA(5)
 215 M_A_CPU0_SA_CA<5>  CA5_A @S9S_MB_2U_LIB.S9S_MB_2U(SCH_1):M_A_CPU0_SA_CA(5)
  80 M_A_CPU0_SB_CA<4>  CA4_B @S9S_MB_2U_LIB.S9S_MB_2U(SCH_1):M_A_CPU0_SB_CA(4)
  70 M_A_CPU0_SA_CA<4>  CA4_A @S9S_MB_2U_LIB.S9S_MB_2U(SCH_1):M_A_CPU0_SA_CA(4)
 223 M_A_CPU0_SB_CA<3>  CA3_B @S9S_MB_2U_LIB.S9S_MB_2U(SCH_1):M_A_CPU0_SB_CA(3)
 213 M_A_CPU0_SA_CA<3>  CA3_A @S9S_MB_2U_LIB.S9S_MB_2U(SCH_1):M_A_CPU0_SA_CA(3)
  78 M_A_CPU0_SB_CA<2>  CA2_B @S9S_MB_2U_LIB.S9S_MB_2U(SCH_1):M_A_CPU0_SB_CA(2)
  68 M_A_CPU0_SA_CA<2>  CA2_A @S9S_MB_2U_LIB.S9S_MB_2U(SCH_1):M_A_CPU0_SA_CA(2)
 221 M_A_CPU0_SB_CA<1>  CA1_B @S9S_MB_2U_LIB.S9S_MB_2U(SCH_1):M_A_CPU0_SB_CA(1)
 211 M_A_CPU0_SA_CA<1>  CA1_A @S9S_MB_2U_LIB.S9S_MB_2U(SCH_1):M_A_CPU0_SA_CA(1)
  76 M_A_CPU0_SB_CA<0>  CA0_B @S9S_MB_2U_LIB.S9S_MB_2U(SCH_1):M_A_CPU0_SB_CA(0)
  66 M_A_CPU0_SA_CA<0>  CA0_A @S9S_MB_2U_LIB.S9S_MB_2U(SCH_1):M_A_CPU0_SA_CA(0)
  62 M_A_CPU0_ALERT_N ALERT_N @S9S_MB_2U_LIB.S9S_MB_2U(SCH_1):M_A_CPU0_ALERT_N
 236 M_A_CPU0_SB_CB<7>  CB7_B @S9S_MB_2U_LIB.S9S_MB_2U(SCH_1):M_A_CPU0_SB_CB(7)
  53 M_A_CPU0_SA_CB<1>  CB1_A @S9S_MB_2U_LIB.S9S_MB_2U(SCH_1):M_A_CPU0_SA_CB(1)
  58 M_A_CPU0_SA_CB<4>  CB4_A @S9S_MB_2U_LIB.S9S_MB_2U(SCH_1):M_A_CPU0_SA_CB(4)
 205 M_A_CPU0_SA_CB<7>  CB7_A @S9S_MB_2U_LIB.S9S_MB_2U(SCH_1):M_A_CPU0_SA_CB(7)
 194 M_A_CPU0_SA_DQ<31> DQ31_A @S9S_MB_2U_LIB.S9S_MB_2U(SCH_1):M_A_CPU0_SA_DQ(31)

SCONN288_ADR50017P130CC-SCONN2A  I202  J1
  93 M_A_CPU0_SB_DQS_DP<9> DQS9_B_T||TDQS9_B_T||DBI4_B_N @S9S_MB_2U_LIB.S9S_MB_2U(SCH_1):M_A_CPU0_SB_DQS_DP(9)
  94 M_A_CPU0_SB_DQS_DN<9> DQS9_B_C||TDQS9_B_C @S9S_MB_2U_LIB.S9S_MB_2U(SCH_1):M_A_CPU0_SB_DQS_DN(9)
 201 M_A_CPU0_SA_DQS_DP<9> DQS9_A_T||TDQS9_A_T @S9S_MB_2U_LIB.S9S_MB_2U(SCH_1):M_A_CPU0_SA_DQS_DP(9)
 200 M_A_CPU0_SA_DQS_DN<9> DQS9_A_C||TDQS9_A_C @S9S_MB_2U_LIB.S9S_MB_2U(SCH_1):M_A_CPU0_SA_DQS_DN(9)
 190 M_A_CPU0_SA_DQS_DP<8> DQS8_A_T||TDQS8_A_T @S9S_MB_2U_LIB.S9S_MB_2U(SCH_1):M_A_CPU0_SA_DQS_DP(8)
 189 M_A_CPU0_SA_DQS_DN<8> DQS8_A_C||TDQS8_A_C @S9S_MB_2U_LIB.S9S_MB_2U(SCH_1):M_A_CPU0_SA_DQS_DN(8)
 271 M_A_CPU0_SB_DQS_DN<7> DQS7_B_C||TDQS7_B_C @S9S_MB_2U_LIB.S9S_MB_2U(SCH_1):M_A_CPU0_SB_DQS_DN(7)
 179 M_A_CPU0_SA_DQS_DP<7> DQS7_A_T||TDQS7_A_T @S9S_MB_2U_LIB.S9S_MB_2U(SCH_1):M_A_CPU0_SA_DQS_DP(7)
 261 M_A_CPU0_SB_DQS_DP<6> DQS6_B_T||TDQS6_B_T @S9S_MB_2U_LIB.S9S_MB_2U(SCH_1):M_A_CPU0_SB_DQS_DP(6)
 260 M_A_CPU0_SB_DQS_DN<6> DQS6_B_C||TDQS6_B_C @S9S_MB_2U_LIB.S9S_MB_2U(SCH_1):M_A_CPU0_SB_DQS_DN(6)
 167 M_A_CPU0_SA_DQS_DN<6> DQS6_A_C||TDQS6_A_C||DQS6_A_T||TDQS6_A_T @S9S_MB_2U_LIB.S9S_MB_2U(SCH_1):M_A_CPU0_SA_DQS_DN(6)
 250 M_A_CPU0_SB_DQS_DP<5> DQS5_B_T||TDQS5_B_T @S9S_MB_2U_LIB.S9S_MB_2U(SCH_1):M_A_CPU0_SB_DQS_DP(5)
 249 M_A_CPU0_SB_DQS_DN<5> DQS5_B_C||TDQS5_B_C @S9S_MB_2U_LIB.S9S_MB_2U(SCH_1):M_A_CPU0_SB_DQS_DN(5)
 157 M_A_CPU0_SA_DQS_DP<5> DQS5_A_T||TDQS5_A_T @S9S_MB_2U_LIB.S9S_MB_2U(SCH_1):M_A_CPU0_SA_DQS_DP(5)
 156 M_A_CPU0_SA_DQS_DN<5> DQS5_A_C||TDQS5_A_C||DQS5_A_T||TDQS5_A_T @S9S_MB_2U_LIB.S9S_MB_2U(SCH_1):M_A_CPU0_SA_DQS_DN(5)
 239 M_A_CPU0_SB_DQS_DP<4> DQS4_B_T @S9S_MB_2U_LIB.S9S_MB_2U(SCH_1):M_A_CPU0_SB_DQS_DP(4)
 238 M_A_CPU0_SB_DQS_DN<4> DQS4_B_C @S9S_MB_2U_LIB.S9S_MB_2U(SCH_1):M_A_CPU0_SB_DQS_DN(4)
  55 M_A_CPU0_SA_DQS_DP<4> DQS4_A_T @S9S_MB_2U_LIB.S9S_MB_2U(SCH_1):M_A_CPU0_SA_DQS_DP(4)
  56 M_A_CPU0_SA_DQS_DN<4> DQS4_A_C @S9S_MB_2U_LIB.S9S_MB_2U(SCH_1):M_A_CPU0_SA_DQS_DN(4)
 137 M_A_CPU0_SB_DQS_DP<3> DQS3_B_T @S9S_MB_2U_LIB.S9S_MB_2U(SCH_1):M_A_CPU0_SB_DQS_DP(3)
 138 M_A_CPU0_SB_DQS_DN<3> DQS3_B_C @S9S_MB_2U_LIB.S9S_MB_2U(SCH_1):M_A_CPU0_SB_DQS_DN(3)
  44 M_A_CPU0_SA_DQS_DP<3> DQS3_A_T @S9S_MB_2U_LIB.S9S_MB_2U(SCH_1):M_A_CPU0_SA_DQS_DP(3)
  45 M_A_CPU0_SA_DQS_DN<3> DQS3_A_C @S9S_MB_2U_LIB.S9S_MB_2U(SCH_1):M_A_CPU0_SA_DQS_DN(3)
 126 M_A_CPU0_SB_DQS_DP<2> DQS2_B_T @S9S_MB_2U_LIB.S9S_MB_2U(SCH_1):M_A_CPU0_SB_DQS_DP(2)
 127 M_A_CPU0_SB_DQS_DN<2> DQS2_B_C @S9S_MB_2U_LIB.S9S_MB_2U(SCH_1):M_A_CPU0_SB_DQS_DN(2)
  33 M_A_CPU0_SA_DQS_DP<2> DQS2_A_T @S9S_MB_2U_LIB.S9S_MB_2U(SCH_1):M_A_CPU0_SA_DQS_DP(2)
  34 M_A_CPU0_SA_DQS_DN<2> DQS2_A_C @S9S_MB_2U_LIB.S9S_MB_2U(SCH_1):M_A_CPU0_SA_DQS_DN(2)
 115 M_A_CPU0_SB_DQS_DP<1> DQS1_B_T @S9S_MB_2U_LIB.S9S_MB_2U(SCH_1):M_A_CPU0_SB_DQS_DP(1)
 116 M_A_CPU0_SB_DQS_DN<1> DQS1_B_C @S9S_MB_2U_LIB.S9S_MB_2U(SCH_1):M_A_CPU0_SB_DQS_DN(1)
  22 M_A_CPU0_SA_DQS_DP<1> DQS1_A_T @S9S_MB_2U_LIB.S9S_MB_2U(SCH_1):M_A_CPU0_SA_DQS_DP(1)
  23 M_A_CPU0_SA_DQS_DN<1> DQS1_A_C @S9S_MB_2U_LIB.S9S_MB_2U(SCH_1):M_A_CPU0_SA_DQS_DN(1)
 104 M_A_CPU0_SB_DQS_DP<0> DQS0_B_T @S9S_MB_2U_LIB.S9S_MB_2U(SCH_1):M_A_CPU0_SB_DQS_DP(0)
 105 M_A_CPU0_SB_DQS_DN<0> DQS0_B_C @S9S_MB_2U_LIB.S9S_MB_2U(SCH_1):M_A_CPU0_SB_DQS_DN(0)
  11 M_A_CPU0_SA_DQS_DP<0> DQS0_A_T @S9S_MB_2U_LIB.S9S_MB_2U(SCH_1):M_A_CPU0_SA_DQS_DP(0)
  12 M_A_CPU0_SA_DQS_DN<0> DQS0_A_C @S9S_MB_2U_LIB.S9S_MB_2U(SCH_1):M_A_CPU0_SA_DQS_DN(0)
 272 M_A_CPU0_SB_DQS_DP<7> DQS7_B_T||TDQS7_B_T @S9S_MB_2U_LIB.S9S_MB_2U(SCH_1):M_A_CPU0_SB_DQS_DP(7)
 282 M_A_CPU0_SB_DQS_DN<8> DQS8_B_C||TDQS8_B_C @S9S_MB_2U_LIB.S9S_MB_2U(SCH_1):M_A_CPU0_SB_DQS_DN(8)
 283 M_A_CPU0_SB_DQS_DP<8> DQS8_B_T||TDQS8_B_T @S9S_MB_2U_LIB.S9S_MB_2U(SCH_1):M_A_CPU0_SB_DQS_DP(8)
 168 M_A_CPU0_SA_DQS_DP<6> DQS6_A_T||TDQS6_A_T @S9S_MB_2U_LIB.S9S_MB_2U(SCH_1):M_A_CPU0_SA_DQS_DP(6)
 178 M_A_CPU0_SA_DQS_DN<7> DQS7_A_C||TDQS7_A_C @S9S_MB_2U_LIB.S9S_MB_2U(SCH_1):M_A_CPU0_SA_DQS_DN(7)

SCONN288_ADR50017P130CC-SCONN2A  I203  J1
   6    GND   VSS0 @S9S_MB_2U_LIB.S9S_MB_2U(SCH_1):GND
   8    GND   VSS1 @S9S_MB_2U_LIB.S9S_MB_2U(SCH_1):GND
  10    GND   VSS2 @S9S_MB_2U_LIB.S9S_MB_2U(SCH_1):GND
  13    GND   VSS3 @S9S_MB_2U_LIB.S9S_MB_2U(SCH_1):GND
  15    GND   VSS4 @S9S_MB_2U_LIB.S9S_MB_2U(SCH_1):GND
  17    GND   VSS5 @S9S_MB_2U_LIB.S9S_MB_2U(SCH_1):GND
  19    GND   VSS6 @S9S_MB_2U_LIB.S9S_MB_2U(SCH_1):GND
  21    GND   VSS7 @S9S_MB_2U_LIB.S9S_MB_2U(SCH_1):GND
  24    GND   VSS8 @S9S_MB_2U_LIB.S9S_MB_2U(SCH_1):GND
  26    GND   VSS9 @S9S_MB_2U_LIB.S9S_MB_2U(SCH_1):GND
  28    GND  VSS10 @S9S_MB_2U_LIB.S9S_MB_2U(SCH_1):GND
  30    GND  VSS11 @S9S_MB_2U_LIB.S9S_MB_2U(SCH_1):GND
  32    GND  VSS12 @S9S_MB_2U_LIB.S9S_MB_2U(SCH_1):GND
  35    GND  VSS13 @S9S_MB_2U_LIB.S9S_MB_2U(SCH_1):GND
  37    GND  VSS14 @S9S_MB_2U_LIB.S9S_MB_2U(SCH_1):GND
  39    GND  VSS15 @S9S_MB_2U_LIB.S9S_MB_2U(SCH_1):GND
  41    GND  VSS16 @S9S_MB_2U_LIB.S9S_MB_2U(SCH_1):GND
  43    GND  VSS17 @S9S_MB_2U_LIB.S9S_MB_2U(SCH_1):GND
  46    GND  VSS18 @S9S_MB_2U_LIB.S9S_MB_2U(SCH_1):GND
  48    GND  VSS19 @S9S_MB_2U_LIB.S9S_MB_2U(SCH_1):GND
  50    GND  VSS20 @S9S_MB_2U_LIB.S9S_MB_2U(SCH_1):GND
  52    GND  VSS21 @S9S_MB_2U_LIB.S9S_MB_2U(SCH_1):GND
  54    GND  VSS22 @S9S_MB_2U_LIB.S9S_MB_2U(SCH_1):GND
  57    GND  VSS23 @S9S_MB_2U_LIB.S9S_MB_2U(SCH_1):GND
  59    GND  VSS24 @S9S_MB_2U_LIB.S9S_MB_2U(SCH_1):GND
  61    GND  VSS25 @S9S_MB_2U_LIB.S9S_MB_2U(SCH_1):GND
  63    GND  VSS26 @S9S_MB_2U_LIB.S9S_MB_2U(SCH_1):GND
  65    GND  VSS27 @S9S_MB_2U_LIB.S9S_MB_2U(SCH_1):GND
  67    GND  VSS28 @S9S_MB_2U_LIB.S9S_MB_2U(SCH_1):GND
  69    GND  VSS29 @S9S_MB_2U_LIB.S9S_MB_2U(SCH_1):GND
  71    GND  VSS30 @S9S_MB_2U_LIB.S9S_MB_2U(SCH_1):GND
  73    GND  VSS31 @S9S_MB_2U_LIB.S9S_MB_2U(SCH_1):GND
  75    GND  VSS32 @S9S_MB_2U_LIB.S9S_MB_2U(SCH_1):GND
  77    GND  VSS33 @S9S_MB_2U_LIB.S9S_MB_2U(SCH_1):GND
  79    GND  VSS34 @S9S_MB_2U_LIB.S9S_MB_2U(SCH_1):GND
  81    GND  VSS35 @S9S_MB_2U_LIB.S9S_MB_2U(SCH_1):GND
  83    GND  VSS36 @S9S_MB_2U_LIB.S9S_MB_2U(SCH_1):GND
  85    GND  VSS37 @S9S_MB_2U_LIB.S9S_MB_2U(SCH_1):GND
  88    GND  VSS38 @S9S_MB_2U_LIB.S9S_MB_2U(SCH_1):GND
  90    GND  VSS39 @S9S_MB_2U_LIB.S9S_MB_2U(SCH_1):GND
  92    GND  VSS40 @S9S_MB_2U_LIB.S9S_MB_2U(SCH_1):GND
  95    GND  VSS41 @S9S_MB_2U_LIB.S9S_MB_2U(SCH_1):GND
  97    GND  VSS42 @S9S_MB_2U_LIB.S9S_MB_2U(SCH_1):GND
  99    GND  VSS43 @S9S_MB_2U_LIB.S9S_MB_2U(SCH_1):GND
 101    GND  VSS44 @S9S_MB_2U_LIB.S9S_MB_2U(SCH_1):GND
 103    GND  VSS45 @S9S_MB_2U_LIB.S9S_MB_2U(SCH_1):GND
 106    GND  VSS46 @S9S_MB_2U_LIB.S9S_MB_2U(SCH_1):GND
 108    GND  VSS47 @S9S_MB_2U_LIB.S9S_MB_2U(SCH_1):GND
 110    GND  VSS48 @S9S_MB_2U_LIB.S9S_MB_2U(SCH_1):GND
 112    GND  VSS49 @S9S_MB_2U_LIB.S9S_MB_2U(SCH_1):GND
 114    GND  VSS50 @S9S_MB_2U_LIB.S9S_MB_2U(SCH_1):GND
 117    GND  VSS51 @S9S_MB_2U_LIB.S9S_MB_2U(SCH_1):GND
 119    GND  VSS52 @S9S_MB_2U_LIB.S9S_MB_2U(SCH_1):GND
 121    GND  VSS53 @S9S_MB_2U_LIB.S9S_MB_2U(SCH_1):GND
 123    GND  VSS54 @S9S_MB_2U_LIB.S9S_MB_2U(SCH_1):GND
 125    GND  VSS55 @S9S_MB_2U_LIB.S9S_MB_2U(SCH_1):GND
 128    GND  VSS56 @S9S_MB_2U_LIB.S9S_MB_2U(SCH_1):GND
 130    GND  VSS57 @S9S_MB_2U_LIB.S9S_MB_2U(SCH_1):GND
 134    GND  VSS59 @S9S_MB_2U_LIB.S9S_MB_2U(SCH_1):GND
 143    GND  VSS63 @S9S_MB_2U_LIB.S9S_MB_2U(SCH_1):GND
 151    GND  VSS64 @S9S_MB_2U_LIB.S9S_MB_2U(SCH_1):GND
 153    GND  VSS65 @S9S_MB_2U_LIB.S9S_MB_2U(SCH_1):GND
 155    GND  VSS66 @S9S_MB_2U_LIB.S9S_MB_2U(SCH_1):GND
 158    GND  VSS67 @S9S_MB_2U_LIB.S9S_MB_2U(SCH_1):GND
 160    GND  VSS68 @S9S_MB_2U_LIB.S9S_MB_2U(SCH_1):GND
 162    GND  VSS69 @S9S_MB_2U_LIB.S9S_MB_2U(SCH_1):GND
 164    GND  VSS70 @S9S_MB_2U_LIB.S9S_MB_2U(SCH_1):GND
 166    GND  VSS71 @S9S_MB_2U_LIB.S9S_MB_2U(SCH_1):GND
 169    GND  VSS72 @S9S_MB_2U_LIB.S9S_MB_2U(SCH_1):GND
 171    GND  VSS73 @S9S_MB_2U_LIB.S9S_MB_2U(SCH_1):GND
 173    GND  VSS74 @S9S_MB_2U_LIB.S9S_MB_2U(SCH_1):GND
 175    GND  VSS75 @S9S_MB_2U_LIB.S9S_MB_2U(SCH_1):GND
 177    GND  VSS76 @S9S_MB_2U_LIB.S9S_MB_2U(SCH_1):GND
 180    GND  VSS77 @S9S_MB_2U_LIB.S9S_MB_2U(SCH_1):GND
 182    GND  VSS78 @S9S_MB_2U_LIB.S9S_MB_2U(SCH_1):GND
 184    GND  VSS79 @S9S_MB_2U_LIB.S9S_MB_2U(SCH_1):GND
 186    GND  VSS80 @S9S_MB_2U_LIB.S9S_MB_2U(SCH_1):GND
 188    GND  VSS81 @S9S_MB_2U_LIB.S9S_MB_2U(SCH_1):GND
 191    GND  VSS82 @S9S_MB_2U_LIB.S9S_MB_2U(SCH_1):GND
 193    GND  VSS83 @S9S_MB_2U_LIB.S9S_MB_2U(SCH_1):GND
 195    GND  VSS84 @S9S_MB_2U_LIB.S9S_MB_2U(SCH_1):GND
 197    GND  VSS85 @S9S_MB_2U_LIB.S9S_MB_2U(SCH_1):GND
 199    GND  VSS86 @S9S_MB_2U_LIB.S9S_MB_2U(SCH_1):GND
 202    GND  VSS87 @S9S_MB_2U_LIB.S9S_MB_2U(SCH_1):GND
 204    GND  VSS88 @S9S_MB_2U_LIB.S9S_MB_2U(SCH_1):GND
 206    GND  VSS89 @S9S_MB_2U_LIB.S9S_MB_2U(SCH_1):GND
 208    GND  VSS90 @S9S_MB_2U_LIB.S9S_MB_2U(SCH_1):GND
 210    GND  VSS91 @S9S_MB_2U_LIB.S9S_MB_2U(SCH_1):GND
 212    GND  VSS92 @S9S_MB_2U_LIB.S9S_MB_2U(SCH_1):GND
 214    GND  VSS93 @S9S_MB_2U_LIB.S9S_MB_2U(SCH_1):GND
 216    GND  VSS94 @S9S_MB_2U_LIB.S9S_MB_2U(SCH_1):GND
 219    GND  VSS95 @S9S_MB_2U_LIB.S9S_MB_2U(SCH_1):GND
 222    GND  VSS96 @S9S_MB_2U_LIB.S9S_MB_2U(SCH_1):GND
 224    GND  VSS97 @S9S_MB_2U_LIB.S9S_MB_2U(SCH_1):GND
 226    GND  VSS98 @S9S_MB_2U_LIB.S9S_MB_2U(SCH_1):GND
 228    GND  VSS99 @S9S_MB_2U_LIB.S9S_MB_2U(SCH_1):GND
 233    GND VSS101 @S9S_MB_2U_LIB.S9S_MB_2U(SCH_1):GND
 237    GND VSS103 @S9S_MB_2U_LIB.S9S_MB_2U(SCH_1):GND
 242    GND VSS105 @S9S_MB_2U_LIB.S9S_MB_2U(SCH_1):GND
 244    GND VSS106 @S9S_MB_2U_LIB.S9S_MB_2U(SCH_1):GND
 246    GND VSS107 @S9S_MB_2U_LIB.S9S_MB_2U(SCH_1):GND
 248    GND VSS108 @S9S_MB_2U_LIB.S9S_MB_2U(SCH_1):GND
 251    GND VSS109 @S9S_MB_2U_LIB.S9S_MB_2U(SCH_1):GND
 253    GND VSS110 @S9S_MB_2U_LIB.S9S_MB_2U(SCH_1):GND
 255    GND VSS111 @S9S_MB_2U_LIB.S9S_MB_2U(SCH_1):GND
 257    GND VSS112 @S9S_MB_2U_LIB.S9S_MB_2U(SCH_1):GND
 259    GND VSS113 @S9S_MB_2U_LIB.S9S_MB_2U(SCH_1):GND
 262    GND VSS114 @S9S_MB_2U_LIB.S9S_MB_2U(SCH_1):GND
 264    GND VSS115 @S9S_MB_2U_LIB.S9S_MB_2U(SCH_1):GND
 266    GND VSS116 @S9S_MB_2U_LIB.S9S_MB_2U(SCH_1):GND
 268    GND VSS117 @S9S_MB_2U_LIB.S9S_MB_2U(SCH_1):GND
 270    GND VSS118 @S9S_MB_2U_LIB.S9S_MB_2U(SCH_1):GND
 273    GND VSS119 @S9S_MB_2U_LIB.S9S_MB_2U(SCH_1):GND
 275    GND VSS120 @S9S_MB_2U_LIB.S9S_MB_2U(SCH_1):GND
 277    GND VSS121 @S9S_MB_2U_LIB.S9S_MB_2U(SCH_1):GND
 279    GND VSS122 @S9S_MB_2U_LIB.S9S_MB_2U(SCH_1):GND
 281    GND VSS123 @S9S_MB_2U_LIB.S9S_MB_2U(SCH_1):GND
 284    GND VSS124 @S9S_MB_2U_LIB.S9S_MB_2U(SCH_1):GND
 286    GND VSS125 @S9S_MB_2U_LIB.S9S_MB_2U(SCH_1):GND
 288    GND VSS126 @S9S_MB_2U_LIB.S9S_MB_2U(SCH_1):GND
   1 P12V_S3_AUX_CPU0_NVDIMM VIN_BULK0 @S9S_MB_2U_LIB.S9S_MB_2U(SCH_1):P12V_S3_AUX_CPU0_NVDIMM
 145 P12V_S3_AUX_CPU0_NVDIMM VIN_BULK1 @S9S_MB_2U_LIB.S9S_MB_2U(SCH_1):P12V_S3_AUX_CPU0_NVDIMM
 146 P12V_S3_AUX_CPU0_NVDIMM VIN_BULK2 @S9S_MB_2U_LIB.S9S_MB_2U(SCH_1):P12V_S3_AUX_CPU0_NVDIMM
 230    GND VSS100 @S9S_MB_2U_LIB.S9S_MB_2U(SCH_1):GND
 235    GND VSS102 @S9S_MB_2U_LIB.S9S_MB_2U(SCH_1):GND
 240    GND VSS104 @S9S_MB_2U_LIB.S9S_MB_2U(SCH_1):GND
 132    GND  VSS58 @S9S_MB_2U_LIB.S9S_MB_2U(SCH_1):GND
 136    GND  VSS60 @S9S_MB_2U_LIB.S9S_MB_2U(SCH_1):GND
 139    GND  VSS61 @S9S_MB_2U_LIB.S9S_MB_2U(SCH_1):GND
 141    GND  VSS62 @S9S_MB_2U_LIB.S9S_MB_2U(SCH_1):GND
  G1    GND     G1 @S9S_MB_2U_LIB.S9S_MB_2U(SCH_1):GND
  G2    GND     G2 @S9S_MB_2U_LIB.S9S_MB_2U(SCH_1):GND
  G3    GND     G3 @S9S_MB_2U_LIB.S9S_MB_2U(SCH_1):GND

Q_RES_0402LF-49.9,1%,1/16W,CHIA  I204  R3875
   1 I3C_SPD_DDRABCD_CPU0_LVC1_SCL_R      A @S9S_MB_2U_LIB.S9S_MB_2U(SCH_1):I3C_SPD_DDRABCD_CPU0_LVC1_SCL_R1
   2 I3C_SPD_DDRABCD_CPU0_LVC1_SCL      B @S9S_MB_2U_LIB.S9S_MB_2U(SCH_1):I3C_SPD_DDRABCD_CPU0_LVC1_SCL


DRAWING: @S9S_MB_2U_LIB.S9S_MB_2U(SCH_1):PAGE83 

Q_RES_0402LF-15.4K,1%,1/16W,CHA  I10  R27
   1 PD_CHA_CPU0_DIMM2_SAA      A @S9S_MB_2U_LIB.S9S_MB_2U(SCH_1):PD_CHA_CPU0_DIMM2_SAA
   2    GND      B @S9S_MB_2U_LIB.S9S_MB_2U(SCH_1):GND

Q_CAP_C0402-2.2UF,6.3V,20%,X6SA  I120  C5
   1 P3V3_AUX      A @S9S_MB_2U_LIB.S9S_MB_2U(SCH_1):P3V3_AUX
   2    GND      B @S9S_MB_2U_LIB.S9S_MB_2U(SCH_1):GND

Q_CAP_C0805-10UF,16V,10%,X6S,CA  I122  C6
   1 P12V_S3_AUX_CPU0_NVDIMM      A @S9S_MB_2U_LIB.S9S_MB_2U(SCH_1):P12V_S3_AUX_CPU0_NVDIMM
   2    GND      B @S9S_MB_2U_LIB.S9S_MB_2U(SCH_1):GND

Q_CAP_C0805-10UF,16V,10%,X6S,CA  I144  C7
   1 P12V_S3_AUX_CPU0_NVDIMM      A @S9S_MB_2U_LIB.S9S_MB_2U(SCH_1):P12V_S3_AUX_CPU0_NVDIMM
   2    GND      B @S9S_MB_2U_LIB.S9S_MB_2U(SCH_1):GND

SCONN288_ADR50017P087CC-SCONN2A  I177  J2
   3 P3V3_AUX VIN_MGMT @S9S_MB_2U_LIB.S9S_MB_2U(SCH_1):P3V3_AUX
   2 TP_CHA_CPU0_DIMM2_FRU_0   RFU0 @S9S_MB_2U_LIB.S9S_MB_2U(SCH_1):TP_CHA_CPU0_DIMM2_FRU_0
 144 TP_CHA_CPU0_DIMM2_FRU_1   RFU1 @S9S_MB_2U_LIB.S9S_MB_2U(SCH_1):TP_CHA_CPU0_DIMM2_FRU_1
 149 TP_CHA_CPU0_DIMM2_FRU_2   RFU2 @S9S_MB_2U_LIB.S9S_MB_2U(SCH_1):TP_CHA_CPU0_DIMM2_FRU_2
 150 TP_CHA_CPU0_DIMM2_FRU_3   RFU3 @S9S_MB_2U_LIB.S9S_MB_2U(SCH_1):TP_CHA_CPU0_DIMM2_FRU_3
 220 TP_CHA_CPU0_DIMM2_FRU_4   RFU4 @S9S_MB_2U_LIB.S9S_MB_2U(SCH_1):TP_CHA_CPU0_DIMM2_FRU_4
 231 TP_CHA_CPU0_DIMM2_FRU_5   RFU5 @S9S_MB_2U_LIB.S9S_MB_2U(SCH_1):TP_CHA_CPU0_DIMM2_FRU_5
 232 TP_CHA_CPU0_DIMM2_FRU_6   RFU6 @S9S_MB_2U_LIB.S9S_MB_2U(SCH_1):TP_CHA_CPU0_DIMM2_FRU_6
 207 RST_M_AB_CPU0_FPGA_N RESET_N @S9S_MB_2U_LIB.S9S_MB_2U(SCH_1):RST_M_AB_CPU0_FPGA_N
 147 PWRGD_CHA_CPU0_DIMM2 PWR_GOOD||FAIL_N @S9S_MB_2U_LIB.S9S_MB_2U(SCH_1):PWRGD_CHA_CPU0_DIMM2
 227 M_A_CPU0_SB_PAR  PAR_B @S9S_MB_2U_LIB.S9S_MB_2U(SCH_1):M_A_CPU0_SB_PAR
  74 M_A_CPU0_SA_PAR  PAR_A @S9S_MB_2U_LIB.S9S_MB_2U(SCH_1):M_A_CPU0_SA_PAR
  87 M_A_CPU0_SB_RSP<1> LBS||RSP_B_N @S9S_MB_2U_LIB.S9S_MB_2U(SCH_1):M_A_CPU0_SB_RSP(1)
  86 M_A_CPU0_SA_RSP<1> LBD||RSP_A_N @S9S_MB_2U_LIB.S9S_MB_2U(SCH_1):M_A_CPU0_SA_RSP(1)
   5 I3C_SPD_DDRABCD_CPU0_LVC1_SDA   HSDA @S9S_MB_2U_LIB.S9S_MB_2U(SCH_1):I3C_SPD_DDRABCD_CPU0_LVC1_SDA
   4 I3C_SPD_DDRABCD_CPU0_LVC1_SCL_1   HSCL @S9S_MB_2U_LIB.S9S_MB_2U(SCH_1):I3C_SPD_DDRABCD_CPU0_LVC1_SCL_R2
 148 PD_CHA_CPU0_DIMM2_SAA    HSA @S9S_MB_2U_LIB.S9S_MB_2U(SCH_1):PD_CHA_CPU0_DIMM2_SAA
 100 M_A_CPU0_SB_DQ<0>  DQ0_B @S9S_MB_2U_LIB.S9S_MB_2U(SCH_1):M_A_CPU0_SB_DQ(0)
 102 M_A_CPU0_SB_DQ<1>  DQ1_B @S9S_MB_2U_LIB.S9S_MB_2U(SCH_1):M_A_CPU0_SB_DQ(1)
 245 M_A_CPU0_SB_DQ<2>  DQ2_B @S9S_MB_2U_LIB.S9S_MB_2U(SCH_1):M_A_CPU0_SB_DQ(2)
 247 M_A_CPU0_SB_DQ<3>  DQ3_B @S9S_MB_2U_LIB.S9S_MB_2U(SCH_1):M_A_CPU0_SB_DQ(3)
 107 M_A_CPU0_SB_DQ<4>  DQ4_B @S9S_MB_2U_LIB.S9S_MB_2U(SCH_1):M_A_CPU0_SB_DQ(4)
 109 M_A_CPU0_SB_DQ<5>  DQ5_B @S9S_MB_2U_LIB.S9S_MB_2U(SCH_1):M_A_CPU0_SB_DQ(5)
 252 M_A_CPU0_SB_DQ<6>  DQ6_B @S9S_MB_2U_LIB.S9S_MB_2U(SCH_1):M_A_CPU0_SB_DQ(6)
 254 M_A_CPU0_SB_DQ<7>  DQ7_B @S9S_MB_2U_LIB.S9S_MB_2U(SCH_1):M_A_CPU0_SB_DQ(7)
 111 M_A_CPU0_SB_DQ<8>  DQ8_B @S9S_MB_2U_LIB.S9S_MB_2U(SCH_1):M_A_CPU0_SB_DQ(8)
 113 M_A_CPU0_SB_DQ<9>  DQ9_B @S9S_MB_2U_LIB.S9S_MB_2U(SCH_1):M_A_CPU0_SB_DQ(9)
 256 M_A_CPU0_SB_DQ<10> DQ10_B @S9S_MB_2U_LIB.S9S_MB_2U(SCH_1):M_A_CPU0_SB_DQ(10)
 258 M_A_CPU0_SB_DQ<11> DQ11_B @S9S_MB_2U_LIB.S9S_MB_2U(SCH_1):M_A_CPU0_SB_DQ(11)
 118 M_A_CPU0_SB_DQ<12> DQ12_B @S9S_MB_2U_LIB.S9S_MB_2U(SCH_1):M_A_CPU0_SB_DQ(12)
 120 M_A_CPU0_SB_DQ<13> DQ13_B @S9S_MB_2U_LIB.S9S_MB_2U(SCH_1):M_A_CPU0_SB_DQ(13)
 263 M_A_CPU0_SB_DQ<14> DQ14_B @S9S_MB_2U_LIB.S9S_MB_2U(SCH_1):M_A_CPU0_SB_DQ(14)
 265 M_A_CPU0_SB_DQ<15> DQ15_B @S9S_MB_2U_LIB.S9S_MB_2U(SCH_1):M_A_CPU0_SB_DQ(15)
 122 M_A_CPU0_SB_DQ<16> DQ16_B @S9S_MB_2U_LIB.S9S_MB_2U(SCH_1):M_A_CPU0_SB_DQ(16)
 124 M_A_CPU0_SB_DQ<17> DQ17_B @S9S_MB_2U_LIB.S9S_MB_2U(SCH_1):M_A_CPU0_SB_DQ(17)
 267 M_A_CPU0_SB_DQ<18> DQ18_B @S9S_MB_2U_LIB.S9S_MB_2U(SCH_1):M_A_CPU0_SB_DQ(18)
 269 M_A_CPU0_SB_DQ<19> DQ19_B @S9S_MB_2U_LIB.S9S_MB_2U(SCH_1):M_A_CPU0_SB_DQ(19)
 129 M_A_CPU0_SB_DQ<20> DQ20_B @S9S_MB_2U_LIB.S9S_MB_2U(SCH_1):M_A_CPU0_SB_DQ(20)
 131 M_A_CPU0_SB_DQ<21> DQ21_B @S9S_MB_2U_LIB.S9S_MB_2U(SCH_1):M_A_CPU0_SB_DQ(21)
 274 M_A_CPU0_SB_DQ<22> DQ22_B @S9S_MB_2U_LIB.S9S_MB_2U(SCH_1):M_A_CPU0_SB_DQ(22)
 276 M_A_CPU0_SB_DQ<23> DQ23_B @S9S_MB_2U_LIB.S9S_MB_2U(SCH_1):M_A_CPU0_SB_DQ(23)
 133 M_A_CPU0_SB_DQ<24> DQ24_B @S9S_MB_2U_LIB.S9S_MB_2U(SCH_1):M_A_CPU0_SB_DQ(24)
 135 M_A_CPU0_SB_DQ<25> DQ25_B @S9S_MB_2U_LIB.S9S_MB_2U(SCH_1):M_A_CPU0_SB_DQ(25)
 278 M_A_CPU0_SB_DQ<26> DQ26_B @S9S_MB_2U_LIB.S9S_MB_2U(SCH_1):M_A_CPU0_SB_DQ(26)
 280 M_A_CPU0_SB_DQ<27> DQ27_B @S9S_MB_2U_LIB.S9S_MB_2U(SCH_1):M_A_CPU0_SB_DQ(27)
 140 M_A_CPU0_SB_DQ<28> DQ28_B @S9S_MB_2U_LIB.S9S_MB_2U(SCH_1):M_A_CPU0_SB_DQ(28)
 142 M_A_CPU0_SB_DQ<29> DQ29_B @S9S_MB_2U_LIB.S9S_MB_2U(SCH_1):M_A_CPU0_SB_DQ(29)
 285 M_A_CPU0_SB_DQ<30> DQ30_B @S9S_MB_2U_LIB.S9S_MB_2U(SCH_1):M_A_CPU0_SB_DQ(30)
 287 M_A_CPU0_SB_DQ<31> DQ31_B @S9S_MB_2U_LIB.S9S_MB_2U(SCH_1):M_A_CPU0_SB_DQ(31)
   7 M_A_CPU0_SA_DQ<0>  DQ0_A @S9S_MB_2U_LIB.S9S_MB_2U(SCH_1):M_A_CPU0_SA_DQ(0)
   9 M_A_CPU0_SA_DQ<1>  DQ1_A @S9S_MB_2U_LIB.S9S_MB_2U(SCH_1):M_A_CPU0_SA_DQ(1)
 152 M_A_CPU0_SA_DQ<2>  DQ2_A @S9S_MB_2U_LIB.S9S_MB_2U(SCH_1):M_A_CPU0_SA_DQ(2)
 154 M_A_CPU0_SA_DQ<3>  DQ3_A @S9S_MB_2U_LIB.S9S_MB_2U(SCH_1):M_A_CPU0_SA_DQ(3)
  14 M_A_CPU0_SA_DQ<4>  DQ4_A @S9S_MB_2U_LIB.S9S_MB_2U(SCH_1):M_A_CPU0_SA_DQ(4)
  16 M_A_CPU0_SA_DQ<5>  DQ5_A @S9S_MB_2U_LIB.S9S_MB_2U(SCH_1):M_A_CPU0_SA_DQ(5)
 159 M_A_CPU0_SA_DQ<6>  DQ6_A @S9S_MB_2U_LIB.S9S_MB_2U(SCH_1):M_A_CPU0_SA_DQ(6)
 161 M_A_CPU0_SA_DQ<7>  DQ7_A @S9S_MB_2U_LIB.S9S_MB_2U(SCH_1):M_A_CPU0_SA_DQ(7)
  18 M_A_CPU0_SA_DQ<8>  DQ8_A @S9S_MB_2U_LIB.S9S_MB_2U(SCH_1):M_A_CPU0_SA_DQ(8)
  20 M_A_CPU0_SA_DQ<9>  DQ9_A @S9S_MB_2U_LIB.S9S_MB_2U(SCH_1):M_A_CPU0_SA_DQ(9)
 163 M_A_CPU0_SA_DQ<10> DQ10_A @S9S_MB_2U_LIB.S9S_MB_2U(SCH_1):M_A_CPU0_SA_DQ(10)
 165 M_A_CPU0_SA_DQ<11> DQ11_A @S9S_MB_2U_LIB.S9S_MB_2U(SCH_1):M_A_CPU0_SA_DQ(11)
  25 M_A_CPU0_SA_DQ<12> DQ12_A @S9S_MB_2U_LIB.S9S_MB_2U(SCH_1):M_A_CPU0_SA_DQ(12)
  27 M_A_CPU0_SA_DQ<13> DQ13_A @S9S_MB_2U_LIB.S9S_MB_2U(SCH_1):M_A_CPU0_SA_DQ(13)
 170 M_A_CPU0_SA_DQ<14> DQ14_A @S9S_MB_2U_LIB.S9S_MB_2U(SCH_1):M_A_CPU0_SA_DQ(14)
 172 M_A_CPU0_SA_DQ<15> DQ15_A @S9S_MB_2U_LIB.S9S_MB_2U(SCH_1):M_A_CPU0_SA_DQ(15)
  29 M_A_CPU0_SA_DQ<16> DQ16_A @S9S_MB_2U_LIB.S9S_MB_2U(SCH_1):M_A_CPU0_SA_DQ(16)
  31 M_A_CPU0_SA_DQ<17> DQ17_A @S9S_MB_2U_LIB.S9S_MB_2U(SCH_1):M_A_CPU0_SA_DQ(17)
 174 M_A_CPU0_SA_DQ<18> DQ18_A @S9S_MB_2U_LIB.S9S_MB_2U(SCH_1):M_A_CPU0_SA_DQ(18)
 176 M_A_CPU0_SA_DQ<19> DQ19_A @S9S_MB_2U_LIB.S9S_MB_2U(SCH_1):M_A_CPU0_SA_DQ(19)
  36 M_A_CPU0_SA_DQ<20> DQ20_A @S9S_MB_2U_LIB.S9S_MB_2U(SCH_1):M_A_CPU0_SA_DQ(20)
  38 M_A_CPU0_SA_DQ<21> DQ21_A @S9S_MB_2U_LIB.S9S_MB_2U(SCH_1):M_A_CPU0_SA_DQ(21)
 181 M_A_CPU0_SA_DQ<22> DQ22_A @S9S_MB_2U_LIB.S9S_MB_2U(SCH_1):M_A_CPU0_SA_DQ(22)
 183 M_A_CPU0_SA_DQ<23> DQ23_A @S9S_MB_2U_LIB.S9S_MB_2U(SCH_1):M_A_CPU0_SA_DQ(23)
  40 M_A_CPU0_SA_DQ<24> DQ24_A @S9S_MB_2U_LIB.S9S_MB_2U(SCH_1):M_A_CPU0_SA_DQ(24)
  42 M_A_CPU0_SA_DQ<25> DQ25_A @S9S_MB_2U_LIB.S9S_MB_2U(SCH_1):M_A_CPU0_SA_DQ(25)
 185 M_A_CPU0_SA_DQ<26> DQ26_A @S9S_MB_2U_LIB.S9S_MB_2U(SCH_1):M_A_CPU0_SA_DQ(26)
 187 M_A_CPU0_SA_DQ<27> DQ27_A @S9S_MB_2U_LIB.S9S_MB_2U(SCH_1):M_A_CPU0_SA_DQ(27)
  47 M_A_CPU0_SA_DQ<28> DQ28_A @S9S_MB_2U_LIB.S9S_MB_2U(SCH_1):M_A_CPU0_SA_DQ(28)
  49 M_A_CPU0_SA_DQ<29> DQ29_A @S9S_MB_2U_LIB.S9S_MB_2U(SCH_1):M_A_CPU0_SA_DQ(29)
 192 M_A_CPU0_SA_DQ<30> DQ30_A @S9S_MB_2U_LIB.S9S_MB_2U(SCH_1):M_A_CPU0_SA_DQ(30)
 229 M_A_CPU0_SB_CS_N<3> CS1_B_N @S9S_MB_2U_LIB.S9S_MB_2U(SCH_1):M_A_CPU0_SB_CS_N(3)
 209 M_A_CPU0_SA_CS_N<3> CS1_A_N @S9S_MB_2U_LIB.S9S_MB_2U(SCH_1):M_A_CPU0_SA_CS_N(3)
  84 M_A_CPU0_SB_CS_N<2> CS0_B_N @S9S_MB_2U_LIB.S9S_MB_2U(SCH_1):M_A_CPU0_SB_CS_N(2)
  64 M_A_CPU0_SA_CS_N<2> CS0_A_N @S9S_MB_2U_LIB.S9S_MB_2U(SCH_1):M_A_CPU0_SA_CS_N(2)
 217 M_A_CPU0_CLK_DP<1>   CK_T @S9S_MB_2U_LIB.S9S_MB_2U(SCH_1):M_A_CPU0_CLK_DP(1)
 218 M_A_CPU0_CLK_DN<1>   CK_C @S9S_MB_2U_LIB.S9S_MB_2U(SCH_1):M_A_CPU0_CLK_DN(1)
  96 M_A_CPU0_SB_CB<0>  CB0_B @S9S_MB_2U_LIB.S9S_MB_2U(SCH_1):M_A_CPU0_SB_CB(0)
  98 M_A_CPU0_SB_CB<1>  CB1_B @S9S_MB_2U_LIB.S9S_MB_2U(SCH_1):M_A_CPU0_SB_CB(1)
 241 M_A_CPU0_SB_CB<2>  CB2_B @S9S_MB_2U_LIB.S9S_MB_2U(SCH_1):M_A_CPU0_SB_CB(2)
 243 M_A_CPU0_SB_CB<3>  CB3_B @S9S_MB_2U_LIB.S9S_MB_2U(SCH_1):M_A_CPU0_SB_CB(3)
  89 M_A_CPU0_SB_CB<4>  CB4_B @S9S_MB_2U_LIB.S9S_MB_2U(SCH_1):M_A_CPU0_SB_CB(4)
  91 M_A_CPU0_SB_CB<5>  CB5_B @S9S_MB_2U_LIB.S9S_MB_2U(SCH_1):M_A_CPU0_SB_CB(5)
 234 M_A_CPU0_SB_CB<6>  CB6_B @S9S_MB_2U_LIB.S9S_MB_2U(SCH_1):M_A_CPU0_SB_CB(6)
  51 M_A_CPU0_SA_CB<0>  CB0_A @S9S_MB_2U_LIB.S9S_MB_2U(SCH_1):M_A_CPU0_SA_CB(0)
 196 M_A_CPU0_SA_CB<2>  CB2_A @S9S_MB_2U_LIB.S9S_MB_2U(SCH_1):M_A_CPU0_SA_CB(2)
 198 M_A_CPU0_SA_CB<3>  CB3_A @S9S_MB_2U_LIB.S9S_MB_2U(SCH_1):M_A_CPU0_SA_CB(3)
  60 M_A_CPU0_SA_CB<5>  CB5_A @S9S_MB_2U_LIB.S9S_MB_2U(SCH_1):M_A_CPU0_SA_CB(5)
 203 M_A_CPU0_SA_CB<6>  CB6_A @S9S_MB_2U_LIB.S9S_MB_2U(SCH_1):M_A_CPU0_SA_CB(6)
  82 M_A_CPU0_SB_CA<6>  CA6_B @S9S_MB_2U_LIB.S9S_MB_2U(SCH_1):M_A_CPU0_SB_CA(6)
  72 M_A_CPU0_SA_CA<6>  CA6_A @S9S_MB_2U_LIB.S9S_MB_2U(SCH_1):M_A_CPU0_SA_CA(6)
 225 M_A_CPU0_SB_CA<5>  CA5_B @S9S_MB_2U_LIB.S9S_MB_2U(SCH_1):M_A_CPU0_SB_CA(5)
 215 M_A_CPU0_SA_CA<5>  CA5_A @S9S_MB_2U_LIB.S9S_MB_2U(SCH_1):M_A_CPU0_SA_CA(5)
  80 M_A_CPU0_SB_CA<4>  CA4_B @S9S_MB_2U_LIB.S9S_MB_2U(SCH_1):M_A_CPU0_SB_CA(4)
  70 M_A_CPU0_SA_CA<4>  CA4_A @S9S_MB_2U_LIB.S9S_MB_2U(SCH_1):M_A_CPU0_SA_CA(4)
 223 M_A_CPU0_SB_CA<3>  CA3_B @S9S_MB_2U_LIB.S9S_MB_2U(SCH_1):M_A_CPU0_SB_CA(3)
 213 M_A_CPU0_SA_CA<3>  CA3_A @S9S_MB_2U_LIB.S9S_MB_2U(SCH_1):M_A_CPU0_SA_CA(3)
  78 M_A_CPU0_SB_CA<2>  CA2_B @S9S_MB_2U_LIB.S9S_MB_2U(SCH_1):M_A_CPU0_SB_CA(2)
  68 M_A_CPU0_SA_CA<2>  CA2_A @S9S_MB_2U_LIB.S9S_MB_2U(SCH_1):M_A_CPU0_SA_CA(2)
 221 M_A_CPU0_SB_CA<1>  CA1_B @S9S_MB_2U_LIB.S9S_MB_2U(SCH_1):M_A_CPU0_SB_CA(1)
 211 M_A_CPU0_SA_CA<1>  CA1_A @S9S_MB_2U_LIB.S9S_MB_2U(SCH_1):M_A_CPU0_SA_CA(1)
  76 M_A_CPU0_SB_CA<0>  CA0_B @S9S_MB_2U_LIB.S9S_MB_2U(SCH_1):M_A_CPU0_SB_CA(0)
  66 M_A_CPU0_SA_CA<0>  CA0_A @S9S_MB_2U_LIB.S9S_MB_2U(SCH_1):M_A_CPU0_SA_CA(0)
  62 M_A_CPU0_ALERT_N ALERT_N @S9S_MB_2U_LIB.S9S_MB_2U(SCH_1):M_A_CPU0_ALERT_N
 236 M_A_CPU0_SB_CB<7>  CB7_B @S9S_MB_2U_LIB.S9S_MB_2U(SCH_1):M_A_CPU0_SB_CB(7)
  53 M_A_CPU0_SA_CB<1>  CB1_A @S9S_MB_2U_LIB.S9S_MB_2U(SCH_1):M_A_CPU0_SA_CB(1)
  58 M_A_CPU0_SA_CB<4>  CB4_A @S9S_MB_2U_LIB.S9S_MB_2U(SCH_1):M_A_CPU0_SA_CB(4)
 205 M_A_CPU0_SA_CB<7>  CB7_A @S9S_MB_2U_LIB.S9S_MB_2U(SCH_1):M_A_CPU0_SA_CB(7)
 194 M_A_CPU0_SA_DQ<31> DQ31_A @S9S_MB_2U_LIB.S9S_MB_2U(SCH_1):M_A_CPU0_SA_DQ(31)

SCONN288_ADR50017P087CC-SCONN2A  I179  J2
   6    GND   VSS0 @S9S_MB_2U_LIB.S9S_MB_2U(SCH_1):GND
   8    GND   VSS1 @S9S_MB_2U_LIB.S9S_MB_2U(SCH_1):GND
  10    GND   VSS2 @S9S_MB_2U_LIB.S9S_MB_2U(SCH_1):GND
  13    GND   VSS3 @S9S_MB_2U_LIB.S9S_MB_2U(SCH_1):GND
  15    GND   VSS4 @S9S_MB_2U_LIB.S9S_MB_2U(SCH_1):GND
  17    GND   VSS5 @S9S_MB_2U_LIB.S9S_MB_2U(SCH_1):GND
  19    GND   VSS6 @S9S_MB_2U_LIB.S9S_MB_2U(SCH_1):GND
  21    GND   VSS7 @S9S_MB_2U_LIB.S9S_MB_2U(SCH_1):GND
  24    GND   VSS8 @S9S_MB_2U_LIB.S9S_MB_2U(SCH_1):GND
  26    GND   VSS9 @S9S_MB_2U_LIB.S9S_MB_2U(SCH_1):GND
  28    GND  VSS10 @S9S_MB_2U_LIB.S9S_MB_2U(SCH_1):GND
  30    GND  VSS11 @S9S_MB_2U_LIB.S9S_MB_2U(SCH_1):GND
  32    GND  VSS12 @S9S_MB_2U_LIB.S9S_MB_2U(SCH_1):GND
  35    GND  VSS13 @S9S_MB_2U_LIB.S9S_MB_2U(SCH_1):GND
  37    GND  VSS14 @S9S_MB_2U_LIB.S9S_MB_2U(SCH_1):GND
  39    GND  VSS15 @S9S_MB_2U_LIB.S9S_MB_2U(SCH_1):GND
  41    GND  VSS16 @S9S_MB_2U_LIB.S9S_MB_2U(SCH_1):GND
  43    GND  VSS17 @S9S_MB_2U_LIB.S9S_MB_2U(SCH_1):GND
  46    GND  VSS18 @S9S_MB_2U_LIB.S9S_MB_2U(SCH_1):GND
  48    GND  VSS19 @S9S_MB_2U_LIB.S9S_MB_2U(SCH_1):GND
  50    GND  VSS20 @S9S_MB_2U_LIB.S9S_MB_2U(SCH_1):GND
  52    GND  VSS21 @S9S_MB_2U_LIB.S9S_MB_2U(SCH_1):GND
  54    GND  VSS22 @S9S_MB_2U_LIB.S9S_MB_2U(SCH_1):GND
  57    GND  VSS23 @S9S_MB_2U_LIB.S9S_MB_2U(SCH_1):GND
  59    GND  VSS24 @S9S_MB_2U_LIB.S9S_MB_2U(SCH_1):GND
  61    GND  VSS25 @S9S_MB_2U_LIB.S9S_MB_2U(SCH_1):GND
  63    GND  VSS26 @S9S_MB_2U_LIB.S9S_MB_2U(SCH_1):GND
  65    GND  VSS27 @S9S_MB_2U_LIB.S9S_MB_2U(SCH_1):GND
  67    GND  VSS28 @S9S_MB_2U_LIB.S9S_MB_2U(SCH_1):GND
  69    GND  VSS29 @S9S_MB_2U_LIB.S9S_MB_2U(SCH_1):GND
  71    GND  VSS30 @S9S_MB_2U_LIB.S9S_MB_2U(SCH_1):GND
  73    GND  VSS31 @S9S_MB_2U_LIB.S9S_MB_2U(SCH_1):GND
  75    GND  VSS32 @S9S_MB_2U_LIB.S9S_MB_2U(SCH_1):GND
  77    GND  VSS33 @S9S_MB_2U_LIB.S9S_MB_2U(SCH_1):GND
  79    GND  VSS34 @S9S_MB_2U_LIB.S9S_MB_2U(SCH_1):GND
  81    GND  VSS35 @S9S_MB_2U_LIB.S9S_MB_2U(SCH_1):GND
  83    GND  VSS36 @S9S_MB_2U_LIB.S9S_MB_2U(SCH_1):GND
  85    GND  VSS37 @S9S_MB_2U_LIB.S9S_MB_2U(SCH_1):GND
  88    GND  VSS38 @S9S_MB_2U_LIB.S9S_MB_2U(SCH_1):GND
  90    GND  VSS39 @S9S_MB_2U_LIB.S9S_MB_2U(SCH_1):GND
  92    GND  VSS40 @S9S_MB_2U_LIB.S9S_MB_2U(SCH_1):GND
  95    GND  VSS41 @S9S_MB_2U_LIB.S9S_MB_2U(SCH_1):GND
  97    GND  VSS42 @S9S_MB_2U_LIB.S9S_MB_2U(SCH_1):GND
  99    GND  VSS43 @S9S_MB_2U_LIB.S9S_MB_2U(SCH_1):GND
 101    GND  VSS44 @S9S_MB_2U_LIB.S9S_MB_2U(SCH_1):GND
 103    GND  VSS45 @S9S_MB_2U_LIB.S9S_MB_2U(SCH_1):GND
 106    GND  VSS46 @S9S_MB_2U_LIB.S9S_MB_2U(SCH_1):GND
 108    GND  VSS47 @S9S_MB_2U_LIB.S9S_MB_2U(SCH_1):GND
 110    GND  VSS48 @S9S_MB_2U_LIB.S9S_MB_2U(SCH_1):GND
 112    GND  VSS49 @S9S_MB_2U_LIB.S9S_MB_2U(SCH_1):GND
 114    GND  VSS50 @S9S_MB_2U_LIB.S9S_MB_2U(SCH_1):GND
 117    GND  VSS51 @S9S_MB_2U_LIB.S9S_MB_2U(SCH_1):GND
 119    GND  VSS52 @S9S_MB_2U_LIB.S9S_MB_2U(SCH_1):GND
 121    GND  VSS53 @S9S_MB_2U_LIB.S9S_MB_2U(SCH_1):GND
 123    GND  VSS54 @S9S_MB_2U_LIB.S9S_MB_2U(SCH_1):GND
 125    GND  VSS55 @S9S_MB_2U_LIB.S9S_MB_2U(SCH_1):GND
 128    GND  VSS56 @S9S_MB_2U_LIB.S9S_MB_2U(SCH_1):GND
 130    GND  VSS57 @S9S_MB_2U_LIB.S9S_MB_2U(SCH_1):GND
 134    GND  VSS59 @S9S_MB_2U_LIB.S9S_MB_2U(SCH_1):GND
 143    GND  VSS63 @S9S_MB_2U_LIB.S9S_MB_2U(SCH_1):GND
 151    GND  VSS64 @S9S_MB_2U_LIB.S9S_MB_2U(SCH_1):GND
 153    GND  VSS65 @S9S_MB_2U_LIB.S9S_MB_2U(SCH_1):GND
 155    GND  VSS66 @S9S_MB_2U_LIB.S9S_MB_2U(SCH_1):GND
 158    GND  VSS67 @S9S_MB_2U_LIB.S9S_MB_2U(SCH_1):GND
 160    GND  VSS68 @S9S_MB_2U_LIB.S9S_MB_2U(SCH_1):GND
 162    GND  VSS69 @S9S_MB_2U_LIB.S9S_MB_2U(SCH_1):GND
 164    GND  VSS70 @S9S_MB_2U_LIB.S9S_MB_2U(SCH_1):GND
 166    GND  VSS71 @S9S_MB_2U_LIB.S9S_MB_2U(SCH_1):GND
 169    GND  VSS72 @S9S_MB_2U_LIB.S9S_MB_2U(SCH_1):GND
 171    GND  VSS73 @S9S_MB_2U_LIB.S9S_MB_2U(SCH_1):GND
 173    GND  VSS74 @S9S_MB_2U_LIB.S9S_MB_2U(SCH_1):GND
 175    GND  VSS75 @S9S_MB_2U_LIB.S9S_MB_2U(SCH_1):GND
 177    GND  VSS76 @S9S_MB_2U_LIB.S9S_MB_2U(SCH_1):GND
 180    GND  VSS77 @S9S_MB_2U_LIB.S9S_MB_2U(SCH_1):GND
 182    GND  VSS78 @S9S_MB_2U_LIB.S9S_MB_2U(SCH_1):GND
 184    GND  VSS79 @S9S_MB_2U_LIB.S9S_MB_2U(SCH_1):GND
 186    GND  VSS80 @S9S_MB_2U_LIB.S9S_MB_2U(SCH_1):GND
 188    GND  VSS81 @S9S_MB_2U_LIB.S9S_MB_2U(SCH_1):GND
 191    GND  VSS82 @S9S_MB_2U_LIB.S9S_MB_2U(SCH_1):GND
 193    GND  VSS83 @S9S_MB_2U_LIB.S9S_MB_2U(SCH_1):GND
 195    GND  VSS84 @S9S_MB_2U_LIB.S9S_MB_2U(SCH_1):GND
 197    GND  VSS85 @S9S_MB_2U_LIB.S9S_MB_2U(SCH_1):GND
 199    GND  VSS86 @S9S_MB_2U_LIB.S9S_MB_2U(SCH_1):GND
 202    GND  VSS87 @S9S_MB_2U_LIB.S9S_MB_2U(SCH_1):GND
 204    GND  VSS88 @S9S_MB_2U_LIB.S9S_MB_2U(SCH_1):GND
 206    GND  VSS89 @S9S_MB_2U_LIB.S9S_MB_2U(SCH_1):GND
 208    GND  VSS90 @S9S_MB_2U_LIB.S9S_MB_2U(SCH_1):GND
 210    GND  VSS91 @S9S_MB_2U_LIB.S9S_MB_2U(SCH_1):GND
 212    GND  VSS92 @S9S_MB_2U_LIB.S9S_MB_2U(SCH_1):GND
 214    GND  VSS93 @S9S_MB_2U_LIB.S9S_MB_2U(SCH_1):GND
 216    GND  VSS94 @S9S_MB_2U_LIB.S9S_MB_2U(SCH_1):GND
 219    GND  VSS95 @S9S_MB_2U_LIB.S9S_MB_2U(SCH_1):GND
 222    GND  VSS96 @S9S_MB_2U_LIB.S9S_MB_2U(SCH_1):GND
 224    GND  VSS97 @S9S_MB_2U_LIB.S9S_MB_2U(SCH_1):GND
 226    GND  VSS98 @S9S_MB_2U_LIB.S9S_MB_2U(SCH_1):GND
 228    GND  VSS99 @S9S_MB_2U_LIB.S9S_MB_2U(SCH_1):GND
 233    GND VSS101 @S9S_MB_2U_LIB.S9S_MB_2U(SCH_1):GND
 237    GND VSS103 @S9S_MB_2U_LIB.S9S_MB_2U(SCH_1):GND
 242    GND VSS105 @S9S_MB_2U_LIB.S9S_MB_2U(SCH_1):GND
 244    GND VSS106 @S9S_MB_2U_LIB.S9S_MB_2U(SCH_1):GND
 246    GND VSS107 @S9S_MB_2U_LIB.S9S_MB_2U(SCH_1):GND
 248    GND VSS108 @S9S_MB_2U_LIB.S9S_MB_2U(SCH_1):GND
 251    GND VSS109 @S9S_MB_2U_LIB.S9S_MB_2U(SCH_1):GND
 253    GND VSS110 @S9S_MB_2U_LIB.S9S_MB_2U(SCH_1):GND
 255    GND VSS111 @S9S_MB_2U_LIB.S9S_MB_2U(SCH_1):GND
 257    GND VSS112 @S9S_MB_2U_LIB.S9S_MB_2U(SCH_1):GND
 259    GND VSS113 @S9S_MB_2U_LIB.S9S_MB_2U(SCH_1):GND
 262    GND VSS114 @S9S_MB_2U_LIB.S9S_MB_2U(SCH_1):GND
 264    GND VSS115 @S9S_MB_2U_LIB.S9S_MB_2U(SCH_1):GND
 266    GND VSS116 @S9S_MB_2U_LIB.S9S_MB_2U(SCH_1):GND
 268    GND VSS117 @S9S_MB_2U_LIB.S9S_MB_2U(SCH_1):GND
 270    GND VSS118 @S9S_MB_2U_LIB.S9S_MB_2U(SCH_1):GND
 273    GND VSS119 @S9S_MB_2U_LIB.S9S_MB_2U(SCH_1):GND
 275    GND VSS120 @S9S_MB_2U_LIB.S9S_MB_2U(SCH_1):GND
 277    GND VSS121 @S9S_MB_2U_LIB.S9S_MB_2U(SCH_1):GND
 279    GND VSS122 @S9S_MB_2U_LIB.S9S_MB_2U(SCH_1):GND
 281    GND VSS123 @S9S_MB_2U_LIB.S9S_MB_2U(SCH_1):GND
 284    GND VSS124 @S9S_MB_2U_LIB.S9S_MB_2U(SCH_1):GND
 286    GND VSS125 @S9S_MB_2U_LIB.S9S_MB_2U(SCH_1):GND
 288    GND VSS126 @S9S_MB_2U_LIB.S9S_MB_2U(SCH_1):GND
   1 P12V_S3_AUX_CPU0_NVDIMM VIN_BULK0 @S9S_MB_2U_LIB.S9S_MB_2U(SCH_1):P12V_S3_AUX_CPU0_NVDIMM
 145 P12V_S3_AUX_CPU0_NVDIMM VIN_BULK1 @S9S_MB_2U_LIB.S9S_MB_2U(SCH_1):P12V_S3_AUX_CPU0_NVDIMM
 146 P12V_S3_AUX_CPU0_NVDIMM VIN_BULK2 @S9S_MB_2U_LIB.S9S_MB_2U(SCH_1):P12V_S3_AUX_CPU0_NVDIMM
 230    GND VSS100 @S9S_MB_2U_LIB.S9S_MB_2U(SCH_1):GND
 235    GND VSS102 @S9S_MB_2U_LIB.S9S_MB_2U(SCH_1):GND
 240    GND VSS104 @S9S_MB_2U_LIB.S9S_MB_2U(SCH_1):GND
 132    GND  VSS58 @S9S_MB_2U_LIB.S9S_MB_2U(SCH_1):GND
 136    GND  VSS60 @S9S_MB_2U_LIB.S9S_MB_2U(SCH_1):GND
 139    GND  VSS61 @S9S_MB_2U_LIB.S9S_MB_2U(SCH_1):GND
 141    GND  VSS62 @S9S_MB_2U_LIB.S9S_MB_2U(SCH_1):GND
  G1    GND     G1 @S9S_MB_2U_LIB.S9S_MB_2U(SCH_1):GND
  G2    GND     G2 @S9S_MB_2U_LIB.S9S_MB_2U(SCH_1):GND
  G3    GND     G3 @S9S_MB_2U_LIB.S9S_MB_2U(SCH_1):GND

SCONN288_ADR50017P087CC-SCONN2A  I181  J2
  93 M_A_CPU0_SB_DQS_DP<9> DQS9_B_T||TDQS9_B_T||DBI4_B_N @S9S_MB_2U_LIB.S9S_MB_2U(SCH_1):M_A_CPU0_SB_DQS_DP(9)
  94 M_A_CPU0_SB_DQS_DN<9> DQS9_B_C||TDQS9_B_C @S9S_MB_2U_LIB.S9S_MB_2U(SCH_1):M_A_CPU0_SB_DQS_DN(9)
 201 M_A_CPU0_SA_DQS_DP<9> DQS9_A_T||TDQS9_A_T @S9S_MB_2U_LIB.S9S_MB_2U(SCH_1):M_A_CPU0_SA_DQS_DP(9)
 200 M_A_CPU0_SA_DQS_DN<9> DQS9_A_C||TDQS9_A_C @S9S_MB_2U_LIB.S9S_MB_2U(SCH_1):M_A_CPU0_SA_DQS_DN(9)
 190 M_A_CPU0_SA_DQS_DP<8> DQS8_A_T||TDQS8_A_T @S9S_MB_2U_LIB.S9S_MB_2U(SCH_1):M_A_CPU0_SA_DQS_DP(8)
 189 M_A_CPU0_SA_DQS_DN<8> DQS8_A_C||TDQS8_A_C @S9S_MB_2U_LIB.S9S_MB_2U(SCH_1):M_A_CPU0_SA_DQS_DN(8)
 271 M_A_CPU0_SB_DQS_DN<7> DQS7_B_C||TDQS7_B_C @S9S_MB_2U_LIB.S9S_MB_2U(SCH_1):M_A_CPU0_SB_DQS_DN(7)
 179 M_A_CPU0_SA_DQS_DP<7> DQS7_A_T||TDQS7_A_T @S9S_MB_2U_LIB.S9S_MB_2U(SCH_1):M_A_CPU0_SA_DQS_DP(7)
 261 M_A_CPU0_SB_DQS_DP<6> DQS6_B_T||TDQS6_B_T @S9S_MB_2U_LIB.S9S_MB_2U(SCH_1):M_A_CPU0_SB_DQS_DP(6)
 260 M_A_CPU0_SB_DQS_DN<6> DQS6_B_C||TDQS6_B_C @S9S_MB_2U_LIB.S9S_MB_2U(SCH_1):M_A_CPU0_SB_DQS_DN(6)
 167 M_A_CPU0_SA_DQS_DN<6> DQS6_A_C||TDQS6_A_C||DQS6_A_T||TDQS6_A_T @S9S_MB_2U_LIB.S9S_MB_2U(SCH_1):M_A_CPU0_SA_DQS_DN(6)
 250 M_A_CPU0_SB_DQS_DP<5> DQS5_B_T||TDQS5_B_T @S9S_MB_2U_LIB.S9S_MB_2U(SCH_1):M_A_CPU0_SB_DQS_DP(5)
 249 M_A_CPU0_SB_DQS_DN<5> DQS5_B_C||TDQS5_B_C @S9S_MB_2U_LIB.S9S_MB_2U(SCH_1):M_A_CPU0_SB_DQS_DN(5)
 157 M_A_CPU0_SA_DQS_DP<5> DQS5_A_T||TDQS5_A_T @S9S_MB_2U_LIB.S9S_MB_2U(SCH_1):M_A_CPU0_SA_DQS_DP(5)
 156 M_A_CPU0_SA_DQS_DN<5> DQS5_A_C||TDQS5_A_C||DQS5_A_T||TDQS5_A_T @S9S_MB_2U_LIB.S9S_MB_2U(SCH_1):M_A_CPU0_SA_DQS_DN(5)
 239 M_A_CPU0_SB_DQS_DP<4> DQS4_B_T @S9S_MB_2U_LIB.S9S_MB_2U(SCH_1):M_A_CPU0_SB_DQS_DP(4)
 238 M_A_CPU0_SB_DQS_DN<4> DQS4_B_C @S9S_MB_2U_LIB.S9S_MB_2U(SCH_1):M_A_CPU0_SB_DQS_DN(4)
  55 M_A_CPU0_SA_DQS_DP<4> DQS4_A_T @S9S_MB_2U_LIB.S9S_MB_2U(SCH_1):M_A_CPU0_SA_DQS_DP(4)
  56 M_A_CPU0_SA_DQS_DN<4> DQS4_A_C @S9S_MB_2U_LIB.S9S_MB_2U(SCH_1):M_A_CPU0_SA_DQS_DN(4)
 137 M_A_CPU0_SB_DQS_DP<3> DQS3_B_T @S9S_MB_2U_LIB.S9S_MB_2U(SCH_1):M_A_CPU0_SB_DQS_DP(3)
 138 M_A_CPU0_SB_DQS_DN<3> DQS3_B_C @S9S_MB_2U_LIB.S9S_MB_2U(SCH_1):M_A_CPU0_SB_DQS_DN(3)
  44 M_A_CPU0_SA_DQS_DP<3> DQS3_A_T @S9S_MB_2U_LIB.S9S_MB_2U(SCH_1):M_A_CPU0_SA_DQS_DP(3)
  45 M_A_CPU0_SA_DQS_DN<3> DQS3_A_C @S9S_MB_2U_LIB.S9S_MB_2U(SCH_1):M_A_CPU0_SA_DQS_DN(3)
 126 M_A_CPU0_SB_DQS_DP<2> DQS2_B_T @S9S_MB_2U_LIB.S9S_MB_2U(SCH_1):M_A_CPU0_SB_DQS_DP(2)
 127 M_A_CPU0_SB_DQS_DN<2> DQS2_B_C @S9S_MB_2U_LIB.S9S_MB_2U(SCH_1):M_A_CPU0_SB_DQS_DN(2)
  33 M_A_CPU0_SA_DQS_DP<2> DQS2_A_T @S9S_MB_2U_LIB.S9S_MB_2U(SCH_1):M_A_CPU0_SA_DQS_DP(2)
  34 M_A_CPU0_SA_DQS_DN<2> DQS2_A_C @S9S_MB_2U_LIB.S9S_MB_2U(SCH_1):M_A_CPU0_SA_DQS_DN(2)
 115 M_A_CPU0_SB_DQS_DP<1> DQS1_B_T @S9S_MB_2U_LIB.S9S_MB_2U(SCH_1):M_A_CPU0_SB_DQS_DP(1)
 116 M_A_CPU0_SB_DQS_DN<1> DQS1_B_C @S9S_MB_2U_LIB.S9S_MB_2U(SCH_1):M_A_CPU0_SB_DQS_DN(1)
  22 M_A_CPU0_SA_DQS_DP<1> DQS1_A_T @S9S_MB_2U_LIB.S9S_MB_2U(SCH_1):M_A_CPU0_SA_DQS_DP(1)
  23 M_A_CPU0_SA_DQS_DN<1> DQS1_A_C @S9S_MB_2U_LIB.S9S_MB_2U(SCH_1):M_A_CPU0_SA_DQS_DN(1)
 104 M_A_CPU0_SB_DQS_DP<0> DQS0_B_T @S9S_MB_2U_LIB.S9S_MB_2U(SCH_1):M_A_CPU0_SB_DQS_DP(0)
 105 M_A_CPU0_SB_DQS_DN<0> DQS0_B_C @S9S_MB_2U_LIB.S9S_MB_2U(SCH_1):M_A_CPU0_SB_DQS_DN(0)
  11 M_A_CPU0_SA_DQS_DP<0> DQS0_A_T @S9S_MB_2U_LIB.S9S_MB_2U(SCH_1):M_A_CPU0_SA_DQS_DP(0)
  12 M_A_CPU0_SA_DQS_DN<0> DQS0_A_C @S9S_MB_2U_LIB.S9S_MB_2U(SCH_1):M_A_CPU0_SA_DQS_DN(0)
 272 M_A_CPU0_SB_DQS_DP<7> DQS7_B_T||TDQS7_B_T @S9S_MB_2U_LIB.S9S_MB_2U(SCH_1):M_A_CPU0_SB_DQS_DP(7)
 282 M_A_CPU0_SB_DQS_DN<8> DQS8_B_C||TDQS8_B_C @S9S_MB_2U_LIB.S9S_MB_2U(SCH_1):M_A_CPU0_SB_DQS_DN(8)
 283 M_A_CPU0_SB_DQS_DP<8> DQS8_B_T||TDQS8_B_T @S9S_MB_2U_LIB.S9S_MB_2U(SCH_1):M_A_CPU0_SB_DQS_DP(8)
 168 M_A_CPU0_SA_DQS_DP<6> DQS6_A_T||TDQS6_A_T @S9S_MB_2U_LIB.S9S_MB_2U(SCH_1):M_A_CPU0_SA_DQS_DP(6)
 178 M_A_CPU0_SA_DQS_DN<7> DQS7_A_C||TDQS7_A_C @S9S_MB_2U_LIB.S9S_MB_2U(SCH_1):M_A_CPU0_SA_DQS_DN(7)

Q_RES_0402LF-49.9,1%,1/16W,CHIA  I182  R3876
   1 I3C_SPD_DDRABCD_CPU0_LVC1_SCL_1      A @S9S_MB_2U_LIB.S9S_MB_2U(SCH_1):I3C_SPD_DDRABCD_CPU0_LVC1_SCL_R2
   2 I3C_SPD_DDRABCD_CPU0_LVC1_SCL      B @S9S_MB_2U_LIB.S9S_MB_2U(SCH_1):I3C_SPD_DDRABCD_CPU0_LVC1_SCL


DRAWING: @S9S_MB_2U_LIB.S9S_MB_2U(SCH_1):PAGE84 

Q_RES_0402LF-23.2K,1%,1/16W,CHA  I10  R28
   1 PD_CHB_CPU0_DIMM1_SAA      A @S9S_MB_2U_LIB.S9S_MB_2U(SCH_1):PD_CHB_CPU0_DIMM1_SAA
   2    GND      B @S9S_MB_2U_LIB.S9S_MB_2U(SCH_1):GND

Q_CAP_C0402-2.2UF,6.3V,20%,X6SA  I121  C8
   1 P3V3_AUX      A @S9S_MB_2U_LIB.S9S_MB_2U(SCH_1):P3V3_AUX
   2    GND      B @S9S_MB_2U_LIB.S9S_MB_2U(SCH_1):GND

Q_CAP_C0805-10UF,16V,10%,X6S,CA  I122  C9
   1 P12V_S3_AUX_CPU0_NVDIMM      A @S9S_MB_2U_LIB.S9S_MB_2U(SCH_1):P12V_S3_AUX_CPU0_NVDIMM
   2    GND      B @S9S_MB_2U_LIB.S9S_MB_2U(SCH_1):GND

Q_CAP_C0805-10UF,16V,10%,X6S,CA  I144  C10
   1 P12V_S3_AUX_CPU0_NVDIMM      A @S9S_MB_2U_LIB.S9S_MB_2U(SCH_1):P12V_S3_AUX_CPU0_NVDIMM
   2    GND      B @S9S_MB_2U_LIB.S9S_MB_2U(SCH_1):GND

SCONN288_ADR50017P130CC-SCONN2A  I178  J3
   6    GND   VSS0 @S9S_MB_2U_LIB.S9S_MB_2U(SCH_1):GND
   8    GND   VSS1 @S9S_MB_2U_LIB.S9S_MB_2U(SCH_1):GND
  10    GND   VSS2 @S9S_MB_2U_LIB.S9S_MB_2U(SCH_1):GND
  13    GND   VSS3 @S9S_MB_2U_LIB.S9S_MB_2U(SCH_1):GND
  15    GND   VSS4 @S9S_MB_2U_LIB.S9S_MB_2U(SCH_1):GND
  17    GND   VSS5 @S9S_MB_2U_LIB.S9S_MB_2U(SCH_1):GND
  19    GND   VSS6 @S9S_MB_2U_LIB.S9S_MB_2U(SCH_1):GND
  21    GND   VSS7 @S9S_MB_2U_LIB.S9S_MB_2U(SCH_1):GND
  24    GND   VSS8 @S9S_MB_2U_LIB.S9S_MB_2U(SCH_1):GND
  26    GND   VSS9 @S9S_MB_2U_LIB.S9S_MB_2U(SCH_1):GND
  28    GND  VSS10 @S9S_MB_2U_LIB.S9S_MB_2U(SCH_1):GND
  30    GND  VSS11 @S9S_MB_2U_LIB.S9S_MB_2U(SCH_1):GND
  32    GND  VSS12 @S9S_MB_2U_LIB.S9S_MB_2U(SCH_1):GND
  35    GND  VSS13 @S9S_MB_2U_LIB.S9S_MB_2U(SCH_1):GND
  37    GND  VSS14 @S9S_MB_2U_LIB.S9S_MB_2U(SCH_1):GND
  39    GND  VSS15 @S9S_MB_2U_LIB.S9S_MB_2U(SCH_1):GND
  41    GND  VSS16 @S9S_MB_2U_LIB.S9S_MB_2U(SCH_1):GND
  43    GND  VSS17 @S9S_MB_2U_LIB.S9S_MB_2U(SCH_1):GND
  46    GND  VSS18 @S9S_MB_2U_LIB.S9S_MB_2U(SCH_1):GND
  48    GND  VSS19 @S9S_MB_2U_LIB.S9S_MB_2U(SCH_1):GND
  50    GND  VSS20 @S9S_MB_2U_LIB.S9S_MB_2U(SCH_1):GND
  52    GND  VSS21 @S9S_MB_2U_LIB.S9S_MB_2U(SCH_1):GND
  54    GND  VSS22 @S9S_MB_2U_LIB.S9S_MB_2U(SCH_1):GND
  57    GND  VSS23 @S9S_MB_2U_LIB.S9S_MB_2U(SCH_1):GND
  59    GND  VSS24 @S9S_MB_2U_LIB.S9S_MB_2U(SCH_1):GND
  61    GND  VSS25 @S9S_MB_2U_LIB.S9S_MB_2U(SCH_1):GND
  63    GND  VSS26 @S9S_MB_2U_LIB.S9S_MB_2U(SCH_1):GND
  65    GND  VSS27 @S9S_MB_2U_LIB.S9S_MB_2U(SCH_1):GND
  67    GND  VSS28 @S9S_MB_2U_LIB.S9S_MB_2U(SCH_1):GND
  69    GND  VSS29 @S9S_MB_2U_LIB.S9S_MB_2U(SCH_1):GND
  71    GND  VSS30 @S9S_MB_2U_LIB.S9S_MB_2U(SCH_1):GND
  73    GND  VSS31 @S9S_MB_2U_LIB.S9S_MB_2U(SCH_1):GND
  75    GND  VSS32 @S9S_MB_2U_LIB.S9S_MB_2U(SCH_1):GND
  77    GND  VSS33 @S9S_MB_2U_LIB.S9S_MB_2U(SCH_1):GND
  79    GND  VSS34 @S9S_MB_2U_LIB.S9S_MB_2U(SCH_1):GND
  81    GND  VSS35 @S9S_MB_2U_LIB.S9S_MB_2U(SCH_1):GND
  83    GND  VSS36 @S9S_MB_2U_LIB.S9S_MB_2U(SCH_1):GND
  85    GND  VSS37 @S9S_MB_2U_LIB.S9S_MB_2U(SCH_1):GND
  88    GND  VSS38 @S9S_MB_2U_LIB.S9S_MB_2U(SCH_1):GND
  90    GND  VSS39 @S9S_MB_2U_LIB.S9S_MB_2U(SCH_1):GND
  92    GND  VSS40 @S9S_MB_2U_LIB.S9S_MB_2U(SCH_1):GND
  95    GND  VSS41 @S9S_MB_2U_LIB.S9S_MB_2U(SCH_1):GND
  97    GND  VSS42 @S9S_MB_2U_LIB.S9S_MB_2U(SCH_1):GND
  99    GND  VSS43 @S9S_MB_2U_LIB.S9S_MB_2U(SCH_1):GND
 101    GND  VSS44 @S9S_MB_2U_LIB.S9S_MB_2U(SCH_1):GND
 103    GND  VSS45 @S9S_MB_2U_LIB.S9S_MB_2U(SCH_1):GND
 106    GND  VSS46 @S9S_MB_2U_LIB.S9S_MB_2U(SCH_1):GND
 108    GND  VSS47 @S9S_MB_2U_LIB.S9S_MB_2U(SCH_1):GND
 110    GND  VSS48 @S9S_MB_2U_LIB.S9S_MB_2U(SCH_1):GND
 112    GND  VSS49 @S9S_MB_2U_LIB.S9S_MB_2U(SCH_1):GND
 114    GND  VSS50 @S9S_MB_2U_LIB.S9S_MB_2U(SCH_1):GND
 117    GND  VSS51 @S9S_MB_2U_LIB.S9S_MB_2U(SCH_1):GND
 119    GND  VSS52 @S9S_MB_2U_LIB.S9S_MB_2U(SCH_1):GND
 121    GND  VSS53 @S9S_MB_2U_LIB.S9S_MB_2U(SCH_1):GND
 123    GND  VSS54 @S9S_MB_2U_LIB.S9S_MB_2U(SCH_1):GND
 125    GND  VSS55 @S9S_MB_2U_LIB.S9S_MB_2U(SCH_1):GND
 128    GND  VSS56 @S9S_MB_2U_LIB.S9S_MB_2U(SCH_1):GND
 130    GND  VSS57 @S9S_MB_2U_LIB.S9S_MB_2U(SCH_1):GND
 134    GND  VSS59 @S9S_MB_2U_LIB.S9S_MB_2U(SCH_1):GND
 143    GND  VSS63 @S9S_MB_2U_LIB.S9S_MB_2U(SCH_1):GND
 151    GND  VSS64 @S9S_MB_2U_LIB.S9S_MB_2U(SCH_1):GND
 153    GND  VSS65 @S9S_MB_2U_LIB.S9S_MB_2U(SCH_1):GND
 155    GND  VSS66 @S9S_MB_2U_LIB.S9S_MB_2U(SCH_1):GND
 158    GND  VSS67 @S9S_MB_2U_LIB.S9S_MB_2U(SCH_1):GND
 160    GND  VSS68 @S9S_MB_2U_LIB.S9S_MB_2U(SCH_1):GND
 162    GND  VSS69 @S9S_MB_2U_LIB.S9S_MB_2U(SCH_1):GND
 164    GND  VSS70 @S9S_MB_2U_LIB.S9S_MB_2U(SCH_1):GND
 166    GND  VSS71 @S9S_MB_2U_LIB.S9S_MB_2U(SCH_1):GND
 169    GND  VSS72 @S9S_MB_2U_LIB.S9S_MB_2U(SCH_1):GND
 171    GND  VSS73 @S9S_MB_2U_LIB.S9S_MB_2U(SCH_1):GND
 173    GND  VSS74 @S9S_MB_2U_LIB.S9S_MB_2U(SCH_1):GND
 175    GND  VSS75 @S9S_MB_2U_LIB.S9S_MB_2U(SCH_1):GND
 177    GND  VSS76 @S9S_MB_2U_LIB.S9S_MB_2U(SCH_1):GND
 180    GND  VSS77 @S9S_MB_2U_LIB.S9S_MB_2U(SCH_1):GND
 182    GND  VSS78 @S9S_MB_2U_LIB.S9S_MB_2U(SCH_1):GND
 184    GND  VSS79 @S9S_MB_2U_LIB.S9S_MB_2U(SCH_1):GND
 186    GND  VSS80 @S9S_MB_2U_LIB.S9S_MB_2U(SCH_1):GND
 188    GND  VSS81 @S9S_MB_2U_LIB.S9S_MB_2U(SCH_1):GND
 191    GND  VSS82 @S9S_MB_2U_LIB.S9S_MB_2U(SCH_1):GND
 193    GND  VSS83 @S9S_MB_2U_LIB.S9S_MB_2U(SCH_1):GND
 195    GND  VSS84 @S9S_MB_2U_LIB.S9S_MB_2U(SCH_1):GND
 197    GND  VSS85 @S9S_MB_2U_LIB.S9S_MB_2U(SCH_1):GND
 199    GND  VSS86 @S9S_MB_2U_LIB.S9S_MB_2U(SCH_1):GND
 202    GND  VSS87 @S9S_MB_2U_LIB.S9S_MB_2U(SCH_1):GND
 204    GND  VSS88 @S9S_MB_2U_LIB.S9S_MB_2U(SCH_1):GND
 206    GND  VSS89 @S9S_MB_2U_LIB.S9S_MB_2U(SCH_1):GND
 208    GND  VSS90 @S9S_MB_2U_LIB.S9S_MB_2U(SCH_1):GND
 210    GND  VSS91 @S9S_MB_2U_LIB.S9S_MB_2U(SCH_1):GND
 212    GND  VSS92 @S9S_MB_2U_LIB.S9S_MB_2U(SCH_1):GND
 214    GND  VSS93 @S9S_MB_2U_LIB.S9S_MB_2U(SCH_1):GND
 216    GND  VSS94 @S9S_MB_2U_LIB.S9S_MB_2U(SCH_1):GND
 219    GND  VSS95 @S9S_MB_2U_LIB.S9S_MB_2U(SCH_1):GND
 222    GND  VSS96 @S9S_MB_2U_LIB.S9S_MB_2U(SCH_1):GND
 224    GND  VSS97 @S9S_MB_2U_LIB.S9S_MB_2U(SCH_1):GND
 226    GND  VSS98 @S9S_MB_2U_LIB.S9S_MB_2U(SCH_1):GND
 228    GND  VSS99 @S9S_MB_2U_LIB.S9S_MB_2U(SCH_1):GND
 233    GND VSS101 @S9S_MB_2U_LIB.S9S_MB_2U(SCH_1):GND
 237    GND VSS103 @S9S_MB_2U_LIB.S9S_MB_2U(SCH_1):GND
 242    GND VSS105 @S9S_MB_2U_LIB.S9S_MB_2U(SCH_1):GND
 244    GND VSS106 @S9S_MB_2U_LIB.S9S_MB_2U(SCH_1):GND
 246    GND VSS107 @S9S_MB_2U_LIB.S9S_MB_2U(SCH_1):GND
 248    GND VSS108 @S9S_MB_2U_LIB.S9S_MB_2U(SCH_1):GND
 251    GND VSS109 @S9S_MB_2U_LIB.S9S_MB_2U(SCH_1):GND
 253    GND VSS110 @S9S_MB_2U_LIB.S9S_MB_2U(SCH_1):GND
 255    GND VSS111 @S9S_MB_2U_LIB.S9S_MB_2U(SCH_1):GND
 257    GND VSS112 @S9S_MB_2U_LIB.S9S_MB_2U(SCH_1):GND
 259    GND VSS113 @S9S_MB_2U_LIB.S9S_MB_2U(SCH_1):GND
 262    GND VSS114 @S9S_MB_2U_LIB.S9S_MB_2U(SCH_1):GND
 264    GND VSS115 @S9S_MB_2U_LIB.S9S_MB_2U(SCH_1):GND
 266    GND VSS116 @S9S_MB_2U_LIB.S9S_MB_2U(SCH_1):GND
 268    GND VSS117 @S9S_MB_2U_LIB.S9S_MB_2U(SCH_1):GND
 270    GND VSS118 @S9S_MB_2U_LIB.S9S_MB_2U(SCH_1):GND
 273    GND VSS119 @S9S_MB_2U_LIB.S9S_MB_2U(SCH_1):GND
 275    GND VSS120 @S9S_MB_2U_LIB.S9S_MB_2U(SCH_1):GND
 277    GND VSS121 @S9S_MB_2U_LIB.S9S_MB_2U(SCH_1):GND
 279    GND VSS122 @S9S_MB_2U_LIB.S9S_MB_2U(SCH_1):GND
 281    GND VSS123 @S9S_MB_2U_LIB.S9S_MB_2U(SCH_1):GND
 284    GND VSS124 @S9S_MB_2U_LIB.S9S_MB_2U(SCH_1):GND
 286    GND VSS125 @S9S_MB_2U_LIB.S9S_MB_2U(SCH_1):GND
 288    GND VSS126 @S9S_MB_2U_LIB.S9S_MB_2U(SCH_1):GND
   1 P12V_S3_AUX_CPU0_NVDIMM VIN_BULK0 @S9S_MB_2U_LIB.S9S_MB_2U(SCH_1):P12V_S3_AUX_CPU0_NVDIMM
 145 P12V_S3_AUX_CPU0_NVDIMM VIN_BULK1 @S9S_MB_2U_LIB.S9S_MB_2U(SCH_1):P12V_S3_AUX_CPU0_NVDIMM
 146 P12V_S3_AUX_CPU0_NVDIMM VIN_BULK2 @S9S_MB_2U_LIB.S9S_MB_2U(SCH_1):P12V_S3_AUX_CPU0_NVDIMM
 230    GND VSS100 @S9S_MB_2U_LIB.S9S_MB_2U(SCH_1):GND
 235    GND VSS102 @S9S_MB_2U_LIB.S9S_MB_2U(SCH_1):GND
 240    GND VSS104 @S9S_MB_2U_LIB.S9S_MB_2U(SCH_1):GND
 132    GND  VSS58 @S9S_MB_2U_LIB.S9S_MB_2U(SCH_1):GND
 136    GND  VSS60 @S9S_MB_2U_LIB.S9S_MB_2U(SCH_1):GND
 139    GND  VSS61 @S9S_MB_2U_LIB.S9S_MB_2U(SCH_1):GND
 141    GND  VSS62 @S9S_MB_2U_LIB.S9S_MB_2U(SCH_1):GND
  G1    GND     G1 @S9S_MB_2U_LIB.S9S_MB_2U(SCH_1):GND
  G2    GND     G2 @S9S_MB_2U_LIB.S9S_MB_2U(SCH_1):GND
  G3    GND     G3 @S9S_MB_2U_LIB.S9S_MB_2U(SCH_1):GND

SCONN288_ADR50017P130CC-SCONN2A  I179  J3
  93 M_B_CPU0_SB_DQS_DP<9> DQS9_B_T||TDQS9_B_T||DBI4_B_N @S9S_MB_2U_LIB.S9S_MB_2U(SCH_1):M_B_CPU0_SB_DQS_DP(9)
  94 M_B_CPU0_SB_DQS_DN<9> DQS9_B_C||TDQS9_B_C @S9S_MB_2U_LIB.S9S_MB_2U(SCH_1):M_B_CPU0_SB_DQS_DN(9)
 201 M_B_CPU0_SA_DQS_DP<9> DQS9_A_T||TDQS9_A_T @S9S_MB_2U_LIB.S9S_MB_2U(SCH_1):M_B_CPU0_SA_DQS_DP(9)
 200 M_B_CPU0_SA_DQS_DN<9> DQS9_A_C||TDQS9_A_C @S9S_MB_2U_LIB.S9S_MB_2U(SCH_1):M_B_CPU0_SA_DQS_DN(9)
 190 M_B_CPU0_SA_DQS_DP<8> DQS8_A_T||TDQS8_A_T @S9S_MB_2U_LIB.S9S_MB_2U(SCH_1):M_B_CPU0_SA_DQS_DP(8)
 189 M_B_CPU0_SA_DQS_DN<8> DQS8_A_C||TDQS8_A_C @S9S_MB_2U_LIB.S9S_MB_2U(SCH_1):M_B_CPU0_SA_DQS_DN(8)
 271 M_B_CPU0_SB_DQS_DN<7> DQS7_B_C||TDQS7_B_C @S9S_MB_2U_LIB.S9S_MB_2U(SCH_1):M_B_CPU0_SB_DQS_DN(7)
 179 M_B_CPU0_SA_DQS_DP<7> DQS7_A_T||TDQS7_A_T @S9S_MB_2U_LIB.S9S_MB_2U(SCH_1):M_B_CPU0_SA_DQS_DP(7)
 261 M_B_CPU0_SB_DQS_DP<6> DQS6_B_T||TDQS6_B_T @S9S_MB_2U_LIB.S9S_MB_2U(SCH_1):M_B_CPU0_SB_DQS_DP(6)
 260 M_B_CPU0_SB_DQS_DN<6> DQS6_B_C||TDQS6_B_C @S9S_MB_2U_LIB.S9S_MB_2U(SCH_1):M_B_CPU0_SB_DQS_DN(6)
 167 M_B_CPU0_SA_DQS_DN<6> DQS6_A_C||TDQS6_A_C||DQS6_A_T||TDQS6_A_T @S9S_MB_2U_LIB.S9S_MB_2U(SCH_1):M_B_CPU0_SA_DQS_DN(6)
 250 M_B_CPU0_SB_DQS_DP<5> DQS5_B_T||TDQS5_B_T @S9S_MB_2U_LIB.S9S_MB_2U(SCH_1):M_B_CPU0_SB_DQS_DP(5)
 249 M_B_CPU0_SB_DQS_DN<5> DQS5_B_C||TDQS5_B_C @S9S_MB_2U_LIB.S9S_MB_2U(SCH_1):M_B_CPU0_SB_DQS_DN(5)
 157 M_B_CPU0_SA_DQS_DP<5> DQS5_A_T||TDQS5_A_T @S9S_MB_2U_LIB.S9S_MB_2U(SCH_1):M_B_CPU0_SA_DQS_DP(5)
 156 M_B_CPU0_SA_DQS_DN<5> DQS5_A_C||TDQS5_A_C||DQS5_A_T||TDQS5_A_T @S9S_MB_2U_LIB.S9S_MB_2U(SCH_1):M_B_CPU0_SA_DQS_DN(5)
 239 M_B_CPU0_SB_DQS_DP<4> DQS4_B_T @S9S_MB_2U_LIB.S9S_MB_2U(SCH_1):M_B_CPU0_SB_DQS_DP(4)
 238 M_B_CPU0_SB_DQS_DN<4> DQS4_B_C @S9S_MB_2U_LIB.S9S_MB_2U(SCH_1):M_B_CPU0_SB_DQS_DN(4)
  55 M_B_CPU0_SA_DQS_DP<4> DQS4_A_T @S9S_MB_2U_LIB.S9S_MB_2U(SCH_1):M_B_CPU0_SA_DQS_DP(4)
  56 M_B_CPU0_SA_DQS_DN<4> DQS4_A_C @S9S_MB_2U_LIB.S9S_MB_2U(SCH_1):M_B_CPU0_SA_DQS_DN(4)
 137 M_B_CPU0_SB_DQS_DP<3> DQS3_B_T @S9S_MB_2U_LIB.S9S_MB_2U(SCH_1):M_B_CPU0_SB_DQS_DP(3)
 138 M_B_CPU0_SB_DQS_DN<3> DQS3_B_C @S9S_MB_2U_LIB.S9S_MB_2U(SCH_1):M_B_CPU0_SB_DQS_DN(3)
  44 M_B_CPU0_SA_DQS_DP<3> DQS3_A_T @S9S_MB_2U_LIB.S9S_MB_2U(SCH_1):M_B_CPU0_SA_DQS_DP(3)
  45 M_B_CPU0_SA_DQS_DN<3> DQS3_A_C @S9S_MB_2U_LIB.S9S_MB_2U(SCH_1):M_B_CPU0_SA_DQS_DN(3)
 126 M_B_CPU0_SB_DQS_DP<2> DQS2_B_T @S9S_MB_2U_LIB.S9S_MB_2U(SCH_1):M_B_CPU0_SB_DQS_DP(2)
 127 M_B_CPU0_SB_DQS_DN<2> DQS2_B_C @S9S_MB_2U_LIB.S9S_MB_2U(SCH_1):M_B_CPU0_SB_DQS_DN(2)
  33 M_B_CPU0_SA_DQS_DP<2> DQS2_A_T @S9S_MB_2U_LIB.S9S_MB_2U(SCH_1):M_B_CPU0_SA_DQS_DP(2)
  34 M_B_CPU0_SA_DQS_DN<2> DQS2_A_C @S9S_MB_2U_LIB.S9S_MB_2U(SCH_1):M_B_CPU0_SA_DQS_DN(2)
 115 M_B_CPU0_SB_DQS_DP<1> DQS1_B_T @S9S_MB_2U_LIB.S9S_MB_2U(SCH_1):M_B_CPU0_SB_DQS_DP(1)
 116 M_B_CPU0_SB_DQS_DN<1> DQS1_B_C @S9S_MB_2U_LIB.S9S_MB_2U(SCH_1):M_B_CPU0_SB_DQS_DN(1)
  22 M_B_CPU0_SA_DQS_DP<1> DQS1_A_T @S9S_MB_2U_LIB.S9S_MB_2U(SCH_1):M_B_CPU0_SA_DQS_DP(1)
  23 M_B_CPU0_SA_DQS_DN<1> DQS1_A_C @S9S_MB_2U_LIB.S9S_MB_2U(SCH_1):M_B_CPU0_SA_DQS_DN(1)
 104 M_B_CPU0_SB_DQS_DP<0> DQS0_B_T @S9S_MB_2U_LIB.S9S_MB_2U(SCH_1):M_B_CPU0_SB_DQS_DP(0)
 105 M_B_CPU0_SB_DQS_DN<0> DQS0_B_C @S9S_MB_2U_LIB.S9S_MB_2U(SCH_1):M_B_CPU0_SB_DQS_DN(0)
  11 M_B_CPU0_SA_DQS_DP<0> DQS0_A_T @S9S_MB_2U_LIB.S9S_MB_2U(SCH_1):M_B_CPU0_SA_DQS_DP(0)
  12 M_B_CPU0_SA_DQS_DN<0> DQS0_A_C @S9S_MB_2U_LIB.S9S_MB_2U(SCH_1):M_B_CPU0_SA_DQS_DN(0)
 272 M_B_CPU0_SB_DQS_DP<7> DQS7_B_T||TDQS7_B_T @S9S_MB_2U_LIB.S9S_MB_2U(SCH_1):M_B_CPU0_SB_DQS_DP(7)
 282 M_B_CPU0_SB_DQS_DN<8> DQS8_B_C||TDQS8_B_C @S9S_MB_2U_LIB.S9S_MB_2U(SCH_1):M_B_CPU0_SB_DQS_DN(8)
 283 M_B_CPU0_SB_DQS_DP<8> DQS8_B_T||TDQS8_B_T @S9S_MB_2U_LIB.S9S_MB_2U(SCH_1):M_B_CPU0_SB_DQS_DP(8)
 168 M_B_CPU0_SA_DQS_DP<6> DQS6_A_T||TDQS6_A_T @S9S_MB_2U_LIB.S9S_MB_2U(SCH_1):M_B_CPU0_SA_DQS_DP(6)
 178 M_B_CPU0_SA_DQS_DN<7> DQS7_A_C||TDQS7_A_C @S9S_MB_2U_LIB.S9S_MB_2U(SCH_1):M_B_CPU0_SA_DQS_DN(7)

SCONN288_ADR50017P130CC-SCONN2A  I180  J3
   3 P3V3_AUX VIN_MGMT @S9S_MB_2U_LIB.S9S_MB_2U(SCH_1):P3V3_AUX
   2 TP_CHB_CPU0_DIMM1_FRU_0   RFU0 @S9S_MB_2U_LIB.S9S_MB_2U(SCH_1):TP_CHB_CPU0_DIMM1_FRU_0
 144 TP_CHB_CPU0_DIMM1_FRU_1   RFU1 @S9S_MB_2U_LIB.S9S_MB_2U(SCH_1):TP_CHB_CPU0_DIMM1_FRU_1
 149 TP_CHB_CPU0_DIMM1_FRU_2   RFU2 @S9S_MB_2U_LIB.S9S_MB_2U(SCH_1):TP_CHB_CPU0_DIMM1_FRU_2
 150 TP_CHB_CPU0_DIMM1_FRU_3   RFU3 @S9S_MB_2U_LIB.S9S_MB_2U(SCH_1):TP_CHB_CPU0_DIMM1_FRU_3
 220 TP_CHB_CPU0_DIMM1_FRU_4   RFU4 @S9S_MB_2U_LIB.S9S_MB_2U(SCH_1):TP_CHB_CPU0_DIMM1_FRU_4
 231 TP_CHB_CPU0_DIMM1_FRU_5   RFU5 @S9S_MB_2U_LIB.S9S_MB_2U(SCH_1):TP_CHB_CPU0_DIMM1_FRU_5
 232 TP_CHB_CPU0_DIMM1_FRU_6   RFU6 @S9S_MB_2U_LIB.S9S_MB_2U(SCH_1):TP_CHB_CPU0_DIMM1_FRU_6
 207 RST_M_AB_CPU0_FPGA_N RESET_N @S9S_MB_2U_LIB.S9S_MB_2U(SCH_1):RST_M_AB_CPU0_FPGA_N
 147 PWRGD_CHB_CPU0_DIMM1 PWR_GOOD||FAIL_N @S9S_MB_2U_LIB.S9S_MB_2U(SCH_1):PWRGD_CHB_CPU0_DIMM1
 227 M_B_CPU0_SB_PAR  PAR_B @S9S_MB_2U_LIB.S9S_MB_2U(SCH_1):M_B_CPU0_SB_PAR
  74 M_B_CPU0_SA_PAR  PAR_A @S9S_MB_2U_LIB.S9S_MB_2U(SCH_1):M_B_CPU0_SA_PAR
  87 M_B_CPU0_SB_RSP<0> LBS||RSP_B_N @S9S_MB_2U_LIB.S9S_MB_2U(SCH_1):M_B_CPU0_SB_RSP(0)
  86 M_B_CPU0_SA_RSP<0> LBD||RSP_A_N @S9S_MB_2U_LIB.S9S_MB_2U(SCH_1):M_B_CPU0_SA_RSP(0)
   5 I3C_SPD_DDRABCD_CPU0_LVC1_SDA   HSDA @S9S_MB_2U_LIB.S9S_MB_2U(SCH_1):I3C_SPD_DDRABCD_CPU0_LVC1_SDA
   4 I3C_SPD_DDRABCD_CPU0_LVC1_SCL_2   HSCL @S9S_MB_2U_LIB.S9S_MB_2U(SCH_1):I3C_SPD_DDRABCD_CPU0_LVC1_SCL_R3
 148 PD_CHB_CPU0_DIMM1_SAA    HSA @S9S_MB_2U_LIB.S9S_MB_2U(SCH_1):PD_CHB_CPU0_DIMM1_SAA
 100 M_B_CPU0_SB_DQ<0>  DQ0_B @S9S_MB_2U_LIB.S9S_MB_2U(SCH_1):M_B_CPU0_SB_DQ(0)
 102 M_B_CPU0_SB_DQ<1>  DQ1_B @S9S_MB_2U_LIB.S9S_MB_2U(SCH_1):M_B_CPU0_SB_DQ(1)
 245 M_B_CPU0_SB_DQ<2>  DQ2_B @S9S_MB_2U_LIB.S9S_MB_2U(SCH_1):M_B_CPU0_SB_DQ(2)
 247 M_B_CPU0_SB_DQ<3>  DQ3_B @S9S_MB_2U_LIB.S9S_MB_2U(SCH_1):M_B_CPU0_SB_DQ(3)
 107 M_B_CPU0_SB_DQ<4>  DQ4_B @S9S_MB_2U_LIB.S9S_MB_2U(SCH_1):M_B_CPU0_SB_DQ(4)
 109 M_B_CPU0_SB_DQ<5>  DQ5_B @S9S_MB_2U_LIB.S9S_MB_2U(SCH_1):M_B_CPU0_SB_DQ(5)
 252 M_B_CPU0_SB_DQ<6>  DQ6_B @S9S_MB_2U_LIB.S9S_MB_2U(SCH_1):M_B_CPU0_SB_DQ(6)
 254 M_B_CPU0_SB_DQ<7>  DQ7_B @S9S_MB_2U_LIB.S9S_MB_2U(SCH_1):M_B_CPU0_SB_DQ(7)
 111 M_B_CPU0_SB_DQ<8>  DQ8_B @S9S_MB_2U_LIB.S9S_MB_2U(SCH_1):M_B_CPU0_SB_DQ(8)
 113 M_B_CPU0_SB_DQ<9>  DQ9_B @S9S_MB_2U_LIB.S9S_MB_2U(SCH_1):M_B_CPU0_SB_DQ(9)
 256 M_B_CPU0_SB_DQ<10> DQ10_B @S9S_MB_2U_LIB.S9S_MB_2U(SCH_1):M_B_CPU0_SB_DQ(10)
 258 M_B_CPU0_SB_DQ<11> DQ11_B @S9S_MB_2U_LIB.S9S_MB_2U(SCH_1):M_B_CPU0_SB_DQ(11)
 118 M_B_CPU0_SB_DQ<12> DQ12_B @S9S_MB_2U_LIB.S9S_MB_2U(SCH_1):M_B_CPU0_SB_DQ(12)
 120 M_B_CPU0_SB_DQ<13> DQ13_B @S9S_MB_2U_LIB.S9S_MB_2U(SCH_1):M_B_CPU0_SB_DQ(13)
 263 M_B_CPU0_SB_DQ<14> DQ14_B @S9S_MB_2U_LIB.S9S_MB_2U(SCH_1):M_B_CPU0_SB_DQ(14)
 265 M_B_CPU0_SB_DQ<15> DQ15_B @S9S_MB_2U_LIB.S9S_MB_2U(SCH_1):M_B_CPU0_SB_DQ(15)
 122 M_B_CPU0_SB_DQ<16> DQ16_B @S9S_MB_2U_LIB.S9S_MB_2U(SCH_1):M_B_CPU0_SB_DQ(16)
 124 M_B_CPU0_SB_DQ<17> DQ17_B @S9S_MB_2U_LIB.S9S_MB_2U(SCH_1):M_B_CPU0_SB_DQ(17)
 267 M_B_CPU0_SB_DQ<18> DQ18_B @S9S_MB_2U_LIB.S9S_MB_2U(SCH_1):M_B_CPU0_SB_DQ(18)
 269 M_B_CPU0_SB_DQ<19> DQ19_B @S9S_MB_2U_LIB.S9S_MB_2U(SCH_1):M_B_CPU0_SB_DQ(19)
 129 M_B_CPU0_SB_DQ<20> DQ20_B @S9S_MB_2U_LIB.S9S_MB_2U(SCH_1):M_B_CPU0_SB_DQ(20)
 131 M_B_CPU0_SB_DQ<21> DQ21_B @S9S_MB_2U_LIB.S9S_MB_2U(SCH_1):M_B_CPU0_SB_DQ(21)
 274 M_B_CPU0_SB_DQ<22> DQ22_B @S9S_MB_2U_LIB.S9S_MB_2U(SCH_1):M_B_CPU0_SB_DQ(22)
 276 M_B_CPU0_SB_DQ<23> DQ23_B @S9S_MB_2U_LIB.S9S_MB_2U(SCH_1):M_B_CPU0_SB_DQ(23)
 133 M_B_CPU0_SB_DQ<24> DQ24_B @S9S_MB_2U_LIB.S9S_MB_2U(SCH_1):M_B_CPU0_SB_DQ(24)
 135 M_B_CPU0_SB_DQ<25> DQ25_B @S9S_MB_2U_LIB.S9S_MB_2U(SCH_1):M_B_CPU0_SB_DQ(25)
 278 M_B_CPU0_SB_DQ<26> DQ26_B @S9S_MB_2U_LIB.S9S_MB_2U(SCH_1):M_B_CPU0_SB_DQ(26)
 280 M_B_CPU0_SB_DQ<27> DQ27_B @S9S_MB_2U_LIB.S9S_MB_2U(SCH_1):M_B_CPU0_SB_DQ(27)
 140 M_B_CPU0_SB_DQ<28> DQ28_B @S9S_MB_2U_LIB.S9S_MB_2U(SCH_1):M_B_CPU0_SB_DQ(28)
 142 M_B_CPU0_SB_DQ<29> DQ29_B @S9S_MB_2U_LIB.S9S_MB_2U(SCH_1):M_B_CPU0_SB_DQ(29)
 285 M_B_CPU0_SB_DQ<30> DQ30_B @S9S_MB_2U_LIB.S9S_MB_2U(SCH_1):M_B_CPU0_SB_DQ(30)
 287 M_B_CPU0_SB_DQ<31> DQ31_B @S9S_MB_2U_LIB.S9S_MB_2U(SCH_1):M_B_CPU0_SB_DQ(31)
   7 M_B_CPU0_SA_DQ<0>  DQ0_A @S9S_MB_2U_LIB.S9S_MB_2U(SCH_1):M_B_CPU0_SA_DQ(0)
   9 M_B_CPU0_SA_DQ<1>  DQ1_A @S9S_MB_2U_LIB.S9S_MB_2U(SCH_1):M_B_CPU0_SA_DQ(1)
 152 M_B_CPU0_SA_DQ<2>  DQ2_A @S9S_MB_2U_LIB.S9S_MB_2U(SCH_1):M_B_CPU0_SA_DQ(2)
 154 M_B_CPU0_SA_DQ<3>  DQ3_A @S9S_MB_2U_LIB.S9S_MB_2U(SCH_1):M_B_CPU0_SA_DQ(3)
  14 M_B_CPU0_SA_DQ<4>  DQ4_A @S9S_MB_2U_LIB.S9S_MB_2U(SCH_1):M_B_CPU0_SA_DQ(4)
  16 M_B_CPU0_SA_DQ<5>  DQ5_A @S9S_MB_2U_LIB.S9S_MB_2U(SCH_1):M_B_CPU0_SA_DQ(5)
 159 M_B_CPU0_SA_DQ<6>  DQ6_A @S9S_MB_2U_LIB.S9S_MB_2U(SCH_1):M_B_CPU0_SA_DQ(6)
 161 M_B_CPU0_SA_DQ<7>  DQ7_A @S9S_MB_2U_LIB.S9S_MB_2U(SCH_1):M_B_CPU0_SA_DQ(7)
  18 M_B_CPU0_SA_DQ<8>  DQ8_A @S9S_MB_2U_LIB.S9S_MB_2U(SCH_1):M_B_CPU0_SA_DQ(8)
  20 M_B_CPU0_SA_DQ<9>  DQ9_A @S9S_MB_2U_LIB.S9S_MB_2U(SCH_1):M_B_CPU0_SA_DQ(9)
 163 M_B_CPU0_SA_DQ<10> DQ10_A @S9S_MB_2U_LIB.S9S_MB_2U(SCH_1):M_B_CPU0_SA_DQ(10)
 165 M_B_CPU0_SA_DQ<11> DQ11_A @S9S_MB_2U_LIB.S9S_MB_2U(SCH_1):M_B_CPU0_SA_DQ(11)
  25 M_B_CPU0_SA_DQ<12> DQ12_A @S9S_MB_2U_LIB.S9S_MB_2U(SCH_1):M_B_CPU0_SA_DQ(12)
  27 M_B_CPU0_SA_DQ<13> DQ13_A @S9S_MB_2U_LIB.S9S_MB_2U(SCH_1):M_B_CPU0_SA_DQ(13)
 170 M_B_CPU0_SA_DQ<14> DQ14_A @S9S_MB_2U_LIB.S9S_MB_2U(SCH_1):M_B_CPU0_SA_DQ(14)
 172 M_B_CPU0_SA_DQ<15> DQ15_A @S9S_MB_2U_LIB.S9S_MB_2U(SCH_1):M_B_CPU0_SA_DQ(15)
  29 M_B_CPU0_SA_DQ<16> DQ16_A @S9S_MB_2U_LIB.S9S_MB_2U(SCH_1):M_B_CPU0_SA_DQ(16)
  31 M_B_CPU0_SA_DQ<17> DQ17_A @S9S_MB_2U_LIB.S9S_MB_2U(SCH_1):M_B_CPU0_SA_DQ(17)
 174 M_B_CPU0_SA_DQ<18> DQ18_A @S9S_MB_2U_LIB.S9S_MB_2U(SCH_1):M_B_CPU0_SA_DQ(18)
 176 M_B_CPU0_SA_DQ<19> DQ19_A @S9S_MB_2U_LIB.S9S_MB_2U(SCH_1):M_B_CPU0_SA_DQ(19)
  36 M_B_CPU0_SA_DQ<20> DQ20_A @S9S_MB_2U_LIB.S9S_MB_2U(SCH_1):M_B_CPU0_SA_DQ(20)
  38 M_B_CPU0_SA_DQ<21> DQ21_A @S9S_MB_2U_LIB.S9S_MB_2U(SCH_1):M_B_CPU0_SA_DQ(21)
 181 M_B_CPU0_SA_DQ<22> DQ22_A @S9S_MB_2U_LIB.S9S_MB_2U(SCH_1):M_B_CPU0_SA_DQ(22)
 183 M_B_CPU0_SA_DQ<23> DQ23_A @S9S_MB_2U_LIB.S9S_MB_2U(SCH_1):M_B_CPU0_SA_DQ(23)
  40 M_B_CPU0_SA_DQ<24> DQ24_A @S9S_MB_2U_LIB.S9S_MB_2U(SCH_1):M_B_CPU0_SA_DQ(24)
  42 M_B_CPU0_SA_DQ<25> DQ25_A @S9S_MB_2U_LIB.S9S_MB_2U(SCH_1):M_B_CPU0_SA_DQ(25)
 185 M_B_CPU0_SA_DQ<26> DQ26_A @S9S_MB_2U_LIB.S9S_MB_2U(SCH_1):M_B_CPU0_SA_DQ(26)
 187 M_B_CPU0_SA_DQ<27> DQ27_A @S9S_MB_2U_LIB.S9S_MB_2U(SCH_1):M_B_CPU0_SA_DQ(27)
  47 M_B_CPU0_SA_DQ<28> DQ28_A @S9S_MB_2U_LIB.S9S_MB_2U(SCH_1):M_B_CPU0_SA_DQ(28)
  49 M_B_CPU0_SA_DQ<29> DQ29_A @S9S_MB_2U_LIB.S9S_MB_2U(SCH_1):M_B_CPU0_SA_DQ(29)
 192 M_B_CPU0_SA_DQ<30> DQ30_A @S9S_MB_2U_LIB.S9S_MB_2U(SCH_1):M_B_CPU0_SA_DQ(30)
 229 M_B_CPU0_SB_CS_N<1> CS1_B_N @S9S_MB_2U_LIB.S9S_MB_2U(SCH_1):M_B_CPU0_SB_CS_N(1)
 209 M_B_CPU0_SA_CS_N<1> CS1_A_N @S9S_MB_2U_LIB.S9S_MB_2U(SCH_1):M_B_CPU0_SA_CS_N(1)
  84 M_B_CPU0_SB_CS_N<0> CS0_B_N @S9S_MB_2U_LIB.S9S_MB_2U(SCH_1):M_B_CPU0_SB_CS_N(0)
  64 M_B_CPU0_SA_CS_N<0> CS0_A_N @S9S_MB_2U_LIB.S9S_MB_2U(SCH_1):M_B_CPU0_SA_CS_N(0)
 217 M_B_CPU0_CLK_DP<0>   CK_T @S9S_MB_2U_LIB.S9S_MB_2U(SCH_1):M_B_CPU0_CLK_DP(0)
 218 M_B_CPU0_CLK_DN<0>   CK_C @S9S_MB_2U_LIB.S9S_MB_2U(SCH_1):M_B_CPU0_CLK_DN(0)
  96 M_B_CPU0_SB_CB<0>  CB0_B @S9S_MB_2U_LIB.S9S_MB_2U(SCH_1):M_B_CPU0_SB_CB(0)
  98 M_B_CPU0_SB_CB<1>  CB1_B @S9S_MB_2U_LIB.S9S_MB_2U(SCH_1):M_B_CPU0_SB_CB(1)
 241 M_B_CPU0_SB_CB<2>  CB2_B @S9S_MB_2U_LIB.S9S_MB_2U(SCH_1):M_B_CPU0_SB_CB(2)
 243 M_B_CPU0_SB_CB<3>  CB3_B @S9S_MB_2U_LIB.S9S_MB_2U(SCH_1):M_B_CPU0_SB_CB(3)
  89 M_B_CPU0_SB_CB<4>  CB4_B @S9S_MB_2U_LIB.S9S_MB_2U(SCH_1):M_B_CPU0_SB_CB(4)
  91 M_B_CPU0_SB_CB<5>  CB5_B @S9S_MB_2U_LIB.S9S_MB_2U(SCH_1):M_B_CPU0_SB_CB(5)
 234 M_B_CPU0_SB_CB<6>  CB6_B @S9S_MB_2U_LIB.S9S_MB_2U(SCH_1):M_B_CPU0_SB_CB(6)
  51 M_B_CPU0_SA_CB<0>  CB0_A @S9S_MB_2U_LIB.S9S_MB_2U(SCH_1):M_B_CPU0_SA_CB(0)
 196 M_B_CPU0_SA_CB<2>  CB2_A @S9S_MB_2U_LIB.S9S_MB_2U(SCH_1):M_B_CPU0_SA_CB(2)
 198 M_B_CPU0_SA_CB<3>  CB3_A @S9S_MB_2U_LIB.S9S_MB_2U(SCH_1):M_B_CPU0_SA_CB(3)
  60 M_B_CPU0_SA_CB<5>  CB5_A @S9S_MB_2U_LIB.S9S_MB_2U(SCH_1):M_B_CPU0_SA_CB(5)
 203 M_B_CPU0_SA_CB<6>  CB6_A @S9S_MB_2U_LIB.S9S_MB_2U(SCH_1):M_B_CPU0_SA_CB(6)
  82 M_B_CPU0_SB_CA<6>  CA6_B @S9S_MB_2U_LIB.S9S_MB_2U(SCH_1):M_B_CPU0_SB_CA(6)
  72 M_B_CPU0_SA_CA<6>  CA6_A @S9S_MB_2U_LIB.S9S_MB_2U(SCH_1):M_B_CPU0_SA_CA(6)
 225 M_B_CPU0_SB_CA<5>  CA5_B @S9S_MB_2U_LIB.S9S_MB_2U(SCH_1):M_B_CPU0_SB_CA(5)
 215 M_B_CPU0_SA_CA<5>  CA5_A @S9S_MB_2U_LIB.S9S_MB_2U(SCH_1):M_B_CPU0_SA_CA(5)
  80 M_B_CPU0_SB_CA<4>  CA4_B @S9S_MB_2U_LIB.S9S_MB_2U(SCH_1):M_B_CPU0_SB_CA(4)
  70 M_B_CPU0_SA_CA<4>  CA4_A @S9S_MB_2U_LIB.S9S_MB_2U(SCH_1):M_B_CPU0_SA_CA(4)
 223 M_B_CPU0_SB_CA<3>  CA3_B @S9S_MB_2U_LIB.S9S_MB_2U(SCH_1):M_B_CPU0_SB_CA(3)
 213 M_B_CPU0_SA_CA<3>  CA3_A @S9S_MB_2U_LIB.S9S_MB_2U(SCH_1):M_B_CPU0_SA_CA(3)
  78 M_B_CPU0_SB_CA<2>  CA2_B @S9S_MB_2U_LIB.S9S_MB_2U(SCH_1):M_B_CPU0_SB_CA(2)
  68 M_B_CPU0_SA_CA<2>  CA2_A @S9S_MB_2U_LIB.S9S_MB_2U(SCH_1):M_B_CPU0_SA_CA(2)
 221 M_B_CPU0_SB_CA<1>  CA1_B @S9S_MB_2U_LIB.S9S_MB_2U(SCH_1):M_B_CPU0_SB_CA(1)
 211 M_B_CPU0_SA_CA<1>  CA1_A @S9S_MB_2U_LIB.S9S_MB_2U(SCH_1):M_B_CPU0_SA_CA(1)
  76 M_B_CPU0_SB_CA<0>  CA0_B @S9S_MB_2U_LIB.S9S_MB_2U(SCH_1):M_B_CPU0_SB_CA(0)
  66 M_B_CPU0_SA_CA<0>  CA0_A @S9S_MB_2U_LIB.S9S_MB_2U(SCH_1):M_B_CPU0_SA_CA(0)
  62 M_B_CPU0_ALERT_N ALERT_N @S9S_MB_2U_LIB.S9S_MB_2U(SCH_1):M_B_CPU0_ALERT_N
 236 M_B_CPU0_SB_CB<7>  CB7_B @S9S_MB_2U_LIB.S9S_MB_2U(SCH_1):M_B_CPU0_SB_CB(7)
  53 M_B_CPU0_SA_CB<1>  CB1_A @S9S_MB_2U_LIB.S9S_MB_2U(SCH_1):M_B_CPU0_SA_CB(1)
  58 M_B_CPU0_SA_CB<4>  CB4_A @S9S_MB_2U_LIB.S9S_MB_2U(SCH_1):M_B_CPU0_SA_CB(4)
 205 M_B_CPU0_SA_CB<7>  CB7_A @S9S_MB_2U_LIB.S9S_MB_2U(SCH_1):M_B_CPU0_SA_CB(7)
 194 M_B_CPU0_SA_DQ<31> DQ31_A @S9S_MB_2U_LIB.S9S_MB_2U(SCH_1):M_B_CPU0_SA_DQ(31)

Q_RES_0402LF-49.9,1%,1/16W,CHIA  I182  R3877
   1 I3C_SPD_DDRABCD_CPU0_LVC1_SCL_2      A @S9S_MB_2U_LIB.S9S_MB_2U(SCH_1):I3C_SPD_DDRABCD_CPU0_LVC1_SCL_R3
   2 I3C_SPD_DDRABCD_CPU0_LVC1_SCL      B @S9S_MB_2U_LIB.S9S_MB_2U(SCH_1):I3C_SPD_DDRABCD_CPU0_LVC1_SCL


DRAWING: @S9S_MB_2U_LIB.S9S_MB_2U(SCH_1):PAGE85 

Q_RES_0402LF-35.7K,1%,1/16W,CHA  I1  R29
   1 PD_CHB_CPU0_DIMM2_SAA      A @S9S_MB_2U_LIB.S9S_MB_2U(SCH_1):PD_CHB_CPU0_DIMM2_SAA
   2    GND      B @S9S_MB_2U_LIB.S9S_MB_2U(SCH_1):GND

SCONN288_ADR50017P087CC-SCONN2A  I23  J4
   3 P3V3_AUX VIN_MGMT @S9S_MB_2U_LIB.S9S_MB_2U(SCH_1):P3V3_AUX
   2 TP_CHB_CPU0_DIMM2_FRU_0   RFU0 @S9S_MB_2U_LIB.S9S_MB_2U(SCH_1):TP_CHB_CPU0_DIMM2_FRU_0
 144 TP_CHB_CPU0_DIMM2_FRU_1   RFU1 @S9S_MB_2U_LIB.S9S_MB_2U(SCH_1):TP_CHB_CPU0_DIMM2_FRU_1
 149 TP_CHB_CPU0_DIMM2_FRU_2   RFU2 @S9S_MB_2U_LIB.S9S_MB_2U(SCH_1):TP_CHB_CPU0_DIMM2_FRU_2
 150 TP_CHB_CPU0_DIMM2_FRU_3   RFU3 @S9S_MB_2U_LIB.S9S_MB_2U(SCH_1):TP_CHB_CPU0_DIMM2_FRU_3
 220 TP_CHB_CPU0_DIMM2_FRU_4   RFU4 @S9S_MB_2U_LIB.S9S_MB_2U(SCH_1):TP_CHB_CPU0_DIMM2_FRU_4
 231 TP_CHB_CPU0_DIMM2_FRU_5   RFU5 @S9S_MB_2U_LIB.S9S_MB_2U(SCH_1):TP_CHB_CPU0_DIMM2_FRU_5
 232 TP_CHB_CPU0_DIMM2_FRU_6   RFU6 @S9S_MB_2U_LIB.S9S_MB_2U(SCH_1):TP_CHB_CPU0_DIMM2_FRU_6
 207 RST_M_AB_CPU0_FPGA_N RESET_N @S9S_MB_2U_LIB.S9S_MB_2U(SCH_1):RST_M_AB_CPU0_FPGA_N
 147 PWRGD_CHB_CPU0_DIMM2 PWR_GOOD||FAIL_N @S9S_MB_2U_LIB.S9S_MB_2U(SCH_1):PWRGD_CHB_CPU0_DIMM2
 227 M_B_CPU0_SB_PAR  PAR_B @S9S_MB_2U_LIB.S9S_MB_2U(SCH_1):M_B_CPU0_SB_PAR
  74 M_B_CPU0_SA_PAR  PAR_A @S9S_MB_2U_LIB.S9S_MB_2U(SCH_1):M_B_CPU0_SA_PAR
  87 M_B_CPU0_SB_RSP<1> LBS||RSP_B_N @S9S_MB_2U_LIB.S9S_MB_2U(SCH_1):M_B_CPU0_SB_RSP(1)
  86 M_B_CPU0_SA_RSP<1> LBD||RSP_A_N @S9S_MB_2U_LIB.S9S_MB_2U(SCH_1):M_B_CPU0_SA_RSP(1)
   5 I3C_SPD_DDRABCD_CPU0_LVC1_SDA   HSDA @S9S_MB_2U_LIB.S9S_MB_2U(SCH_1):I3C_SPD_DDRABCD_CPU0_LVC1_SDA
   4 I3C_SPD_DDRABCD_CPU0_LVC1_SCL_3   HSCL @S9S_MB_2U_LIB.S9S_MB_2U(SCH_1):I3C_SPD_DDRABCD_CPU0_LVC1_SCL_R4
 148 PD_CHB_CPU0_DIMM2_SAA    HSA @S9S_MB_2U_LIB.S9S_MB_2U(SCH_1):PD_CHB_CPU0_DIMM2_SAA
 100 M_B_CPU0_SB_DQ<0>  DQ0_B @S9S_MB_2U_LIB.S9S_MB_2U(SCH_1):M_B_CPU0_SB_DQ(0)
 102 M_B_CPU0_SB_DQ<1>  DQ1_B @S9S_MB_2U_LIB.S9S_MB_2U(SCH_1):M_B_CPU0_SB_DQ(1)
 245 M_B_CPU0_SB_DQ<2>  DQ2_B @S9S_MB_2U_LIB.S9S_MB_2U(SCH_1):M_B_CPU0_SB_DQ(2)
 247 M_B_CPU0_SB_DQ<3>  DQ3_B @S9S_MB_2U_LIB.S9S_MB_2U(SCH_1):M_B_CPU0_SB_DQ(3)
 107 M_B_CPU0_SB_DQ<4>  DQ4_B @S9S_MB_2U_LIB.S9S_MB_2U(SCH_1):M_B_CPU0_SB_DQ(4)
 109 M_B_CPU0_SB_DQ<5>  DQ5_B @S9S_MB_2U_LIB.S9S_MB_2U(SCH_1):M_B_CPU0_SB_DQ(5)
 252 M_B_CPU0_SB_DQ<6>  DQ6_B @S9S_MB_2U_LIB.S9S_MB_2U(SCH_1):M_B_CPU0_SB_DQ(6)
 254 M_B_CPU0_SB_DQ<7>  DQ7_B @S9S_MB_2U_LIB.S9S_MB_2U(SCH_1):M_B_CPU0_SB_DQ(7)
 111 M_B_CPU0_SB_DQ<8>  DQ8_B @S9S_MB_2U_LIB.S9S_MB_2U(SCH_1):M_B_CPU0_SB_DQ(8)
 113 M_B_CPU0_SB_DQ<9>  DQ9_B @S9S_MB_2U_LIB.S9S_MB_2U(SCH_1):M_B_CPU0_SB_DQ(9)
 256 M_B_CPU0_SB_DQ<10> DQ10_B @S9S_MB_2U_LIB.S9S_MB_2U(SCH_1):M_B_CPU0_SB_DQ(10)
 258 M_B_CPU0_SB_DQ<11> DQ11_B @S9S_MB_2U_LIB.S9S_MB_2U(SCH_1):M_B_CPU0_SB_DQ(11)
 118 M_B_CPU0_SB_DQ<12> DQ12_B @S9S_MB_2U_LIB.S9S_MB_2U(SCH_1):M_B_CPU0_SB_DQ(12)
 120 M_B_CPU0_SB_DQ<13> DQ13_B @S9S_MB_2U_LIB.S9S_MB_2U(SCH_1):M_B_CPU0_SB_DQ(13)
 263 M_B_CPU0_SB_DQ<14> DQ14_B @S9S_MB_2U_LIB.S9S_MB_2U(SCH_1):M_B_CPU0_SB_DQ(14)
 265 M_B_CPU0_SB_DQ<15> DQ15_B @S9S_MB_2U_LIB.S9S_MB_2U(SCH_1):M_B_CPU0_SB_DQ(15)
 122 M_B_CPU0_SB_DQ<16> DQ16_B @S9S_MB_2U_LIB.S9S_MB_2U(SCH_1):M_B_CPU0_SB_DQ(16)
 124 M_B_CPU0_SB_DQ<17> DQ17_B @S9S_MB_2U_LIB.S9S_MB_2U(SCH_1):M_B_CPU0_SB_DQ(17)
 267 M_B_CPU0_SB_DQ<18> DQ18_B @S9S_MB_2U_LIB.S9S_MB_2U(SCH_1):M_B_CPU0_SB_DQ(18)
 269 M_B_CPU0_SB_DQ<19> DQ19_B @S9S_MB_2U_LIB.S9S_MB_2U(SCH_1):M_B_CPU0_SB_DQ(19)
 129 M_B_CPU0_SB_DQ<20> DQ20_B @S9S_MB_2U_LIB.S9S_MB_2U(SCH_1):M_B_CPU0_SB_DQ(20)
 131 M_B_CPU0_SB_DQ<21> DQ21_B @S9S_MB_2U_LIB.S9S_MB_2U(SCH_1):M_B_CPU0_SB_DQ(21)
 274 M_B_CPU0_SB_DQ<22> DQ22_B @S9S_MB_2U_LIB.S9S_MB_2U(SCH_1):M_B_CPU0_SB_DQ(22)
 276 M_B_CPU0_SB_DQ<23> DQ23_B @S9S_MB_2U_LIB.S9S_MB_2U(SCH_1):M_B_CPU0_SB_DQ(23)
 133 M_B_CPU0_SB_DQ<24> DQ24_B @S9S_MB_2U_LIB.S9S_MB_2U(SCH_1):M_B_CPU0_SB_DQ(24)
 135 M_B_CPU0_SB_DQ<25> DQ25_B @S9S_MB_2U_LIB.S9S_MB_2U(SCH_1):M_B_CPU0_SB_DQ(25)
 278 M_B_CPU0_SB_DQ<26> DQ26_B @S9S_MB_2U_LIB.S9S_MB_2U(SCH_1):M_B_CPU0_SB_DQ(26)
 280 M_B_CPU0_SB_DQ<27> DQ27_B @S9S_MB_2U_LIB.S9S_MB_2U(SCH_1):M_B_CPU0_SB_DQ(27)
 140 M_B_CPU0_SB_DQ<28> DQ28_B @S9S_MB_2U_LIB.S9S_MB_2U(SCH_1):M_B_CPU0_SB_DQ(28)
 142 M_B_CPU0_SB_DQ<29> DQ29_B @S9S_MB_2U_LIB.S9S_MB_2U(SCH_1):M_B_CPU0_SB_DQ(29)
 285 M_B_CPU0_SB_DQ<30> DQ30_B @S9S_MB_2U_LIB.S9S_MB_2U(SCH_1):M_B_CPU0_SB_DQ(30)
 287 M_B_CPU0_SB_DQ<31> DQ31_B @S9S_MB_2U_LIB.S9S_MB_2U(SCH_1):M_B_CPU0_SB_DQ(31)
   7 M_B_CPU0_SA_DQ<0>  DQ0_A @S9S_MB_2U_LIB.S9S_MB_2U(SCH_1):M_B_CPU0_SA_DQ(0)
   9 M_B_CPU0_SA_DQ<1>  DQ1_A @S9S_MB_2U_LIB.S9S_MB_2U(SCH_1):M_B_CPU0_SA_DQ(1)
 152 M_B_CPU0_SA_DQ<2>  DQ2_A @S9S_MB_2U_LIB.S9S_MB_2U(SCH_1):M_B_CPU0_SA_DQ(2)
 154 M_B_CPU0_SA_DQ<3>  DQ3_A @S9S_MB_2U_LIB.S9S_MB_2U(SCH_1):M_B_CPU0_SA_DQ(3)
  14 M_B_CPU0_SA_DQ<4>  DQ4_A @S9S_MB_2U_LIB.S9S_MB_2U(SCH_1):M_B_CPU0_SA_DQ(4)
  16 M_B_CPU0_SA_DQ<5>  DQ5_A @S9S_MB_2U_LIB.S9S_MB_2U(SCH_1):M_B_CPU0_SA_DQ(5)
 159 M_B_CPU0_SA_DQ<6>  DQ6_A @S9S_MB_2U_LIB.S9S_MB_2U(SCH_1):M_B_CPU0_SA_DQ(6)
 161 M_B_CPU0_SA_DQ<7>  DQ7_A @S9S_MB_2U_LIB.S9S_MB_2U(SCH_1):M_B_CPU0_SA_DQ(7)
  18 M_B_CPU0_SA_DQ<8>  DQ8_A @S9S_MB_2U_LIB.S9S_MB_2U(SCH_1):M_B_CPU0_SA_DQ(8)
  20 M_B_CPU0_SA_DQ<9>  DQ9_A @S9S_MB_2U_LIB.S9S_MB_2U(SCH_1):M_B_CPU0_SA_DQ(9)
 163 M_B_CPU0_SA_DQ<10> DQ10_A @S9S_MB_2U_LIB.S9S_MB_2U(SCH_1):M_B_CPU0_SA_DQ(10)
 165 M_B_CPU0_SA_DQ<11> DQ11_A @S9S_MB_2U_LIB.S9S_MB_2U(SCH_1):M_B_CPU0_SA_DQ(11)
  25 M_B_CPU0_SA_DQ<12> DQ12_A @S9S_MB_2U_LIB.S9S_MB_2U(SCH_1):M_B_CPU0_SA_DQ(12)
  27 M_B_CPU0_SA_DQ<13> DQ13_A @S9S_MB_2U_LIB.S9S_MB_2U(SCH_1):M_B_CPU0_SA_DQ(13)
 170 M_B_CPU0_SA_DQ<14> DQ14_A @S9S_MB_2U_LIB.S9S_MB_2U(SCH_1):M_B_CPU0_SA_DQ(14)
 172 M_B_CPU0_SA_DQ<15> DQ15_A @S9S_MB_2U_LIB.S9S_MB_2U(SCH_1):M_B_CPU0_SA_DQ(15)
  29 M_B_CPU0_SA_DQ<16> DQ16_A @S9S_MB_2U_LIB.S9S_MB_2U(SCH_1):M_B_CPU0_SA_DQ(16)
  31 M_B_CPU0_SA_DQ<17> DQ17_A @S9S_MB_2U_LIB.S9S_MB_2U(SCH_1):M_B_CPU0_SA_DQ(17)
 174 M_B_CPU0_SA_DQ<18> DQ18_A @S9S_MB_2U_LIB.S9S_MB_2U(SCH_1):M_B_CPU0_SA_DQ(18)
 176 M_B_CPU0_SA_DQ<19> DQ19_A @S9S_MB_2U_LIB.S9S_MB_2U(SCH_1):M_B_CPU0_SA_DQ(19)
  36 M_B_CPU0_SA_DQ<20> DQ20_A @S9S_MB_2U_LIB.S9S_MB_2U(SCH_1):M_B_CPU0_SA_DQ(20)
  38 M_B_CPU0_SA_DQ<21> DQ21_A @S9S_MB_2U_LIB.S9S_MB_2U(SCH_1):M_B_CPU0_SA_DQ(21)
 181 M_B_CPU0_SA_DQ<22> DQ22_A @S9S_MB_2U_LIB.S9S_MB_2U(SCH_1):M_B_CPU0_SA_DQ(22)
 183 M_B_CPU0_SA_DQ<23> DQ23_A @S9S_MB_2U_LIB.S9S_MB_2U(SCH_1):M_B_CPU0_SA_DQ(23)
  40 M_B_CPU0_SA_DQ<24> DQ24_A @S9S_MB_2U_LIB.S9S_MB_2U(SCH_1):M_B_CPU0_SA_DQ(24)
  42 M_B_CPU0_SA_DQ<25> DQ25_A @S9S_MB_2U_LIB.S9S_MB_2U(SCH_1):M_B_CPU0_SA_DQ(25)
 185 M_B_CPU0_SA_DQ<26> DQ26_A @S9S_MB_2U_LIB.S9S_MB_2U(SCH_1):M_B_CPU0_SA_DQ(26)
 187 M_B_CPU0_SA_DQ<27> DQ27_A @S9S_MB_2U_LIB.S9S_MB_2U(SCH_1):M_B_CPU0_SA_DQ(27)
  47 M_B_CPU0_SA_DQ<28> DQ28_A @S9S_MB_2U_LIB.S9S_MB_2U(SCH_1):M_B_CPU0_SA_DQ(28)
  49 M_B_CPU0_SA_DQ<29> DQ29_A @S9S_MB_2U_LIB.S9S_MB_2U(SCH_1):M_B_CPU0_SA_DQ(29)
 192 M_B_CPU0_SA_DQ<30> DQ30_A @S9S_MB_2U_LIB.S9S_MB_2U(SCH_1):M_B_CPU0_SA_DQ(30)
 229 M_B_CPU0_SB_CS_N<3> CS1_B_N @S9S_MB_2U_LIB.S9S_MB_2U(SCH_1):M_B_CPU0_SB_CS_N(3)
 209 M_B_CPU0_SA_CS_N<3> CS1_A_N @S9S_MB_2U_LIB.S9S_MB_2U(SCH_1):M_B_CPU0_SA_CS_N(3)
  84 M_B_CPU0_SB_CS_N<2> CS0_B_N @S9S_MB_2U_LIB.S9S_MB_2U(SCH_1):M_B_CPU0_SB_CS_N(2)
  64 M_B_CPU0_SA_CS_N<2> CS0_A_N @S9S_MB_2U_LIB.S9S_MB_2U(SCH_1):M_B_CPU0_SA_CS_N(2)
 217 M_B_CPU0_CLK_DP<1>   CK_T @S9S_MB_2U_LIB.S9S_MB_2U(SCH_1):M_B_CPU0_CLK_DP(1)
 218 M_B_CPU0_CLK_DN<1>   CK_C @S9S_MB_2U_LIB.S9S_MB_2U(SCH_1):M_B_CPU0_CLK_DN(1)
  96 M_B_CPU0_SB_CB<0>  CB0_B @S9S_MB_2U_LIB.S9S_MB_2U(SCH_1):M_B_CPU0_SB_CB(0)
  98 M_B_CPU0_SB_CB<1>  CB1_B @S9S_MB_2U_LIB.S9S_MB_2U(SCH_1):M_B_CPU0_SB_CB(1)
 241 M_B_CPU0_SB_CB<2>  CB2_B @S9S_MB_2U_LIB.S9S_MB_2U(SCH_1):M_B_CPU0_SB_CB(2)
 243 M_B_CPU0_SB_CB<3>  CB3_B @S9S_MB_2U_LIB.S9S_MB_2U(SCH_1):M_B_CPU0_SB_CB(3)
  89 M_B_CPU0_SB_CB<4>  CB4_B @S9S_MB_2U_LIB.S9S_MB_2U(SCH_1):M_B_CPU0_SB_CB(4)
  91 M_B_CPU0_SB_CB<5>  CB5_B @S9S_MB_2U_LIB.S9S_MB_2U(SCH_1):M_B_CPU0_SB_CB(5)
 234 M_B_CPU0_SB_CB<6>  CB6_B @S9S_MB_2U_LIB.S9S_MB_2U(SCH_1):M_B_CPU0_SB_CB(6)
  51 M_B_CPU0_SA_CB<0>  CB0_A @S9S_MB_2U_LIB.S9S_MB_2U(SCH_1):M_B_CPU0_SA_CB(0)
 196 M_B_CPU0_SA_CB<2>  CB2_A @S9S_MB_2U_LIB.S9S_MB_2U(SCH_1):M_B_CPU0_SA_CB(2)
 198 M_B_CPU0_SA_CB<3>  CB3_A @S9S_MB_2U_LIB.S9S_MB_2U(SCH_1):M_B_CPU0_SA_CB(3)
  60 M_B_CPU0_SA_CB<5>  CB5_A @S9S_MB_2U_LIB.S9S_MB_2U(SCH_1):M_B_CPU0_SA_CB(5)
 203 M_B_CPU0_SA_CB<6>  CB6_A @S9S_MB_2U_LIB.S9S_MB_2U(SCH_1):M_B_CPU0_SA_CB(6)
  82 M_B_CPU0_SB_CA<6>  CA6_B @S9S_MB_2U_LIB.S9S_MB_2U(SCH_1):M_B_CPU0_SB_CA(6)
  72 M_B_CPU0_SA_CA<6>  CA6_A @S9S_MB_2U_LIB.S9S_MB_2U(SCH_1):M_B_CPU0_SA_CA(6)
 225 M_B_CPU0_SB_CA<5>  CA5_B @S9S_MB_2U_LIB.S9S_MB_2U(SCH_1):M_B_CPU0_SB_CA(5)
 215 M_B_CPU0_SA_CA<5>  CA5_A @S9S_MB_2U_LIB.S9S_MB_2U(SCH_1):M_B_CPU0_SA_CA(5)
  80 M_B_CPU0_SB_CA<4>  CA4_B @S9S_MB_2U_LIB.S9S_MB_2U(SCH_1):M_B_CPU0_SB_CA(4)
  70 M_B_CPU0_SA_CA<4>  CA4_A @S9S_MB_2U_LIB.S9S_MB_2U(SCH_1):M_B_CPU0_SA_CA(4)
 223 M_B_CPU0_SB_CA<3>  CA3_B @S9S_MB_2U_LIB.S9S_MB_2U(SCH_1):M_B_CPU0_SB_CA(3)
 213 M_B_CPU0_SA_CA<3>  CA3_A @S9S_MB_2U_LIB.S9S_MB_2U(SCH_1):M_B_CPU0_SA_CA(3)
  78 M_B_CPU0_SB_CA<2>  CA2_B @S9S_MB_2U_LIB.S9S_MB_2U(SCH_1):M_B_CPU0_SB_CA(2)
  68 M_B_CPU0_SA_CA<2>  CA2_A @S9S_MB_2U_LIB.S9S_MB_2U(SCH_1):M_B_CPU0_SA_CA(2)
 221 M_B_CPU0_SB_CA<1>  CA1_B @S9S_MB_2U_LIB.S9S_MB_2U(SCH_1):M_B_CPU0_SB_CA(1)
 211 M_B_CPU0_SA_CA<1>  CA1_A @S9S_MB_2U_LIB.S9S_MB_2U(SCH_1):M_B_CPU0_SA_CA(1)
  76 M_B_CPU0_SB_CA<0>  CA0_B @S9S_MB_2U_LIB.S9S_MB_2U(SCH_1):M_B_CPU0_SB_CA(0)
  66 M_B_CPU0_SA_CA<0>  CA0_A @S9S_MB_2U_LIB.S9S_MB_2U(SCH_1):M_B_CPU0_SA_CA(0)
  62 M_B_CPU0_ALERT_N ALERT_N @S9S_MB_2U_LIB.S9S_MB_2U(SCH_1):M_B_CPU0_ALERT_N
 236 M_B_CPU0_SB_CB<7>  CB7_B @S9S_MB_2U_LIB.S9S_MB_2U(SCH_1):M_B_CPU0_SB_CB(7)
  53 M_B_CPU0_SA_CB<1>  CB1_A @S9S_MB_2U_LIB.S9S_MB_2U(SCH_1):M_B_CPU0_SA_CB(1)
  58 M_B_CPU0_SA_CB<4>  CB4_A @S9S_MB_2U_LIB.S9S_MB_2U(SCH_1):M_B_CPU0_SA_CB(4)
 205 M_B_CPU0_SA_CB<7>  CB7_A @S9S_MB_2U_LIB.S9S_MB_2U(SCH_1):M_B_CPU0_SA_CB(7)
 194 M_B_CPU0_SA_DQ<31> DQ31_A @S9S_MB_2U_LIB.S9S_MB_2U(SCH_1):M_B_CPU0_SA_DQ(31)

Q_CAP_C0402-2.2UF,6.3V,20%,X6SA  I121  C11
   1 P3V3_AUX      A @S9S_MB_2U_LIB.S9S_MB_2U(SCH_1):P3V3_AUX
   2    GND      B @S9S_MB_2U_LIB.S9S_MB_2U(SCH_1):GND

Q_CAP_C0805-10UF,16V,10%,X6S,CA  I125  C12
   1 P12V_S3_AUX_CPU0_NVDIMM      A @S9S_MB_2U_LIB.S9S_MB_2U(SCH_1):P12V_S3_AUX_CPU0_NVDIMM
   2    GND      B @S9S_MB_2U_LIB.S9S_MB_2U(SCH_1):GND

Q_CAP_C0805-10UF,16V,10%,X6S,CA  I127  C13
   1 P12V_S3_AUX_CPU0_NVDIMM      A @S9S_MB_2U_LIB.S9S_MB_2U(SCH_1):P12V_S3_AUX_CPU0_NVDIMM
   2    GND      B @S9S_MB_2U_LIB.S9S_MB_2U(SCH_1):GND

SCONN288_ADR50017P087CC-SCONN2A  I174  J4
   6    GND   VSS0 @S9S_MB_2U_LIB.S9S_MB_2U(SCH_1):GND
   8    GND   VSS1 @S9S_MB_2U_LIB.S9S_MB_2U(SCH_1):GND
  10    GND   VSS2 @S9S_MB_2U_LIB.S9S_MB_2U(SCH_1):GND
  13    GND   VSS3 @S9S_MB_2U_LIB.S9S_MB_2U(SCH_1):GND
  15    GND   VSS4 @S9S_MB_2U_LIB.S9S_MB_2U(SCH_1):GND
  17    GND   VSS5 @S9S_MB_2U_LIB.S9S_MB_2U(SCH_1):GND
  19    GND   VSS6 @S9S_MB_2U_LIB.S9S_MB_2U(SCH_1):GND
  21    GND   VSS7 @S9S_MB_2U_LIB.S9S_MB_2U(SCH_1):GND
  24    GND   VSS8 @S9S_MB_2U_LIB.S9S_MB_2U(SCH_1):GND
  26    GND   VSS9 @S9S_MB_2U_LIB.S9S_MB_2U(SCH_1):GND
  28    GND  VSS10 @S9S_MB_2U_LIB.S9S_MB_2U(SCH_1):GND
  30    GND  VSS11 @S9S_MB_2U_LIB.S9S_MB_2U(SCH_1):GND
  32    GND  VSS12 @S9S_MB_2U_LIB.S9S_MB_2U(SCH_1):GND
  35    GND  VSS13 @S9S_MB_2U_LIB.S9S_MB_2U(SCH_1):GND
  37    GND  VSS14 @S9S_MB_2U_LIB.S9S_MB_2U(SCH_1):GND
  39    GND  VSS15 @S9S_MB_2U_LIB.S9S_MB_2U(SCH_1):GND
  41    GND  VSS16 @S9S_MB_2U_LIB.S9S_MB_2U(SCH_1):GND
  43    GND  VSS17 @S9S_MB_2U_LIB.S9S_MB_2U(SCH_1):GND
  46    GND  VSS18 @S9S_MB_2U_LIB.S9S_MB_2U(SCH_1):GND
  48    GND  VSS19 @S9S_MB_2U_LIB.S9S_MB_2U(SCH_1):GND
  50    GND  VSS20 @S9S_MB_2U_LIB.S9S_MB_2U(SCH_1):GND
  52    GND  VSS21 @S9S_MB_2U_LIB.S9S_MB_2U(SCH_1):GND
  54    GND  VSS22 @S9S_MB_2U_LIB.S9S_MB_2U(SCH_1):GND
  57    GND  VSS23 @S9S_MB_2U_LIB.S9S_MB_2U(SCH_1):GND
  59    GND  VSS24 @S9S_MB_2U_LIB.S9S_MB_2U(SCH_1):GND
  61    GND  VSS25 @S9S_MB_2U_LIB.S9S_MB_2U(SCH_1):GND
  63    GND  VSS26 @S9S_MB_2U_LIB.S9S_MB_2U(SCH_1):GND
  65    GND  VSS27 @S9S_MB_2U_LIB.S9S_MB_2U(SCH_1):GND
  67    GND  VSS28 @S9S_MB_2U_LIB.S9S_MB_2U(SCH_1):GND
  69    GND  VSS29 @S9S_MB_2U_LIB.S9S_MB_2U(SCH_1):GND
  71    GND  VSS30 @S9S_MB_2U_LIB.S9S_MB_2U(SCH_1):GND
  73    GND  VSS31 @S9S_MB_2U_LIB.S9S_MB_2U(SCH_1):GND
  75    GND  VSS32 @S9S_MB_2U_LIB.S9S_MB_2U(SCH_1):GND
  77    GND  VSS33 @S9S_MB_2U_LIB.S9S_MB_2U(SCH_1):GND
  79    GND  VSS34 @S9S_MB_2U_LIB.S9S_MB_2U(SCH_1):GND
  81    GND  VSS35 @S9S_MB_2U_LIB.S9S_MB_2U(SCH_1):GND
  83    GND  VSS36 @S9S_MB_2U_LIB.S9S_MB_2U(SCH_1):GND
  85    GND  VSS37 @S9S_MB_2U_LIB.S9S_MB_2U(SCH_1):GND
  88    GND  VSS38 @S9S_MB_2U_LIB.S9S_MB_2U(SCH_1):GND
  90    GND  VSS39 @S9S_MB_2U_LIB.S9S_MB_2U(SCH_1):GND
  92    GND  VSS40 @S9S_MB_2U_LIB.S9S_MB_2U(SCH_1):GND
  95    GND  VSS41 @S9S_MB_2U_LIB.S9S_MB_2U(SCH_1):GND
  97    GND  VSS42 @S9S_MB_2U_LIB.S9S_MB_2U(SCH_1):GND
  99    GND  VSS43 @S9S_MB_2U_LIB.S9S_MB_2U(SCH_1):GND
 101    GND  VSS44 @S9S_MB_2U_LIB.S9S_MB_2U(SCH_1):GND
 103    GND  VSS45 @S9S_MB_2U_LIB.S9S_MB_2U(SCH_1):GND
 106    GND  VSS46 @S9S_MB_2U_LIB.S9S_MB_2U(SCH_1):GND
 108    GND  VSS47 @S9S_MB_2U_LIB.S9S_MB_2U(SCH_1):GND
 110    GND  VSS48 @S9S_MB_2U_LIB.S9S_MB_2U(SCH_1):GND
 112    GND  VSS49 @S9S_MB_2U_LIB.S9S_MB_2U(SCH_1):GND
 114    GND  VSS50 @S9S_MB_2U_LIB.S9S_MB_2U(SCH_1):GND
 117    GND  VSS51 @S9S_MB_2U_LIB.S9S_MB_2U(SCH_1):GND
 119    GND  VSS52 @S9S_MB_2U_LIB.S9S_MB_2U(SCH_1):GND
 121    GND  VSS53 @S9S_MB_2U_LIB.S9S_MB_2U(SCH_1):GND
 123    GND  VSS54 @S9S_MB_2U_LIB.S9S_MB_2U(SCH_1):GND
 125    GND  VSS55 @S9S_MB_2U_LIB.S9S_MB_2U(SCH_1):GND
 128    GND  VSS56 @S9S_MB_2U_LIB.S9S_MB_2U(SCH_1):GND
 130    GND  VSS57 @S9S_MB_2U_LIB.S9S_MB_2U(SCH_1):GND
 134    GND  VSS59 @S9S_MB_2U_LIB.S9S_MB_2U(SCH_1):GND
 143    GND  VSS63 @S9S_MB_2U_LIB.S9S_MB_2U(SCH_1):GND
 151    GND  VSS64 @S9S_MB_2U_LIB.S9S_MB_2U(SCH_1):GND
 153    GND  VSS65 @S9S_MB_2U_LIB.S9S_MB_2U(SCH_1):GND
 155    GND  VSS66 @S9S_MB_2U_LIB.S9S_MB_2U(SCH_1):GND
 158    GND  VSS67 @S9S_MB_2U_LIB.S9S_MB_2U(SCH_1):GND
 160    GND  VSS68 @S9S_MB_2U_LIB.S9S_MB_2U(SCH_1):GND
 162    GND  VSS69 @S9S_MB_2U_LIB.S9S_MB_2U(SCH_1):GND
 164    GND  VSS70 @S9S_MB_2U_LIB.S9S_MB_2U(SCH_1):GND
 166    GND  VSS71 @S9S_MB_2U_LIB.S9S_MB_2U(SCH_1):GND
 169    GND  VSS72 @S9S_MB_2U_LIB.S9S_MB_2U(SCH_1):GND
 171    GND  VSS73 @S9S_MB_2U_LIB.S9S_MB_2U(SCH_1):GND
 173    GND  VSS74 @S9S_MB_2U_LIB.S9S_MB_2U(SCH_1):GND
 175    GND  VSS75 @S9S_MB_2U_LIB.S9S_MB_2U(SCH_1):GND
 177    GND  VSS76 @S9S_MB_2U_LIB.S9S_MB_2U(SCH_1):GND
 180    GND  VSS77 @S9S_MB_2U_LIB.S9S_MB_2U(SCH_1):GND
 182    GND  VSS78 @S9S_MB_2U_LIB.S9S_MB_2U(SCH_1):GND
 184    GND  VSS79 @S9S_MB_2U_LIB.S9S_MB_2U(SCH_1):GND
 186    GND  VSS80 @S9S_MB_2U_LIB.S9S_MB_2U(SCH_1):GND
 188    GND  VSS81 @S9S_MB_2U_LIB.S9S_MB_2U(SCH_1):GND
 191    GND  VSS82 @S9S_MB_2U_LIB.S9S_MB_2U(SCH_1):GND
 193    GND  VSS83 @S9S_MB_2U_LIB.S9S_MB_2U(SCH_1):GND
 195    GND  VSS84 @S9S_MB_2U_LIB.S9S_MB_2U(SCH_1):GND
 197    GND  VSS85 @S9S_MB_2U_LIB.S9S_MB_2U(SCH_1):GND
 199    GND  VSS86 @S9S_MB_2U_LIB.S9S_MB_2U(SCH_1):GND
 202    GND  VSS87 @S9S_MB_2U_LIB.S9S_MB_2U(SCH_1):GND
 204    GND  VSS88 @S9S_MB_2U_LIB.S9S_MB_2U(SCH_1):GND
 206    GND  VSS89 @S9S_MB_2U_LIB.S9S_MB_2U(SCH_1):GND
 208    GND  VSS90 @S9S_MB_2U_LIB.S9S_MB_2U(SCH_1):GND
 210    GND  VSS91 @S9S_MB_2U_LIB.S9S_MB_2U(SCH_1):GND
 212    GND  VSS92 @S9S_MB_2U_LIB.S9S_MB_2U(SCH_1):GND
 214    GND  VSS93 @S9S_MB_2U_LIB.S9S_MB_2U(SCH_1):GND
 216    GND  VSS94 @S9S_MB_2U_LIB.S9S_MB_2U(SCH_1):GND
 219    GND  VSS95 @S9S_MB_2U_LIB.S9S_MB_2U(SCH_1):GND
 222    GND  VSS96 @S9S_MB_2U_LIB.S9S_MB_2U(SCH_1):GND
 224    GND  VSS97 @S9S_MB_2U_LIB.S9S_MB_2U(SCH_1):GND
 226    GND  VSS98 @S9S_MB_2U_LIB.S9S_MB_2U(SCH_1):GND
 228    GND  VSS99 @S9S_MB_2U_LIB.S9S_MB_2U(SCH_1):GND
 233    GND VSS101 @S9S_MB_2U_LIB.S9S_MB_2U(SCH_1):GND
 237    GND VSS103 @S9S_MB_2U_LIB.S9S_MB_2U(SCH_1):GND
 242    GND VSS105 @S9S_MB_2U_LIB.S9S_MB_2U(SCH_1):GND
 244    GND VSS106 @S9S_MB_2U_LIB.S9S_MB_2U(SCH_1):GND
 246    GND VSS107 @S9S_MB_2U_LIB.S9S_MB_2U(SCH_1):GND
 248    GND VSS108 @S9S_MB_2U_LIB.S9S_MB_2U(SCH_1):GND
 251    GND VSS109 @S9S_MB_2U_LIB.S9S_MB_2U(SCH_1):GND
 253    GND VSS110 @S9S_MB_2U_LIB.S9S_MB_2U(SCH_1):GND
 255    GND VSS111 @S9S_MB_2U_LIB.S9S_MB_2U(SCH_1):GND
 257    GND VSS112 @S9S_MB_2U_LIB.S9S_MB_2U(SCH_1):GND
 259    GND VSS113 @S9S_MB_2U_LIB.S9S_MB_2U(SCH_1):GND
 262    GND VSS114 @S9S_MB_2U_LIB.S9S_MB_2U(SCH_1):GND
 264    GND VSS115 @S9S_MB_2U_LIB.S9S_MB_2U(SCH_1):GND
 266    GND VSS116 @S9S_MB_2U_LIB.S9S_MB_2U(SCH_1):GND
 268    GND VSS117 @S9S_MB_2U_LIB.S9S_MB_2U(SCH_1):GND
 270    GND VSS118 @S9S_MB_2U_LIB.S9S_MB_2U(SCH_1):GND
 273    GND VSS119 @S9S_MB_2U_LIB.S9S_MB_2U(SCH_1):GND
 275    GND VSS120 @S9S_MB_2U_LIB.S9S_MB_2U(SCH_1):GND
 277    GND VSS121 @S9S_MB_2U_LIB.S9S_MB_2U(SCH_1):GND
 279    GND VSS122 @S9S_MB_2U_LIB.S9S_MB_2U(SCH_1):GND
 281    GND VSS123 @S9S_MB_2U_LIB.S9S_MB_2U(SCH_1):GND
 284    GND VSS124 @S9S_MB_2U_LIB.S9S_MB_2U(SCH_1):GND
 286    GND VSS125 @S9S_MB_2U_LIB.S9S_MB_2U(SCH_1):GND
 288    GND VSS126 @S9S_MB_2U_LIB.S9S_MB_2U(SCH_1):GND
   1 P12V_S3_AUX_CPU0_NVDIMM VIN_BULK0 @S9S_MB_2U_LIB.S9S_MB_2U(SCH_1):P12V_S3_AUX_CPU0_NVDIMM
 145 P12V_S3_AUX_CPU0_NVDIMM VIN_BULK1 @S9S_MB_2U_LIB.S9S_MB_2U(SCH_1):P12V_S3_AUX_CPU0_NVDIMM
 146 P12V_S3_AUX_CPU0_NVDIMM VIN_BULK2 @S9S_MB_2U_LIB.S9S_MB_2U(SCH_1):P12V_S3_AUX_CPU0_NVDIMM
 230    GND VSS100 @S9S_MB_2U_LIB.S9S_MB_2U(SCH_1):GND
 235    GND VSS102 @S9S_MB_2U_LIB.S9S_MB_2U(SCH_1):GND
 240    GND VSS104 @S9S_MB_2U_LIB.S9S_MB_2U(SCH_1):GND
 132    GND  VSS58 @S9S_MB_2U_LIB.S9S_MB_2U(SCH_1):GND
 136    GND  VSS60 @S9S_MB_2U_LIB.S9S_MB_2U(SCH_1):GND
 139    GND  VSS61 @S9S_MB_2U_LIB.S9S_MB_2U(SCH_1):GND
 141    GND  VSS62 @S9S_MB_2U_LIB.S9S_MB_2U(SCH_1):GND
  G1    GND     G1 @S9S_MB_2U_LIB.S9S_MB_2U(SCH_1):GND
  G2    GND     G2 @S9S_MB_2U_LIB.S9S_MB_2U(SCH_1):GND
  G3    GND     G3 @S9S_MB_2U_LIB.S9S_MB_2U(SCH_1):GND

SCONN288_ADR50017P087CC-SCONN2A  I178  J4
  93 M_B_CPU0_SB_DQS_DP<9> DQS9_B_T||TDQS9_B_T||DBI4_B_N @S9S_MB_2U_LIB.S9S_MB_2U(SCH_1):M_B_CPU0_SB_DQS_DP(9)
  94 M_B_CPU0_SB_DQS_DN<9> DQS9_B_C||TDQS9_B_C @S9S_MB_2U_LIB.S9S_MB_2U(SCH_1):M_B_CPU0_SB_DQS_DN(9)
 201 M_B_CPU0_SA_DQS_DP<9> DQS9_A_T||TDQS9_A_T @S9S_MB_2U_LIB.S9S_MB_2U(SCH_1):M_B_CPU0_SA_DQS_DP(9)
 200 M_B_CPU0_SA_DQS_DN<9> DQS9_A_C||TDQS9_A_C @S9S_MB_2U_LIB.S9S_MB_2U(SCH_1):M_B_CPU0_SA_DQS_DN(9)
 190 M_B_CPU0_SA_DQS_DP<8> DQS8_A_T||TDQS8_A_T @S9S_MB_2U_LIB.S9S_MB_2U(SCH_1):M_B_CPU0_SA_DQS_DP(8)
 189 M_B_CPU0_SA_DQS_DN<8> DQS8_A_C||TDQS8_A_C @S9S_MB_2U_LIB.S9S_MB_2U(SCH_1):M_B_CPU0_SA_DQS_DN(8)
 271 M_B_CPU0_SB_DQS_DN<7> DQS7_B_C||TDQS7_B_C @S9S_MB_2U_LIB.S9S_MB_2U(SCH_1):M_B_CPU0_SB_DQS_DN(7)
 179 M_B_CPU0_SA_DQS_DP<7> DQS7_A_T||TDQS7_A_T @S9S_MB_2U_LIB.S9S_MB_2U(SCH_1):M_B_CPU0_SA_DQS_DP(7)
 261 M_B_CPU0_SB_DQS_DP<6> DQS6_B_T||TDQS6_B_T @S9S_MB_2U_LIB.S9S_MB_2U(SCH_1):M_B_CPU0_SB_DQS_DP(6)
 260 M_B_CPU0_SB_DQS_DN<6> DQS6_B_C||TDQS6_B_C @S9S_MB_2U_LIB.S9S_MB_2U(SCH_1):M_B_CPU0_SB_DQS_DN(6)
 167 M_B_CPU0_SA_DQS_DN<6> DQS6_A_C||TDQS6_A_C||DQS6_A_T||TDQS6_A_T @S9S_MB_2U_LIB.S9S_MB_2U(SCH_1):M_B_CPU0_SA_DQS_DN(6)
 250 M_B_CPU0_SB_DQS_DP<5> DQS5_B_T||TDQS5_B_T @S9S_MB_2U_LIB.S9S_MB_2U(SCH_1):M_B_CPU0_SB_DQS_DP(5)
 249 M_B_CPU0_SB_DQS_DN<5> DQS5_B_C||TDQS5_B_C @S9S_MB_2U_LIB.S9S_MB_2U(SCH_1):M_B_CPU0_SB_DQS_DN(5)
 157 M_B_CPU0_SA_DQS_DP<5> DQS5_A_T||TDQS5_A_T @S9S_MB_2U_LIB.S9S_MB_2U(SCH_1):M_B_CPU0_SA_DQS_DP(5)
 156 M_B_CPU0_SA_DQS_DN<5> DQS5_A_C||TDQS5_A_C||DQS5_A_T||TDQS5_A_T @S9S_MB_2U_LIB.S9S_MB_2U(SCH_1):M_B_CPU0_SA_DQS_DN(5)
 239 M_B_CPU0_SB_DQS_DP<4> DQS4_B_T @S9S_MB_2U_LIB.S9S_MB_2U(SCH_1):M_B_CPU0_SB_DQS_DP(4)
 238 M_B_CPU0_SB_DQS_DN<4> DQS4_B_C @S9S_MB_2U_LIB.S9S_MB_2U(SCH_1):M_B_CPU0_SB_DQS_DN(4)
  55 M_B_CPU0_SA_DQS_DP<4> DQS4_A_T @S9S_MB_2U_LIB.S9S_MB_2U(SCH_1):M_B_CPU0_SA_DQS_DP(4)
  56 M_B_CPU0_SA_DQS_DN<4> DQS4_A_C @S9S_MB_2U_LIB.S9S_MB_2U(SCH_1):M_B_CPU0_SA_DQS_DN(4)
 137 M_B_CPU0_SB_DQS_DP<3> DQS3_B_T @S9S_MB_2U_LIB.S9S_MB_2U(SCH_1):M_B_CPU0_SB_DQS_DP(3)
 138 M_B_CPU0_SB_DQS_DN<3> DQS3_B_C @S9S_MB_2U_LIB.S9S_MB_2U(SCH_1):M_B_CPU0_SB_DQS_DN(3)
  44 M_B_CPU0_SA_DQS_DP<3> DQS3_A_T @S9S_MB_2U_LIB.S9S_MB_2U(SCH_1):M_B_CPU0_SA_DQS_DP(3)
  45 M_B_CPU0_SA_DQS_DN<3> DQS3_A_C @S9S_MB_2U_LIB.S9S_MB_2U(SCH_1):M_B_CPU0_SA_DQS_DN(3)
 126 M_B_CPU0_SB_DQS_DP<2> DQS2_B_T @S9S_MB_2U_LIB.S9S_MB_2U(SCH_1):M_B_CPU0_SB_DQS_DP(2)
 127 M_B_CPU0_SB_DQS_DN<2> DQS2_B_C @S9S_MB_2U_LIB.S9S_MB_2U(SCH_1):M_B_CPU0_SB_DQS_DN(2)
  33 M_B_CPU0_SA_DQS_DP<2> DQS2_A_T @S9S_MB_2U_LIB.S9S_MB_2U(SCH_1):M_B_CPU0_SA_DQS_DP(2)
  34 M_B_CPU0_SA_DQS_DN<2> DQS2_A_C @S9S_MB_2U_LIB.S9S_MB_2U(SCH_1):M_B_CPU0_SA_DQS_DN(2)
 115 M_B_CPU0_SB_DQS_DP<1> DQS1_B_T @S9S_MB_2U_LIB.S9S_MB_2U(SCH_1):M_B_CPU0_SB_DQS_DP(1)
 116 M_B_CPU0_SB_DQS_DN<1> DQS1_B_C @S9S_MB_2U_LIB.S9S_MB_2U(SCH_1):M_B_CPU0_SB_DQS_DN(1)
  22 M_B_CPU0_SA_DQS_DP<1> DQS1_A_T @S9S_MB_2U_LIB.S9S_MB_2U(SCH_1):M_B_CPU0_SA_DQS_DP(1)
  23 M_B_CPU0_SA_DQS_DN<1> DQS1_A_C @S9S_MB_2U_LIB.S9S_MB_2U(SCH_1):M_B_CPU0_SA_DQS_DN(1)
 104 M_B_CPU0_SB_DQS_DP<0> DQS0_B_T @S9S_MB_2U_LIB.S9S_MB_2U(SCH_1):M_B_CPU0_SB_DQS_DP(0)
 105 M_B_CPU0_SB_DQS_DN<0> DQS0_B_C @S9S_MB_2U_LIB.S9S_MB_2U(SCH_1):M_B_CPU0_SB_DQS_DN(0)
  11 M_B_CPU0_SA_DQS_DP<0> DQS0_A_T @S9S_MB_2U_LIB.S9S_MB_2U(SCH_1):M_B_CPU0_SA_DQS_DP(0)
  12 M_B_CPU0_SA_DQS_DN<0> DQS0_A_C @S9S_MB_2U_LIB.S9S_MB_2U(SCH_1):M_B_CPU0_SA_DQS_DN(0)
 272 M_B_CPU0_SB_DQS_DP<7> DQS7_B_T||TDQS7_B_T @S9S_MB_2U_LIB.S9S_MB_2U(SCH_1):M_B_CPU0_SB_DQS_DP(7)
 282 M_B_CPU0_SB_DQS_DN<8> DQS8_B_C||TDQS8_B_C @S9S_MB_2U_LIB.S9S_MB_2U(SCH_1):M_B_CPU0_SB_DQS_DN(8)
 283 M_B_CPU0_SB_DQS_DP<8> DQS8_B_T||TDQS8_B_T @S9S_MB_2U_LIB.S9S_MB_2U(SCH_1):M_B_CPU0_SB_DQS_DP(8)
 168 M_B_CPU0_SA_DQS_DP<6> DQS6_A_T||TDQS6_A_T @S9S_MB_2U_LIB.S9S_MB_2U(SCH_1):M_B_CPU0_SA_DQS_DP(6)
 178 M_B_CPU0_SA_DQS_DN<7> DQS7_A_C||TDQS7_A_C @S9S_MB_2U_LIB.S9S_MB_2U(SCH_1):M_B_CPU0_SA_DQS_DN(7)

Q_RES_0402LF-49.9,1%,1/16W,CHIA  I180  R3878
   1 I3C_SPD_DDRABCD_CPU0_LVC1_SCL_3      A @S9S_MB_2U_LIB.S9S_MB_2U(SCH_1):I3C_SPD_DDRABCD_CPU0_LVC1_SCL_R4
   2 I3C_SPD_DDRABCD_CPU0_LVC1_SCL      B @S9S_MB_2U_LIB.S9S_MB_2U(SCH_1):I3C_SPD_DDRABCD_CPU0_LVC1_SCL


DRAWING: @S9S_MB_2U_LIB.S9S_MB_2U(SCH_1):PAGE86 

Q_RES_0402LF-54.9K,1%,1/16W,CHA  I3  R30
   1 PD_CHC_CPU0_DIMM1_SAA      A @S9S_MB_2U_LIB.S9S_MB_2U(SCH_1):PD_CHC_CPU0_DIMM1_SAA
   2    GND      B @S9S_MB_2U_LIB.S9S_MB_2U(SCH_1):GND

SCONN288_ADR50017P130CC-SCONN2A  I24  J5
   3 P3V3_AUX VIN_MGMT @S9S_MB_2U_LIB.S9S_MB_2U(SCH_1):P3V3_AUX
   2 TP_CHC_CPU0_DIMM1_FRU_0   RFU0 @S9S_MB_2U_LIB.S9S_MB_2U(SCH_1):TP_CHC_CPU0_DIMM1_FRU_0
 144 TP_CHC_CPU0_DIMM1_FRU_1   RFU1 @S9S_MB_2U_LIB.S9S_MB_2U(SCH_1):TP_CHC_CPU0_DIMM1_FRU_1
 149 TP_CHC_CPU0_DIMM1_FRU_2   RFU2 @S9S_MB_2U_LIB.S9S_MB_2U(SCH_1):TP_CHC_CPU0_DIMM1_FRU_2
 150 TP_CHC_CPU0_DIMM1_FRU_3   RFU3 @S9S_MB_2U_LIB.S9S_MB_2U(SCH_1):TP_CHC_CPU0_DIMM1_FRU_3
 220 TP_CHC_CPU0_DIMM1_FRU_4   RFU4 @S9S_MB_2U_LIB.S9S_MB_2U(SCH_1):TP_CHC_CPU0_DIMM1_FRU_4
 231 TP_CHC_CPU0_DIMM1_FRU_5   RFU5 @S9S_MB_2U_LIB.S9S_MB_2U(SCH_1):TP_CHC_CPU0_DIMM1_FRU_5
 232 TP_CHC_CPU0_DIMM1_FRU_6   RFU6 @S9S_MB_2U_LIB.S9S_MB_2U(SCH_1):TP_CHC_CPU0_DIMM1_FRU_6
 207 RST_M_CD_CPU0_FPGA_N RESET_N @S9S_MB_2U_LIB.S9S_MB_2U(SCH_1):RST_M_CD_CPU0_FPGA_N
 147 PWRGD_CHC_CPU0_DIMM1 PWR_GOOD||FAIL_N @S9S_MB_2U_LIB.S9S_MB_2U(SCH_1):PWRGD_CHC_CPU0_DIMM1
 227 M_C_CPU0_SB_PAR  PAR_B @S9S_MB_2U_LIB.S9S_MB_2U(SCH_1):M_C_CPU0_SB_PAR
  74 M_C_CPU0_SA_PAR  PAR_A @S9S_MB_2U_LIB.S9S_MB_2U(SCH_1):M_C_CPU0_SA_PAR
  87 M_C_CPU0_SB_RSP<0> LBS||RSP_B_N @S9S_MB_2U_LIB.S9S_MB_2U(SCH_1):M_C_CPU0_SB_RSP(0)
  86 M_C_CPU0_SA_RSP<0> LBD||RSP_A_N @S9S_MB_2U_LIB.S9S_MB_2U(SCH_1):M_C_CPU0_SA_RSP(0)
   5 I3C_SPD_DDRABCD_CPU0_LVC1_SDA   HSDA @S9S_MB_2U_LIB.S9S_MB_2U(SCH_1):I3C_SPD_DDRABCD_CPU0_LVC1_SDA
   4 I3C_SPD_DDRABCD_CPU0_LVC1_SCL_4   HSCL @S9S_MB_2U_LIB.S9S_MB_2U(SCH_1):I3C_SPD_DDRABCD_CPU0_LVC1_SCL_R5
 148 PD_CHC_CPU0_DIMM1_SAA    HSA @S9S_MB_2U_LIB.S9S_MB_2U(SCH_1):PD_CHC_CPU0_DIMM1_SAA
 100 M_C_CPU0_SB_DQ<0>  DQ0_B @S9S_MB_2U_LIB.S9S_MB_2U(SCH_1):M_C_CPU0_SB_DQ(0)
 102 M_C_CPU0_SB_DQ<1>  DQ1_B @S9S_MB_2U_LIB.S9S_MB_2U(SCH_1):M_C_CPU0_SB_DQ(1)
 245 M_C_CPU0_SB_DQ<2>  DQ2_B @S9S_MB_2U_LIB.S9S_MB_2U(SCH_1):M_C_CPU0_SB_DQ(2)
 247 M_C_CPU0_SB_DQ<3>  DQ3_B @S9S_MB_2U_LIB.S9S_MB_2U(SCH_1):M_C_CPU0_SB_DQ(3)
 107 M_C_CPU0_SB_DQ<4>  DQ4_B @S9S_MB_2U_LIB.S9S_MB_2U(SCH_1):M_C_CPU0_SB_DQ(4)
 109 M_C_CPU0_SB_DQ<5>  DQ5_B @S9S_MB_2U_LIB.S9S_MB_2U(SCH_1):M_C_CPU0_SB_DQ(5)
 252 M_C_CPU0_SB_DQ<6>  DQ6_B @S9S_MB_2U_LIB.S9S_MB_2U(SCH_1):M_C_CPU0_SB_DQ(6)
 254 M_C_CPU0_SB_DQ<7>  DQ7_B @S9S_MB_2U_LIB.S9S_MB_2U(SCH_1):M_C_CPU0_SB_DQ(7)
 111 M_C_CPU0_SB_DQ<8>  DQ8_B @S9S_MB_2U_LIB.S9S_MB_2U(SCH_1):M_C_CPU0_SB_DQ(8)
 113 M_C_CPU0_SB_DQ<9>  DQ9_B @S9S_MB_2U_LIB.S9S_MB_2U(SCH_1):M_C_CPU0_SB_DQ(9)
 256 M_C_CPU0_SB_DQ<10> DQ10_B @S9S_MB_2U_LIB.S9S_MB_2U(SCH_1):M_C_CPU0_SB_DQ(10)
 258 M_C_CPU0_SB_DQ<11> DQ11_B @S9S_MB_2U_LIB.S9S_MB_2U(SCH_1):M_C_CPU0_SB_DQ(11)
 118 M_C_CPU0_SB_DQ<12> DQ12_B @S9S_MB_2U_LIB.S9S_MB_2U(SCH_1):M_C_CPU0_SB_DQ(12)
 120 M_C_CPU0_SB_DQ<13> DQ13_B @S9S_MB_2U_LIB.S9S_MB_2U(SCH_1):M_C_CPU0_SB_DQ(13)
 263 M_C_CPU0_SB_DQ<14> DQ14_B @S9S_MB_2U_LIB.S9S_MB_2U(SCH_1):M_C_CPU0_SB_DQ(14)
 265 M_C_CPU0_SB_DQ<15> DQ15_B @S9S_MB_2U_LIB.S9S_MB_2U(SCH_1):M_C_CPU0_SB_DQ(15)
 122 M_C_CPU0_SB_DQ<16> DQ16_B @S9S_MB_2U_LIB.S9S_MB_2U(SCH_1):M_C_CPU0_SB_DQ(16)
 124 M_C_CPU0_SB_DQ<17> DQ17_B @S9S_MB_2U_LIB.S9S_MB_2U(SCH_1):M_C_CPU0_SB_DQ(17)
 267 M_C_CPU0_SB_DQ<18> DQ18_B @S9S_MB_2U_LIB.S9S_MB_2U(SCH_1):M_C_CPU0_SB_DQ(18)
 269 M_C_CPU0_SB_DQ<19> DQ19_B @S9S_MB_2U_LIB.S9S_MB_2U(SCH_1):M_C_CPU0_SB_DQ(19)
 129 M_C_CPU0_SB_DQ<20> DQ20_B @S9S_MB_2U_LIB.S9S_MB_2U(SCH_1):M_C_CPU0_SB_DQ(20)
 131 M_C_CPU0_SB_DQ<21> DQ21_B @S9S_MB_2U_LIB.S9S_MB_2U(SCH_1):M_C_CPU0_SB_DQ(21)
 274 M_C_CPU0_SB_DQ<22> DQ22_B @S9S_MB_2U_LIB.S9S_MB_2U(SCH_1):M_C_CPU0_SB_DQ(22)
 276 M_C_CPU0_SB_DQ<23> DQ23_B @S9S_MB_2U_LIB.S9S_MB_2U(SCH_1):M_C_CPU0_SB_DQ(23)
 133 M_C_CPU0_SB_DQ<24> DQ24_B @S9S_MB_2U_LIB.S9S_MB_2U(SCH_1):M_C_CPU0_SB_DQ(24)
 135 M_C_CPU0_SB_DQ<25> DQ25_B @S9S_MB_2U_LIB.S9S_MB_2U(SCH_1):M_C_CPU0_SB_DQ(25)
 278 M_C_CPU0_SB_DQ<26> DQ26_B @S9S_MB_2U_LIB.S9S_MB_2U(SCH_1):M_C_CPU0_SB_DQ(26)
 280 M_C_CPU0_SB_DQ<27> DQ27_B @S9S_MB_2U_LIB.S9S_MB_2U(SCH_1):M_C_CPU0_SB_DQ(27)
 140 M_C_CPU0_SB_DQ<28> DQ28_B @S9S_MB_2U_LIB.S9S_MB_2U(SCH_1):M_C_CPU0_SB_DQ(28)
 142 M_C_CPU0_SB_DQ<29> DQ29_B @S9S_MB_2U_LIB.S9S_MB_2U(SCH_1):M_C_CPU0_SB_DQ(29)
 285 M_C_CPU0_SB_DQ<30> DQ30_B @S9S_MB_2U_LIB.S9S_MB_2U(SCH_1):M_C_CPU0_SB_DQ(30)
 287 M_C_CPU0_SB_DQ<31> DQ31_B @S9S_MB_2U_LIB.S9S_MB_2U(SCH_1):M_C_CPU0_SB_DQ(31)
   7 M_C_CPU0_SA_DQ<0>  DQ0_A @S9S_MB_2U_LIB.S9S_MB_2U(SCH_1):M_C_CPU0_SA_DQ(0)
   9 M_C_CPU0_SA_DQ<1>  DQ1_A @S9S_MB_2U_LIB.S9S_MB_2U(SCH_1):M_C_CPU0_SA_DQ(1)
 152 M_C_CPU0_SA_DQ<2>  DQ2_A @S9S_MB_2U_LIB.S9S_MB_2U(SCH_1):M_C_CPU0_SA_DQ(2)
 154 M_C_CPU0_SA_DQ<3>  DQ3_A @S9S_MB_2U_LIB.S9S_MB_2U(SCH_1):M_C_CPU0_SA_DQ(3)
  14 M_C_CPU0_SA_DQ<4>  DQ4_A @S9S_MB_2U_LIB.S9S_MB_2U(SCH_1):M_C_CPU0_SA_DQ(4)
  16 M_C_CPU0_SA_DQ<5>  DQ5_A @S9S_MB_2U_LIB.S9S_MB_2U(SCH_1):M_C_CPU0_SA_DQ(5)
 159 M_C_CPU0_SA_DQ<6>  DQ6_A @S9S_MB_2U_LIB.S9S_MB_2U(SCH_1):M_C_CPU0_SA_DQ(6)
 161 M_C_CPU0_SA_DQ<7>  DQ7_A @S9S_MB_2U_LIB.S9S_MB_2U(SCH_1):M_C_CPU0_SA_DQ(7)
  18 M_C_CPU0_SA_DQ<8>  DQ8_A @S9S_MB_2U_LIB.S9S_MB_2U(SCH_1):M_C_CPU0_SA_DQ(8)
  20 M_C_CPU0_SA_DQ<9>  DQ9_A @S9S_MB_2U_LIB.S9S_MB_2U(SCH_1):M_C_CPU0_SA_DQ(9)
 163 M_C_CPU0_SA_DQ<10> DQ10_A @S9S_MB_2U_LIB.S9S_MB_2U(SCH_1):M_C_CPU0_SA_DQ(10)
 165 M_C_CPU0_SA_DQ<11> DQ11_A @S9S_MB_2U_LIB.S9S_MB_2U(SCH_1):M_C_CPU0_SA_DQ(11)
  25 M_C_CPU0_SA_DQ<12> DQ12_A @S9S_MB_2U_LIB.S9S_MB_2U(SCH_1):M_C_CPU0_SA_DQ(12)
  27 M_C_CPU0_SA_DQ<13> DQ13_A @S9S_MB_2U_LIB.S9S_MB_2U(SCH_1):M_C_CPU0_SA_DQ(13)
 170 M_C_CPU0_SA_DQ<14> DQ14_A @S9S_MB_2U_LIB.S9S_MB_2U(SCH_1):M_C_CPU0_SA_DQ(14)
 172 M_C_CPU0_SA_DQ<15> DQ15_A @S9S_MB_2U_LIB.S9S_MB_2U(SCH_1):M_C_CPU0_SA_DQ(15)
  29 M_C_CPU0_SA_DQ<16> DQ16_A @S9S_MB_2U_LIB.S9S_MB_2U(SCH_1):M_C_CPU0_SA_DQ(16)
  31 M_C_CPU0_SA_DQ<17> DQ17_A @S9S_MB_2U_LIB.S9S_MB_2U(SCH_1):M_C_CPU0_SA_DQ(17)
 174 M_C_CPU0_SA_DQ<18> DQ18_A @S9S_MB_2U_LIB.S9S_MB_2U(SCH_1):M_C_CPU0_SA_DQ(18)
 176 M_C_CPU0_SA_DQ<19> DQ19_A @S9S_MB_2U_LIB.S9S_MB_2U(SCH_1):M_C_CPU0_SA_DQ(19)
  36 M_C_CPU0_SA_DQ<20> DQ20_A @S9S_MB_2U_LIB.S9S_MB_2U(SCH_1):M_C_CPU0_SA_DQ(20)
  38 M_C_CPU0_SA_DQ<21> DQ21_A @S9S_MB_2U_LIB.S9S_MB_2U(SCH_1):M_C_CPU0_SA_DQ(21)
 181 M_C_CPU0_SA_DQ<22> DQ22_A @S9S_MB_2U_LIB.S9S_MB_2U(SCH_1):M_C_CPU0_SA_DQ(22)
 183 M_C_CPU0_SA_DQ<23> DQ23_A @S9S_MB_2U_LIB.S9S_MB_2U(SCH_1):M_C_CPU0_SA_DQ(23)
  40 M_C_CPU0_SA_DQ<24> DQ24_A @S9S_MB_2U_LIB.S9S_MB_2U(SCH_1):M_C_CPU0_SA_DQ(24)
  42 M_C_CPU0_SA_DQ<25> DQ25_A @S9S_MB_2U_LIB.S9S_MB_2U(SCH_1):M_C_CPU0_SA_DQ(25)
 185 M_C_CPU0_SA_DQ<26> DQ26_A @S9S_MB_2U_LIB.S9S_MB_2U(SCH_1):M_C_CPU0_SA_DQ(26)
 187 M_C_CPU0_SA_DQ<27> DQ27_A @S9S_MB_2U_LIB.S9S_MB_2U(SCH_1):M_C_CPU0_SA_DQ(27)
  47 M_C_CPU0_SA_DQ<28> DQ28_A @S9S_MB_2U_LIB.S9S_MB_2U(SCH_1):M_C_CPU0_SA_DQ(28)
  49 M_C_CPU0_SA_DQ<29> DQ29_A @S9S_MB_2U_LIB.S9S_MB_2U(SCH_1):M_C_CPU0_SA_DQ(29)
 192 M_C_CPU0_SA_DQ<30> DQ30_A @S9S_MB_2U_LIB.S9S_MB_2U(SCH_1):M_C_CPU0_SA_DQ(30)
 229 M_C_CPU0_SB_CS_N<1> CS1_B_N @S9S_MB_2U_LIB.S9S_MB_2U(SCH_1):M_C_CPU0_SB_CS_N(1)
 209 M_C_CPU0_SA_CS_N<1> CS1_A_N @S9S_MB_2U_LIB.S9S_MB_2U(SCH_1):M_C_CPU0_SA_CS_N(1)
  84 M_C_CPU0_SB_CS_N<0> CS0_B_N @S9S_MB_2U_LIB.S9S_MB_2U(SCH_1):M_C_CPU0_SB_CS_N(0)
  64 M_C_CPU0_SA_CS_N<0> CS0_A_N @S9S_MB_2U_LIB.S9S_MB_2U(SCH_1):M_C_CPU0_SA_CS_N(0)
 217 M_C_CPU0_CLK_DP<0>   CK_T @S9S_MB_2U_LIB.S9S_MB_2U(SCH_1):M_C_CPU0_CLK_DP(0)
 218 M_C_CPU0_CLK_DN<0>   CK_C @S9S_MB_2U_LIB.S9S_MB_2U(SCH_1):M_C_CPU0_CLK_DN(0)
  96 M_C_CPU0_SB_CB<0>  CB0_B @S9S_MB_2U_LIB.S9S_MB_2U(SCH_1):M_C_CPU0_SB_CB(0)
  98 M_C_CPU0_SB_CB<1>  CB1_B @S9S_MB_2U_LIB.S9S_MB_2U(SCH_1):M_C_CPU0_SB_CB(1)
 241 M_C_CPU0_SB_CB<2>  CB2_B @S9S_MB_2U_LIB.S9S_MB_2U(SCH_1):M_C_CPU0_SB_CB(2)
 243 M_C_CPU0_SB_CB<3>  CB3_B @S9S_MB_2U_LIB.S9S_MB_2U(SCH_1):M_C_CPU0_SB_CB(3)
  89 M_C_CPU0_SB_CB<4>  CB4_B @S9S_MB_2U_LIB.S9S_MB_2U(SCH_1):M_C_CPU0_SB_CB(4)
  91 M_C_CPU0_SB_CB<5>  CB5_B @S9S_MB_2U_LIB.S9S_MB_2U(SCH_1):M_C_CPU0_SB_CB(5)
 234 M_C_CPU0_SB_CB<6>  CB6_B @S9S_MB_2U_LIB.S9S_MB_2U(SCH_1):M_C_CPU0_SB_CB(6)
  51 M_C_CPU0_SA_CB<0>  CB0_A @S9S_MB_2U_LIB.S9S_MB_2U(SCH_1):M_C_CPU0_SA_CB(0)
 196 M_C_CPU0_SA_CB<2>  CB2_A @S9S_MB_2U_LIB.S9S_MB_2U(SCH_1):M_C_CPU0_SA_CB(2)
 198 M_C_CPU0_SA_CB<3>  CB3_A @S9S_MB_2U_LIB.S9S_MB_2U(SCH_1):M_C_CPU0_SA_CB(3)
  60 M_C_CPU0_SA_CB<5>  CB5_A @S9S_MB_2U_LIB.S9S_MB_2U(SCH_1):M_C_CPU0_SA_CB(5)
 203 M_C_CPU0_SA_CB<6>  CB6_A @S9S_MB_2U_LIB.S9S_MB_2U(SCH_1):M_C_CPU0_SA_CB(6)
  82 M_C_CPU0_SB_CA<6>  CA6_B @S9S_MB_2U_LIB.S9S_MB_2U(SCH_1):M_C_CPU0_SB_CA(6)
  72 M_C_CPU0_SA_CA<6>  CA6_A @S9S_MB_2U_LIB.S9S_MB_2U(SCH_1):M_C_CPU0_SA_CA(6)
 225 M_C_CPU0_SB_CA<5>  CA5_B @S9S_MB_2U_LIB.S9S_MB_2U(SCH_1):M_C_CPU0_SB_CA(5)
 215 M_C_CPU0_SA_CA<5>  CA5_A @S9S_MB_2U_LIB.S9S_MB_2U(SCH_1):M_C_CPU0_SA_CA(5)
  80 M_C_CPU0_SB_CA<4>  CA4_B @S9S_MB_2U_LIB.S9S_MB_2U(SCH_1):M_C_CPU0_SB_CA(4)
  70 M_C_CPU0_SA_CA<4>  CA4_A @S9S_MB_2U_LIB.S9S_MB_2U(SCH_1):M_C_CPU0_SA_CA(4)
 223 M_C_CPU0_SB_CA<3>  CA3_B @S9S_MB_2U_LIB.S9S_MB_2U(SCH_1):M_C_CPU0_SB_CA(3)
 213 M_C_CPU0_SA_CA<3>  CA3_A @S9S_MB_2U_LIB.S9S_MB_2U(SCH_1):M_C_CPU0_SA_CA(3)
  78 M_C_CPU0_SB_CA<2>  CA2_B @S9S_MB_2U_LIB.S9S_MB_2U(SCH_1):M_C_CPU0_SB_CA(2)
  68 M_C_CPU0_SA_CA<2>  CA2_A @S9S_MB_2U_LIB.S9S_MB_2U(SCH_1):M_C_CPU0_SA_CA(2)
 221 M_C_CPU0_SB_CA<1>  CA1_B @S9S_MB_2U_LIB.S9S_MB_2U(SCH_1):M_C_CPU0_SB_CA(1)
 211 M_C_CPU0_SA_CA<1>  CA1_A @S9S_MB_2U_LIB.S9S_MB_2U(SCH_1):M_C_CPU0_SA_CA(1)
  76 M_C_CPU0_SB_CA<0>  CA0_B @S9S_MB_2U_LIB.S9S_MB_2U(SCH_1):M_C_CPU0_SB_CA(0)
  66 M_C_CPU0_SA_CA<0>  CA0_A @S9S_MB_2U_LIB.S9S_MB_2U(SCH_1):M_C_CPU0_SA_CA(0)
  62 M_C_CPU0_ALERT_N ALERT_N @S9S_MB_2U_LIB.S9S_MB_2U(SCH_1):M_C_CPU0_ALERT_N
 236 M_C_CPU0_SB_CB<7>  CB7_B @S9S_MB_2U_LIB.S9S_MB_2U(SCH_1):M_C_CPU0_SB_CB(7)
  53 M_C_CPU0_SA_CB<1>  CB1_A @S9S_MB_2U_LIB.S9S_MB_2U(SCH_1):M_C_CPU0_SA_CB(1)
  58 M_C_CPU0_SA_CB<4>  CB4_A @S9S_MB_2U_LIB.S9S_MB_2U(SCH_1):M_C_CPU0_SA_CB(4)
 205 M_C_CPU0_SA_CB<7>  CB7_A @S9S_MB_2U_LIB.S9S_MB_2U(SCH_1):M_C_CPU0_SA_CB(7)
 194 M_C_CPU0_SA_DQ<31> DQ31_A @S9S_MB_2U_LIB.S9S_MB_2U(SCH_1):M_C_CPU0_SA_DQ(31)

Q_CAP_C0402-2.2UF,6.3V,20%,X6SA  I120  C14
   1 P3V3_AUX      A @S9S_MB_2U_LIB.S9S_MB_2U(SCH_1):P3V3_AUX
   2    GND      B @S9S_MB_2U_LIB.S9S_MB_2U(SCH_1):GND

Q_CAP_C0805-10UF,16V,10%,X6S,CA  I121  C15
   1 P12V_S3_AUX_CPU0_NVDIMM      A @S9S_MB_2U_LIB.S9S_MB_2U(SCH_1):P12V_S3_AUX_CPU0_NVDIMM
   2    GND      B @S9S_MB_2U_LIB.S9S_MB_2U(SCH_1):GND

Q_CAP_C0805-10UF,16V,10%,X6S,CA  I123  C16
   1 P12V_S3_AUX_CPU0_NVDIMM      A @S9S_MB_2U_LIB.S9S_MB_2U(SCH_1):P12V_S3_AUX_CPU0_NVDIMM
   2    GND      B @S9S_MB_2U_LIB.S9S_MB_2U(SCH_1):GND

SCONN288_ADR50017P130CC-SCONN2A  I174  J5
   6    GND   VSS0 @S9S_MB_2U_LIB.S9S_MB_2U(SCH_1):GND
   8    GND   VSS1 @S9S_MB_2U_LIB.S9S_MB_2U(SCH_1):GND
  10    GND   VSS2 @S9S_MB_2U_LIB.S9S_MB_2U(SCH_1):GND
  13    GND   VSS3 @S9S_MB_2U_LIB.S9S_MB_2U(SCH_1):GND
  15    GND   VSS4 @S9S_MB_2U_LIB.S9S_MB_2U(SCH_1):GND
  17    GND   VSS5 @S9S_MB_2U_LIB.S9S_MB_2U(SCH_1):GND
  19    GND   VSS6 @S9S_MB_2U_LIB.S9S_MB_2U(SCH_1):GND
  21    GND   VSS7 @S9S_MB_2U_LIB.S9S_MB_2U(SCH_1):GND
  24    GND   VSS8 @S9S_MB_2U_LIB.S9S_MB_2U(SCH_1):GND
  26    GND   VSS9 @S9S_MB_2U_LIB.S9S_MB_2U(SCH_1):GND
  28    GND  VSS10 @S9S_MB_2U_LIB.S9S_MB_2U(SCH_1):GND
  30    GND  VSS11 @S9S_MB_2U_LIB.S9S_MB_2U(SCH_1):GND
  32    GND  VSS12 @S9S_MB_2U_LIB.S9S_MB_2U(SCH_1):GND
  35    GND  VSS13 @S9S_MB_2U_LIB.S9S_MB_2U(SCH_1):GND
  37    GND  VSS14 @S9S_MB_2U_LIB.S9S_MB_2U(SCH_1):GND
  39    GND  VSS15 @S9S_MB_2U_LIB.S9S_MB_2U(SCH_1):GND
  41    GND  VSS16 @S9S_MB_2U_LIB.S9S_MB_2U(SCH_1):GND
  43    GND  VSS17 @S9S_MB_2U_LIB.S9S_MB_2U(SCH_1):GND
  46    GND  VSS18 @S9S_MB_2U_LIB.S9S_MB_2U(SCH_1):GND
  48    GND  VSS19 @S9S_MB_2U_LIB.S9S_MB_2U(SCH_1):GND
  50    GND  VSS20 @S9S_MB_2U_LIB.S9S_MB_2U(SCH_1):GND
  52    GND  VSS21 @S9S_MB_2U_LIB.S9S_MB_2U(SCH_1):GND
  54    GND  VSS22 @S9S_MB_2U_LIB.S9S_MB_2U(SCH_1):GND
  57    GND  VSS23 @S9S_MB_2U_LIB.S9S_MB_2U(SCH_1):GND
  59    GND  VSS24 @S9S_MB_2U_LIB.S9S_MB_2U(SCH_1):GND
  61    GND  VSS25 @S9S_MB_2U_LIB.S9S_MB_2U(SCH_1):GND
  63    GND  VSS26 @S9S_MB_2U_LIB.S9S_MB_2U(SCH_1):GND
  65    GND  VSS27 @S9S_MB_2U_LIB.S9S_MB_2U(SCH_1):GND
  67    GND  VSS28 @S9S_MB_2U_LIB.S9S_MB_2U(SCH_1):GND
  69    GND  VSS29 @S9S_MB_2U_LIB.S9S_MB_2U(SCH_1):GND
  71    GND  VSS30 @S9S_MB_2U_LIB.S9S_MB_2U(SCH_1):GND
  73    GND  VSS31 @S9S_MB_2U_LIB.S9S_MB_2U(SCH_1):GND
  75    GND  VSS32 @S9S_MB_2U_LIB.S9S_MB_2U(SCH_1):GND
  77    GND  VSS33 @S9S_MB_2U_LIB.S9S_MB_2U(SCH_1):GND
  79    GND  VSS34 @S9S_MB_2U_LIB.S9S_MB_2U(SCH_1):GND
  81    GND  VSS35 @S9S_MB_2U_LIB.S9S_MB_2U(SCH_1):GND
  83    GND  VSS36 @S9S_MB_2U_LIB.S9S_MB_2U(SCH_1):GND
  85    GND  VSS37 @S9S_MB_2U_LIB.S9S_MB_2U(SCH_1):GND
  88    GND  VSS38 @S9S_MB_2U_LIB.S9S_MB_2U(SCH_1):GND
  90    GND  VSS39 @S9S_MB_2U_LIB.S9S_MB_2U(SCH_1):GND
  92    GND  VSS40 @S9S_MB_2U_LIB.S9S_MB_2U(SCH_1):GND
  95    GND  VSS41 @S9S_MB_2U_LIB.S9S_MB_2U(SCH_1):GND
  97    GND  VSS42 @S9S_MB_2U_LIB.S9S_MB_2U(SCH_1):GND
  99    GND  VSS43 @S9S_MB_2U_LIB.S9S_MB_2U(SCH_1):GND
 101    GND  VSS44 @S9S_MB_2U_LIB.S9S_MB_2U(SCH_1):GND
 103    GND  VSS45 @S9S_MB_2U_LIB.S9S_MB_2U(SCH_1):GND
 106    GND  VSS46 @S9S_MB_2U_LIB.S9S_MB_2U(SCH_1):GND
 108    GND  VSS47 @S9S_MB_2U_LIB.S9S_MB_2U(SCH_1):GND
 110    GND  VSS48 @S9S_MB_2U_LIB.S9S_MB_2U(SCH_1):GND
 112    GND  VSS49 @S9S_MB_2U_LIB.S9S_MB_2U(SCH_1):GND
 114    GND  VSS50 @S9S_MB_2U_LIB.S9S_MB_2U(SCH_1):GND
 117    GND  VSS51 @S9S_MB_2U_LIB.S9S_MB_2U(SCH_1):GND
 119    GND  VSS52 @S9S_MB_2U_LIB.S9S_MB_2U(SCH_1):GND
 121    GND  VSS53 @S9S_MB_2U_LIB.S9S_MB_2U(SCH_1):GND
 123    GND  VSS54 @S9S_MB_2U_LIB.S9S_MB_2U(SCH_1):GND
 125    GND  VSS55 @S9S_MB_2U_LIB.S9S_MB_2U(SCH_1):GND
 128    GND  VSS56 @S9S_MB_2U_LIB.S9S_MB_2U(SCH_1):GND
 130    GND  VSS57 @S9S_MB_2U_LIB.S9S_MB_2U(SCH_1):GND
 134    GND  VSS59 @S9S_MB_2U_LIB.S9S_MB_2U(SCH_1):GND
 143    GND  VSS63 @S9S_MB_2U_LIB.S9S_MB_2U(SCH_1):GND
 151    GND  VSS64 @S9S_MB_2U_LIB.S9S_MB_2U(SCH_1):GND
 153    GND  VSS65 @S9S_MB_2U_LIB.S9S_MB_2U(SCH_1):GND
 155    GND  VSS66 @S9S_MB_2U_LIB.S9S_MB_2U(SCH_1):GND
 158    GND  VSS67 @S9S_MB_2U_LIB.S9S_MB_2U(SCH_1):GND
 160    GND  VSS68 @S9S_MB_2U_LIB.S9S_MB_2U(SCH_1):GND
 162    GND  VSS69 @S9S_MB_2U_LIB.S9S_MB_2U(SCH_1):GND
 164    GND  VSS70 @S9S_MB_2U_LIB.S9S_MB_2U(SCH_1):GND
 166    GND  VSS71 @S9S_MB_2U_LIB.S9S_MB_2U(SCH_1):GND
 169    GND  VSS72 @S9S_MB_2U_LIB.S9S_MB_2U(SCH_1):GND
 171    GND  VSS73 @S9S_MB_2U_LIB.S9S_MB_2U(SCH_1):GND
 173    GND  VSS74 @S9S_MB_2U_LIB.S9S_MB_2U(SCH_1):GND
 175    GND  VSS75 @S9S_MB_2U_LIB.S9S_MB_2U(SCH_1):GND
 177    GND  VSS76 @S9S_MB_2U_LIB.S9S_MB_2U(SCH_1):GND
 180    GND  VSS77 @S9S_MB_2U_LIB.S9S_MB_2U(SCH_1):GND
 182    GND  VSS78 @S9S_MB_2U_LIB.S9S_MB_2U(SCH_1):GND
 184    GND  VSS79 @S9S_MB_2U_LIB.S9S_MB_2U(SCH_1):GND
 186    GND  VSS80 @S9S_MB_2U_LIB.S9S_MB_2U(SCH_1):GND
 188    GND  VSS81 @S9S_MB_2U_LIB.S9S_MB_2U(SCH_1):GND
 191    GND  VSS82 @S9S_MB_2U_LIB.S9S_MB_2U(SCH_1):GND
 193    GND  VSS83 @S9S_MB_2U_LIB.S9S_MB_2U(SCH_1):GND
 195    GND  VSS84 @S9S_MB_2U_LIB.S9S_MB_2U(SCH_1):GND
 197    GND  VSS85 @S9S_MB_2U_LIB.S9S_MB_2U(SCH_1):GND
 199    GND  VSS86 @S9S_MB_2U_LIB.S9S_MB_2U(SCH_1):GND
 202    GND  VSS87 @S9S_MB_2U_LIB.S9S_MB_2U(SCH_1):GND
 204    GND  VSS88 @S9S_MB_2U_LIB.S9S_MB_2U(SCH_1):GND
 206    GND  VSS89 @S9S_MB_2U_LIB.S9S_MB_2U(SCH_1):GND
 208    GND  VSS90 @S9S_MB_2U_LIB.S9S_MB_2U(SCH_1):GND
 210    GND  VSS91 @S9S_MB_2U_LIB.S9S_MB_2U(SCH_1):GND
 212    GND  VSS92 @S9S_MB_2U_LIB.S9S_MB_2U(SCH_1):GND
 214    GND  VSS93 @S9S_MB_2U_LIB.S9S_MB_2U(SCH_1):GND
 216    GND  VSS94 @S9S_MB_2U_LIB.S9S_MB_2U(SCH_1):GND
 219    GND  VSS95 @S9S_MB_2U_LIB.S9S_MB_2U(SCH_1):GND
 222    GND  VSS96 @S9S_MB_2U_LIB.S9S_MB_2U(SCH_1):GND
 224    GND  VSS97 @S9S_MB_2U_LIB.S9S_MB_2U(SCH_1):GND
 226    GND  VSS98 @S9S_MB_2U_LIB.S9S_MB_2U(SCH_1):GND
 228    GND  VSS99 @S9S_MB_2U_LIB.S9S_MB_2U(SCH_1):GND
 233    GND VSS101 @S9S_MB_2U_LIB.S9S_MB_2U(SCH_1):GND
 237    GND VSS103 @S9S_MB_2U_LIB.S9S_MB_2U(SCH_1):GND
 242    GND VSS105 @S9S_MB_2U_LIB.S9S_MB_2U(SCH_1):GND
 244    GND VSS106 @S9S_MB_2U_LIB.S9S_MB_2U(SCH_1):GND
 246    GND VSS107 @S9S_MB_2U_LIB.S9S_MB_2U(SCH_1):GND
 248    GND VSS108 @S9S_MB_2U_LIB.S9S_MB_2U(SCH_1):GND
 251    GND VSS109 @S9S_MB_2U_LIB.S9S_MB_2U(SCH_1):GND
 253    GND VSS110 @S9S_MB_2U_LIB.S9S_MB_2U(SCH_1):GND
 255    GND VSS111 @S9S_MB_2U_LIB.S9S_MB_2U(SCH_1):GND
 257    GND VSS112 @S9S_MB_2U_LIB.S9S_MB_2U(SCH_1):GND
 259    GND VSS113 @S9S_MB_2U_LIB.S9S_MB_2U(SCH_1):GND
 262    GND VSS114 @S9S_MB_2U_LIB.S9S_MB_2U(SCH_1):GND
 264    GND VSS115 @S9S_MB_2U_LIB.S9S_MB_2U(SCH_1):GND
 266    GND VSS116 @S9S_MB_2U_LIB.S9S_MB_2U(SCH_1):GND
 268    GND VSS117 @S9S_MB_2U_LIB.S9S_MB_2U(SCH_1):GND
 270    GND VSS118 @S9S_MB_2U_LIB.S9S_MB_2U(SCH_1):GND
 273    GND VSS119 @S9S_MB_2U_LIB.S9S_MB_2U(SCH_1):GND
 275    GND VSS120 @S9S_MB_2U_LIB.S9S_MB_2U(SCH_1):GND
 277    GND VSS121 @S9S_MB_2U_LIB.S9S_MB_2U(SCH_1):GND
 279    GND VSS122 @S9S_MB_2U_LIB.S9S_MB_2U(SCH_1):GND
 281    GND VSS123 @S9S_MB_2U_LIB.S9S_MB_2U(SCH_1):GND
 284    GND VSS124 @S9S_MB_2U_LIB.S9S_MB_2U(SCH_1):GND
 286    GND VSS125 @S9S_MB_2U_LIB.S9S_MB_2U(SCH_1):GND
 288    GND VSS126 @S9S_MB_2U_LIB.S9S_MB_2U(SCH_1):GND
   1 P12V_S3_AUX_CPU0_NVDIMM VIN_BULK0 @S9S_MB_2U_LIB.S9S_MB_2U(SCH_1):P12V_S3_AUX_CPU0_NVDIMM
 145 P12V_S3_AUX_CPU0_NVDIMM VIN_BULK1 @S9S_MB_2U_LIB.S9S_MB_2U(SCH_1):P12V_S3_AUX_CPU0_NVDIMM
 146 P12V_S3_AUX_CPU0_NVDIMM VIN_BULK2 @S9S_MB_2U_LIB.S9S_MB_2U(SCH_1):P12V_S3_AUX_CPU0_NVDIMM
 230    GND VSS100 @S9S_MB_2U_LIB.S9S_MB_2U(SCH_1):GND
 235    GND VSS102 @S9S_MB_2U_LIB.S9S_MB_2U(SCH_1):GND
 240    GND VSS104 @S9S_MB_2U_LIB.S9S_MB_2U(SCH_1):GND
 132    GND  VSS58 @S9S_MB_2U_LIB.S9S_MB_2U(SCH_1):GND
 136    GND  VSS60 @S9S_MB_2U_LIB.S9S_MB_2U(SCH_1):GND
 139    GND  VSS61 @S9S_MB_2U_LIB.S9S_MB_2U(SCH_1):GND
 141    GND  VSS62 @S9S_MB_2U_LIB.S9S_MB_2U(SCH_1):GND
  G1    GND     G1 @S9S_MB_2U_LIB.S9S_MB_2U(SCH_1):GND
  G2    GND     G2 @S9S_MB_2U_LIB.S9S_MB_2U(SCH_1):GND
  G3    GND     G3 @S9S_MB_2U_LIB.S9S_MB_2U(SCH_1):GND

SCONN288_ADR50017P130CC-SCONN2A  I178  J5
  93 M_C_CPU0_SB_DQS_DP<9> DQS9_B_T||TDQS9_B_T||DBI4_B_N @S9S_MB_2U_LIB.S9S_MB_2U(SCH_1):M_C_CPU0_SB_DQS_DP(9)
  94 M_C_CPU0_SB_DQS_DN<9> DQS9_B_C||TDQS9_B_C @S9S_MB_2U_LIB.S9S_MB_2U(SCH_1):M_C_CPU0_SB_DQS_DN(9)
 201 M_C_CPU0_SA_DQS_DP<9> DQS9_A_T||TDQS9_A_T @S9S_MB_2U_LIB.S9S_MB_2U(SCH_1):M_C_CPU0_SA_DQS_DP(9)
 200 M_C_CPU0_SA_DQS_DN<9> DQS9_A_C||TDQS9_A_C @S9S_MB_2U_LIB.S9S_MB_2U(SCH_1):M_C_CPU0_SA_DQS_DN(9)
 190 M_C_CPU0_SA_DQS_DP<8> DQS8_A_T||TDQS8_A_T @S9S_MB_2U_LIB.S9S_MB_2U(SCH_1):M_C_CPU0_SA_DQS_DP(8)
 189 M_C_CPU0_SA_DQS_DN<8> DQS8_A_C||TDQS8_A_C @S9S_MB_2U_LIB.S9S_MB_2U(SCH_1):M_C_CPU0_SA_DQS_DN(8)
 271 M_C_CPU0_SB_DQS_DN<7> DQS7_B_C||TDQS7_B_C @S9S_MB_2U_LIB.S9S_MB_2U(SCH_1):M_C_CPU0_SB_DQS_DN(7)
 179 M_C_CPU0_SA_DQS_DP<7> DQS7_A_T||TDQS7_A_T @S9S_MB_2U_LIB.S9S_MB_2U(SCH_1):M_C_CPU0_SA_DQS_DP(7)
 261 M_C_CPU0_SB_DQS_DP<6> DQS6_B_T||TDQS6_B_T @S9S_MB_2U_LIB.S9S_MB_2U(SCH_1):M_C_CPU0_SB_DQS_DP(6)
 260 M_C_CPU0_SB_DQS_DN<6> DQS6_B_C||TDQS6_B_C @S9S_MB_2U_LIB.S9S_MB_2U(SCH_1):M_C_CPU0_SB_DQS_DN(6)
 167 M_C_CPU0_SA_DQS_DN<6> DQS6_A_C||TDQS6_A_C||DQS6_A_T||TDQS6_A_T @S9S_MB_2U_LIB.S9S_MB_2U(SCH_1):M_C_CPU0_SA_DQS_DN(6)
 250 M_C_CPU0_SB_DQS_DP<5> DQS5_B_T||TDQS5_B_T @S9S_MB_2U_LIB.S9S_MB_2U(SCH_1):M_C_CPU0_SB_DQS_DP(5)
 249 M_C_CPU0_SB_DQS_DN<5> DQS5_B_C||TDQS5_B_C @S9S_MB_2U_LIB.S9S_MB_2U(SCH_1):M_C_CPU0_SB_DQS_DN(5)
 157 M_C_CPU0_SA_DQS_DP<5> DQS5_A_T||TDQS5_A_T @S9S_MB_2U_LIB.S9S_MB_2U(SCH_1):M_C_CPU0_SA_DQS_DP(5)
 156 M_C_CPU0_SA_DQS_DN<5> DQS5_A_C||TDQS5_A_C||DQS5_A_T||TDQS5_A_T @S9S_MB_2U_LIB.S9S_MB_2U(SCH_1):M_C_CPU0_SA_DQS_DN(5)
 239 M_C_CPU0_SB_DQS_DP<4> DQS4_B_T @S9S_MB_2U_LIB.S9S_MB_2U(SCH_1):M_C_CPU0_SB_DQS_DP(4)
 238 M_C_CPU0_SB_DQS_DN<4> DQS4_B_C @S9S_MB_2U_LIB.S9S_MB_2U(SCH_1):M_C_CPU0_SB_DQS_DN(4)
  55 M_C_CPU0_SA_DQS_DP<4> DQS4_A_T @S9S_MB_2U_LIB.S9S_MB_2U(SCH_1):M_C_CPU0_SA_DQS_DP(4)
  56 M_C_CPU0_SA_DQS_DN<4> DQS4_A_C @S9S_MB_2U_LIB.S9S_MB_2U(SCH_1):M_C_CPU0_SA_DQS_DN(4)
 137 M_C_CPU0_SB_DQS_DP<3> DQS3_B_T @S9S_MB_2U_LIB.S9S_MB_2U(SCH_1):M_C_CPU0_SB_DQS_DP(3)
 138 M_C_CPU0_SB_DQS_DN<3> DQS3_B_C @S9S_MB_2U_LIB.S9S_MB_2U(SCH_1):M_C_CPU0_SB_DQS_DN(3)
  44 M_C_CPU0_SA_DQS_DP<3> DQS3_A_T @S9S_MB_2U_LIB.S9S_MB_2U(SCH_1):M_C_CPU0_SA_DQS_DP(3)
  45 M_C_CPU0_SA_DQS_DN<3> DQS3_A_C @S9S_MB_2U_LIB.S9S_MB_2U(SCH_1):M_C_CPU0_SA_DQS_DN(3)
 126 M_C_CPU0_SB_DQS_DP<2> DQS2_B_T @S9S_MB_2U_LIB.S9S_MB_2U(SCH_1):M_C_CPU0_SB_DQS_DP(2)
 127 M_C_CPU0_SB_DQS_DN<2> DQS2_B_C @S9S_MB_2U_LIB.S9S_MB_2U(SCH_1):M_C_CPU0_SB_DQS_DN(2)
  33 M_C_CPU0_SA_DQS_DP<2> DQS2_A_T @S9S_MB_2U_LIB.S9S_MB_2U(SCH_1):M_C_CPU0_SA_DQS_DP(2)
  34 M_C_CPU0_SA_DQS_DN<2> DQS2_A_C @S9S_MB_2U_LIB.S9S_MB_2U(SCH_1):M_C_CPU0_SA_DQS_DN(2)
 115 M_C_CPU0_SB_DQS_DP<1> DQS1_B_T @S9S_MB_2U_LIB.S9S_MB_2U(SCH_1):M_C_CPU0_SB_DQS_DP(1)
 116 M_C_CPU0_SB_DQS_DN<1> DQS1_B_C @S9S_MB_2U_LIB.S9S_MB_2U(SCH_1):M_C_CPU0_SB_DQS_DN(1)
  22 M_C_CPU0_SA_DQS_DP<1> DQS1_A_T @S9S_MB_2U_LIB.S9S_MB_2U(SCH_1):M_C_CPU0_SA_DQS_DP(1)
  23 M_C_CPU0_SA_DQS_DN<1> DQS1_A_C @S9S_MB_2U_LIB.S9S_MB_2U(SCH_1):M_C_CPU0_SA_DQS_DN(1)
 104 M_C_CPU0_SB_DQS_DP<0> DQS0_B_T @S9S_MB_2U_LIB.S9S_MB_2U(SCH_1):M_C_CPU0_SB_DQS_DP(0)
 105 M_C_CPU0_SB_DQS_DN<0> DQS0_B_C @S9S_MB_2U_LIB.S9S_MB_2U(SCH_1):M_C_CPU0_SB_DQS_DN(0)
  11 M_C_CPU0_SA_DQS_DP<0> DQS0_A_T @S9S_MB_2U_LIB.S9S_MB_2U(SCH_1):M_C_CPU0_SA_DQS_DP(0)
  12 M_C_CPU0_SA_DQS_DN<0> DQS0_A_C @S9S_MB_2U_LIB.S9S_MB_2U(SCH_1):M_C_CPU0_SA_DQS_DN(0)
 272 M_C_CPU0_SB_DQS_DP<7> DQS7_B_T||TDQS7_B_T @S9S_MB_2U_LIB.S9S_MB_2U(SCH_1):M_C_CPU0_SB_DQS_DP(7)
 282 M_C_CPU0_SB_DQS_DN<8> DQS8_B_C||TDQS8_B_C @S9S_MB_2U_LIB.S9S_MB_2U(SCH_1):M_C_CPU0_SB_DQS_DN(8)
 283 M_C_CPU0_SB_DQS_DP<8> DQS8_B_T||TDQS8_B_T @S9S_MB_2U_LIB.S9S_MB_2U(SCH_1):M_C_CPU0_SB_DQS_DP(8)
 168 M_C_CPU0_SA_DQS_DP<6> DQS6_A_T||TDQS6_A_T @S9S_MB_2U_LIB.S9S_MB_2U(SCH_1):M_C_CPU0_SA_DQS_DP(6)
 178 M_C_CPU0_SA_DQS_DN<7> DQS7_A_C||TDQS7_A_C @S9S_MB_2U_LIB.S9S_MB_2U(SCH_1):M_C_CPU0_SA_DQS_DN(7)

Q_RES_0402LF-49.9,1%,1/16W,CHIA  I180  R3879
   1 I3C_SPD_DDRABCD_CPU0_LVC1_SCL_4      A @S9S_MB_2U_LIB.S9S_MB_2U(SCH_1):I3C_SPD_DDRABCD_CPU0_LVC1_SCL_R5
   2 I3C_SPD_DDRABCD_CPU0_LVC1_SCL      B @S9S_MB_2U_LIB.S9S_MB_2U(SCH_1):I3C_SPD_DDRABCD_CPU0_LVC1_SCL


DRAWING: @S9S_MB_2U_LIB.S9S_MB_2U(SCH_1):PAGE87 

Q_RES_0402LF-84.5K,1%,1/16W,CHA  I45  R31
   1 PD_CHC_CPU0_DIMM2_SAA      A @S9S_MB_2U_LIB.S9S_MB_2U(SCH_1):PD_CHC_CPU0_DIMM2_SAA
   2    GND      B @S9S_MB_2U_LIB.S9S_MB_2U(SCH_1):GND

SCONN288_ADR50017P087CC-SCONN2A  I46  J6
   3 P3V3_AUX VIN_MGMT @S9S_MB_2U_LIB.S9S_MB_2U(SCH_1):P3V3_AUX
   2 TP_CHC_CPU0_DIMM2_FRU_0   RFU0 @S9S_MB_2U_LIB.S9S_MB_2U(SCH_1):TP_CHC_CPU0_DIMM2_FRU_0
 144 TP_CHC_CPU0_DIMM2_FRU_1   RFU1 @S9S_MB_2U_LIB.S9S_MB_2U(SCH_1):TP_CHC_CPU0_DIMM2_FRU_1
 149 TP_CHC_CPU0_DIMM2_FRU_2   RFU2 @S9S_MB_2U_LIB.S9S_MB_2U(SCH_1):TP_CHC_CPU0_DIMM2_FRU_2
 150 TP_CHC_CPU0_DIMM2_FRU_3   RFU3 @S9S_MB_2U_LIB.S9S_MB_2U(SCH_1):TP_CHC_CPU0_DIMM2_FRU_3
 220 TP_CHC_CPU0_DIMM2_FRU_4   RFU4 @S9S_MB_2U_LIB.S9S_MB_2U(SCH_1):TP_CHC_CPU0_DIMM2_FRU_4
 231 TP_CHC_CPU0_DIMM2_FRU_5   RFU5 @S9S_MB_2U_LIB.S9S_MB_2U(SCH_1):TP_CHC_CPU0_DIMM2_FRU_5
 232 TP_CHC_CPU0_DIMM2_FRU_6   RFU6 @S9S_MB_2U_LIB.S9S_MB_2U(SCH_1):TP_CHC_CPU0_DIMM2_FRU_6
 207 RST_M_CD_CPU0_FPGA_N RESET_N @S9S_MB_2U_LIB.S9S_MB_2U(SCH_1):RST_M_CD_CPU0_FPGA_N
 147 PWRGD_CHC_CPU0_DIMM2 PWR_GOOD||FAIL_N @S9S_MB_2U_LIB.S9S_MB_2U(SCH_1):PWRGD_CHC_CPU0_DIMM2
 227 M_C_CPU0_SB_PAR  PAR_B @S9S_MB_2U_LIB.S9S_MB_2U(SCH_1):M_C_CPU0_SB_PAR
  74 M_C_CPU0_SA_PAR  PAR_A @S9S_MB_2U_LIB.S9S_MB_2U(SCH_1):M_C_CPU0_SA_PAR
  87 M_C_CPU0_SB_RSP<1> LBS||RSP_B_N @S9S_MB_2U_LIB.S9S_MB_2U(SCH_1):M_C_CPU0_SB_RSP(1)
  86 M_C_CPU0_SA_RSP<1> LBD||RSP_A_N @S9S_MB_2U_LIB.S9S_MB_2U(SCH_1):M_C_CPU0_SA_RSP(1)
   5 I3C_SPD_DDRABCD_CPU0_LVC1_SDA   HSDA @S9S_MB_2U_LIB.S9S_MB_2U(SCH_1):I3C_SPD_DDRABCD_CPU0_LVC1_SDA
   4 I3C_SPD_DDRABCD_CPU0_LVC1_SCL_5   HSCL @S9S_MB_2U_LIB.S9S_MB_2U(SCH_1):I3C_SPD_DDRABCD_CPU0_LVC1_SCL_R6
 148 PD_CHC_CPU0_DIMM2_SAA    HSA @S9S_MB_2U_LIB.S9S_MB_2U(SCH_1):PD_CHC_CPU0_DIMM2_SAA
 100 M_C_CPU0_SB_DQ<0>  DQ0_B @S9S_MB_2U_LIB.S9S_MB_2U(SCH_1):M_C_CPU0_SB_DQ(0)
 102 M_C_CPU0_SB_DQ<1>  DQ1_B @S9S_MB_2U_LIB.S9S_MB_2U(SCH_1):M_C_CPU0_SB_DQ(1)
 245 M_C_CPU0_SB_DQ<2>  DQ2_B @S9S_MB_2U_LIB.S9S_MB_2U(SCH_1):M_C_CPU0_SB_DQ(2)
 247 M_C_CPU0_SB_DQ<3>  DQ3_B @S9S_MB_2U_LIB.S9S_MB_2U(SCH_1):M_C_CPU0_SB_DQ(3)
 107 M_C_CPU0_SB_DQ<4>  DQ4_B @S9S_MB_2U_LIB.S9S_MB_2U(SCH_1):M_C_CPU0_SB_DQ(4)
 109 M_C_CPU0_SB_DQ<5>  DQ5_B @S9S_MB_2U_LIB.S9S_MB_2U(SCH_1):M_C_CPU0_SB_DQ(5)
 252 M_C_CPU0_SB_DQ<6>  DQ6_B @S9S_MB_2U_LIB.S9S_MB_2U(SCH_1):M_C_CPU0_SB_DQ(6)
 254 M_C_CPU0_SB_DQ<7>  DQ7_B @S9S_MB_2U_LIB.S9S_MB_2U(SCH_1):M_C_CPU0_SB_DQ(7)
 111 M_C_CPU0_SB_DQ<8>  DQ8_B @S9S_MB_2U_LIB.S9S_MB_2U(SCH_1):M_C_CPU0_SB_DQ(8)
 113 M_C_CPU0_SB_DQ<9>  DQ9_B @S9S_MB_2U_LIB.S9S_MB_2U(SCH_1):M_C_CPU0_SB_DQ(9)
 256 M_C_CPU0_SB_DQ<10> DQ10_B @S9S_MB_2U_LIB.S9S_MB_2U(SCH_1):M_C_CPU0_SB_DQ(10)
 258 M_C_CPU0_SB_DQ<11> DQ11_B @S9S_MB_2U_LIB.S9S_MB_2U(SCH_1):M_C_CPU0_SB_DQ(11)
 118 M_C_CPU0_SB_DQ<12> DQ12_B @S9S_MB_2U_LIB.S9S_MB_2U(SCH_1):M_C_CPU0_SB_DQ(12)
 120 M_C_CPU0_SB_DQ<13> DQ13_B @S9S_MB_2U_LIB.S9S_MB_2U(SCH_1):M_C_CPU0_SB_DQ(13)
 263 M_C_CPU0_SB_DQ<14> DQ14_B @S9S_MB_2U_LIB.S9S_MB_2U(SCH_1):M_C_CPU0_SB_DQ(14)
 265 M_C_CPU0_SB_DQ<15> DQ15_B @S9S_MB_2U_LIB.S9S_MB_2U(SCH_1):M_C_CPU0_SB_DQ(15)
 122 M_C_CPU0_SB_DQ<16> DQ16_B @S9S_MB_2U_LIB.S9S_MB_2U(SCH_1):M_C_CPU0_SB_DQ(16)
 124 M_C_CPU0_SB_DQ<17> DQ17_B @S9S_MB_2U_LIB.S9S_MB_2U(SCH_1):M_C_CPU0_SB_DQ(17)
 267 M_C_CPU0_SB_DQ<18> DQ18_B @S9S_MB_2U_LIB.S9S_MB_2U(SCH_1):M_C_CPU0_SB_DQ(18)
 269 M_C_CPU0_SB_DQ<19> DQ19_B @S9S_MB_2U_LIB.S9S_MB_2U(SCH_1):M_C_CPU0_SB_DQ(19)
 129 M_C_CPU0_SB_DQ<20> DQ20_B @S9S_MB_2U_LIB.S9S_MB_2U(SCH_1):M_C_CPU0_SB_DQ(20)
 131 M_C_CPU0_SB_DQ<21> DQ21_B @S9S_MB_2U_LIB.S9S_MB_2U(SCH_1):M_C_CPU0_SB_DQ(21)
 274 M_C_CPU0_SB_DQ<22> DQ22_B @S9S_MB_2U_LIB.S9S_MB_2U(SCH_1):M_C_CPU0_SB_DQ(22)
 276 M_C_CPU0_SB_DQ<23> DQ23_B @S9S_MB_2U_LIB.S9S_MB_2U(SCH_1):M_C_CPU0_SB_DQ(23)
 133 M_C_CPU0_SB_DQ<24> DQ24_B @S9S_MB_2U_LIB.S9S_MB_2U(SCH_1):M_C_CPU0_SB_DQ(24)
 135 M_C_CPU0_SB_DQ<25> DQ25_B @S9S_MB_2U_LIB.S9S_MB_2U(SCH_1):M_C_CPU0_SB_DQ(25)
 278 M_C_CPU0_SB_DQ<26> DQ26_B @S9S_MB_2U_LIB.S9S_MB_2U(SCH_1):M_C_CPU0_SB_DQ(26)
 280 M_C_CPU0_SB_DQ<27> DQ27_B @S9S_MB_2U_LIB.S9S_MB_2U(SCH_1):M_C_CPU0_SB_DQ(27)
 140 M_C_CPU0_SB_DQ<28> DQ28_B @S9S_MB_2U_LIB.S9S_MB_2U(SCH_1):M_C_CPU0_SB_DQ(28)
 142 M_C_CPU0_SB_DQ<29> DQ29_B @S9S_MB_2U_LIB.S9S_MB_2U(SCH_1):M_C_CPU0_SB_DQ(29)
 285 M_C_CPU0_SB_DQ<30> DQ30_B @S9S_MB_2U_LIB.S9S_MB_2U(SCH_1):M_C_CPU0_SB_DQ(30)
 287 M_C_CPU0_SB_DQ<31> DQ31_B @S9S_MB_2U_LIB.S9S_MB_2U(SCH_1):M_C_CPU0_SB_DQ(31)
   7 M_C_CPU0_SA_DQ<0>  DQ0_A @S9S_MB_2U_LIB.S9S_MB_2U(SCH_1):M_C_CPU0_SA_DQ(0)
   9 M_C_CPU0_SA_DQ<1>  DQ1_A @S9S_MB_2U_LIB.S9S_MB_2U(SCH_1):M_C_CPU0_SA_DQ(1)
 152 M_C_CPU0_SA_DQ<2>  DQ2_A @S9S_MB_2U_LIB.S9S_MB_2U(SCH_1):M_C_CPU0_SA_DQ(2)
 154 M_C_CPU0_SA_DQ<3>  DQ3_A @S9S_MB_2U_LIB.S9S_MB_2U(SCH_1):M_C_CPU0_SA_DQ(3)
  14 M_C_CPU0_SA_DQ<4>  DQ4_A @S9S_MB_2U_LIB.S9S_MB_2U(SCH_1):M_C_CPU0_SA_DQ(4)
  16 M_C_CPU0_SA_DQ<5>  DQ5_A @S9S_MB_2U_LIB.S9S_MB_2U(SCH_1):M_C_CPU0_SA_DQ(5)
 159 M_C_CPU0_SA_DQ<6>  DQ6_A @S9S_MB_2U_LIB.S9S_MB_2U(SCH_1):M_C_CPU0_SA_DQ(6)
 161 M_C_CPU0_SA_DQ<7>  DQ7_A @S9S_MB_2U_LIB.S9S_MB_2U(SCH_1):M_C_CPU0_SA_DQ(7)
  18 M_C_CPU0_SA_DQ<8>  DQ8_A @S9S_MB_2U_LIB.S9S_MB_2U(SCH_1):M_C_CPU0_SA_DQ(8)
  20 M_C_CPU0_SA_DQ<9>  DQ9_A @S9S_MB_2U_LIB.S9S_MB_2U(SCH_1):M_C_CPU0_SA_DQ(9)
 163 M_C_CPU0_SA_DQ<10> DQ10_A @S9S_MB_2U_LIB.S9S_MB_2U(SCH_1):M_C_CPU0_SA_DQ(10)
 165 M_C_CPU0_SA_DQ<11> DQ11_A @S9S_MB_2U_LIB.S9S_MB_2U(SCH_1):M_C_CPU0_SA_DQ(11)
  25 M_C_CPU0_SA_DQ<12> DQ12_A @S9S_MB_2U_LIB.S9S_MB_2U(SCH_1):M_C_CPU0_SA_DQ(12)
  27 M_C_CPU0_SA_DQ<13> DQ13_A @S9S_MB_2U_LIB.S9S_MB_2U(SCH_1):M_C_CPU0_SA_DQ(13)
 170 M_C_CPU0_SA_DQ<14> DQ14_A @S9S_MB_2U_LIB.S9S_MB_2U(SCH_1):M_C_CPU0_SA_DQ(14)
 172 M_C_CPU0_SA_DQ<15> DQ15_A @S9S_MB_2U_LIB.S9S_MB_2U(SCH_1):M_C_CPU0_SA_DQ(15)
  29 M_C_CPU0_SA_DQ<16> DQ16_A @S9S_MB_2U_LIB.S9S_MB_2U(SCH_1):M_C_CPU0_SA_DQ(16)
  31 M_C_CPU0_SA_DQ<17> DQ17_A @S9S_MB_2U_LIB.S9S_MB_2U(SCH_1):M_C_CPU0_SA_DQ(17)
 174 M_C_CPU0_SA_DQ<18> DQ18_A @S9S_MB_2U_LIB.S9S_MB_2U(SCH_1):M_C_CPU0_SA_DQ(18)
 176 M_C_CPU0_SA_DQ<19> DQ19_A @S9S_MB_2U_LIB.S9S_MB_2U(SCH_1):M_C_CPU0_SA_DQ(19)
  36 M_C_CPU0_SA_DQ<20> DQ20_A @S9S_MB_2U_LIB.S9S_MB_2U(SCH_1):M_C_CPU0_SA_DQ(20)
  38 M_C_CPU0_SA_DQ<21> DQ21_A @S9S_MB_2U_LIB.S9S_MB_2U(SCH_1):M_C_CPU0_SA_DQ(21)
 181 M_C_CPU0_SA_DQ<22> DQ22_A @S9S_MB_2U_LIB.S9S_MB_2U(SCH_1):M_C_CPU0_SA_DQ(22)
 183 M_C_CPU0_SA_DQ<23> DQ23_A @S9S_MB_2U_LIB.S9S_MB_2U(SCH_1):M_C_CPU0_SA_DQ(23)
  40 M_C_CPU0_SA_DQ<24> DQ24_A @S9S_MB_2U_LIB.S9S_MB_2U(SCH_1):M_C_CPU0_SA_DQ(24)
  42 M_C_CPU0_SA_DQ<25> DQ25_A @S9S_MB_2U_LIB.S9S_MB_2U(SCH_1):M_C_CPU0_SA_DQ(25)
 185 M_C_CPU0_SA_DQ<26> DQ26_A @S9S_MB_2U_LIB.S9S_MB_2U(SCH_1):M_C_CPU0_SA_DQ(26)
 187 M_C_CPU0_SA_DQ<27> DQ27_A @S9S_MB_2U_LIB.S9S_MB_2U(SCH_1):M_C_CPU0_SA_DQ(27)
  47 M_C_CPU0_SA_DQ<28> DQ28_A @S9S_MB_2U_LIB.S9S_MB_2U(SCH_1):M_C_CPU0_SA_DQ(28)
  49 M_C_CPU0_SA_DQ<29> DQ29_A @S9S_MB_2U_LIB.S9S_MB_2U(SCH_1):M_C_CPU0_SA_DQ(29)
 192 M_C_CPU0_SA_DQ<30> DQ30_A @S9S_MB_2U_LIB.S9S_MB_2U(SCH_1):M_C_CPU0_SA_DQ(30)
 229 M_C_CPU0_SB_CS_N<3> CS1_B_N @S9S_MB_2U_LIB.S9S_MB_2U(SCH_1):M_C_CPU0_SB_CS_N(3)
 209 M_C_CPU0_SA_CS_N<3> CS1_A_N @S9S_MB_2U_LIB.S9S_MB_2U(SCH_1):M_C_CPU0_SA_CS_N(3)
  84 M_C_CPU0_SB_CS_N<2> CS0_B_N @S9S_MB_2U_LIB.S9S_MB_2U(SCH_1):M_C_CPU0_SB_CS_N(2)
  64 M_C_CPU0_SA_CS_N<2> CS0_A_N @S9S_MB_2U_LIB.S9S_MB_2U(SCH_1):M_C_CPU0_SA_CS_N(2)
 217 M_C_CPU0_CLK_DP<1>   CK_T @S9S_MB_2U_LIB.S9S_MB_2U(SCH_1):M_C_CPU0_CLK_DP(1)
 218 M_C_CPU0_CLK_DN<1>   CK_C @S9S_MB_2U_LIB.S9S_MB_2U(SCH_1):M_C_CPU0_CLK_DN(1)
  96 M_C_CPU0_SB_CB<0>  CB0_B @S9S_MB_2U_LIB.S9S_MB_2U(SCH_1):M_C_CPU0_SB_CB(0)
  98 M_C_CPU0_SB_CB<1>  CB1_B @S9S_MB_2U_LIB.S9S_MB_2U(SCH_1):M_C_CPU0_SB_CB(1)
 241 M_C_CPU0_SB_CB<2>  CB2_B @S9S_MB_2U_LIB.S9S_MB_2U(SCH_1):M_C_CPU0_SB_CB(2)
 243 M_C_CPU0_SB_CB<3>  CB3_B @S9S_MB_2U_LIB.S9S_MB_2U(SCH_1):M_C_CPU0_SB_CB(3)
  89 M_C_CPU0_SB_CB<4>  CB4_B @S9S_MB_2U_LIB.S9S_MB_2U(SCH_1):M_C_CPU0_SB_CB(4)
  91 M_C_CPU0_SB_CB<5>  CB5_B @S9S_MB_2U_LIB.S9S_MB_2U(SCH_1):M_C_CPU0_SB_CB(5)
 234 M_C_CPU0_SB_CB<6>  CB6_B @S9S_MB_2U_LIB.S9S_MB_2U(SCH_1):M_C_CPU0_SB_CB(6)
  51 M_C_CPU0_SA_CB<0>  CB0_A @S9S_MB_2U_LIB.S9S_MB_2U(SCH_1):M_C_CPU0_SA_CB(0)
 196 M_C_CPU0_SA_CB<2>  CB2_A @S9S_MB_2U_LIB.S9S_MB_2U(SCH_1):M_C_CPU0_SA_CB(2)
 198 M_C_CPU0_SA_CB<3>  CB3_A @S9S_MB_2U_LIB.S9S_MB_2U(SCH_1):M_C_CPU0_SA_CB(3)
  60 M_C_CPU0_SA_CB<5>  CB5_A @S9S_MB_2U_LIB.S9S_MB_2U(SCH_1):M_C_CPU0_SA_CB(5)
 203 M_C_CPU0_SA_CB<6>  CB6_A @S9S_MB_2U_LIB.S9S_MB_2U(SCH_1):M_C_CPU0_SA_CB(6)
  82 M_C_CPU0_SB_CA<6>  CA6_B @S9S_MB_2U_LIB.S9S_MB_2U(SCH_1):M_C_CPU0_SB_CA(6)
  72 M_C_CPU0_SA_CA<6>  CA6_A @S9S_MB_2U_LIB.S9S_MB_2U(SCH_1):M_C_CPU0_SA_CA(6)
 225 M_C_CPU0_SB_CA<5>  CA5_B @S9S_MB_2U_LIB.S9S_MB_2U(SCH_1):M_C_CPU0_SB_CA(5)
 215 M_C_CPU0_SA_CA<5>  CA5_A @S9S_MB_2U_LIB.S9S_MB_2U(SCH_1):M_C_CPU0_SA_CA(5)
  80 M_C_CPU0_SB_CA<4>  CA4_B @S9S_MB_2U_LIB.S9S_MB_2U(SCH_1):M_C_CPU0_SB_CA(4)
  70 M_C_CPU0_SA_CA<4>  CA4_A @S9S_MB_2U_LIB.S9S_MB_2U(SCH_1):M_C_CPU0_SA_CA(4)
 223 M_C_CPU0_SB_CA<3>  CA3_B @S9S_MB_2U_LIB.S9S_MB_2U(SCH_1):M_C_CPU0_SB_CA(3)
 213 M_C_CPU0_SA_CA<3>  CA3_A @S9S_MB_2U_LIB.S9S_MB_2U(SCH_1):M_C_CPU0_SA_CA(3)
  78 M_C_CPU0_SB_CA<2>  CA2_B @S9S_MB_2U_LIB.S9S_MB_2U(SCH_1):M_C_CPU0_SB_CA(2)
  68 M_C_CPU0_SA_CA<2>  CA2_A @S9S_MB_2U_LIB.S9S_MB_2U(SCH_1):M_C_CPU0_SA_CA(2)
 221 M_C_CPU0_SB_CA<1>  CA1_B @S9S_MB_2U_LIB.S9S_MB_2U(SCH_1):M_C_CPU0_SB_CA(1)
 211 M_C_CPU0_SA_CA<1>  CA1_A @S9S_MB_2U_LIB.S9S_MB_2U(SCH_1):M_C_CPU0_SA_CA(1)
  76 M_C_CPU0_SB_CA<0>  CA0_B @S9S_MB_2U_LIB.S9S_MB_2U(SCH_1):M_C_CPU0_SB_CA(0)
  66 M_C_CPU0_SA_CA<0>  CA0_A @S9S_MB_2U_LIB.S9S_MB_2U(SCH_1):M_C_CPU0_SA_CA(0)
  62 M_C_CPU0_ALERT_N ALERT_N @S9S_MB_2U_LIB.S9S_MB_2U(SCH_1):M_C_CPU0_ALERT_N
 236 M_C_CPU0_SB_CB<7>  CB7_B @S9S_MB_2U_LIB.S9S_MB_2U(SCH_1):M_C_CPU0_SB_CB(7)
  53 M_C_CPU0_SA_CB<1>  CB1_A @S9S_MB_2U_LIB.S9S_MB_2U(SCH_1):M_C_CPU0_SA_CB(1)
  58 M_C_CPU0_SA_CB<4>  CB4_A @S9S_MB_2U_LIB.S9S_MB_2U(SCH_1):M_C_CPU0_SA_CB(4)
 205 M_C_CPU0_SA_CB<7>  CB7_A @S9S_MB_2U_LIB.S9S_MB_2U(SCH_1):M_C_CPU0_SA_CB(7)
 194 M_C_CPU0_SA_DQ<31> DQ31_A @S9S_MB_2U_LIB.S9S_MB_2U(SCH_1):M_C_CPU0_SA_DQ(31)

Q_CAP_C0402-2.2UF,6.3V,20%,X6SA  I120  C17
   1 P3V3_AUX      A @S9S_MB_2U_LIB.S9S_MB_2U(SCH_1):P3V3_AUX
   2    GND      B @S9S_MB_2U_LIB.S9S_MB_2U(SCH_1):GND

Q_CAP_C0805-10UF,16V,10%,X6S,CA  I124  C18
   1 P12V_S3_AUX_CPU0_NVDIMM      A @S9S_MB_2U_LIB.S9S_MB_2U(SCH_1):P12V_S3_AUX_CPU0_NVDIMM
   2    GND      B @S9S_MB_2U_LIB.S9S_MB_2U(SCH_1):GND

Q_CAP_C0805-10UF,16V,10%,X6S,CA  I127  C19
   1 P12V_S3_AUX_CPU0_NVDIMM      A @S9S_MB_2U_LIB.S9S_MB_2U(SCH_1):P12V_S3_AUX_CPU0_NVDIMM
   2    GND      B @S9S_MB_2U_LIB.S9S_MB_2U(SCH_1):GND

SCONN288_ADR50017P087CC-SCONN2A  I175  J6
   6    GND   VSS0 @S9S_MB_2U_LIB.S9S_MB_2U(SCH_1):GND
   8    GND   VSS1 @S9S_MB_2U_LIB.S9S_MB_2U(SCH_1):GND
  10    GND   VSS2 @S9S_MB_2U_LIB.S9S_MB_2U(SCH_1):GND
  13    GND   VSS3 @S9S_MB_2U_LIB.S9S_MB_2U(SCH_1):GND
  15    GND   VSS4 @S9S_MB_2U_LIB.S9S_MB_2U(SCH_1):GND
  17    GND   VSS5 @S9S_MB_2U_LIB.S9S_MB_2U(SCH_1):GND
  19    GND   VSS6 @S9S_MB_2U_LIB.S9S_MB_2U(SCH_1):GND
  21    GND   VSS7 @S9S_MB_2U_LIB.S9S_MB_2U(SCH_1):GND
  24    GND   VSS8 @S9S_MB_2U_LIB.S9S_MB_2U(SCH_1):GND
  26    GND   VSS9 @S9S_MB_2U_LIB.S9S_MB_2U(SCH_1):GND
  28    GND  VSS10 @S9S_MB_2U_LIB.S9S_MB_2U(SCH_1):GND
  30    GND  VSS11 @S9S_MB_2U_LIB.S9S_MB_2U(SCH_1):GND
  32    GND  VSS12 @S9S_MB_2U_LIB.S9S_MB_2U(SCH_1):GND
  35    GND  VSS13 @S9S_MB_2U_LIB.S9S_MB_2U(SCH_1):GND
  37    GND  VSS14 @S9S_MB_2U_LIB.S9S_MB_2U(SCH_1):GND
  39    GND  VSS15 @S9S_MB_2U_LIB.S9S_MB_2U(SCH_1):GND
  41    GND  VSS16 @S9S_MB_2U_LIB.S9S_MB_2U(SCH_1):GND
  43    GND  VSS17 @S9S_MB_2U_LIB.S9S_MB_2U(SCH_1):GND
  46    GND  VSS18 @S9S_MB_2U_LIB.S9S_MB_2U(SCH_1):GND
  48    GND  VSS19 @S9S_MB_2U_LIB.S9S_MB_2U(SCH_1):GND
  50    GND  VSS20 @S9S_MB_2U_LIB.S9S_MB_2U(SCH_1):GND
  52    GND  VSS21 @S9S_MB_2U_LIB.S9S_MB_2U(SCH_1):GND
  54    GND  VSS22 @S9S_MB_2U_LIB.S9S_MB_2U(SCH_1):GND
  57    GND  VSS23 @S9S_MB_2U_LIB.S9S_MB_2U(SCH_1):GND
  59    GND  VSS24 @S9S_MB_2U_LIB.S9S_MB_2U(SCH_1):GND
  61    GND  VSS25 @S9S_MB_2U_LIB.S9S_MB_2U(SCH_1):GND
  63    GND  VSS26 @S9S_MB_2U_LIB.S9S_MB_2U(SCH_1):GND
  65    GND  VSS27 @S9S_MB_2U_LIB.S9S_MB_2U(SCH_1):GND
  67    GND  VSS28 @S9S_MB_2U_LIB.S9S_MB_2U(SCH_1):GND
  69    GND  VSS29 @S9S_MB_2U_LIB.S9S_MB_2U(SCH_1):GND
  71    GND  VSS30 @S9S_MB_2U_LIB.S9S_MB_2U(SCH_1):GND
  73    GND  VSS31 @S9S_MB_2U_LIB.S9S_MB_2U(SCH_1):GND
  75    GND  VSS32 @S9S_MB_2U_LIB.S9S_MB_2U(SCH_1):GND
  77    GND  VSS33 @S9S_MB_2U_LIB.S9S_MB_2U(SCH_1):GND
  79    GND  VSS34 @S9S_MB_2U_LIB.S9S_MB_2U(SCH_1):GND
  81    GND  VSS35 @S9S_MB_2U_LIB.S9S_MB_2U(SCH_1):GND
  83    GND  VSS36 @S9S_MB_2U_LIB.S9S_MB_2U(SCH_1):GND
  85    GND  VSS37 @S9S_MB_2U_LIB.S9S_MB_2U(SCH_1):GND
  88    GND  VSS38 @S9S_MB_2U_LIB.S9S_MB_2U(SCH_1):GND
  90    GND  VSS39 @S9S_MB_2U_LIB.S9S_MB_2U(SCH_1):GND
  92    GND  VSS40 @S9S_MB_2U_LIB.S9S_MB_2U(SCH_1):GND
  95    GND  VSS41 @S9S_MB_2U_LIB.S9S_MB_2U(SCH_1):GND
  97    GND  VSS42 @S9S_MB_2U_LIB.S9S_MB_2U(SCH_1):GND
  99    GND  VSS43 @S9S_MB_2U_LIB.S9S_MB_2U(SCH_1):GND
 101    GND  VSS44 @S9S_MB_2U_LIB.S9S_MB_2U(SCH_1):GND
 103    GND  VSS45 @S9S_MB_2U_LIB.S9S_MB_2U(SCH_1):GND
 106    GND  VSS46 @S9S_MB_2U_LIB.S9S_MB_2U(SCH_1):GND
 108    GND  VSS47 @S9S_MB_2U_LIB.S9S_MB_2U(SCH_1):GND
 110    GND  VSS48 @S9S_MB_2U_LIB.S9S_MB_2U(SCH_1):GND
 112    GND  VSS49 @S9S_MB_2U_LIB.S9S_MB_2U(SCH_1):GND
 114    GND  VSS50 @S9S_MB_2U_LIB.S9S_MB_2U(SCH_1):GND
 117    GND  VSS51 @S9S_MB_2U_LIB.S9S_MB_2U(SCH_1):GND
 119    GND  VSS52 @S9S_MB_2U_LIB.S9S_MB_2U(SCH_1):GND
 121    GND  VSS53 @S9S_MB_2U_LIB.S9S_MB_2U(SCH_1):GND
 123    GND  VSS54 @S9S_MB_2U_LIB.S9S_MB_2U(SCH_1):GND
 125    GND  VSS55 @S9S_MB_2U_LIB.S9S_MB_2U(SCH_1):GND
 128    GND  VSS56 @S9S_MB_2U_LIB.S9S_MB_2U(SCH_1):GND
 130    GND  VSS57 @S9S_MB_2U_LIB.S9S_MB_2U(SCH_1):GND
 134    GND  VSS59 @S9S_MB_2U_LIB.S9S_MB_2U(SCH_1):GND
 143    GND  VSS63 @S9S_MB_2U_LIB.S9S_MB_2U(SCH_1):GND
 151    GND  VSS64 @S9S_MB_2U_LIB.S9S_MB_2U(SCH_1):GND
 153    GND  VSS65 @S9S_MB_2U_LIB.S9S_MB_2U(SCH_1):GND
 155    GND  VSS66 @S9S_MB_2U_LIB.S9S_MB_2U(SCH_1):GND
 158    GND  VSS67 @S9S_MB_2U_LIB.S9S_MB_2U(SCH_1):GND
 160    GND  VSS68 @S9S_MB_2U_LIB.S9S_MB_2U(SCH_1):GND
 162    GND  VSS69 @S9S_MB_2U_LIB.S9S_MB_2U(SCH_1):GND
 164    GND  VSS70 @S9S_MB_2U_LIB.S9S_MB_2U(SCH_1):GND
 166    GND  VSS71 @S9S_MB_2U_LIB.S9S_MB_2U(SCH_1):GND
 169    GND  VSS72 @S9S_MB_2U_LIB.S9S_MB_2U(SCH_1):GND
 171    GND  VSS73 @S9S_MB_2U_LIB.S9S_MB_2U(SCH_1):GND
 173    GND  VSS74 @S9S_MB_2U_LIB.S9S_MB_2U(SCH_1):GND
 175    GND  VSS75 @S9S_MB_2U_LIB.S9S_MB_2U(SCH_1):GND
 177    GND  VSS76 @S9S_MB_2U_LIB.S9S_MB_2U(SCH_1):GND
 180    GND  VSS77 @S9S_MB_2U_LIB.S9S_MB_2U(SCH_1):GND
 182    GND  VSS78 @S9S_MB_2U_LIB.S9S_MB_2U(SCH_1):GND
 184    GND  VSS79 @S9S_MB_2U_LIB.S9S_MB_2U(SCH_1):GND
 186    GND  VSS80 @S9S_MB_2U_LIB.S9S_MB_2U(SCH_1):GND
 188    GND  VSS81 @S9S_MB_2U_LIB.S9S_MB_2U(SCH_1):GND
 191    GND  VSS82 @S9S_MB_2U_LIB.S9S_MB_2U(SCH_1):GND
 193    GND  VSS83 @S9S_MB_2U_LIB.S9S_MB_2U(SCH_1):GND
 195    GND  VSS84 @S9S_MB_2U_LIB.S9S_MB_2U(SCH_1):GND
 197    GND  VSS85 @S9S_MB_2U_LIB.S9S_MB_2U(SCH_1):GND
 199    GND  VSS86 @S9S_MB_2U_LIB.S9S_MB_2U(SCH_1):GND
 202    GND  VSS87 @S9S_MB_2U_LIB.S9S_MB_2U(SCH_1):GND
 204    GND  VSS88 @S9S_MB_2U_LIB.S9S_MB_2U(SCH_1):GND
 206    GND  VSS89 @S9S_MB_2U_LIB.S9S_MB_2U(SCH_1):GND
 208    GND  VSS90 @S9S_MB_2U_LIB.S9S_MB_2U(SCH_1):GND
 210    GND  VSS91 @S9S_MB_2U_LIB.S9S_MB_2U(SCH_1):GND
 212    GND  VSS92 @S9S_MB_2U_LIB.S9S_MB_2U(SCH_1):GND
 214    GND  VSS93 @S9S_MB_2U_LIB.S9S_MB_2U(SCH_1):GND
 216    GND  VSS94 @S9S_MB_2U_LIB.S9S_MB_2U(SCH_1):GND
 219    GND  VSS95 @S9S_MB_2U_LIB.S9S_MB_2U(SCH_1):GND
 222    GND  VSS96 @S9S_MB_2U_LIB.S9S_MB_2U(SCH_1):GND
 224    GND  VSS97 @S9S_MB_2U_LIB.S9S_MB_2U(SCH_1):GND
 226    GND  VSS98 @S9S_MB_2U_LIB.S9S_MB_2U(SCH_1):GND
 228    GND  VSS99 @S9S_MB_2U_LIB.S9S_MB_2U(SCH_1):GND
 233    GND VSS101 @S9S_MB_2U_LIB.S9S_MB_2U(SCH_1):GND
 237    GND VSS103 @S9S_MB_2U_LIB.S9S_MB_2U(SCH_1):GND
 242    GND VSS105 @S9S_MB_2U_LIB.S9S_MB_2U(SCH_1):GND
 244    GND VSS106 @S9S_MB_2U_LIB.S9S_MB_2U(SCH_1):GND
 246    GND VSS107 @S9S_MB_2U_LIB.S9S_MB_2U(SCH_1):GND
 248    GND VSS108 @S9S_MB_2U_LIB.S9S_MB_2U(SCH_1):GND
 251    GND VSS109 @S9S_MB_2U_LIB.S9S_MB_2U(SCH_1):GND
 253    GND VSS110 @S9S_MB_2U_LIB.S9S_MB_2U(SCH_1):GND
 255    GND VSS111 @S9S_MB_2U_LIB.S9S_MB_2U(SCH_1):GND
 257    GND VSS112 @S9S_MB_2U_LIB.S9S_MB_2U(SCH_1):GND
 259    GND VSS113 @S9S_MB_2U_LIB.S9S_MB_2U(SCH_1):GND
 262    GND VSS114 @S9S_MB_2U_LIB.S9S_MB_2U(SCH_1):GND
 264    GND VSS115 @S9S_MB_2U_LIB.S9S_MB_2U(SCH_1):GND
 266    GND VSS116 @S9S_MB_2U_LIB.S9S_MB_2U(SCH_1):GND
 268    GND VSS117 @S9S_MB_2U_LIB.S9S_MB_2U(SCH_1):GND
 270    GND VSS118 @S9S_MB_2U_LIB.S9S_MB_2U(SCH_1):GND
 273    GND VSS119 @S9S_MB_2U_LIB.S9S_MB_2U(SCH_1):GND
 275    GND VSS120 @S9S_MB_2U_LIB.S9S_MB_2U(SCH_1):GND
 277    GND VSS121 @S9S_MB_2U_LIB.S9S_MB_2U(SCH_1):GND
 279    GND VSS122 @S9S_MB_2U_LIB.S9S_MB_2U(SCH_1):GND
 281    GND VSS123 @S9S_MB_2U_LIB.S9S_MB_2U(SCH_1):GND
 284    GND VSS124 @S9S_MB_2U_LIB.S9S_MB_2U(SCH_1):GND
 286    GND VSS125 @S9S_MB_2U_LIB.S9S_MB_2U(SCH_1):GND
 288    GND VSS126 @S9S_MB_2U_LIB.S9S_MB_2U(SCH_1):GND
   1 P12V_S3_AUX_CPU0_NVDIMM VIN_BULK0 @S9S_MB_2U_LIB.S9S_MB_2U(SCH_1):P12V_S3_AUX_CPU0_NVDIMM
 145 P12V_S3_AUX_CPU0_NVDIMM VIN_BULK1 @S9S_MB_2U_LIB.S9S_MB_2U(SCH_1):P12V_S3_AUX_CPU0_NVDIMM
 146 P12V_S3_AUX_CPU0_NVDIMM VIN_BULK2 @S9S_MB_2U_LIB.S9S_MB_2U(SCH_1):P12V_S3_AUX_CPU0_NVDIMM
 230    GND VSS100 @S9S_MB_2U_LIB.S9S_MB_2U(SCH_1):GND
 235    GND VSS102 @S9S_MB_2U_LIB.S9S_MB_2U(SCH_1):GND
 240    GND VSS104 @S9S_MB_2U_LIB.S9S_MB_2U(SCH_1):GND
 132    GND  VSS58 @S9S_MB_2U_LIB.S9S_MB_2U(SCH_1):GND
 136    GND  VSS60 @S9S_MB_2U_LIB.S9S_MB_2U(SCH_1):GND
 139    GND  VSS61 @S9S_MB_2U_LIB.S9S_MB_2U(SCH_1):GND
 141    GND  VSS62 @S9S_MB_2U_LIB.S9S_MB_2U(SCH_1):GND
  G1    GND     G1 @S9S_MB_2U_LIB.S9S_MB_2U(SCH_1):GND
  G2    GND     G2 @S9S_MB_2U_LIB.S9S_MB_2U(SCH_1):GND
  G3    GND     G3 @S9S_MB_2U_LIB.S9S_MB_2U(SCH_1):GND

SCONN288_ADR50017P087CC-SCONN2A  I178  J6
  93 M_C_CPU0_SB_DQS_DP<9> DQS9_B_T||TDQS9_B_T||DBI4_B_N @S9S_MB_2U_LIB.S9S_MB_2U(SCH_1):M_C_CPU0_SB_DQS_DP(9)
  94 M_C_CPU0_SB_DQS_DN<9> DQS9_B_C||TDQS9_B_C @S9S_MB_2U_LIB.S9S_MB_2U(SCH_1):M_C_CPU0_SB_DQS_DN(9)
 201 M_C_CPU0_SA_DQS_DP<9> DQS9_A_T||TDQS9_A_T @S9S_MB_2U_LIB.S9S_MB_2U(SCH_1):M_C_CPU0_SA_DQS_DP(9)
 200 M_C_CPU0_SA_DQS_DN<9> DQS9_A_C||TDQS9_A_C @S9S_MB_2U_LIB.S9S_MB_2U(SCH_1):M_C_CPU0_SA_DQS_DN(9)
 190 M_C_CPU0_SA_DQS_DP<8> DQS8_A_T||TDQS8_A_T @S9S_MB_2U_LIB.S9S_MB_2U(SCH_1):M_C_CPU0_SA_DQS_DP(8)
 189 M_C_CPU0_SA_DQS_DN<8> DQS8_A_C||TDQS8_A_C @S9S_MB_2U_LIB.S9S_MB_2U(SCH_1):M_C_CPU0_SA_DQS_DN(8)
 271 M_C_CPU0_SB_DQS_DN<7> DQS7_B_C||TDQS7_B_C @S9S_MB_2U_LIB.S9S_MB_2U(SCH_1):M_C_CPU0_SB_DQS_DN(7)
 179 M_C_CPU0_SA_DQS_DP<7> DQS7_A_T||TDQS7_A_T @S9S_MB_2U_LIB.S9S_MB_2U(SCH_1):M_C_CPU0_SA_DQS_DP(7)
 261 M_C_CPU0_SB_DQS_DP<6> DQS6_B_T||TDQS6_B_T @S9S_MB_2U_LIB.S9S_MB_2U(SCH_1):M_C_CPU0_SB_DQS_DP(6)
 260 M_C_CPU0_SB_DQS_DN<6> DQS6_B_C||TDQS6_B_C @S9S_MB_2U_LIB.S9S_MB_2U(SCH_1):M_C_CPU0_SB_DQS_DN(6)
 167 M_C_CPU0_SA_DQS_DN<6> DQS6_A_C||TDQS6_A_C||DQS6_A_T||TDQS6_A_T @S9S_MB_2U_LIB.S9S_MB_2U(SCH_1):M_C_CPU0_SA_DQS_DN(6)
 250 M_C_CPU0_SB_DQS_DP<5> DQS5_B_T||TDQS5_B_T @S9S_MB_2U_LIB.S9S_MB_2U(SCH_1):M_C_CPU0_SB_DQS_DP(5)
 249 M_C_CPU0_SB_DQS_DN<5> DQS5_B_C||TDQS5_B_C @S9S_MB_2U_LIB.S9S_MB_2U(SCH_1):M_C_CPU0_SB_DQS_DN(5)
 157 M_C_CPU0_SA_DQS_DP<5> DQS5_A_T||TDQS5_A_T @S9S_MB_2U_LIB.S9S_MB_2U(SCH_1):M_C_CPU0_SA_DQS_DP(5)
 156 M_C_CPU0_SA_DQS_DN<5> DQS5_A_C||TDQS5_A_C||DQS5_A_T||TDQS5_A_T @S9S_MB_2U_LIB.S9S_MB_2U(SCH_1):M_C_CPU0_SA_DQS_DN(5)
 239 M_C_CPU0_SB_DQS_DP<4> DQS4_B_T @S9S_MB_2U_LIB.S9S_MB_2U(SCH_1):M_C_CPU0_SB_DQS_DP(4)
 238 M_C_CPU0_SB_DQS_DN<4> DQS4_B_C @S9S_MB_2U_LIB.S9S_MB_2U(SCH_1):M_C_CPU0_SB_DQS_DN(4)
  55 M_C_CPU0_SA_DQS_DP<4> DQS4_A_T @S9S_MB_2U_LIB.S9S_MB_2U(SCH_1):M_C_CPU0_SA_DQS_DP(4)
  56 M_C_CPU0_SA_DQS_DN<4> DQS4_A_C @S9S_MB_2U_LIB.S9S_MB_2U(SCH_1):M_C_CPU0_SA_DQS_DN(4)
 137 M_C_CPU0_SB_DQS_DP<3> DQS3_B_T @S9S_MB_2U_LIB.S9S_MB_2U(SCH_1):M_C_CPU0_SB_DQS_DP(3)
 138 M_C_CPU0_SB_DQS_DN<3> DQS3_B_C @S9S_MB_2U_LIB.S9S_MB_2U(SCH_1):M_C_CPU0_SB_DQS_DN(3)
  44 M_C_CPU0_SA_DQS_DP<3> DQS3_A_T @S9S_MB_2U_LIB.S9S_MB_2U(SCH_1):M_C_CPU0_SA_DQS_DP(3)
  45 M_C_CPU0_SA_DQS_DN<3> DQS3_A_C @S9S_MB_2U_LIB.S9S_MB_2U(SCH_1):M_C_CPU0_SA_DQS_DN(3)
 126 M_C_CPU0_SB_DQS_DP<2> DQS2_B_T @S9S_MB_2U_LIB.S9S_MB_2U(SCH_1):M_C_CPU0_SB_DQS_DP(2)
 127 M_C_CPU0_SB_DQS_DN<2> DQS2_B_C @S9S_MB_2U_LIB.S9S_MB_2U(SCH_1):M_C_CPU0_SB_DQS_DN(2)
  33 M_C_CPU0_SA_DQS_DP<2> DQS2_A_T @S9S_MB_2U_LIB.S9S_MB_2U(SCH_1):M_C_CPU0_SA_DQS_DP(2)
  34 M_C_CPU0_SA_DQS_DN<2> DQS2_A_C @S9S_MB_2U_LIB.S9S_MB_2U(SCH_1):M_C_CPU0_SA_DQS_DN(2)
 115 M_C_CPU0_SB_DQS_DP<1> DQS1_B_T @S9S_MB_2U_LIB.S9S_MB_2U(SCH_1):M_C_CPU0_SB_DQS_DP(1)
 116 M_C_CPU0_SB_DQS_DN<1> DQS1_B_C @S9S_MB_2U_LIB.S9S_MB_2U(SCH_1):M_C_CPU0_SB_DQS_DN(1)
  22 M_C_CPU0_SA_DQS_DP<1> DQS1_A_T @S9S_MB_2U_LIB.S9S_MB_2U(SCH_1):M_C_CPU0_SA_DQS_DP(1)
  23 M_C_CPU0_SA_DQS_DN<1> DQS1_A_C @S9S_MB_2U_LIB.S9S_MB_2U(SCH_1):M_C_CPU0_SA_DQS_DN(1)
 104 M_C_CPU0_SB_DQS_DP<0> DQS0_B_T @S9S_MB_2U_LIB.S9S_MB_2U(SCH_1):M_C_CPU0_SB_DQS_DP(0)
 105 M_C_CPU0_SB_DQS_DN<0> DQS0_B_C @S9S_MB_2U_LIB.S9S_MB_2U(SCH_1):M_C_CPU0_SB_DQS_DN(0)
  11 M_C_CPU0_SA_DQS_DP<0> DQS0_A_T @S9S_MB_2U_LIB.S9S_MB_2U(SCH_1):M_C_CPU0_SA_DQS_DP(0)
  12 M_C_CPU0_SA_DQS_DN<0> DQS0_A_C @S9S_MB_2U_LIB.S9S_MB_2U(SCH_1):M_C_CPU0_SA_DQS_DN(0)
 272 M_C_CPU0_SB_DQS_DP<7> DQS7_B_T||TDQS7_B_T @S9S_MB_2U_LIB.S9S_MB_2U(SCH_1):M_C_CPU0_SB_DQS_DP(7)
 282 M_C_CPU0_SB_DQS_DN<8> DQS8_B_C||TDQS8_B_C @S9S_MB_2U_LIB.S9S_MB_2U(SCH_1):M_C_CPU0_SB_DQS_DN(8)
 283 M_C_CPU0_SB_DQS_DP<8> DQS8_B_T||TDQS8_B_T @S9S_MB_2U_LIB.S9S_MB_2U(SCH_1):M_C_CPU0_SB_DQS_DP(8)
 168 M_C_CPU0_SA_DQS_DP<6> DQS6_A_T||TDQS6_A_T @S9S_MB_2U_LIB.S9S_MB_2U(SCH_1):M_C_CPU0_SA_DQS_DP(6)
 178 M_C_CPU0_SA_DQS_DN<7> DQS7_A_C||TDQS7_A_C @S9S_MB_2U_LIB.S9S_MB_2U(SCH_1):M_C_CPU0_SA_DQS_DN(7)

Q_RES_0402LF-49.9,1%,1/16W,CHIA  I180  R3880
   1 I3C_SPD_DDRABCD_CPU0_LVC1_SCL_5      A @S9S_MB_2U_LIB.S9S_MB_2U(SCH_1):I3C_SPD_DDRABCD_CPU0_LVC1_SCL_R6
   2 I3C_SPD_DDRABCD_CPU0_LVC1_SCL      B @S9S_MB_2U_LIB.S9S_MB_2U(SCH_1):I3C_SPD_DDRABCD_CPU0_LVC1_SCL


DRAWING: @S9S_MB_2U_LIB.S9S_MB_2U(SCH_1):PAGE88 

Q_RES_0402LF-127K,1%,1/16W,CHIA  I2  R32
   1 PD_CHD_CPU0_DIMM1_SAA      A @S9S_MB_2U_LIB.S9S_MB_2U(SCH_1):PD_CHD_CPU0_DIMM1_SAA
   2    GND      B @S9S_MB_2U_LIB.S9S_MB_2U(SCH_1):GND

SCONN288_ADR50017P130CC-SCONN2A  I12  J7
   3 P3V3_AUX VIN_MGMT @S9S_MB_2U_LIB.S9S_MB_2U(SCH_1):P3V3_AUX
   2 TP_CHD_CPU0_DIMM1_FRU_0   RFU0 @S9S_MB_2U_LIB.S9S_MB_2U(SCH_1):TP_CHD_CPU0_DIMM1_FRU_0
 144 TP_CHD_CPU0_DIMM1_FRU_1   RFU1 @S9S_MB_2U_LIB.S9S_MB_2U(SCH_1):TP_CHD_CPU0_DIMM1_FRU_1
 149 TP_CHD_CPU0_DIMM1_FRU_2   RFU2 @S9S_MB_2U_LIB.S9S_MB_2U(SCH_1):TP_CHD_CPU0_DIMM1_FRU_2
 150 TP_CHD_CPU0_DIMM1_FRU_3   RFU3 @S9S_MB_2U_LIB.S9S_MB_2U(SCH_1):TP_CHD_CPU0_DIMM1_FRU_3
 220 TP_CHD_CPU0_DIMM1_FRU_4   RFU4 @S9S_MB_2U_LIB.S9S_MB_2U(SCH_1):TP_CHD_CPU0_DIMM1_FRU_4
 231 TP_CHD_CPU0_DIMM1_FRU_5   RFU5 @S9S_MB_2U_LIB.S9S_MB_2U(SCH_1):TP_CHD_CPU0_DIMM1_FRU_5
 232 TP_CHD_CPU0_DIMM1_FRU_6   RFU6 @S9S_MB_2U_LIB.S9S_MB_2U(SCH_1):TP_CHD_CPU0_DIMM1_FRU_6
 207 RST_M_CD_CPU0_FPGA_N RESET_N @S9S_MB_2U_LIB.S9S_MB_2U(SCH_1):RST_M_CD_CPU0_FPGA_N
 147 PWRGD_CHD_CPU0_DIMM1 PWR_GOOD||FAIL_N @S9S_MB_2U_LIB.S9S_MB_2U(SCH_1):PWRGD_CHD_CPU0_DIMM1
 227 M_D_CPU0_SB_PAR  PAR_B @S9S_MB_2U_LIB.S9S_MB_2U(SCH_1):M_D_CPU0_SB_PAR
  74 M_D_CPU0_SA_PAR  PAR_A @S9S_MB_2U_LIB.S9S_MB_2U(SCH_1):M_D_CPU0_SA_PAR
  87 M_D_CPU0_SB_RSP<0> LBS||RSP_B_N @S9S_MB_2U_LIB.S9S_MB_2U(SCH_1):M_D_CPU0_SB_RSP(0)
  86 M_D_CPU0_SA_RSP<0> LBD||RSP_A_N @S9S_MB_2U_LIB.S9S_MB_2U(SCH_1):M_D_CPU0_SA_RSP(0)
   5 I3C_SPD_DDRABCD_CPU0_LVC1_SDA   HSDA @S9S_MB_2U_LIB.S9S_MB_2U(SCH_1):I3C_SPD_DDRABCD_CPU0_LVC1_SDA
   4 I3C_SPD_DDRABCD_CPU0_LVC1_SCL_6   HSCL @S9S_MB_2U_LIB.S9S_MB_2U(SCH_1):I3C_SPD_DDRABCD_CPU0_LVC1_SCL_R7
 148 PD_CHD_CPU0_DIMM1_SAA    HSA @S9S_MB_2U_LIB.S9S_MB_2U(SCH_1):PD_CHD_CPU0_DIMM1_SAA
 100 M_D_CPU0_SB_DQ<0>  DQ0_B @S9S_MB_2U_LIB.S9S_MB_2U(SCH_1):M_D_CPU0_SB_DQ(0)
 102 M_D_CPU0_SB_DQ<1>  DQ1_B @S9S_MB_2U_LIB.S9S_MB_2U(SCH_1):M_D_CPU0_SB_DQ(1)
 245 M_D_CPU0_SB_DQ<2>  DQ2_B @S9S_MB_2U_LIB.S9S_MB_2U(SCH_1):M_D_CPU0_SB_DQ(2)
 247 M_D_CPU0_SB_DQ<3>  DQ3_B @S9S_MB_2U_LIB.S9S_MB_2U(SCH_1):M_D_CPU0_SB_DQ(3)
 107 M_D_CPU0_SB_DQ<4>  DQ4_B @S9S_MB_2U_LIB.S9S_MB_2U(SCH_1):M_D_CPU0_SB_DQ(4)
 109 M_D_CPU0_SB_DQ<5>  DQ5_B @S9S_MB_2U_LIB.S9S_MB_2U(SCH_1):M_D_CPU0_SB_DQ(5)
 252 M_D_CPU0_SB_DQ<6>  DQ6_B @S9S_MB_2U_LIB.S9S_MB_2U(SCH_1):M_D_CPU0_SB_DQ(6)
 254 M_D_CPU0_SB_DQ<7>  DQ7_B @S9S_MB_2U_LIB.S9S_MB_2U(SCH_1):M_D_CPU0_SB_DQ(7)
 111 M_D_CPU0_SB_DQ<8>  DQ8_B @S9S_MB_2U_LIB.S9S_MB_2U(SCH_1):M_D_CPU0_SB_DQ(8)
 113 M_D_CPU0_SB_DQ<9>  DQ9_B @S9S_MB_2U_LIB.S9S_MB_2U(SCH_1):M_D_CPU0_SB_DQ(9)
 256 M_D_CPU0_SB_DQ<10> DQ10_B @S9S_MB_2U_LIB.S9S_MB_2U(SCH_1):M_D_CPU0_SB_DQ(10)
 258 M_D_CPU0_SB_DQ<11> DQ11_B @S9S_MB_2U_LIB.S9S_MB_2U(SCH_1):M_D_CPU0_SB_DQ(11)
 118 M_D_CPU0_SB_DQ<12> DQ12_B @S9S_MB_2U_LIB.S9S_MB_2U(SCH_1):M_D_CPU0_SB_DQ(12)
 120 M_D_CPU0_SB_DQ<13> DQ13_B @S9S_MB_2U_LIB.S9S_MB_2U(SCH_1):M_D_CPU0_SB_DQ(13)
 263 M_D_CPU0_SB_DQ<14> DQ14_B @S9S_MB_2U_LIB.S9S_MB_2U(SCH_1):M_D_CPU0_SB_DQ(14)
 265 M_D_CPU0_SB_DQ<15> DQ15_B @S9S_MB_2U_LIB.S9S_MB_2U(SCH_1):M_D_CPU0_SB_DQ(15)
 122 M_D_CPU0_SB_DQ<16> DQ16_B @S9S_MB_2U_LIB.S9S_MB_2U(SCH_1):M_D_CPU0_SB_DQ(16)
 124 M_D_CPU0_SB_DQ<17> DQ17_B @S9S_MB_2U_LIB.S9S_MB_2U(SCH_1):M_D_CPU0_SB_DQ(17)
 267 M_D_CPU0_SB_DQ<18> DQ18_B @S9S_MB_2U_LIB.S9S_MB_2U(SCH_1):M_D_CPU0_SB_DQ(18)
 269 M_D_CPU0_SB_DQ<19> DQ19_B @S9S_MB_2U_LIB.S9S_MB_2U(SCH_1):M_D_CPU0_SB_DQ(19)
 129 M_D_CPU0_SB_DQ<20> DQ20_B @S9S_MB_2U_LIB.S9S_MB_2U(SCH_1):M_D_CPU0_SB_DQ(20)
 131 M_D_CPU0_SB_DQ<21> DQ21_B @S9S_MB_2U_LIB.S9S_MB_2U(SCH_1):M_D_CPU0_SB_DQ(21)
 274 M_D_CPU0_SB_DQ<22> DQ22_B @S9S_MB_2U_LIB.S9S_MB_2U(SCH_1):M_D_CPU0_SB_DQ(22)
 276 M_D_CPU0_SB_DQ<23> DQ23_B @S9S_MB_2U_LIB.S9S_MB_2U(SCH_1):M_D_CPU0_SB_DQ(23)
 133 M_D_CPU0_SB_DQ<24> DQ24_B @S9S_MB_2U_LIB.S9S_MB_2U(SCH_1):M_D_CPU0_SB_DQ(24)
 135 M_D_CPU0_SB_DQ<25> DQ25_B @S9S_MB_2U_LIB.S9S_MB_2U(SCH_1):M_D_CPU0_SB_DQ(25)
 278 M_D_CPU0_SB_DQ<26> DQ26_B @S9S_MB_2U_LIB.S9S_MB_2U(SCH_1):M_D_CPU0_SB_DQ(26)
 280 M_D_CPU0_SB_DQ<27> DQ27_B @S9S_MB_2U_LIB.S9S_MB_2U(SCH_1):M_D_CPU0_SB_DQ(27)
 140 M_D_CPU0_SB_DQ<28> DQ28_B @S9S_MB_2U_LIB.S9S_MB_2U(SCH_1):M_D_CPU0_SB_DQ(28)
 142 M_D_CPU0_SB_DQ<29> DQ29_B @S9S_MB_2U_LIB.S9S_MB_2U(SCH_1):M_D_CPU0_SB_DQ(29)
 285 M_D_CPU0_SB_DQ<30> DQ30_B @S9S_MB_2U_LIB.S9S_MB_2U(SCH_1):M_D_CPU0_SB_DQ(30)
 287 M_D_CPU0_SB_DQ<31> DQ31_B @S9S_MB_2U_LIB.S9S_MB_2U(SCH_1):M_D_CPU0_SB_DQ(31)
   7 M_D_CPU0_SA_DQ<0>  DQ0_A @S9S_MB_2U_LIB.S9S_MB_2U(SCH_1):M_D_CPU0_SA_DQ(0)
   9 M_D_CPU0_SA_DQ<1>  DQ1_A @S9S_MB_2U_LIB.S9S_MB_2U(SCH_1):M_D_CPU0_SA_DQ(1)
 152 M_D_CPU0_SA_DQ<2>  DQ2_A @S9S_MB_2U_LIB.S9S_MB_2U(SCH_1):M_D_CPU0_SA_DQ(2)
 154 M_D_CPU0_SA_DQ<3>  DQ3_A @S9S_MB_2U_LIB.S9S_MB_2U(SCH_1):M_D_CPU0_SA_DQ(3)
  14 M_D_CPU0_SA_DQ<4>  DQ4_A @S9S_MB_2U_LIB.S9S_MB_2U(SCH_1):M_D_CPU0_SA_DQ(4)
  16 M_D_CPU0_SA_DQ<5>  DQ5_A @S9S_MB_2U_LIB.S9S_MB_2U(SCH_1):M_D_CPU0_SA_DQ(5)
 159 M_D_CPU0_SA_DQ<6>  DQ6_A @S9S_MB_2U_LIB.S9S_MB_2U(SCH_1):M_D_CPU0_SA_DQ(6)
 161 M_D_CPU0_SA_DQ<7>  DQ7_A @S9S_MB_2U_LIB.S9S_MB_2U(SCH_1):M_D_CPU0_SA_DQ(7)
  18 M_D_CPU0_SA_DQ<8>  DQ8_A @S9S_MB_2U_LIB.S9S_MB_2U(SCH_1):M_D_CPU0_SA_DQ(8)
  20 M_D_CPU0_SA_DQ<9>  DQ9_A @S9S_MB_2U_LIB.S9S_MB_2U(SCH_1):M_D_CPU0_SA_DQ(9)
 163 M_D_CPU0_SA_DQ<10> DQ10_A @S9S_MB_2U_LIB.S9S_MB_2U(SCH_1):M_D_CPU0_SA_DQ(10)
 165 M_D_CPU0_SA_DQ<11> DQ11_A @S9S_MB_2U_LIB.S9S_MB_2U(SCH_1):M_D_CPU0_SA_DQ(11)
  25 M_D_CPU0_SA_DQ<12> DQ12_A @S9S_MB_2U_LIB.S9S_MB_2U(SCH_1):M_D_CPU0_SA_DQ(12)
  27 M_D_CPU0_SA_DQ<13> DQ13_A @S9S_MB_2U_LIB.S9S_MB_2U(SCH_1):M_D_CPU0_SA_DQ(13)
 170 M_D_CPU0_SA_DQ<14> DQ14_A @S9S_MB_2U_LIB.S9S_MB_2U(SCH_1):M_D_CPU0_SA_DQ(14)
 172 M_D_CPU0_SA_DQ<15> DQ15_A @S9S_MB_2U_LIB.S9S_MB_2U(SCH_1):M_D_CPU0_SA_DQ(15)
  29 M_D_CPU0_SA_DQ<16> DQ16_A @S9S_MB_2U_LIB.S9S_MB_2U(SCH_1):M_D_CPU0_SA_DQ(16)
  31 M_D_CPU0_SA_DQ<17> DQ17_A @S9S_MB_2U_LIB.S9S_MB_2U(SCH_1):M_D_CPU0_SA_DQ(17)
 174 M_D_CPU0_SA_DQ<18> DQ18_A @S9S_MB_2U_LIB.S9S_MB_2U(SCH_1):M_D_CPU0_SA_DQ(18)
 176 M_D_CPU0_SA_DQ<19> DQ19_A @S9S_MB_2U_LIB.S9S_MB_2U(SCH_1):M_D_CPU0_SA_DQ(19)
  36 M_D_CPU0_SA_DQ<20> DQ20_A @S9S_MB_2U_LIB.S9S_MB_2U(SCH_1):M_D_CPU0_SA_DQ(20)
  38 M_D_CPU0_SA_DQ<21> DQ21_A @S9S_MB_2U_LIB.S9S_MB_2U(SCH_1):M_D_CPU0_SA_DQ(21)
 181 M_D_CPU0_SA_DQ<22> DQ22_A @S9S_MB_2U_LIB.S9S_MB_2U(SCH_1):M_D_CPU0_SA_DQ(22)
 183 M_D_CPU0_SA_DQ<23> DQ23_A @S9S_MB_2U_LIB.S9S_MB_2U(SCH_1):M_D_CPU0_SA_DQ(23)
  40 M_D_CPU0_SA_DQ<24> DQ24_A @S9S_MB_2U_LIB.S9S_MB_2U(SCH_1):M_D_CPU0_SA_DQ(24)
  42 M_D_CPU0_SA_DQ<25> DQ25_A @S9S_MB_2U_LIB.S9S_MB_2U(SCH_1):M_D_CPU0_SA_DQ(25)
 185 M_D_CPU0_SA_DQ<26> DQ26_A @S9S_MB_2U_LIB.S9S_MB_2U(SCH_1):M_D_CPU0_SA_DQ(26)
 187 M_D_CPU0_SA_DQ<27> DQ27_A @S9S_MB_2U_LIB.S9S_MB_2U(SCH_1):M_D_CPU0_SA_DQ(27)
  47 M_D_CPU0_SA_DQ<28> DQ28_A @S9S_MB_2U_LIB.S9S_MB_2U(SCH_1):M_D_CPU0_SA_DQ(28)
  49 M_D_CPU0_SA_DQ<29> DQ29_A @S9S_MB_2U_LIB.S9S_MB_2U(SCH_1):M_D_CPU0_SA_DQ(29)
 192 M_D_CPU0_SA_DQ<30> DQ30_A @S9S_MB_2U_LIB.S9S_MB_2U(SCH_1):M_D_CPU0_SA_DQ(30)
 229 M_D_CPU0_SB_CS_N<1> CS1_B_N @S9S_MB_2U_LIB.S9S_MB_2U(SCH_1):M_D_CPU0_SB_CS_N(1)
 209 M_D_CPU0_SA_CS_N<1> CS1_A_N @S9S_MB_2U_LIB.S9S_MB_2U(SCH_1):M_D_CPU0_SA_CS_N(1)
  84 M_D_CPU0_SB_CS_N<0> CS0_B_N @S9S_MB_2U_LIB.S9S_MB_2U(SCH_1):M_D_CPU0_SB_CS_N(0)
  64 M_D_CPU0_SA_CS_N<0> CS0_A_N @S9S_MB_2U_LIB.S9S_MB_2U(SCH_1):M_D_CPU0_SA_CS_N(0)
 217 M_D_CPU0_CLK_DP<0>   CK_T @S9S_MB_2U_LIB.S9S_MB_2U(SCH_1):M_D_CPU0_CLK_DP(0)
 218 M_D_CPU0_CLK_DN<0>   CK_C @S9S_MB_2U_LIB.S9S_MB_2U(SCH_1):M_D_CPU0_CLK_DN(0)
  96 M_D_CPU0_SB_CB<0>  CB0_B @S9S_MB_2U_LIB.S9S_MB_2U(SCH_1):M_D_CPU0_SB_CB(0)
  98 M_D_CPU0_SB_CB<1>  CB1_B @S9S_MB_2U_LIB.S9S_MB_2U(SCH_1):M_D_CPU0_SB_CB(1)
 241 M_D_CPU0_SB_CB<2>  CB2_B @S9S_MB_2U_LIB.S9S_MB_2U(SCH_1):M_D_CPU0_SB_CB(2)
 243 M_D_CPU0_SB_CB<3>  CB3_B @S9S_MB_2U_LIB.S9S_MB_2U(SCH_1):M_D_CPU0_SB_CB(3)
  89 M_D_CPU0_SB_CB<4>  CB4_B @S9S_MB_2U_LIB.S9S_MB_2U(SCH_1):M_D_CPU0_SB_CB(4)
  91 M_D_CPU0_SB_CB<5>  CB5_B @S9S_MB_2U_LIB.S9S_MB_2U(SCH_1):M_D_CPU0_SB_CB(5)
 234 M_D_CPU0_SB_CB<6>  CB6_B @S9S_MB_2U_LIB.S9S_MB_2U(SCH_1):M_D_CPU0_SB_CB(6)
  51 M_D_CPU0_SA_CB<0>  CB0_A @S9S_MB_2U_LIB.S9S_MB_2U(SCH_1):M_D_CPU0_SA_CB(0)
 196 M_D_CPU0_SA_CB<2>  CB2_A @S9S_MB_2U_LIB.S9S_MB_2U(SCH_1):M_D_CPU0_SA_CB(2)
 198 M_D_CPU0_SA_CB<3>  CB3_A @S9S_MB_2U_LIB.S9S_MB_2U(SCH_1):M_D_CPU0_SA_CB(3)
  60 M_D_CPU0_SA_CB<5>  CB5_A @S9S_MB_2U_LIB.S9S_MB_2U(SCH_1):M_D_CPU0_SA_CB(5)
 203 M_D_CPU0_SA_CB<6>  CB6_A @S9S_MB_2U_LIB.S9S_MB_2U(SCH_1):M_D_CPU0_SA_CB(6)
  82 M_D_CPU0_SB_CA<6>  CA6_B @S9S_MB_2U_LIB.S9S_MB_2U(SCH_1):M_D_CPU0_SB_CA(6)
  72 M_D_CPU0_SA_CA<6>  CA6_A @S9S_MB_2U_LIB.S9S_MB_2U(SCH_1):M_D_CPU0_SA_CA(6)
 225 M_D_CPU0_SB_CA<5>  CA5_B @S9S_MB_2U_LIB.S9S_MB_2U(SCH_1):M_D_CPU0_SB_CA(5)
 215 M_D_CPU0_SA_CA<5>  CA5_A @S9S_MB_2U_LIB.S9S_MB_2U(SCH_1):M_D_CPU0_SA_CA(5)
  80 M_D_CPU0_SB_CA<4>  CA4_B @S9S_MB_2U_LIB.S9S_MB_2U(SCH_1):M_D_CPU0_SB_CA(4)
  70 M_D_CPU0_SA_CA<4>  CA4_A @S9S_MB_2U_LIB.S9S_MB_2U(SCH_1):M_D_CPU0_SA_CA(4)
 223 M_D_CPU0_SB_CA<3>  CA3_B @S9S_MB_2U_LIB.S9S_MB_2U(SCH_1):M_D_CPU0_SB_CA(3)
 213 M_D_CPU0_SA_CA<3>  CA3_A @S9S_MB_2U_LIB.S9S_MB_2U(SCH_1):M_D_CPU0_SA_CA(3)
  78 M_D_CPU0_SB_CA<2>  CA2_B @S9S_MB_2U_LIB.S9S_MB_2U(SCH_1):M_D_CPU0_SB_CA(2)
  68 M_D_CPU0_SA_CA<2>  CA2_A @S9S_MB_2U_LIB.S9S_MB_2U(SCH_1):M_D_CPU0_SA_CA(2)
 221 M_D_CPU0_SB_CA<1>  CA1_B @S9S_MB_2U_LIB.S9S_MB_2U(SCH_1):M_D_CPU0_SB_CA(1)
 211 M_D_CPU0_SA_CA<1>  CA1_A @S9S_MB_2U_LIB.S9S_MB_2U(SCH_1):M_D_CPU0_SA_CA(1)
  76 M_D_CPU0_SB_CA<0>  CA0_B @S9S_MB_2U_LIB.S9S_MB_2U(SCH_1):M_D_CPU0_SB_CA(0)
  66 M_D_CPU0_SA_CA<0>  CA0_A @S9S_MB_2U_LIB.S9S_MB_2U(SCH_1):M_D_CPU0_SA_CA(0)
  62 M_D_CPU0_ALERT_N ALERT_N @S9S_MB_2U_LIB.S9S_MB_2U(SCH_1):M_D_CPU0_ALERT_N
 236 M_D_CPU0_SB_CB<7>  CB7_B @S9S_MB_2U_LIB.S9S_MB_2U(SCH_1):M_D_CPU0_SB_CB(7)
  53 M_D_CPU0_SA_CB<1>  CB1_A @S9S_MB_2U_LIB.S9S_MB_2U(SCH_1):M_D_CPU0_SA_CB(1)
  58 M_D_CPU0_SA_CB<4>  CB4_A @S9S_MB_2U_LIB.S9S_MB_2U(SCH_1):M_D_CPU0_SA_CB(4)
 205 M_D_CPU0_SA_CB<7>  CB7_A @S9S_MB_2U_LIB.S9S_MB_2U(SCH_1):M_D_CPU0_SA_CB(7)
 194 M_D_CPU0_SA_DQ<31> DQ31_A @S9S_MB_2U_LIB.S9S_MB_2U(SCH_1):M_D_CPU0_SA_DQ(31)

Q_CAP_C0402-2.2UF,6.3V,20%,X6SA  I123  C20
   1 P3V3_AUX      A @S9S_MB_2U_LIB.S9S_MB_2U(SCH_1):P3V3_AUX
   2    GND      B @S9S_MB_2U_LIB.S9S_MB_2U(SCH_1):GND

Q_CAP_C0805-10UF,16V,10%,X6S,CA  I126  C21
   1 P12V_S3_AUX_CPU0_NVDIMM      A @S9S_MB_2U_LIB.S9S_MB_2U(SCH_1):P12V_S3_AUX_CPU0_NVDIMM
   2    GND      B @S9S_MB_2U_LIB.S9S_MB_2U(SCH_1):GND

Q_CAP_C0805-10UF,16V,10%,X6S,CA  I166  C22
   1 P12V_S3_AUX_CPU0_NVDIMM      A @S9S_MB_2U_LIB.S9S_MB_2U(SCH_1):P12V_S3_AUX_CPU0_NVDIMM
   2    GND      B @S9S_MB_2U_LIB.S9S_MB_2U(SCH_1):GND

SCONN288_ADR50017P130CC-SCONN2A  I168  J7
   6    GND   VSS0 @S9S_MB_2U_LIB.S9S_MB_2U(SCH_1):GND
   8    GND   VSS1 @S9S_MB_2U_LIB.S9S_MB_2U(SCH_1):GND
  10    GND   VSS2 @S9S_MB_2U_LIB.S9S_MB_2U(SCH_1):GND
  13    GND   VSS3 @S9S_MB_2U_LIB.S9S_MB_2U(SCH_1):GND
  15    GND   VSS4 @S9S_MB_2U_LIB.S9S_MB_2U(SCH_1):GND
  17    GND   VSS5 @S9S_MB_2U_LIB.S9S_MB_2U(SCH_1):GND
  19    GND   VSS6 @S9S_MB_2U_LIB.S9S_MB_2U(SCH_1):GND
  21    GND   VSS7 @S9S_MB_2U_LIB.S9S_MB_2U(SCH_1):GND
  24    GND   VSS8 @S9S_MB_2U_LIB.S9S_MB_2U(SCH_1):GND
  26    GND   VSS9 @S9S_MB_2U_LIB.S9S_MB_2U(SCH_1):GND
  28    GND  VSS10 @S9S_MB_2U_LIB.S9S_MB_2U(SCH_1):GND
  30    GND  VSS11 @S9S_MB_2U_LIB.S9S_MB_2U(SCH_1):GND
  32    GND  VSS12 @S9S_MB_2U_LIB.S9S_MB_2U(SCH_1):GND
  35    GND  VSS13 @S9S_MB_2U_LIB.S9S_MB_2U(SCH_1):GND
  37    GND  VSS14 @S9S_MB_2U_LIB.S9S_MB_2U(SCH_1):GND
  39    GND  VSS15 @S9S_MB_2U_LIB.S9S_MB_2U(SCH_1):GND
  41    GND  VSS16 @S9S_MB_2U_LIB.S9S_MB_2U(SCH_1):GND
  43    GND  VSS17 @S9S_MB_2U_LIB.S9S_MB_2U(SCH_1):GND
  46    GND  VSS18 @S9S_MB_2U_LIB.S9S_MB_2U(SCH_1):GND
  48    GND  VSS19 @S9S_MB_2U_LIB.S9S_MB_2U(SCH_1):GND
  50    GND  VSS20 @S9S_MB_2U_LIB.S9S_MB_2U(SCH_1):GND
  52    GND  VSS21 @S9S_MB_2U_LIB.S9S_MB_2U(SCH_1):GND
  54    GND  VSS22 @S9S_MB_2U_LIB.S9S_MB_2U(SCH_1):GND
  57    GND  VSS23 @S9S_MB_2U_LIB.S9S_MB_2U(SCH_1):GND
  59    GND  VSS24 @S9S_MB_2U_LIB.S9S_MB_2U(SCH_1):GND
  61    GND  VSS25 @S9S_MB_2U_LIB.S9S_MB_2U(SCH_1):GND
  63    GND  VSS26 @S9S_MB_2U_LIB.S9S_MB_2U(SCH_1):GND
  65    GND  VSS27 @S9S_MB_2U_LIB.S9S_MB_2U(SCH_1):GND
  67    GND  VSS28 @S9S_MB_2U_LIB.S9S_MB_2U(SCH_1):GND
  69    GND  VSS29 @S9S_MB_2U_LIB.S9S_MB_2U(SCH_1):GND
  71    GND  VSS30 @S9S_MB_2U_LIB.S9S_MB_2U(SCH_1):GND
  73    GND  VSS31 @S9S_MB_2U_LIB.S9S_MB_2U(SCH_1):GND
  75    GND  VSS32 @S9S_MB_2U_LIB.S9S_MB_2U(SCH_1):GND
  77    GND  VSS33 @S9S_MB_2U_LIB.S9S_MB_2U(SCH_1):GND
  79    GND  VSS34 @S9S_MB_2U_LIB.S9S_MB_2U(SCH_1):GND
  81    GND  VSS35 @S9S_MB_2U_LIB.S9S_MB_2U(SCH_1):GND
  83    GND  VSS36 @S9S_MB_2U_LIB.S9S_MB_2U(SCH_1):GND
  85    GND  VSS37 @S9S_MB_2U_LIB.S9S_MB_2U(SCH_1):GND
  88    GND  VSS38 @S9S_MB_2U_LIB.S9S_MB_2U(SCH_1):GND
  90    GND  VSS39 @S9S_MB_2U_LIB.S9S_MB_2U(SCH_1):GND
  92    GND  VSS40 @S9S_MB_2U_LIB.S9S_MB_2U(SCH_1):GND
  95    GND  VSS41 @S9S_MB_2U_LIB.S9S_MB_2U(SCH_1):GND
  97    GND  VSS42 @S9S_MB_2U_LIB.S9S_MB_2U(SCH_1):GND
  99    GND  VSS43 @S9S_MB_2U_LIB.S9S_MB_2U(SCH_1):GND
 101    GND  VSS44 @S9S_MB_2U_LIB.S9S_MB_2U(SCH_1):GND
 103    GND  VSS45 @S9S_MB_2U_LIB.S9S_MB_2U(SCH_1):GND
 106    GND  VSS46 @S9S_MB_2U_LIB.S9S_MB_2U(SCH_1):GND
 108    GND  VSS47 @S9S_MB_2U_LIB.S9S_MB_2U(SCH_1):GND
 110    GND  VSS48 @S9S_MB_2U_LIB.S9S_MB_2U(SCH_1):GND
 112    GND  VSS49 @S9S_MB_2U_LIB.S9S_MB_2U(SCH_1):GND
 114    GND  VSS50 @S9S_MB_2U_LIB.S9S_MB_2U(SCH_1):GND
 117    GND  VSS51 @S9S_MB_2U_LIB.S9S_MB_2U(SCH_1):GND
 119    GND  VSS52 @S9S_MB_2U_LIB.S9S_MB_2U(SCH_1):GND
 121    GND  VSS53 @S9S_MB_2U_LIB.S9S_MB_2U(SCH_1):GND
 123    GND  VSS54 @S9S_MB_2U_LIB.S9S_MB_2U(SCH_1):GND
 125    GND  VSS55 @S9S_MB_2U_LIB.S9S_MB_2U(SCH_1):GND
 128    GND  VSS56 @S9S_MB_2U_LIB.S9S_MB_2U(SCH_1):GND
 130    GND  VSS57 @S9S_MB_2U_LIB.S9S_MB_2U(SCH_1):GND
 134    GND  VSS59 @S9S_MB_2U_LIB.S9S_MB_2U(SCH_1):GND
 143    GND  VSS63 @S9S_MB_2U_LIB.S9S_MB_2U(SCH_1):GND
 151    GND  VSS64 @S9S_MB_2U_LIB.S9S_MB_2U(SCH_1):GND
 153    GND  VSS65 @S9S_MB_2U_LIB.S9S_MB_2U(SCH_1):GND
 155    GND  VSS66 @S9S_MB_2U_LIB.S9S_MB_2U(SCH_1):GND
 158    GND  VSS67 @S9S_MB_2U_LIB.S9S_MB_2U(SCH_1):GND
 160    GND  VSS68 @S9S_MB_2U_LIB.S9S_MB_2U(SCH_1):GND
 162    GND  VSS69 @S9S_MB_2U_LIB.S9S_MB_2U(SCH_1):GND
 164    GND  VSS70 @S9S_MB_2U_LIB.S9S_MB_2U(SCH_1):GND
 166    GND  VSS71 @S9S_MB_2U_LIB.S9S_MB_2U(SCH_1):GND
 169    GND  VSS72 @S9S_MB_2U_LIB.S9S_MB_2U(SCH_1):GND
 171    GND  VSS73 @S9S_MB_2U_LIB.S9S_MB_2U(SCH_1):GND
 173    GND  VSS74 @S9S_MB_2U_LIB.S9S_MB_2U(SCH_1):GND
 175    GND  VSS75 @S9S_MB_2U_LIB.S9S_MB_2U(SCH_1):GND
 177    GND  VSS76 @S9S_MB_2U_LIB.S9S_MB_2U(SCH_1):GND
 180    GND  VSS77 @S9S_MB_2U_LIB.S9S_MB_2U(SCH_1):GND
 182    GND  VSS78 @S9S_MB_2U_LIB.S9S_MB_2U(SCH_1):GND
 184    GND  VSS79 @S9S_MB_2U_LIB.S9S_MB_2U(SCH_1):GND
 186    GND  VSS80 @S9S_MB_2U_LIB.S9S_MB_2U(SCH_1):GND
 188    GND  VSS81 @S9S_MB_2U_LIB.S9S_MB_2U(SCH_1):GND
 191    GND  VSS82 @S9S_MB_2U_LIB.S9S_MB_2U(SCH_1):GND
 193    GND  VSS83 @S9S_MB_2U_LIB.S9S_MB_2U(SCH_1):GND
 195    GND  VSS84 @S9S_MB_2U_LIB.S9S_MB_2U(SCH_1):GND
 197    GND  VSS85 @S9S_MB_2U_LIB.S9S_MB_2U(SCH_1):GND
 199    GND  VSS86 @S9S_MB_2U_LIB.S9S_MB_2U(SCH_1):GND
 202    GND  VSS87 @S9S_MB_2U_LIB.S9S_MB_2U(SCH_1):GND
 204    GND  VSS88 @S9S_MB_2U_LIB.S9S_MB_2U(SCH_1):GND
 206    GND  VSS89 @S9S_MB_2U_LIB.S9S_MB_2U(SCH_1):GND
 208    GND  VSS90 @S9S_MB_2U_LIB.S9S_MB_2U(SCH_1):GND
 210    GND  VSS91 @S9S_MB_2U_LIB.S9S_MB_2U(SCH_1):GND
 212    GND  VSS92 @S9S_MB_2U_LIB.S9S_MB_2U(SCH_1):GND
 214    GND  VSS93 @S9S_MB_2U_LIB.S9S_MB_2U(SCH_1):GND
 216    GND  VSS94 @S9S_MB_2U_LIB.S9S_MB_2U(SCH_1):GND
 219    GND  VSS95 @S9S_MB_2U_LIB.S9S_MB_2U(SCH_1):GND
 222    GND  VSS96 @S9S_MB_2U_LIB.S9S_MB_2U(SCH_1):GND
 224    GND  VSS97 @S9S_MB_2U_LIB.S9S_MB_2U(SCH_1):GND
 226    GND  VSS98 @S9S_MB_2U_LIB.S9S_MB_2U(SCH_1):GND
 228    GND  VSS99 @S9S_MB_2U_LIB.S9S_MB_2U(SCH_1):GND
 233    GND VSS101 @S9S_MB_2U_LIB.S9S_MB_2U(SCH_1):GND
 237    GND VSS103 @S9S_MB_2U_LIB.S9S_MB_2U(SCH_1):GND
 242    GND VSS105 @S9S_MB_2U_LIB.S9S_MB_2U(SCH_1):GND
 244    GND VSS106 @S9S_MB_2U_LIB.S9S_MB_2U(SCH_1):GND
 246    GND VSS107 @S9S_MB_2U_LIB.S9S_MB_2U(SCH_1):GND
 248    GND VSS108 @S9S_MB_2U_LIB.S9S_MB_2U(SCH_1):GND
 251    GND VSS109 @S9S_MB_2U_LIB.S9S_MB_2U(SCH_1):GND
 253    GND VSS110 @S9S_MB_2U_LIB.S9S_MB_2U(SCH_1):GND
 255    GND VSS111 @S9S_MB_2U_LIB.S9S_MB_2U(SCH_1):GND
 257    GND VSS112 @S9S_MB_2U_LIB.S9S_MB_2U(SCH_1):GND
 259    GND VSS113 @S9S_MB_2U_LIB.S9S_MB_2U(SCH_1):GND
 262    GND VSS114 @S9S_MB_2U_LIB.S9S_MB_2U(SCH_1):GND
 264    GND VSS115 @S9S_MB_2U_LIB.S9S_MB_2U(SCH_1):GND
 266    GND VSS116 @S9S_MB_2U_LIB.S9S_MB_2U(SCH_1):GND
 268    GND VSS117 @S9S_MB_2U_LIB.S9S_MB_2U(SCH_1):GND
 270    GND VSS118 @S9S_MB_2U_LIB.S9S_MB_2U(SCH_1):GND
 273    GND VSS119 @S9S_MB_2U_LIB.S9S_MB_2U(SCH_1):GND
 275    GND VSS120 @S9S_MB_2U_LIB.S9S_MB_2U(SCH_1):GND
 277    GND VSS121 @S9S_MB_2U_LIB.S9S_MB_2U(SCH_1):GND
 279    GND VSS122 @S9S_MB_2U_LIB.S9S_MB_2U(SCH_1):GND
 281    GND VSS123 @S9S_MB_2U_LIB.S9S_MB_2U(SCH_1):GND
 284    GND VSS124 @S9S_MB_2U_LIB.S9S_MB_2U(SCH_1):GND
 286    GND VSS125 @S9S_MB_2U_LIB.S9S_MB_2U(SCH_1):GND
 288    GND VSS126 @S9S_MB_2U_LIB.S9S_MB_2U(SCH_1):GND
   1 P12V_S3_AUX_CPU0_NVDIMM VIN_BULK0 @S9S_MB_2U_LIB.S9S_MB_2U(SCH_1):P12V_S3_AUX_CPU0_NVDIMM
 145 P12V_S3_AUX_CPU0_NVDIMM VIN_BULK1 @S9S_MB_2U_LIB.S9S_MB_2U(SCH_1):P12V_S3_AUX_CPU0_NVDIMM
 146 P12V_S3_AUX_CPU0_NVDIMM VIN_BULK2 @S9S_MB_2U_LIB.S9S_MB_2U(SCH_1):P12V_S3_AUX_CPU0_NVDIMM
 230    GND VSS100 @S9S_MB_2U_LIB.S9S_MB_2U(SCH_1):GND
 235    GND VSS102 @S9S_MB_2U_LIB.S9S_MB_2U(SCH_1):GND
 240    GND VSS104 @S9S_MB_2U_LIB.S9S_MB_2U(SCH_1):GND
 132    GND  VSS58 @S9S_MB_2U_LIB.S9S_MB_2U(SCH_1):GND
 136    GND  VSS60 @S9S_MB_2U_LIB.S9S_MB_2U(SCH_1):GND
 139    GND  VSS61 @S9S_MB_2U_LIB.S9S_MB_2U(SCH_1):GND
 141    GND  VSS62 @S9S_MB_2U_LIB.S9S_MB_2U(SCH_1):GND
  G1    GND     G1 @S9S_MB_2U_LIB.S9S_MB_2U(SCH_1):GND
  G2    GND     G2 @S9S_MB_2U_LIB.S9S_MB_2U(SCH_1):GND
  G3    GND     G3 @S9S_MB_2U_LIB.S9S_MB_2U(SCH_1):GND

SCONN288_ADR50017P130CC-SCONN2A  I178  J7
  93 M_D_CPU0_SB_DQS_DP<9> DQS9_B_T||TDQS9_B_T||DBI4_B_N @S9S_MB_2U_LIB.S9S_MB_2U(SCH_1):M_D_CPU0_SB_DQS_DP(9)
  94 M_D_CPU0_SB_DQS_DN<9> DQS9_B_C||TDQS9_B_C @S9S_MB_2U_LIB.S9S_MB_2U(SCH_1):M_D_CPU0_SB_DQS_DN(9)
 201 M_D_CPU0_SA_DQS_DP<9> DQS9_A_T||TDQS9_A_T @S9S_MB_2U_LIB.S9S_MB_2U(SCH_1):M_D_CPU0_SA_DQS_DP(9)
 200 M_D_CPU0_SA_DQS_DN<9> DQS9_A_C||TDQS9_A_C @S9S_MB_2U_LIB.S9S_MB_2U(SCH_1):M_D_CPU0_SA_DQS_DN(9)
 190 M_D_CPU0_SA_DQS_DP<8> DQS8_A_T||TDQS8_A_T @S9S_MB_2U_LIB.S9S_MB_2U(SCH_1):M_D_CPU0_SA_DQS_DP(8)
 189 M_D_CPU0_SA_DQS_DN<8> DQS8_A_C||TDQS8_A_C @S9S_MB_2U_LIB.S9S_MB_2U(SCH_1):M_D_CPU0_SA_DQS_DN(8)
 271 M_D_CPU0_SB_DQS_DN<7> DQS7_B_C||TDQS7_B_C @S9S_MB_2U_LIB.S9S_MB_2U(SCH_1):M_D_CPU0_SB_DQS_DN(7)
 179 M_D_CPU0_SA_DQS_DP<7> DQS7_A_T||TDQS7_A_T @S9S_MB_2U_LIB.S9S_MB_2U(SCH_1):M_D_CPU0_SA_DQS_DP(7)
 261 M_D_CPU0_SB_DQS_DP<6> DQS6_B_T||TDQS6_B_T @S9S_MB_2U_LIB.S9S_MB_2U(SCH_1):M_D_CPU0_SB_DQS_DP(6)
 260 M_D_CPU0_SB_DQS_DN<6> DQS6_B_C||TDQS6_B_C @S9S_MB_2U_LIB.S9S_MB_2U(SCH_1):M_D_CPU0_SB_DQS_DN(6)
 167 M_D_CPU0_SA_DQS_DN<6> DQS6_A_C||TDQS6_A_C||DQS6_A_T||TDQS6_A_T @S9S_MB_2U_LIB.S9S_MB_2U(SCH_1):M_D_CPU0_SA_DQS_DN(6)
 250 M_D_CPU0_SB_DQS_DP<5> DQS5_B_T||TDQS5_B_T @S9S_MB_2U_LIB.S9S_MB_2U(SCH_1):M_D_CPU0_SB_DQS_DP(5)
 249 M_D_CPU0_SB_DQS_DN<5> DQS5_B_C||TDQS5_B_C @S9S_MB_2U_LIB.S9S_MB_2U(SCH_1):M_D_CPU0_SB_DQS_DN(5)
 157 M_D_CPU0_SA_DQS_DP<5> DQS5_A_T||TDQS5_A_T @S9S_MB_2U_LIB.S9S_MB_2U(SCH_1):M_D_CPU0_SA_DQS_DP(5)
 156 M_D_CPU0_SA_DQS_DN<5> DQS5_A_C||TDQS5_A_C||DQS5_A_T||TDQS5_A_T @S9S_MB_2U_LIB.S9S_MB_2U(SCH_1):M_D_CPU0_SA_DQS_DN(5)
 239 M_D_CPU0_SB_DQS_DP<4> DQS4_B_T @S9S_MB_2U_LIB.S9S_MB_2U(SCH_1):M_D_CPU0_SB_DQS_DP(4)
 238 M_D_CPU0_SB_DQS_DN<4> DQS4_B_C @S9S_MB_2U_LIB.S9S_MB_2U(SCH_1):M_D_CPU0_SB_DQS_DN(4)
  55 M_D_CPU0_SA_DQS_DP<4> DQS4_A_T @S9S_MB_2U_LIB.S9S_MB_2U(SCH_1):M_D_CPU0_SA_DQS_DP(4)
  56 M_D_CPU0_SA_DQS_DN<4> DQS4_A_C @S9S_MB_2U_LIB.S9S_MB_2U(SCH_1):M_D_CPU0_SA_DQS_DN(4)
 137 M_D_CPU0_SB_DQS_DP<3> DQS3_B_T @S9S_MB_2U_LIB.S9S_MB_2U(SCH_1):M_D_CPU0_SB_DQS_DP(3)
 138 M_D_CPU0_SB_DQS_DN<3> DQS3_B_C @S9S_MB_2U_LIB.S9S_MB_2U(SCH_1):M_D_CPU0_SB_DQS_DN(3)
  44 M_D_CPU0_SA_DQS_DP<3> DQS3_A_T @S9S_MB_2U_LIB.S9S_MB_2U(SCH_1):M_D_CPU0_SA_DQS_DP(3)
  45 M_D_CPU0_SA_DQS_DN<3> DQS3_A_C @S9S_MB_2U_LIB.S9S_MB_2U(SCH_1):M_D_CPU0_SA_DQS_DN(3)
 126 M_D_CPU0_SB_DQS_DP<2> DQS2_B_T @S9S_MB_2U_LIB.S9S_MB_2U(SCH_1):M_D_CPU0_SB_DQS_DP(2)
 127 M_D_CPU0_SB_DQS_DN<2> DQS2_B_C @S9S_MB_2U_LIB.S9S_MB_2U(SCH_1):M_D_CPU0_SB_DQS_DN(2)
  33 M_D_CPU0_SA_DQS_DP<2> DQS2_A_T @S9S_MB_2U_LIB.S9S_MB_2U(SCH_1):M_D_CPU0_SA_DQS_DP(2)
  34 M_D_CPU0_SA_DQS_DN<2> DQS2_A_C @S9S_MB_2U_LIB.S9S_MB_2U(SCH_1):M_D_CPU0_SA_DQS_DN(2)
 115 M_D_CPU0_SB_DQS_DP<1> DQS1_B_T @S9S_MB_2U_LIB.S9S_MB_2U(SCH_1):M_D_CPU0_SB_DQS_DP(1)
 116 M_D_CPU0_SB_DQS_DN<1> DQS1_B_C @S9S_MB_2U_LIB.S9S_MB_2U(SCH_1):M_D_CPU0_SB_DQS_DN(1)
  22 M_D_CPU0_SA_DQS_DP<1> DQS1_A_T @S9S_MB_2U_LIB.S9S_MB_2U(SCH_1):M_D_CPU0_SA_DQS_DP(1)
  23 M_D_CPU0_SA_DQS_DN<1> DQS1_A_C @S9S_MB_2U_LIB.S9S_MB_2U(SCH_1):M_D_CPU0_SA_DQS_DN(1)
 104 M_D_CPU0_SB_DQS_DP<0> DQS0_B_T @S9S_MB_2U_LIB.S9S_MB_2U(SCH_1):M_D_CPU0_SB_DQS_DP(0)
 105 M_D_CPU0_SB_DQS_DN<0> DQS0_B_C @S9S_MB_2U_LIB.S9S_MB_2U(SCH_1):M_D_CPU0_SB_DQS_DN(0)
  11 M_D_CPU0_SA_DQS_DP<0> DQS0_A_T @S9S_MB_2U_LIB.S9S_MB_2U(SCH_1):M_D_CPU0_SA_DQS_DP(0)
  12 M_D_CPU0_SA_DQS_DN<0> DQS0_A_C @S9S_MB_2U_LIB.S9S_MB_2U(SCH_1):M_D_CPU0_SA_DQS_DN(0)
 272 M_D_CPU0_SB_DQS_DP<7> DQS7_B_T||TDQS7_B_T @S9S_MB_2U_LIB.S9S_MB_2U(SCH_1):M_D_CPU0_SB_DQS_DP(7)
 282 M_D_CPU0_SB_DQS_DN<8> DQS8_B_C||TDQS8_B_C @S9S_MB_2U_LIB.S9S_MB_2U(SCH_1):M_D_CPU0_SB_DQS_DN(8)
 283 M_D_CPU0_SB_DQS_DP<8> DQS8_B_T||TDQS8_B_T @S9S_MB_2U_LIB.S9S_MB_2U(SCH_1):M_D_CPU0_SB_DQS_DP(8)
 168 M_D_CPU0_SA_DQS_DP<6> DQS6_A_T||TDQS6_A_T @S9S_MB_2U_LIB.S9S_MB_2U(SCH_1):M_D_CPU0_SA_DQS_DP(6)
 178 M_D_CPU0_SA_DQS_DN<7> DQS7_A_C||TDQS7_A_C @S9S_MB_2U_LIB.S9S_MB_2U(SCH_1):M_D_CPU0_SA_DQS_DN(7)

Q_RES_0402LF-49.9,1%,1/16W,CHIA  I180  R3881
   1 I3C_SPD_DDRABCD_CPU0_LVC1_SCL_6      A @S9S_MB_2U_LIB.S9S_MB_2U(SCH_1):I3C_SPD_DDRABCD_CPU0_LVC1_SCL_R7
   2 I3C_SPD_DDRABCD_CPU0_LVC1_SCL      B @S9S_MB_2U_LIB.S9S_MB_2U(SCH_1):I3C_SPD_DDRABCD_CPU0_LVC1_SCL


DRAWING: @S9S_MB_2U_LIB.S9S_MB_2U(SCH_1):PAGE89 

Q_RES_0402LF-196K,1%,1/16W,CHIA  I2  R33
   1 PD_CHD_CPU0_DIMM2_SAA      A @S9S_MB_2U_LIB.S9S_MB_2U(SCH_1):PD_CHD_CPU0_DIMM2_SAA
   2    GND      B @S9S_MB_2U_LIB.S9S_MB_2U(SCH_1):GND

SCONN288_ADR50017P087CC-SCONN2A  I50  J8
   3 P3V3_AUX VIN_MGMT @S9S_MB_2U_LIB.S9S_MB_2U(SCH_1):P3V3_AUX
   2 TP_CHD_CPU0_DIMM2_FRU_0   RFU0 @S9S_MB_2U_LIB.S9S_MB_2U(SCH_1):TP_CHD_CPU0_DIMM2_FRU_0
 144 TP_CHD_CPU0_DIMM2_FRU_1   RFU1 @S9S_MB_2U_LIB.S9S_MB_2U(SCH_1):TP_CHD_CPU0_DIMM2_FRU_1
 149 TP_CHD_CPU0_DIMM2_FRU_2   RFU2 @S9S_MB_2U_LIB.S9S_MB_2U(SCH_1):TP_CHD_CPU0_DIMM2_FRU_2
 150 TP_CHD_CPU0_DIMM2_FRU_3   RFU3 @S9S_MB_2U_LIB.S9S_MB_2U(SCH_1):TP_CHD_CPU0_DIMM2_FRU_3
 220 TP_CHD_CPU0_DIMM2_FRU_4   RFU4 @S9S_MB_2U_LIB.S9S_MB_2U(SCH_1):TP_CHD_CPU0_DIMM2_FRU_4
 231 TP_CHD_CPU0_DIMM2_FRU_5   RFU5 @S9S_MB_2U_LIB.S9S_MB_2U(SCH_1):TP_CHD_CPU0_DIMM2_FRU_5
 232 TP_CHD_CPU0_DIMM2_FRU_6   RFU6 @S9S_MB_2U_LIB.S9S_MB_2U(SCH_1):TP_CHD_CPU0_DIMM2_FRU_6
 207 RST_M_CD_CPU0_FPGA_N RESET_N @S9S_MB_2U_LIB.S9S_MB_2U(SCH_1):RST_M_CD_CPU0_FPGA_N
 147 PWRGD_CHD_CPU0_DIMM2 PWR_GOOD||FAIL_N @S9S_MB_2U_LIB.S9S_MB_2U(SCH_1):PWRGD_CHD_CPU0_DIMM2
 227 M_D_CPU0_SB_PAR  PAR_B @S9S_MB_2U_LIB.S9S_MB_2U(SCH_1):M_D_CPU0_SB_PAR
  74 M_D_CPU0_SA_PAR  PAR_A @S9S_MB_2U_LIB.S9S_MB_2U(SCH_1):M_D_CPU0_SA_PAR
  87 M_D_CPU0_SB_RSP<1> LBS||RSP_B_N @S9S_MB_2U_LIB.S9S_MB_2U(SCH_1):M_D_CPU0_SB_RSP(1)
  86 M_D_CPU0_SA_RSP<1> LBD||RSP_A_N @S9S_MB_2U_LIB.S9S_MB_2U(SCH_1):M_D_CPU0_SA_RSP(1)
   5 I3C_SPD_DDRABCD_CPU0_LVC1_SDA   HSDA @S9S_MB_2U_LIB.S9S_MB_2U(SCH_1):I3C_SPD_DDRABCD_CPU0_LVC1_SDA
   4 I3C_SPD_DDRABCD_CPU0_LVC1_SCL_7   HSCL @S9S_MB_2U_LIB.S9S_MB_2U(SCH_1):I3C_SPD_DDRABCD_CPU0_LVC1_SCL_R8
 148 PD_CHD_CPU0_DIMM2_SAA    HSA @S9S_MB_2U_LIB.S9S_MB_2U(SCH_1):PD_CHD_CPU0_DIMM2_SAA
 100 M_D_CPU0_SB_DQ<0>  DQ0_B @S9S_MB_2U_LIB.S9S_MB_2U(SCH_1):M_D_CPU0_SB_DQ(0)
 102 M_D_CPU0_SB_DQ<1>  DQ1_B @S9S_MB_2U_LIB.S9S_MB_2U(SCH_1):M_D_CPU0_SB_DQ(1)
 245 M_D_CPU0_SB_DQ<2>  DQ2_B @S9S_MB_2U_LIB.S9S_MB_2U(SCH_1):M_D_CPU0_SB_DQ(2)
 247 M_D_CPU0_SB_DQ<3>  DQ3_B @S9S_MB_2U_LIB.S9S_MB_2U(SCH_1):M_D_CPU0_SB_DQ(3)
 107 M_D_CPU0_SB_DQ<4>  DQ4_B @S9S_MB_2U_LIB.S9S_MB_2U(SCH_1):M_D_CPU0_SB_DQ(4)
 109 M_D_CPU0_SB_DQ<5>  DQ5_B @S9S_MB_2U_LIB.S9S_MB_2U(SCH_1):M_D_CPU0_SB_DQ(5)
 252 M_D_CPU0_SB_DQ<6>  DQ6_B @S9S_MB_2U_LIB.S9S_MB_2U(SCH_1):M_D_CPU0_SB_DQ(6)
 254 M_D_CPU0_SB_DQ<7>  DQ7_B @S9S_MB_2U_LIB.S9S_MB_2U(SCH_1):M_D_CPU0_SB_DQ(7)
 111 M_D_CPU0_SB_DQ<8>  DQ8_B @S9S_MB_2U_LIB.S9S_MB_2U(SCH_1):M_D_CPU0_SB_DQ(8)
 113 M_D_CPU0_SB_DQ<9>  DQ9_B @S9S_MB_2U_LIB.S9S_MB_2U(SCH_1):M_D_CPU0_SB_DQ(9)
 256 M_D_CPU0_SB_DQ<10> DQ10_B @S9S_MB_2U_LIB.S9S_MB_2U(SCH_1):M_D_CPU0_SB_DQ(10)
 258 M_D_CPU0_SB_DQ<11> DQ11_B @S9S_MB_2U_LIB.S9S_MB_2U(SCH_1):M_D_CPU0_SB_DQ(11)
 118 M_D_CPU0_SB_DQ<12> DQ12_B @S9S_MB_2U_LIB.S9S_MB_2U(SCH_1):M_D_CPU0_SB_DQ(12)
 120 M_D_CPU0_SB_DQ<13> DQ13_B @S9S_MB_2U_LIB.S9S_MB_2U(SCH_1):M_D_CPU0_SB_DQ(13)
 263 M_D_CPU0_SB_DQ<14> DQ14_B @S9S_MB_2U_LIB.S9S_MB_2U(SCH_1):M_D_CPU0_SB_DQ(14)
 265 M_D_CPU0_SB_DQ<15> DQ15_B @S9S_MB_2U_LIB.S9S_MB_2U(SCH_1):M_D_CPU0_SB_DQ(15)
 122 M_D_CPU0_SB_DQ<16> DQ16_B @S9S_MB_2U_LIB.S9S_MB_2U(SCH_1):M_D_CPU0_SB_DQ(16)
 124 M_D_CPU0_SB_DQ<17> DQ17_B @S9S_MB_2U_LIB.S9S_MB_2U(SCH_1):M_D_CPU0_SB_DQ(17)
 267 M_D_CPU0_SB_DQ<18> DQ18_B @S9S_MB_2U_LIB.S9S_MB_2U(SCH_1):M_D_CPU0_SB_DQ(18)
 269 M_D_CPU0_SB_DQ<19> DQ19_B @S9S_MB_2U_LIB.S9S_MB_2U(SCH_1):M_D_CPU0_SB_DQ(19)
 129 M_D_CPU0_SB_DQ<20> DQ20_B @S9S_MB_2U_LIB.S9S_MB_2U(SCH_1):M_D_CPU0_SB_DQ(20)
 131 M_D_CPU0_SB_DQ<21> DQ21_B @S9S_MB_2U_LIB.S9S_MB_2U(SCH_1):M_D_CPU0_SB_DQ(21)
 274 M_D_CPU0_SB_DQ<22> DQ22_B @S9S_MB_2U_LIB.S9S_MB_2U(SCH_1):M_D_CPU0_SB_DQ(22)
 276 M_D_CPU0_SB_DQ<23> DQ23_B @S9S_MB_2U_LIB.S9S_MB_2U(SCH_1):M_D_CPU0_SB_DQ(23)
 133 M_D_CPU0_SB_DQ<24> DQ24_B @S9S_MB_2U_LIB.S9S_MB_2U(SCH_1):M_D_CPU0_SB_DQ(24)
 135 M_D_CPU0_SB_DQ<25> DQ25_B @S9S_MB_2U_LIB.S9S_MB_2U(SCH_1):M_D_CPU0_SB_DQ(25)
 278 M_D_CPU0_SB_DQ<26> DQ26_B @S9S_MB_2U_LIB.S9S_MB_2U(SCH_1):M_D_CPU0_SB_DQ(26)
 280 M_D_CPU0_SB_DQ<27> DQ27_B @S9S_MB_2U_LIB.S9S_MB_2U(SCH_1):M_D_CPU0_SB_DQ(27)
 140 M_D_CPU0_SB_DQ<28> DQ28_B @S9S_MB_2U_LIB.S9S_MB_2U(SCH_1):M_D_CPU0_SB_DQ(28)
 142 M_D_CPU0_SB_DQ<29> DQ29_B @S9S_MB_2U_LIB.S9S_MB_2U(SCH_1):M_D_CPU0_SB_DQ(29)
 285 M_D_CPU0_SB_DQ<30> DQ30_B @S9S_MB_2U_LIB.S9S_MB_2U(SCH_1):M_D_CPU0_SB_DQ(30)
 287 M_D_CPU0_SB_DQ<31> DQ31_B @S9S_MB_2U_LIB.S9S_MB_2U(SCH_1):M_D_CPU0_SB_DQ(31)
   7 M_D_CPU0_SA_DQ<0>  DQ0_A @S9S_MB_2U_LIB.S9S_MB_2U(SCH_1):M_D_CPU0_SA_DQ(0)
   9 M_D_CPU0_SA_DQ<1>  DQ1_A @S9S_MB_2U_LIB.S9S_MB_2U(SCH_1):M_D_CPU0_SA_DQ(1)
 152 M_D_CPU0_SA_DQ<2>  DQ2_A @S9S_MB_2U_LIB.S9S_MB_2U(SCH_1):M_D_CPU0_SA_DQ(2)
 154 M_D_CPU0_SA_DQ<3>  DQ3_A @S9S_MB_2U_LIB.S9S_MB_2U(SCH_1):M_D_CPU0_SA_DQ(3)
  14 M_D_CPU0_SA_DQ<4>  DQ4_A @S9S_MB_2U_LIB.S9S_MB_2U(SCH_1):M_D_CPU0_SA_DQ(4)
  16 M_D_CPU0_SA_DQ<5>  DQ5_A @S9S_MB_2U_LIB.S9S_MB_2U(SCH_1):M_D_CPU0_SA_DQ(5)
 159 M_D_CPU0_SA_DQ<6>  DQ6_A @S9S_MB_2U_LIB.S9S_MB_2U(SCH_1):M_D_CPU0_SA_DQ(6)
 161 M_D_CPU0_SA_DQ<7>  DQ7_A @S9S_MB_2U_LIB.S9S_MB_2U(SCH_1):M_D_CPU0_SA_DQ(7)
  18 M_D_CPU0_SA_DQ<8>  DQ8_A @S9S_MB_2U_LIB.S9S_MB_2U(SCH_1):M_D_CPU0_SA_DQ(8)
  20 M_D_CPU0_SA_DQ<9>  DQ9_A @S9S_MB_2U_LIB.S9S_MB_2U(SCH_1):M_D_CPU0_SA_DQ(9)
 163 M_D_CPU0_SA_DQ<10> DQ10_A @S9S_MB_2U_LIB.S9S_MB_2U(SCH_1):M_D_CPU0_SA_DQ(10)
 165 M_D_CPU0_SA_DQ<11> DQ11_A @S9S_MB_2U_LIB.S9S_MB_2U(SCH_1):M_D_CPU0_SA_DQ(11)
  25 M_D_CPU0_SA_DQ<12> DQ12_A @S9S_MB_2U_LIB.S9S_MB_2U(SCH_1):M_D_CPU0_SA_DQ(12)
  27 M_D_CPU0_SA_DQ<13> DQ13_A @S9S_MB_2U_LIB.S9S_MB_2U(SCH_1):M_D_CPU0_SA_DQ(13)
 170 M_D_CPU0_SA_DQ<14> DQ14_A @S9S_MB_2U_LIB.S9S_MB_2U(SCH_1):M_D_CPU0_SA_DQ(14)
 172 M_D_CPU0_SA_DQ<15> DQ15_A @S9S_MB_2U_LIB.S9S_MB_2U(SCH_1):M_D_CPU0_SA_DQ(15)
  29 M_D_CPU0_SA_DQ<16> DQ16_A @S9S_MB_2U_LIB.S9S_MB_2U(SCH_1):M_D_CPU0_SA_DQ(16)
  31 M_D_CPU0_SA_DQ<17> DQ17_A @S9S_MB_2U_LIB.S9S_MB_2U(SCH_1):M_D_CPU0_SA_DQ(17)
 174 M_D_CPU0_SA_DQ<18> DQ18_A @S9S_MB_2U_LIB.S9S_MB_2U(SCH_1):M_D_CPU0_SA_DQ(18)
 176 M_D_CPU0_SA_DQ<19> DQ19_A @S9S_MB_2U_LIB.S9S_MB_2U(SCH_1):M_D_CPU0_SA_DQ(19)
  36 M_D_CPU0_SA_DQ<20> DQ20_A @S9S_MB_2U_LIB.S9S_MB_2U(SCH_1):M_D_CPU0_SA_DQ(20)
  38 M_D_CPU0_SA_DQ<21> DQ21_A @S9S_MB_2U_LIB.S9S_MB_2U(SCH_1):M_D_CPU0_SA_DQ(21)
 181 M_D_CPU0_SA_DQ<22> DQ22_A @S9S_MB_2U_LIB.S9S_MB_2U(SCH_1):M_D_CPU0_SA_DQ(22)
 183 M_D_CPU0_SA_DQ<23> DQ23_A @S9S_MB_2U_LIB.S9S_MB_2U(SCH_1):M_D_CPU0_SA_DQ(23)
  40 M_D_CPU0_SA_DQ<24> DQ24_A @S9S_MB_2U_LIB.S9S_MB_2U(SCH_1):M_D_CPU0_SA_DQ(24)
  42 M_D_CPU0_SA_DQ<25> DQ25_A @S9S_MB_2U_LIB.S9S_MB_2U(SCH_1):M_D_CPU0_SA_DQ(25)
 185 M_D_CPU0_SA_DQ<26> DQ26_A @S9S_MB_2U_LIB.S9S_MB_2U(SCH_1):M_D_CPU0_SA_DQ(26)
 187 M_D_CPU0_SA_DQ<27> DQ27_A @S9S_MB_2U_LIB.S9S_MB_2U(SCH_1):M_D_CPU0_SA_DQ(27)
  47 M_D_CPU0_SA_DQ<28> DQ28_A @S9S_MB_2U_LIB.S9S_MB_2U(SCH_1):M_D_CPU0_SA_DQ(28)
  49 M_D_CPU0_SA_DQ<29> DQ29_A @S9S_MB_2U_LIB.S9S_MB_2U(SCH_1):M_D_CPU0_SA_DQ(29)
 192 M_D_CPU0_SA_DQ<30> DQ30_A @S9S_MB_2U_LIB.S9S_MB_2U(SCH_1):M_D_CPU0_SA_DQ(30)
 229 M_D_CPU0_SB_CS_N<3> CS1_B_N @S9S_MB_2U_LIB.S9S_MB_2U(SCH_1):M_D_CPU0_SB_CS_N(3)
 209 M_D_CPU0_SA_CS_N<3> CS1_A_N @S9S_MB_2U_LIB.S9S_MB_2U(SCH_1):M_D_CPU0_SA_CS_N(3)
  84 M_D_CPU0_SB_CS_N<2> CS0_B_N @S9S_MB_2U_LIB.S9S_MB_2U(SCH_1):M_D_CPU0_SB_CS_N(2)
  64 M_D_CPU0_SA_CS_N<2> CS0_A_N @S9S_MB_2U_LIB.S9S_MB_2U(SCH_1):M_D_CPU0_SA_CS_N(2)
 217 M_D_CPU0_CLK_DP<1>   CK_T @S9S_MB_2U_LIB.S9S_MB_2U(SCH_1):M_D_CPU0_CLK_DP(1)
 218 M_D_CPU0_CLK_DN<1>   CK_C @S9S_MB_2U_LIB.S9S_MB_2U(SCH_1):M_D_CPU0_CLK_DN(1)
  96 M_D_CPU0_SB_CB<0>  CB0_B @S9S_MB_2U_LIB.S9S_MB_2U(SCH_1):M_D_CPU0_SB_CB(0)
  98 M_D_CPU0_SB_CB<1>  CB1_B @S9S_MB_2U_LIB.S9S_MB_2U(SCH_1):M_D_CPU0_SB_CB(1)
 241 M_D_CPU0_SB_CB<2>  CB2_B @S9S_MB_2U_LIB.S9S_MB_2U(SCH_1):M_D_CPU0_SB_CB(2)
 243 M_D_CPU0_SB_CB<3>  CB3_B @S9S_MB_2U_LIB.S9S_MB_2U(SCH_1):M_D_CPU0_SB_CB(3)
  89 M_D_CPU0_SB_CB<4>  CB4_B @S9S_MB_2U_LIB.S9S_MB_2U(SCH_1):M_D_CPU0_SB_CB(4)
  91 M_D_CPU0_SB_CB<5>  CB5_B @S9S_MB_2U_LIB.S9S_MB_2U(SCH_1):M_D_CPU0_SB_CB(5)
 234 M_D_CPU0_SB_CB<6>  CB6_B @S9S_MB_2U_LIB.S9S_MB_2U(SCH_1):M_D_CPU0_SB_CB(6)
  51 M_D_CPU0_SA_CB<0>  CB0_A @S9S_MB_2U_LIB.S9S_MB_2U(SCH_1):M_D_CPU0_SA_CB(0)
 196 M_D_CPU0_SA_CB<2>  CB2_A @S9S_MB_2U_LIB.S9S_MB_2U(SCH_1):M_D_CPU0_SA_CB(2)
 198 M_D_CPU0_SA_CB<3>  CB3_A @S9S_MB_2U_LIB.S9S_MB_2U(SCH_1):M_D_CPU0_SA_CB(3)
  60 M_D_CPU0_SA_CB<5>  CB5_A @S9S_MB_2U_LIB.S9S_MB_2U(SCH_1):M_D_CPU0_SA_CB(5)
 203 M_D_CPU0_SA_CB<6>  CB6_A @S9S_MB_2U_LIB.S9S_MB_2U(SCH_1):M_D_CPU0_SA_CB(6)
  82 M_D_CPU0_SB_CA<6>  CA6_B @S9S_MB_2U_LIB.S9S_MB_2U(SCH_1):M_D_CPU0_SB_CA(6)
  72 M_D_CPU0_SA_CA<6>  CA6_A @S9S_MB_2U_LIB.S9S_MB_2U(SCH_1):M_D_CPU0_SA_CA(6)
 225 M_D_CPU0_SB_CA<5>  CA5_B @S9S_MB_2U_LIB.S9S_MB_2U(SCH_1):M_D_CPU0_SB_CA(5)
 215 M_D_CPU0_SA_CA<5>  CA5_A @S9S_MB_2U_LIB.S9S_MB_2U(SCH_1):M_D_CPU0_SA_CA(5)
  80 M_D_CPU0_SB_CA<4>  CA4_B @S9S_MB_2U_LIB.S9S_MB_2U(SCH_1):M_D_CPU0_SB_CA(4)
  70 M_D_CPU0_SA_CA<4>  CA4_A @S9S_MB_2U_LIB.S9S_MB_2U(SCH_1):M_D_CPU0_SA_CA(4)
 223 M_D_CPU0_SB_CA<3>  CA3_B @S9S_MB_2U_LIB.S9S_MB_2U(SCH_1):M_D_CPU0_SB_CA(3)
 213 M_D_CPU0_SA_CA<3>  CA3_A @S9S_MB_2U_LIB.S9S_MB_2U(SCH_1):M_D_CPU0_SA_CA(3)
  78 M_D_CPU0_SB_CA<2>  CA2_B @S9S_MB_2U_LIB.S9S_MB_2U(SCH_1):M_D_CPU0_SB_CA(2)
  68 M_D_CPU0_SA_CA<2>  CA2_A @S9S_MB_2U_LIB.S9S_MB_2U(SCH_1):M_D_CPU0_SA_CA(2)
 221 M_D_CPU0_SB_CA<1>  CA1_B @S9S_MB_2U_LIB.S9S_MB_2U(SCH_1):M_D_CPU0_SB_CA(1)
 211 M_D_CPU0_SA_CA<1>  CA1_A @S9S_MB_2U_LIB.S9S_MB_2U(SCH_1):M_D_CPU0_SA_CA(1)
  76 M_D_CPU0_SB_CA<0>  CA0_B @S9S_MB_2U_LIB.S9S_MB_2U(SCH_1):M_D_CPU0_SB_CA(0)
  66 M_D_CPU0_SA_CA<0>  CA0_A @S9S_MB_2U_LIB.S9S_MB_2U(SCH_1):M_D_CPU0_SA_CA(0)
  62 M_D_CPU0_ALERT_N ALERT_N @S9S_MB_2U_LIB.S9S_MB_2U(SCH_1):M_D_CPU0_ALERT_N
 236 M_D_CPU0_SB_CB<7>  CB7_B @S9S_MB_2U_LIB.S9S_MB_2U(SCH_1):M_D_CPU0_SB_CB(7)
  53 M_D_CPU0_SA_CB<1>  CB1_A @S9S_MB_2U_LIB.S9S_MB_2U(SCH_1):M_D_CPU0_SA_CB(1)
  58 M_D_CPU0_SA_CB<4>  CB4_A @S9S_MB_2U_LIB.S9S_MB_2U(SCH_1):M_D_CPU0_SA_CB(4)
 205 M_D_CPU0_SA_CB<7>  CB7_A @S9S_MB_2U_LIB.S9S_MB_2U(SCH_1):M_D_CPU0_SA_CB(7)
 194 M_D_CPU0_SA_DQ<31> DQ31_A @S9S_MB_2U_LIB.S9S_MB_2U(SCH_1):M_D_CPU0_SA_DQ(31)

Q_CAP_C0402-2.2UF,6.3V,20%,X6SA  I121  C23
   1 P3V3_AUX      A @S9S_MB_2U_LIB.S9S_MB_2U(SCH_1):P3V3_AUX
   2    GND      B @S9S_MB_2U_LIB.S9S_MB_2U(SCH_1):GND

Q_CAP_C0805-10UF,16V,10%,X6S,CA  I125  C24
   1 P12V_S3_AUX_CPU0_NVDIMM      A @S9S_MB_2U_LIB.S9S_MB_2U(SCH_1):P12V_S3_AUX_CPU0_NVDIMM
   2    GND      B @S9S_MB_2U_LIB.S9S_MB_2U(SCH_1):GND

Q_CAP_C0805-10UF,16V,10%,X6S,CA  I127  C25
   1 P12V_S3_AUX_CPU0_NVDIMM      A @S9S_MB_2U_LIB.S9S_MB_2U(SCH_1):P12V_S3_AUX_CPU0_NVDIMM
   2    GND      B @S9S_MB_2U_LIB.S9S_MB_2U(SCH_1):GND

SCONN288_ADR50017P087CC-SCONN2A  I175  J8
   6    GND   VSS0 @S9S_MB_2U_LIB.S9S_MB_2U(SCH_1):GND
   8    GND   VSS1 @S9S_MB_2U_LIB.S9S_MB_2U(SCH_1):GND
  10    GND   VSS2 @S9S_MB_2U_LIB.S9S_MB_2U(SCH_1):GND
  13    GND   VSS3 @S9S_MB_2U_LIB.S9S_MB_2U(SCH_1):GND
  15    GND   VSS4 @S9S_MB_2U_LIB.S9S_MB_2U(SCH_1):GND
  17    GND   VSS5 @S9S_MB_2U_LIB.S9S_MB_2U(SCH_1):GND
  19    GND   VSS6 @S9S_MB_2U_LIB.S9S_MB_2U(SCH_1):GND
  21    GND   VSS7 @S9S_MB_2U_LIB.S9S_MB_2U(SCH_1):GND
  24    GND   VSS8 @S9S_MB_2U_LIB.S9S_MB_2U(SCH_1):GND
  26    GND   VSS9 @S9S_MB_2U_LIB.S9S_MB_2U(SCH_1):GND
  28    GND  VSS10 @S9S_MB_2U_LIB.S9S_MB_2U(SCH_1):GND
  30    GND  VSS11 @S9S_MB_2U_LIB.S9S_MB_2U(SCH_1):GND
  32    GND  VSS12 @S9S_MB_2U_LIB.S9S_MB_2U(SCH_1):GND
  35    GND  VSS13 @S9S_MB_2U_LIB.S9S_MB_2U(SCH_1):GND
  37    GND  VSS14 @S9S_MB_2U_LIB.S9S_MB_2U(SCH_1):GND
  39    GND  VSS15 @S9S_MB_2U_LIB.S9S_MB_2U(SCH_1):GND
  41    GND  VSS16 @S9S_MB_2U_LIB.S9S_MB_2U(SCH_1):GND
  43    GND  VSS17 @S9S_MB_2U_LIB.S9S_MB_2U(SCH_1):GND
  46    GND  VSS18 @S9S_MB_2U_LIB.S9S_MB_2U(SCH_1):GND
  48    GND  VSS19 @S9S_MB_2U_LIB.S9S_MB_2U(SCH_1):GND
  50    GND  VSS20 @S9S_MB_2U_LIB.S9S_MB_2U(SCH_1):GND
  52    GND  VSS21 @S9S_MB_2U_LIB.S9S_MB_2U(SCH_1):GND
  54    GND  VSS22 @S9S_MB_2U_LIB.S9S_MB_2U(SCH_1):GND
  57    GND  VSS23 @S9S_MB_2U_LIB.S9S_MB_2U(SCH_1):GND
  59    GND  VSS24 @S9S_MB_2U_LIB.S9S_MB_2U(SCH_1):GND
  61    GND  VSS25 @S9S_MB_2U_LIB.S9S_MB_2U(SCH_1):GND
  63    GND  VSS26 @S9S_MB_2U_LIB.S9S_MB_2U(SCH_1):GND
  65    GND  VSS27 @S9S_MB_2U_LIB.S9S_MB_2U(SCH_1):GND
  67    GND  VSS28 @S9S_MB_2U_LIB.S9S_MB_2U(SCH_1):GND
  69    GND  VSS29 @S9S_MB_2U_LIB.S9S_MB_2U(SCH_1):GND
  71    GND  VSS30 @S9S_MB_2U_LIB.S9S_MB_2U(SCH_1):GND
  73    GND  VSS31 @S9S_MB_2U_LIB.S9S_MB_2U(SCH_1):GND
  75    GND  VSS32 @S9S_MB_2U_LIB.S9S_MB_2U(SCH_1):GND
  77    GND  VSS33 @S9S_MB_2U_LIB.S9S_MB_2U(SCH_1):GND
  79    GND  VSS34 @S9S_MB_2U_LIB.S9S_MB_2U(SCH_1):GND
  81    GND  VSS35 @S9S_MB_2U_LIB.S9S_MB_2U(SCH_1):GND
  83    GND  VSS36 @S9S_MB_2U_LIB.S9S_MB_2U(SCH_1):GND
  85    GND  VSS37 @S9S_MB_2U_LIB.S9S_MB_2U(SCH_1):GND
  88    GND  VSS38 @S9S_MB_2U_LIB.S9S_MB_2U(SCH_1):GND
  90    GND  VSS39 @S9S_MB_2U_LIB.S9S_MB_2U(SCH_1):GND
  92    GND  VSS40 @S9S_MB_2U_LIB.S9S_MB_2U(SCH_1):GND
  95    GND  VSS41 @S9S_MB_2U_LIB.S9S_MB_2U(SCH_1):GND
  97    GND  VSS42 @S9S_MB_2U_LIB.S9S_MB_2U(SCH_1):GND
  99    GND  VSS43 @S9S_MB_2U_LIB.S9S_MB_2U(SCH_1):GND
 101    GND  VSS44 @S9S_MB_2U_LIB.S9S_MB_2U(SCH_1):GND
 103    GND  VSS45 @S9S_MB_2U_LIB.S9S_MB_2U(SCH_1):GND
 106    GND  VSS46 @S9S_MB_2U_LIB.S9S_MB_2U(SCH_1):GND
 108    GND  VSS47 @S9S_MB_2U_LIB.S9S_MB_2U(SCH_1):GND
 110    GND  VSS48 @S9S_MB_2U_LIB.S9S_MB_2U(SCH_1):GND
 112    GND  VSS49 @S9S_MB_2U_LIB.S9S_MB_2U(SCH_1):GND
 114    GND  VSS50 @S9S_MB_2U_LIB.S9S_MB_2U(SCH_1):GND
 117    GND  VSS51 @S9S_MB_2U_LIB.S9S_MB_2U(SCH_1):GND
 119    GND  VSS52 @S9S_MB_2U_LIB.S9S_MB_2U(SCH_1):GND
 121    GND  VSS53 @S9S_MB_2U_LIB.S9S_MB_2U(SCH_1):GND
 123    GND  VSS54 @S9S_MB_2U_LIB.S9S_MB_2U(SCH_1):GND
 125    GND  VSS55 @S9S_MB_2U_LIB.S9S_MB_2U(SCH_1):GND
 128    GND  VSS56 @S9S_MB_2U_LIB.S9S_MB_2U(SCH_1):GND
 130    GND  VSS57 @S9S_MB_2U_LIB.S9S_MB_2U(SCH_1):GND
 134    GND  VSS59 @S9S_MB_2U_LIB.S9S_MB_2U(SCH_1):GND
 143    GND  VSS63 @S9S_MB_2U_LIB.S9S_MB_2U(SCH_1):GND
 151    GND  VSS64 @S9S_MB_2U_LIB.S9S_MB_2U(SCH_1):GND
 153    GND  VSS65 @S9S_MB_2U_LIB.S9S_MB_2U(SCH_1):GND
 155    GND  VSS66 @S9S_MB_2U_LIB.S9S_MB_2U(SCH_1):GND
 158    GND  VSS67 @S9S_MB_2U_LIB.S9S_MB_2U(SCH_1):GND
 160    GND  VSS68 @S9S_MB_2U_LIB.S9S_MB_2U(SCH_1):GND
 162    GND  VSS69 @S9S_MB_2U_LIB.S9S_MB_2U(SCH_1):GND
 164    GND  VSS70 @S9S_MB_2U_LIB.S9S_MB_2U(SCH_1):GND
 166    GND  VSS71 @S9S_MB_2U_LIB.S9S_MB_2U(SCH_1):GND
 169    GND  VSS72 @S9S_MB_2U_LIB.S9S_MB_2U(SCH_1):GND
 171    GND  VSS73 @S9S_MB_2U_LIB.S9S_MB_2U(SCH_1):GND
 173    GND  VSS74 @S9S_MB_2U_LIB.S9S_MB_2U(SCH_1):GND
 175    GND  VSS75 @S9S_MB_2U_LIB.S9S_MB_2U(SCH_1):GND
 177    GND  VSS76 @S9S_MB_2U_LIB.S9S_MB_2U(SCH_1):GND
 180    GND  VSS77 @S9S_MB_2U_LIB.S9S_MB_2U(SCH_1):GND
 182    GND  VSS78 @S9S_MB_2U_LIB.S9S_MB_2U(SCH_1):GND
 184    GND  VSS79 @S9S_MB_2U_LIB.S9S_MB_2U(SCH_1):GND
 186    GND  VSS80 @S9S_MB_2U_LIB.S9S_MB_2U(SCH_1):GND
 188    GND  VSS81 @S9S_MB_2U_LIB.S9S_MB_2U(SCH_1):GND
 191    GND  VSS82 @S9S_MB_2U_LIB.S9S_MB_2U(SCH_1):GND
 193    GND  VSS83 @S9S_MB_2U_LIB.S9S_MB_2U(SCH_1):GND
 195    GND  VSS84 @S9S_MB_2U_LIB.S9S_MB_2U(SCH_1):GND
 197    GND  VSS85 @S9S_MB_2U_LIB.S9S_MB_2U(SCH_1):GND
 199    GND  VSS86 @S9S_MB_2U_LIB.S9S_MB_2U(SCH_1):GND
 202    GND  VSS87 @S9S_MB_2U_LIB.S9S_MB_2U(SCH_1):GND
 204    GND  VSS88 @S9S_MB_2U_LIB.S9S_MB_2U(SCH_1):GND
 206    GND  VSS89 @S9S_MB_2U_LIB.S9S_MB_2U(SCH_1):GND
 208    GND  VSS90 @S9S_MB_2U_LIB.S9S_MB_2U(SCH_1):GND
 210    GND  VSS91 @S9S_MB_2U_LIB.S9S_MB_2U(SCH_1):GND
 212    GND  VSS92 @S9S_MB_2U_LIB.S9S_MB_2U(SCH_1):GND
 214    GND  VSS93 @S9S_MB_2U_LIB.S9S_MB_2U(SCH_1):GND
 216    GND  VSS94 @S9S_MB_2U_LIB.S9S_MB_2U(SCH_1):GND
 219    GND  VSS95 @S9S_MB_2U_LIB.S9S_MB_2U(SCH_1):GND
 222    GND  VSS96 @S9S_MB_2U_LIB.S9S_MB_2U(SCH_1):GND
 224    GND  VSS97 @S9S_MB_2U_LIB.S9S_MB_2U(SCH_1):GND
 226    GND  VSS98 @S9S_MB_2U_LIB.S9S_MB_2U(SCH_1):GND
 228    GND  VSS99 @S9S_MB_2U_LIB.S9S_MB_2U(SCH_1):GND
 233    GND VSS101 @S9S_MB_2U_LIB.S9S_MB_2U(SCH_1):GND
 237    GND VSS103 @S9S_MB_2U_LIB.S9S_MB_2U(SCH_1):GND
 242    GND VSS105 @S9S_MB_2U_LIB.S9S_MB_2U(SCH_1):GND
 244    GND VSS106 @S9S_MB_2U_LIB.S9S_MB_2U(SCH_1):GND
 246    GND VSS107 @S9S_MB_2U_LIB.S9S_MB_2U(SCH_1):GND
 248    GND VSS108 @S9S_MB_2U_LIB.S9S_MB_2U(SCH_1):GND
 251    GND VSS109 @S9S_MB_2U_LIB.S9S_MB_2U(SCH_1):GND
 253    GND VSS110 @S9S_MB_2U_LIB.S9S_MB_2U(SCH_1):GND
 255    GND VSS111 @S9S_MB_2U_LIB.S9S_MB_2U(SCH_1):GND
 257    GND VSS112 @S9S_MB_2U_LIB.S9S_MB_2U(SCH_1):GND
 259    GND VSS113 @S9S_MB_2U_LIB.S9S_MB_2U(SCH_1):GND
 262    GND VSS114 @S9S_MB_2U_LIB.S9S_MB_2U(SCH_1):GND
 264    GND VSS115 @S9S_MB_2U_LIB.S9S_MB_2U(SCH_1):GND
 266    GND VSS116 @S9S_MB_2U_LIB.S9S_MB_2U(SCH_1):GND
 268    GND VSS117 @S9S_MB_2U_LIB.S9S_MB_2U(SCH_1):GND
 270    GND VSS118 @S9S_MB_2U_LIB.S9S_MB_2U(SCH_1):GND
 273    GND VSS119 @S9S_MB_2U_LIB.S9S_MB_2U(SCH_1):GND
 275    GND VSS120 @S9S_MB_2U_LIB.S9S_MB_2U(SCH_1):GND
 277    GND VSS121 @S9S_MB_2U_LIB.S9S_MB_2U(SCH_1):GND
 279    GND VSS122 @S9S_MB_2U_LIB.S9S_MB_2U(SCH_1):GND
 281    GND VSS123 @S9S_MB_2U_LIB.S9S_MB_2U(SCH_1):GND
 284    GND VSS124 @S9S_MB_2U_LIB.S9S_MB_2U(SCH_1):GND
 286    GND VSS125 @S9S_MB_2U_LIB.S9S_MB_2U(SCH_1):GND
 288    GND VSS126 @S9S_MB_2U_LIB.S9S_MB_2U(SCH_1):GND
   1 P12V_S3_AUX_CPU0_NVDIMM VIN_BULK0 @S9S_MB_2U_LIB.S9S_MB_2U(SCH_1):P12V_S3_AUX_CPU0_NVDIMM
 145 P12V_S3_AUX_CPU0_NVDIMM VIN_BULK1 @S9S_MB_2U_LIB.S9S_MB_2U(SCH_1):P12V_S3_AUX_CPU0_NVDIMM
 146 P12V_S3_AUX_CPU0_NVDIMM VIN_BULK2 @S9S_MB_2U_LIB.S9S_MB_2U(SCH_1):P12V_S3_AUX_CPU0_NVDIMM
 230    GND VSS100 @S9S_MB_2U_LIB.S9S_MB_2U(SCH_1):GND
 235    GND VSS102 @S9S_MB_2U_LIB.S9S_MB_2U(SCH_1):GND
 240    GND VSS104 @S9S_MB_2U_LIB.S9S_MB_2U(SCH_1):GND
 132    GND  VSS58 @S9S_MB_2U_LIB.S9S_MB_2U(SCH_1):GND
 136    GND  VSS60 @S9S_MB_2U_LIB.S9S_MB_2U(SCH_1):GND
 139    GND  VSS61 @S9S_MB_2U_LIB.S9S_MB_2U(SCH_1):GND
 141    GND  VSS62 @S9S_MB_2U_LIB.S9S_MB_2U(SCH_1):GND
  G1    GND     G1 @S9S_MB_2U_LIB.S9S_MB_2U(SCH_1):GND
  G2    GND     G2 @S9S_MB_2U_LIB.S9S_MB_2U(SCH_1):GND
  G3    GND     G3 @S9S_MB_2U_LIB.S9S_MB_2U(SCH_1):GND

SCONN288_ADR50017P087CC-SCONN2A  I178  J8
  93 M_D_CPU0_SB_DQS_DP<9> DQS9_B_T||TDQS9_B_T||DBI4_B_N @S9S_MB_2U_LIB.S9S_MB_2U(SCH_1):M_D_CPU0_SB_DQS_DP(9)
  94 M_D_CPU0_SB_DQS_DN<9> DQS9_B_C||TDQS9_B_C @S9S_MB_2U_LIB.S9S_MB_2U(SCH_1):M_D_CPU0_SB_DQS_DN(9)
 201 M_D_CPU0_SA_DQS_DP<9> DQS9_A_T||TDQS9_A_T @S9S_MB_2U_LIB.S9S_MB_2U(SCH_1):M_D_CPU0_SA_DQS_DP(9)
 200 M_D_CPU0_SA_DQS_DN<9> DQS9_A_C||TDQS9_A_C @S9S_MB_2U_LIB.S9S_MB_2U(SCH_1):M_D_CPU0_SA_DQS_DN(9)
 190 M_D_CPU0_SA_DQS_DP<8> DQS8_A_T||TDQS8_A_T @S9S_MB_2U_LIB.S9S_MB_2U(SCH_1):M_D_CPU0_SA_DQS_DP(8)
 189 M_D_CPU0_SA_DQS_DN<8> DQS8_A_C||TDQS8_A_C @S9S_MB_2U_LIB.S9S_MB_2U(SCH_1):M_D_CPU0_SA_DQS_DN(8)
 271 M_D_CPU0_SB_DQS_DN<7> DQS7_B_C||TDQS7_B_C @S9S_MB_2U_LIB.S9S_MB_2U(SCH_1):M_D_CPU0_SB_DQS_DN(7)
 179 M_D_CPU0_SA_DQS_DP<7> DQS7_A_T||TDQS7_A_T @S9S_MB_2U_LIB.S9S_MB_2U(SCH_1):M_D_CPU0_SA_DQS_DP(7)
 261 M_D_CPU0_SB_DQS_DP<6> DQS6_B_T||TDQS6_B_T @S9S_MB_2U_LIB.S9S_MB_2U(SCH_1):M_D_CPU0_SB_DQS_DP(6)
 260 M_D_CPU0_SB_DQS_DN<6> DQS6_B_C||TDQS6_B_C @S9S_MB_2U_LIB.S9S_MB_2U(SCH_1):M_D_CPU0_SB_DQS_DN(6)
 167 M_D_CPU0_SA_DQS_DN<6> DQS6_A_C||TDQS6_A_C||DQS6_A_T||TDQS6_A_T @S9S_MB_2U_LIB.S9S_MB_2U(SCH_1):M_D_CPU0_SA_DQS_DN(6)
 250 M_D_CPU0_SB_DQS_DP<5> DQS5_B_T||TDQS5_B_T @S9S_MB_2U_LIB.S9S_MB_2U(SCH_1):M_D_CPU0_SB_DQS_DP(5)
 249 M_D_CPU0_SB_DQS_DN<5> DQS5_B_C||TDQS5_B_C @S9S_MB_2U_LIB.S9S_MB_2U(SCH_1):M_D_CPU0_SB_DQS_DN(5)
 157 M_D_CPU0_SA_DQS_DP<5> DQS5_A_T||TDQS5_A_T @S9S_MB_2U_LIB.S9S_MB_2U(SCH_1):M_D_CPU0_SA_DQS_DP(5)
 156 M_D_CPU0_SA_DQS_DN<5> DQS5_A_C||TDQS5_A_C||DQS5_A_T||TDQS5_A_T @S9S_MB_2U_LIB.S9S_MB_2U(SCH_1):M_D_CPU0_SA_DQS_DN(5)
 239 M_D_CPU0_SB_DQS_DP<4> DQS4_B_T @S9S_MB_2U_LIB.S9S_MB_2U(SCH_1):M_D_CPU0_SB_DQS_DP(4)
 238 M_D_CPU0_SB_DQS_DN<4> DQS4_B_C @S9S_MB_2U_LIB.S9S_MB_2U(SCH_1):M_D_CPU0_SB_DQS_DN(4)
  55 M_D_CPU0_SA_DQS_DP<4> DQS4_A_T @S9S_MB_2U_LIB.S9S_MB_2U(SCH_1):M_D_CPU0_SA_DQS_DP(4)
  56 M_D_CPU0_SA_DQS_DN<4> DQS4_A_C @S9S_MB_2U_LIB.S9S_MB_2U(SCH_1):M_D_CPU0_SA_DQS_DN(4)
 137 M_D_CPU0_SB_DQS_DP<3> DQS3_B_T @S9S_MB_2U_LIB.S9S_MB_2U(SCH_1):M_D_CPU0_SB_DQS_DP(3)
 138 M_D_CPU0_SB_DQS_DN<3> DQS3_B_C @S9S_MB_2U_LIB.S9S_MB_2U(SCH_1):M_D_CPU0_SB_DQS_DN(3)
  44 M_D_CPU0_SA_DQS_DP<3> DQS3_A_T @S9S_MB_2U_LIB.S9S_MB_2U(SCH_1):M_D_CPU0_SA_DQS_DP(3)
  45 M_D_CPU0_SA_DQS_DN<3> DQS3_A_C @S9S_MB_2U_LIB.S9S_MB_2U(SCH_1):M_D_CPU0_SA_DQS_DN(3)
 126 M_D_CPU0_SB_DQS_DP<2> DQS2_B_T @S9S_MB_2U_LIB.S9S_MB_2U(SCH_1):M_D_CPU0_SB_DQS_DP(2)
 127 M_D_CPU0_SB_DQS_DN<2> DQS2_B_C @S9S_MB_2U_LIB.S9S_MB_2U(SCH_1):M_D_CPU0_SB_DQS_DN(2)
  33 M_D_CPU0_SA_DQS_DP<2> DQS2_A_T @S9S_MB_2U_LIB.S9S_MB_2U(SCH_1):M_D_CPU0_SA_DQS_DP(2)
  34 M_D_CPU0_SA_DQS_DN<2> DQS2_A_C @S9S_MB_2U_LIB.S9S_MB_2U(SCH_1):M_D_CPU0_SA_DQS_DN(2)
 115 M_D_CPU0_SB_DQS_DP<1> DQS1_B_T @S9S_MB_2U_LIB.S9S_MB_2U(SCH_1):M_D_CPU0_SB_DQS_DP(1)
 116 M_D_CPU0_SB_DQS_DN<1> DQS1_B_C @S9S_MB_2U_LIB.S9S_MB_2U(SCH_1):M_D_CPU0_SB_DQS_DN(1)
  22 M_D_CPU0_SA_DQS_DP<1> DQS1_A_T @S9S_MB_2U_LIB.S9S_MB_2U(SCH_1):M_D_CPU0_SA_DQS_DP(1)
  23 M_D_CPU0_SA_DQS_DN<1> DQS1_A_C @S9S_MB_2U_LIB.S9S_MB_2U(SCH_1):M_D_CPU0_SA_DQS_DN(1)
 104 M_D_CPU0_SB_DQS_DP<0> DQS0_B_T @S9S_MB_2U_LIB.S9S_MB_2U(SCH_1):M_D_CPU0_SB_DQS_DP(0)
 105 M_D_CPU0_SB_DQS_DN<0> DQS0_B_C @S9S_MB_2U_LIB.S9S_MB_2U(SCH_1):M_D_CPU0_SB_DQS_DN(0)
  11 M_D_CPU0_SA_DQS_DP<0> DQS0_A_T @S9S_MB_2U_LIB.S9S_MB_2U(SCH_1):M_D_CPU0_SA_DQS_DP(0)
  12 M_D_CPU0_SA_DQS_DN<0> DQS0_A_C @S9S_MB_2U_LIB.S9S_MB_2U(SCH_1):M_D_CPU0_SA_DQS_DN(0)
 272 M_D_CPU0_SB_DQS_DP<7> DQS7_B_T||TDQS7_B_T @S9S_MB_2U_LIB.S9S_MB_2U(SCH_1):M_D_CPU0_SB_DQS_DP(7)
 282 M_D_CPU0_SB_DQS_DN<8> DQS8_B_C||TDQS8_B_C @S9S_MB_2U_LIB.S9S_MB_2U(SCH_1):M_D_CPU0_SB_DQS_DN(8)
 283 M_D_CPU0_SB_DQS_DP<8> DQS8_B_T||TDQS8_B_T @S9S_MB_2U_LIB.S9S_MB_2U(SCH_1):M_D_CPU0_SB_DQS_DP(8)
 168 M_D_CPU0_SA_DQS_DP<6> DQS6_A_T||TDQS6_A_T @S9S_MB_2U_LIB.S9S_MB_2U(SCH_1):M_D_CPU0_SA_DQS_DP(6)
 178 M_D_CPU0_SA_DQS_DN<7> DQS7_A_C||TDQS7_A_C @S9S_MB_2U_LIB.S9S_MB_2U(SCH_1):M_D_CPU0_SA_DQS_DN(7)

Q_RES_0402LF-49.9,1%,1/16W,CHIA  I180  R3882
   1 I3C_SPD_DDRABCD_CPU0_LVC1_SCL_7      A @S9S_MB_2U_LIB.S9S_MB_2U(SCH_1):I3C_SPD_DDRABCD_CPU0_LVC1_SCL_R8
   2 I3C_SPD_DDRABCD_CPU0_LVC1_SCL      B @S9S_MB_2U_LIB.S9S_MB_2U(SCH_1):I3C_SPD_DDRABCD_CPU0_LVC1_SCL


DRAWING: @S9S_MB_2U_LIB.S9S_MB_2U(SCH_1):PAGE90 

Q_RES_0402LF-10K,1%,1/16W,CHIPA  I11  R34
   1 PD_CHE_CPU0_DIMM1_SAA      A @S9S_MB_2U_LIB.S9S_MB_2U(SCH_1):PD_CHE_CPU0_DIMM1_SAA
   2    GND      B @S9S_MB_2U_LIB.S9S_MB_2U(SCH_1):GND

SCONN288_ADR50017P130CC-SCONN2A  I12  J9
   3 P3V3_AUX VIN_MGMT @S9S_MB_2U_LIB.S9S_MB_2U(SCH_1):P3V3_AUX
   2 TP_CHE_CPU0_DIMM1_FRU_0   RFU0 @S9S_MB_2U_LIB.S9S_MB_2U(SCH_1):TP_CHE_CPU0_DIMM1_FRU_0
 144 TP_CHE_CPU0_DIMM1_FRU_1   RFU1 @S9S_MB_2U_LIB.S9S_MB_2U(SCH_1):TP_CHE_CPU0_DIMM1_FRU_1
 149 TP_CHE_CPU0_DIMM1_FRU_2   RFU2 @S9S_MB_2U_LIB.S9S_MB_2U(SCH_1):TP_CHE_CPU0_DIMM1_FRU_2
 150 TP_CHE_CPU0_DIMM1_FRU_3   RFU3 @S9S_MB_2U_LIB.S9S_MB_2U(SCH_1):TP_CHE_CPU0_DIMM1_FRU_3
 220 TP_CHE_CPU0_DIMM1_FRU_4   RFU4 @S9S_MB_2U_LIB.S9S_MB_2U(SCH_1):TP_CHE_CPU0_DIMM1_FRU_4
 231 TP_CHE_CPU0_DIMM1_FRU_5   RFU5 @S9S_MB_2U_LIB.S9S_MB_2U(SCH_1):TP_CHE_CPU0_DIMM1_FRU_5
 232 TP_CHE_CPU0_DIMM1_FRU_6   RFU6 @S9S_MB_2U_LIB.S9S_MB_2U(SCH_1):TP_CHE_CPU0_DIMM1_FRU_6
 207 RST_M_EF_CPU0_FPGA_N RESET_N @S9S_MB_2U_LIB.S9S_MB_2U(SCH_1):RST_M_EF_CPU0_FPGA_N
 147 PWRGD_CHE_CPU0_DIMM1 PWR_GOOD||FAIL_N @S9S_MB_2U_LIB.S9S_MB_2U(SCH_1):PWRGD_CHE_CPU0_DIMM1
 227 M_E_CPU0_SB_PAR  PAR_B @S9S_MB_2U_LIB.S9S_MB_2U(SCH_1):M_E_CPU0_SB_PAR
  74 M_E_CPU0_SA_PAR  PAR_A @S9S_MB_2U_LIB.S9S_MB_2U(SCH_1):M_E_CPU0_SA_PAR
  87 M_E_CPU0_SB_RSP<0> LBS||RSP_B_N @S9S_MB_2U_LIB.S9S_MB_2U(SCH_1):M_E_CPU0_SB_RSP(0)
  86 M_E_CPU0_SA_RSP<0> LBD||RSP_A_N @S9S_MB_2U_LIB.S9S_MB_2U(SCH_1):M_E_CPU0_SA_RSP(0)
   5 I3C_SPD_DDREFGH_CPU0_LVC1_SDA   HSDA @S9S_MB_2U_LIB.S9S_MB_2U(SCH_1):I3C_SPD_DDREFGH_CPU0_LVC1_SDA
   4 I3C_SPD_DDREFGH_CPU0_LVC1_SCL_R   HSCL @S9S_MB_2U_LIB.S9S_MB_2U(SCH_1):I3C_SPD_DDREFGH_CPU0_LVC1_SCL_R1
 148 PD_CHE_CPU0_DIMM1_SAA    HSA @S9S_MB_2U_LIB.S9S_MB_2U(SCH_1):PD_CHE_CPU0_DIMM1_SAA
 100 M_E_CPU0_SB_DQ<0>  DQ0_B @S9S_MB_2U_LIB.S9S_MB_2U(SCH_1):M_E_CPU0_SB_DQ(0)
 102 M_E_CPU0_SB_DQ<1>  DQ1_B @S9S_MB_2U_LIB.S9S_MB_2U(SCH_1):M_E_CPU0_SB_DQ(1)
 245 M_E_CPU0_SB_DQ<2>  DQ2_B @S9S_MB_2U_LIB.S9S_MB_2U(SCH_1):M_E_CPU0_SB_DQ(2)
 247 M_E_CPU0_SB_DQ<3>  DQ3_B @S9S_MB_2U_LIB.S9S_MB_2U(SCH_1):M_E_CPU0_SB_DQ(3)
 107 M_E_CPU0_SB_DQ<4>  DQ4_B @S9S_MB_2U_LIB.S9S_MB_2U(SCH_1):M_E_CPU0_SB_DQ(4)
 109 M_E_CPU0_SB_DQ<5>  DQ5_B @S9S_MB_2U_LIB.S9S_MB_2U(SCH_1):M_E_CPU0_SB_DQ(5)
 252 M_E_CPU0_SB_DQ<6>  DQ6_B @S9S_MB_2U_LIB.S9S_MB_2U(SCH_1):M_E_CPU0_SB_DQ(6)
 254 M_E_CPU0_SB_DQ<7>  DQ7_B @S9S_MB_2U_LIB.S9S_MB_2U(SCH_1):M_E_CPU0_SB_DQ(7)
 111 M_E_CPU0_SB_DQ<8>  DQ8_B @S9S_MB_2U_LIB.S9S_MB_2U(SCH_1):M_E_CPU0_SB_DQ(8)
 113 M_E_CPU0_SB_DQ<9>  DQ9_B @S9S_MB_2U_LIB.S9S_MB_2U(SCH_1):M_E_CPU0_SB_DQ(9)
 256 M_E_CPU0_SB_DQ<10> DQ10_B @S9S_MB_2U_LIB.S9S_MB_2U(SCH_1):M_E_CPU0_SB_DQ(10)
 258 M_E_CPU0_SB_DQ<11> DQ11_B @S9S_MB_2U_LIB.S9S_MB_2U(SCH_1):M_E_CPU0_SB_DQ(11)
 118 M_E_CPU0_SB_DQ<12> DQ12_B @S9S_MB_2U_LIB.S9S_MB_2U(SCH_1):M_E_CPU0_SB_DQ(12)
 120 M_E_CPU0_SB_DQ<13> DQ13_B @S9S_MB_2U_LIB.S9S_MB_2U(SCH_1):M_E_CPU0_SB_DQ(13)
 263 M_E_CPU0_SB_DQ<14> DQ14_B @S9S_MB_2U_LIB.S9S_MB_2U(SCH_1):M_E_CPU0_SB_DQ(14)
 265 M_E_CPU0_SB_DQ<15> DQ15_B @S9S_MB_2U_LIB.S9S_MB_2U(SCH_1):M_E_CPU0_SB_DQ(15)
 122 M_E_CPU0_SB_DQ<16> DQ16_B @S9S_MB_2U_LIB.S9S_MB_2U(SCH_1):M_E_CPU0_SB_DQ(16)
 124 M_E_CPU0_SB_DQ<17> DQ17_B @S9S_MB_2U_LIB.S9S_MB_2U(SCH_1):M_E_CPU0_SB_DQ(17)
 267 M_E_CPU0_SB_DQ<18> DQ18_B @S9S_MB_2U_LIB.S9S_MB_2U(SCH_1):M_E_CPU0_SB_DQ(18)
 269 M_E_CPU0_SB_DQ<19> DQ19_B @S9S_MB_2U_LIB.S9S_MB_2U(SCH_1):M_E_CPU0_SB_DQ(19)
 129 M_E_CPU0_SB_DQ<20> DQ20_B @S9S_MB_2U_LIB.S9S_MB_2U(SCH_1):M_E_CPU0_SB_DQ(20)
 131 M_E_CPU0_SB_DQ<21> DQ21_B @S9S_MB_2U_LIB.S9S_MB_2U(SCH_1):M_E_CPU0_SB_DQ(21)
 274 M_E_CPU0_SB_DQ<22> DQ22_B @S9S_MB_2U_LIB.S9S_MB_2U(SCH_1):M_E_CPU0_SB_DQ(22)
 276 M_E_CPU0_SB_DQ<23> DQ23_B @S9S_MB_2U_LIB.S9S_MB_2U(SCH_1):M_E_CPU0_SB_DQ(23)
 133 M_E_CPU0_SB_DQ<24> DQ24_B @S9S_MB_2U_LIB.S9S_MB_2U(SCH_1):M_E_CPU0_SB_DQ(24)
 135 M_E_CPU0_SB_DQ<25> DQ25_B @S9S_MB_2U_LIB.S9S_MB_2U(SCH_1):M_E_CPU0_SB_DQ(25)
 278 M_E_CPU0_SB_DQ<26> DQ26_B @S9S_MB_2U_LIB.S9S_MB_2U(SCH_1):M_E_CPU0_SB_DQ(26)
 280 M_E_CPU0_SB_DQ<27> DQ27_B @S9S_MB_2U_LIB.S9S_MB_2U(SCH_1):M_E_CPU0_SB_DQ(27)
 140 M_E_CPU0_SB_DQ<28> DQ28_B @S9S_MB_2U_LIB.S9S_MB_2U(SCH_1):M_E_CPU0_SB_DQ(28)
 142 M_E_CPU0_SB_DQ<29> DQ29_B @S9S_MB_2U_LIB.S9S_MB_2U(SCH_1):M_E_CPU0_SB_DQ(29)
 285 M_E_CPU0_SB_DQ<30> DQ30_B @S9S_MB_2U_LIB.S9S_MB_2U(SCH_1):M_E_CPU0_SB_DQ(30)
 287 M_E_CPU0_SB_DQ<31> DQ31_B @S9S_MB_2U_LIB.S9S_MB_2U(SCH_1):M_E_CPU0_SB_DQ(31)
   7 M_E_CPU0_SA_DQ<0>  DQ0_A @S9S_MB_2U_LIB.S9S_MB_2U(SCH_1):M_E_CPU0_SA_DQ(0)
   9 M_E_CPU0_SA_DQ<1>  DQ1_A @S9S_MB_2U_LIB.S9S_MB_2U(SCH_1):M_E_CPU0_SA_DQ(1)
 152 M_E_CPU0_SA_DQ<2>  DQ2_A @S9S_MB_2U_LIB.S9S_MB_2U(SCH_1):M_E_CPU0_SA_DQ(2)
 154 M_E_CPU0_SA_DQ<3>  DQ3_A @S9S_MB_2U_LIB.S9S_MB_2U(SCH_1):M_E_CPU0_SA_DQ(3)
  14 M_E_CPU0_SA_DQ<4>  DQ4_A @S9S_MB_2U_LIB.S9S_MB_2U(SCH_1):M_E_CPU0_SA_DQ(4)
  16 M_E_CPU0_SA_DQ<5>  DQ5_A @S9S_MB_2U_LIB.S9S_MB_2U(SCH_1):M_E_CPU0_SA_DQ(5)
 159 M_E_CPU0_SA_DQ<6>  DQ6_A @S9S_MB_2U_LIB.S9S_MB_2U(SCH_1):M_E_CPU0_SA_DQ(6)
 161 M_E_CPU0_SA_DQ<7>  DQ7_A @S9S_MB_2U_LIB.S9S_MB_2U(SCH_1):M_E_CPU0_SA_DQ(7)
  18 M_E_CPU0_SA_DQ<8>  DQ8_A @S9S_MB_2U_LIB.S9S_MB_2U(SCH_1):M_E_CPU0_SA_DQ(8)
  20 M_E_CPU0_SA_DQ<9>  DQ9_A @S9S_MB_2U_LIB.S9S_MB_2U(SCH_1):M_E_CPU0_SA_DQ(9)
 163 M_E_CPU0_SA_DQ<10> DQ10_A @S9S_MB_2U_LIB.S9S_MB_2U(SCH_1):M_E_CPU0_SA_DQ(10)
 165 M_E_CPU0_SA_DQ<11> DQ11_A @S9S_MB_2U_LIB.S9S_MB_2U(SCH_1):M_E_CPU0_SA_DQ(11)
  25 M_E_CPU0_SA_DQ<12> DQ12_A @S9S_MB_2U_LIB.S9S_MB_2U(SCH_1):M_E_CPU0_SA_DQ(12)
  27 M_E_CPU0_SA_DQ<13> DQ13_A @S9S_MB_2U_LIB.S9S_MB_2U(SCH_1):M_E_CPU0_SA_DQ(13)
 170 M_E_CPU0_SA_DQ<14> DQ14_A @S9S_MB_2U_LIB.S9S_MB_2U(SCH_1):M_E_CPU0_SA_DQ(14)
 172 M_E_CPU0_SA_DQ<15> DQ15_A @S9S_MB_2U_LIB.S9S_MB_2U(SCH_1):M_E_CPU0_SA_DQ(15)
  29 M_E_CPU0_SA_DQ<16> DQ16_A @S9S_MB_2U_LIB.S9S_MB_2U(SCH_1):M_E_CPU0_SA_DQ(16)
  31 M_E_CPU0_SA_DQ<17> DQ17_A @S9S_MB_2U_LIB.S9S_MB_2U(SCH_1):M_E_CPU0_SA_DQ(17)
 174 M_E_CPU0_SA_DQ<18> DQ18_A @S9S_MB_2U_LIB.S9S_MB_2U(SCH_1):M_E_CPU0_SA_DQ(18)
 176 M_E_CPU0_SA_DQ<19> DQ19_A @S9S_MB_2U_LIB.S9S_MB_2U(SCH_1):M_E_CPU0_SA_DQ(19)
  36 M_E_CPU0_SA_DQ<20> DQ20_A @S9S_MB_2U_LIB.S9S_MB_2U(SCH_1):M_E_CPU0_SA_DQ(20)
  38 M_E_CPU0_SA_DQ<21> DQ21_A @S9S_MB_2U_LIB.S9S_MB_2U(SCH_1):M_E_CPU0_SA_DQ(21)
 181 M_E_CPU0_SA_DQ<22> DQ22_A @S9S_MB_2U_LIB.S9S_MB_2U(SCH_1):M_E_CPU0_SA_DQ(22)
 183 M_E_CPU0_SA_DQ<23> DQ23_A @S9S_MB_2U_LIB.S9S_MB_2U(SCH_1):M_E_CPU0_SA_DQ(23)
  40 M_E_CPU0_SA_DQ<24> DQ24_A @S9S_MB_2U_LIB.S9S_MB_2U(SCH_1):M_E_CPU0_SA_DQ(24)
  42 M_E_CPU0_SA_DQ<25> DQ25_A @S9S_MB_2U_LIB.S9S_MB_2U(SCH_1):M_E_CPU0_SA_DQ(25)
 185 M_E_CPU0_SA_DQ<26> DQ26_A @S9S_MB_2U_LIB.S9S_MB_2U(SCH_1):M_E_CPU0_SA_DQ(26)
 187 M_E_CPU0_SA_DQ<27> DQ27_A @S9S_MB_2U_LIB.S9S_MB_2U(SCH_1):M_E_CPU0_SA_DQ(27)
  47 M_E_CPU0_SA_DQ<28> DQ28_A @S9S_MB_2U_LIB.S9S_MB_2U(SCH_1):M_E_CPU0_SA_DQ(28)
  49 M_E_CPU0_SA_DQ<29> DQ29_A @S9S_MB_2U_LIB.S9S_MB_2U(SCH_1):M_E_CPU0_SA_DQ(29)
 192 M_E_CPU0_SA_DQ<30> DQ30_A @S9S_MB_2U_LIB.S9S_MB_2U(SCH_1):M_E_CPU0_SA_DQ(30)
 229 M_E_CPU0_SB_CS_N<1> CS1_B_N @S9S_MB_2U_LIB.S9S_MB_2U(SCH_1):M_E_CPU0_SB_CS_N(1)
 209 M_E_CPU0_SA_CS_N<1> CS1_A_N @S9S_MB_2U_LIB.S9S_MB_2U(SCH_1):M_E_CPU0_SA_CS_N(1)
  84 M_E_CPU0_SB_CS_N<0> CS0_B_N @S9S_MB_2U_LIB.S9S_MB_2U(SCH_1):M_E_CPU0_SB_CS_N(0)
  64 M_E_CPU0_SA_CS_N<0> CS0_A_N @S9S_MB_2U_LIB.S9S_MB_2U(SCH_1):M_E_CPU0_SA_CS_N(0)
 217 M_E_CPU0_CLK_DP<0>   CK_T @S9S_MB_2U_LIB.S9S_MB_2U(SCH_1):M_E_CPU0_CLK_DP(0)
 218 M_E_CPU0_CLK_DN<0>   CK_C @S9S_MB_2U_LIB.S9S_MB_2U(SCH_1):M_E_CPU0_CLK_DN(0)
  96 M_E_CPU0_SB_CB<0>  CB0_B @S9S_MB_2U_LIB.S9S_MB_2U(SCH_1):M_E_CPU0_SB_CB(0)
  98 M_E_CPU0_SB_CB<1>  CB1_B @S9S_MB_2U_LIB.S9S_MB_2U(SCH_1):M_E_CPU0_SB_CB(1)
 241 M_E_CPU0_SB_CB<2>  CB2_B @S9S_MB_2U_LIB.S9S_MB_2U(SCH_1):M_E_CPU0_SB_CB(2)
 243 M_E_CPU0_SB_CB<3>  CB3_B @S9S_MB_2U_LIB.S9S_MB_2U(SCH_1):M_E_CPU0_SB_CB(3)
  89 M_E_CPU0_SB_CB<4>  CB4_B @S9S_MB_2U_LIB.S9S_MB_2U(SCH_1):M_E_CPU0_SB_CB(4)
  91 M_E_CPU0_SB_CB<5>  CB5_B @S9S_MB_2U_LIB.S9S_MB_2U(SCH_1):M_E_CPU0_SB_CB(5)
 234 M_E_CPU0_SB_CB<6>  CB6_B @S9S_MB_2U_LIB.S9S_MB_2U(SCH_1):M_E_CPU0_SB_CB(6)
  51 M_E_CPU0_SA_CB<0>  CB0_A @S9S_MB_2U_LIB.S9S_MB_2U(SCH_1):M_E_CPU0_SA_CB(0)
 196 M_E_CPU0_SA_CB<2>  CB2_A @S9S_MB_2U_LIB.S9S_MB_2U(SCH_1):M_E_CPU0_SA_CB(2)
 198 M_E_CPU0_SA_CB<3>  CB3_A @S9S_MB_2U_LIB.S9S_MB_2U(SCH_1):M_E_CPU0_SA_CB(3)
  60 M_E_CPU0_SA_CB<5>  CB5_A @S9S_MB_2U_LIB.S9S_MB_2U(SCH_1):M_E_CPU0_SA_CB(5)
 203 M_E_CPU0_SA_CB<6>  CB6_A @S9S_MB_2U_LIB.S9S_MB_2U(SCH_1):M_E_CPU0_SA_CB(6)
  82 M_E_CPU0_SB_CA<6>  CA6_B @S9S_MB_2U_LIB.S9S_MB_2U(SCH_1):M_E_CPU0_SB_CA(6)
  72 M_E_CPU0_SA_CA<6>  CA6_A @S9S_MB_2U_LIB.S9S_MB_2U(SCH_1):M_E_CPU0_SA_CA(6)
 225 M_E_CPU0_SB_CA<5>  CA5_B @S9S_MB_2U_LIB.S9S_MB_2U(SCH_1):M_E_CPU0_SB_CA(5)
 215 M_E_CPU0_SA_CA<5>  CA5_A @S9S_MB_2U_LIB.S9S_MB_2U(SCH_1):M_E_CPU0_SA_CA(5)
  80 M_E_CPU0_SB_CA<4>  CA4_B @S9S_MB_2U_LIB.S9S_MB_2U(SCH_1):M_E_CPU0_SB_CA(4)
  70 M_E_CPU0_SA_CA<4>  CA4_A @S9S_MB_2U_LIB.S9S_MB_2U(SCH_1):M_E_CPU0_SA_CA(4)
 223 M_E_CPU0_SB_CA<3>  CA3_B @S9S_MB_2U_LIB.S9S_MB_2U(SCH_1):M_E_CPU0_SB_CA(3)
 213 M_E_CPU0_SA_CA<3>  CA3_A @S9S_MB_2U_LIB.S9S_MB_2U(SCH_1):M_E_CPU0_SA_CA(3)
  78 M_E_CPU0_SB_CA<2>  CA2_B @S9S_MB_2U_LIB.S9S_MB_2U(SCH_1):M_E_CPU0_SB_CA(2)
  68 M_E_CPU0_SA_CA<2>  CA2_A @S9S_MB_2U_LIB.S9S_MB_2U(SCH_1):M_E_CPU0_SA_CA(2)
 221 M_E_CPU0_SB_CA<1>  CA1_B @S9S_MB_2U_LIB.S9S_MB_2U(SCH_1):M_E_CPU0_SB_CA(1)
 211 M_E_CPU0_SA_CA<1>  CA1_A @S9S_MB_2U_LIB.S9S_MB_2U(SCH_1):M_E_CPU0_SA_CA(1)
  76 M_E_CPU0_SB_CA<0>  CA0_B @S9S_MB_2U_LIB.S9S_MB_2U(SCH_1):M_E_CPU0_SB_CA(0)
  66 M_E_CPU0_SA_CA<0>  CA0_A @S9S_MB_2U_LIB.S9S_MB_2U(SCH_1):M_E_CPU0_SA_CA(0)
  62 M_E_CPU0_ALERT_N ALERT_N @S9S_MB_2U_LIB.S9S_MB_2U(SCH_1):M_E_CPU0_ALERT_N
 236 M_E_CPU0_SB_CB<7>  CB7_B @S9S_MB_2U_LIB.S9S_MB_2U(SCH_1):M_E_CPU0_SB_CB(7)
  53 M_E_CPU0_SA_CB<1>  CB1_A @S9S_MB_2U_LIB.S9S_MB_2U(SCH_1):M_E_CPU0_SA_CB(1)
  58 M_E_CPU0_SA_CB<4>  CB4_A @S9S_MB_2U_LIB.S9S_MB_2U(SCH_1):M_E_CPU0_SA_CB(4)
 205 M_E_CPU0_SA_CB<7>  CB7_A @S9S_MB_2U_LIB.S9S_MB_2U(SCH_1):M_E_CPU0_SA_CB(7)
 194 M_E_CPU0_SA_DQ<31> DQ31_A @S9S_MB_2U_LIB.S9S_MB_2U(SCH_1):M_E_CPU0_SA_DQ(31)

Q_CAP_C0402-2.2UF,6.3V,20%,X6SA  I122  C26
   1 P3V3_AUX      A @S9S_MB_2U_LIB.S9S_MB_2U(SCH_1):P3V3_AUX
   2    GND      B @S9S_MB_2U_LIB.S9S_MB_2U(SCH_1):GND

Q_CAP_C0805-10UF,16V,10%,X6S,CA  I123  C27
   1 P12V_S3_AUX_CPU0_NVDIMM      A @S9S_MB_2U_LIB.S9S_MB_2U(SCH_1):P12V_S3_AUX_CPU0_NVDIMM
   2    GND      B @S9S_MB_2U_LIB.S9S_MB_2U(SCH_1):GND

Q_CAP_C0805-10UF,16V,10%,X6S,CA  I145  C28
   1 P12V_S3_AUX_CPU0_NVDIMM      A @S9S_MB_2U_LIB.S9S_MB_2U(SCH_1):P12V_S3_AUX_CPU0_NVDIMM
   2    GND      B @S9S_MB_2U_LIB.S9S_MB_2U(SCH_1):GND

SCONN288_ADR50017P130CC-SCONN2A  I147  J9
   6    GND   VSS0 @S9S_MB_2U_LIB.S9S_MB_2U(SCH_1):GND
   8    GND   VSS1 @S9S_MB_2U_LIB.S9S_MB_2U(SCH_1):GND
  10    GND   VSS2 @S9S_MB_2U_LIB.S9S_MB_2U(SCH_1):GND
  13    GND   VSS3 @S9S_MB_2U_LIB.S9S_MB_2U(SCH_1):GND
  15    GND   VSS4 @S9S_MB_2U_LIB.S9S_MB_2U(SCH_1):GND
  17    GND   VSS5 @S9S_MB_2U_LIB.S9S_MB_2U(SCH_1):GND
  19    GND   VSS6 @S9S_MB_2U_LIB.S9S_MB_2U(SCH_1):GND
  21    GND   VSS7 @S9S_MB_2U_LIB.S9S_MB_2U(SCH_1):GND
  24    GND   VSS8 @S9S_MB_2U_LIB.S9S_MB_2U(SCH_1):GND
  26    GND   VSS9 @S9S_MB_2U_LIB.S9S_MB_2U(SCH_1):GND
  28    GND  VSS10 @S9S_MB_2U_LIB.S9S_MB_2U(SCH_1):GND
  30    GND  VSS11 @S9S_MB_2U_LIB.S9S_MB_2U(SCH_1):GND
  32    GND  VSS12 @S9S_MB_2U_LIB.S9S_MB_2U(SCH_1):GND
  35    GND  VSS13 @S9S_MB_2U_LIB.S9S_MB_2U(SCH_1):GND
  37    GND  VSS14 @S9S_MB_2U_LIB.S9S_MB_2U(SCH_1):GND
  39    GND  VSS15 @S9S_MB_2U_LIB.S9S_MB_2U(SCH_1):GND
  41    GND  VSS16 @S9S_MB_2U_LIB.S9S_MB_2U(SCH_1):GND
  43    GND  VSS17 @S9S_MB_2U_LIB.S9S_MB_2U(SCH_1):GND
  46    GND  VSS18 @S9S_MB_2U_LIB.S9S_MB_2U(SCH_1):GND
  48    GND  VSS19 @S9S_MB_2U_LIB.S9S_MB_2U(SCH_1):GND
  50    GND  VSS20 @S9S_MB_2U_LIB.S9S_MB_2U(SCH_1):GND
  52    GND  VSS21 @S9S_MB_2U_LIB.S9S_MB_2U(SCH_1):GND
  54    GND  VSS22 @S9S_MB_2U_LIB.S9S_MB_2U(SCH_1):GND
  57    GND  VSS23 @S9S_MB_2U_LIB.S9S_MB_2U(SCH_1):GND
  59    GND  VSS24 @S9S_MB_2U_LIB.S9S_MB_2U(SCH_1):GND
  61    GND  VSS25 @S9S_MB_2U_LIB.S9S_MB_2U(SCH_1):GND
  63    GND  VSS26 @S9S_MB_2U_LIB.S9S_MB_2U(SCH_1):GND
  65    GND  VSS27 @S9S_MB_2U_LIB.S9S_MB_2U(SCH_1):GND
  67    GND  VSS28 @S9S_MB_2U_LIB.S9S_MB_2U(SCH_1):GND
  69    GND  VSS29 @S9S_MB_2U_LIB.S9S_MB_2U(SCH_1):GND
  71    GND  VSS30 @S9S_MB_2U_LIB.S9S_MB_2U(SCH_1):GND
  73    GND  VSS31 @S9S_MB_2U_LIB.S9S_MB_2U(SCH_1):GND
  75    GND  VSS32 @S9S_MB_2U_LIB.S9S_MB_2U(SCH_1):GND
  77    GND  VSS33 @S9S_MB_2U_LIB.S9S_MB_2U(SCH_1):GND
  79    GND  VSS34 @S9S_MB_2U_LIB.S9S_MB_2U(SCH_1):GND
  81    GND  VSS35 @S9S_MB_2U_LIB.S9S_MB_2U(SCH_1):GND
  83    GND  VSS36 @S9S_MB_2U_LIB.S9S_MB_2U(SCH_1):GND
  85    GND  VSS37 @S9S_MB_2U_LIB.S9S_MB_2U(SCH_1):GND
  88    GND  VSS38 @S9S_MB_2U_LIB.S9S_MB_2U(SCH_1):GND
  90    GND  VSS39 @S9S_MB_2U_LIB.S9S_MB_2U(SCH_1):GND
  92    GND  VSS40 @S9S_MB_2U_LIB.S9S_MB_2U(SCH_1):GND
  95    GND  VSS41 @S9S_MB_2U_LIB.S9S_MB_2U(SCH_1):GND
  97    GND  VSS42 @S9S_MB_2U_LIB.S9S_MB_2U(SCH_1):GND
  99    GND  VSS43 @S9S_MB_2U_LIB.S9S_MB_2U(SCH_1):GND
 101    GND  VSS44 @S9S_MB_2U_LIB.S9S_MB_2U(SCH_1):GND
 103    GND  VSS45 @S9S_MB_2U_LIB.S9S_MB_2U(SCH_1):GND
 106    GND  VSS46 @S9S_MB_2U_LIB.S9S_MB_2U(SCH_1):GND
 108    GND  VSS47 @S9S_MB_2U_LIB.S9S_MB_2U(SCH_1):GND
 110    GND  VSS48 @S9S_MB_2U_LIB.S9S_MB_2U(SCH_1):GND
 112    GND  VSS49 @S9S_MB_2U_LIB.S9S_MB_2U(SCH_1):GND
 114    GND  VSS50 @S9S_MB_2U_LIB.S9S_MB_2U(SCH_1):GND
 117    GND  VSS51 @S9S_MB_2U_LIB.S9S_MB_2U(SCH_1):GND
 119    GND  VSS52 @S9S_MB_2U_LIB.S9S_MB_2U(SCH_1):GND
 121    GND  VSS53 @S9S_MB_2U_LIB.S9S_MB_2U(SCH_1):GND
 123    GND  VSS54 @S9S_MB_2U_LIB.S9S_MB_2U(SCH_1):GND
 125    GND  VSS55 @S9S_MB_2U_LIB.S9S_MB_2U(SCH_1):GND
 128    GND  VSS56 @S9S_MB_2U_LIB.S9S_MB_2U(SCH_1):GND
 130    GND  VSS57 @S9S_MB_2U_LIB.S9S_MB_2U(SCH_1):GND
 134    GND  VSS59 @S9S_MB_2U_LIB.S9S_MB_2U(SCH_1):GND
 143    GND  VSS63 @S9S_MB_2U_LIB.S9S_MB_2U(SCH_1):GND
 151    GND  VSS64 @S9S_MB_2U_LIB.S9S_MB_2U(SCH_1):GND
 153    GND  VSS65 @S9S_MB_2U_LIB.S9S_MB_2U(SCH_1):GND
 155    GND  VSS66 @S9S_MB_2U_LIB.S9S_MB_2U(SCH_1):GND
 158    GND  VSS67 @S9S_MB_2U_LIB.S9S_MB_2U(SCH_1):GND
 160    GND  VSS68 @S9S_MB_2U_LIB.S9S_MB_2U(SCH_1):GND
 162    GND  VSS69 @S9S_MB_2U_LIB.S9S_MB_2U(SCH_1):GND
 164    GND  VSS70 @S9S_MB_2U_LIB.S9S_MB_2U(SCH_1):GND
 166    GND  VSS71 @S9S_MB_2U_LIB.S9S_MB_2U(SCH_1):GND
 169    GND  VSS72 @S9S_MB_2U_LIB.S9S_MB_2U(SCH_1):GND
 171    GND  VSS73 @S9S_MB_2U_LIB.S9S_MB_2U(SCH_1):GND
 173    GND  VSS74 @S9S_MB_2U_LIB.S9S_MB_2U(SCH_1):GND
 175    GND  VSS75 @S9S_MB_2U_LIB.S9S_MB_2U(SCH_1):GND
 177    GND  VSS76 @S9S_MB_2U_LIB.S9S_MB_2U(SCH_1):GND
 180    GND  VSS77 @S9S_MB_2U_LIB.S9S_MB_2U(SCH_1):GND
 182    GND  VSS78 @S9S_MB_2U_LIB.S9S_MB_2U(SCH_1):GND
 184    GND  VSS79 @S9S_MB_2U_LIB.S9S_MB_2U(SCH_1):GND
 186    GND  VSS80 @S9S_MB_2U_LIB.S9S_MB_2U(SCH_1):GND
 188    GND  VSS81 @S9S_MB_2U_LIB.S9S_MB_2U(SCH_1):GND
 191    GND  VSS82 @S9S_MB_2U_LIB.S9S_MB_2U(SCH_1):GND
 193    GND  VSS83 @S9S_MB_2U_LIB.S9S_MB_2U(SCH_1):GND
 195    GND  VSS84 @S9S_MB_2U_LIB.S9S_MB_2U(SCH_1):GND
 197    GND  VSS85 @S9S_MB_2U_LIB.S9S_MB_2U(SCH_1):GND
 199    GND  VSS86 @S9S_MB_2U_LIB.S9S_MB_2U(SCH_1):GND
 202    GND  VSS87 @S9S_MB_2U_LIB.S9S_MB_2U(SCH_1):GND
 204    GND  VSS88 @S9S_MB_2U_LIB.S9S_MB_2U(SCH_1):GND
 206    GND  VSS89 @S9S_MB_2U_LIB.S9S_MB_2U(SCH_1):GND
 208    GND  VSS90 @S9S_MB_2U_LIB.S9S_MB_2U(SCH_1):GND
 210    GND  VSS91 @S9S_MB_2U_LIB.S9S_MB_2U(SCH_1):GND
 212    GND  VSS92 @S9S_MB_2U_LIB.S9S_MB_2U(SCH_1):GND
 214    GND  VSS93 @S9S_MB_2U_LIB.S9S_MB_2U(SCH_1):GND
 216    GND  VSS94 @S9S_MB_2U_LIB.S9S_MB_2U(SCH_1):GND
 219    GND  VSS95 @S9S_MB_2U_LIB.S9S_MB_2U(SCH_1):GND
 222    GND  VSS96 @S9S_MB_2U_LIB.S9S_MB_2U(SCH_1):GND
 224    GND  VSS97 @S9S_MB_2U_LIB.S9S_MB_2U(SCH_1):GND
 226    GND  VSS98 @S9S_MB_2U_LIB.S9S_MB_2U(SCH_1):GND
 228    GND  VSS99 @S9S_MB_2U_LIB.S9S_MB_2U(SCH_1):GND
 233    GND VSS101 @S9S_MB_2U_LIB.S9S_MB_2U(SCH_1):GND
 237    GND VSS103 @S9S_MB_2U_LIB.S9S_MB_2U(SCH_1):GND
 242    GND VSS105 @S9S_MB_2U_LIB.S9S_MB_2U(SCH_1):GND
 244    GND VSS106 @S9S_MB_2U_LIB.S9S_MB_2U(SCH_1):GND
 246    GND VSS107 @S9S_MB_2U_LIB.S9S_MB_2U(SCH_1):GND
 248    GND VSS108 @S9S_MB_2U_LIB.S9S_MB_2U(SCH_1):GND
 251    GND VSS109 @S9S_MB_2U_LIB.S9S_MB_2U(SCH_1):GND
 253    GND VSS110 @S9S_MB_2U_LIB.S9S_MB_2U(SCH_1):GND
 255    GND VSS111 @S9S_MB_2U_LIB.S9S_MB_2U(SCH_1):GND
 257    GND VSS112 @S9S_MB_2U_LIB.S9S_MB_2U(SCH_1):GND
 259    GND VSS113 @S9S_MB_2U_LIB.S9S_MB_2U(SCH_1):GND
 262    GND VSS114 @S9S_MB_2U_LIB.S9S_MB_2U(SCH_1):GND
 264    GND VSS115 @S9S_MB_2U_LIB.S9S_MB_2U(SCH_1):GND
 266    GND VSS116 @S9S_MB_2U_LIB.S9S_MB_2U(SCH_1):GND
 268    GND VSS117 @S9S_MB_2U_LIB.S9S_MB_2U(SCH_1):GND
 270    GND VSS118 @S9S_MB_2U_LIB.S9S_MB_2U(SCH_1):GND
 273    GND VSS119 @S9S_MB_2U_LIB.S9S_MB_2U(SCH_1):GND
 275    GND VSS120 @S9S_MB_2U_LIB.S9S_MB_2U(SCH_1):GND
 277    GND VSS121 @S9S_MB_2U_LIB.S9S_MB_2U(SCH_1):GND
 279    GND VSS122 @S9S_MB_2U_LIB.S9S_MB_2U(SCH_1):GND
 281    GND VSS123 @S9S_MB_2U_LIB.S9S_MB_2U(SCH_1):GND
 284    GND VSS124 @S9S_MB_2U_LIB.S9S_MB_2U(SCH_1):GND
 286    GND VSS125 @S9S_MB_2U_LIB.S9S_MB_2U(SCH_1):GND
 288    GND VSS126 @S9S_MB_2U_LIB.S9S_MB_2U(SCH_1):GND
   1 P12V_S3_AUX_CPU0_NVDIMM VIN_BULK0 @S9S_MB_2U_LIB.S9S_MB_2U(SCH_1):P12V_S3_AUX_CPU0_NVDIMM
 145 P12V_S3_AUX_CPU0_NVDIMM VIN_BULK1 @S9S_MB_2U_LIB.S9S_MB_2U(SCH_1):P12V_S3_AUX_CPU0_NVDIMM
 146 P12V_S3_AUX_CPU0_NVDIMM VIN_BULK2 @S9S_MB_2U_LIB.S9S_MB_2U(SCH_1):P12V_S3_AUX_CPU0_NVDIMM
 230    GND VSS100 @S9S_MB_2U_LIB.S9S_MB_2U(SCH_1):GND
 235    GND VSS102 @S9S_MB_2U_LIB.S9S_MB_2U(SCH_1):GND
 240    GND VSS104 @S9S_MB_2U_LIB.S9S_MB_2U(SCH_1):GND
 132    GND  VSS58 @S9S_MB_2U_LIB.S9S_MB_2U(SCH_1):GND
 136    GND  VSS60 @S9S_MB_2U_LIB.S9S_MB_2U(SCH_1):GND
 139    GND  VSS61 @S9S_MB_2U_LIB.S9S_MB_2U(SCH_1):GND
 141    GND  VSS62 @S9S_MB_2U_LIB.S9S_MB_2U(SCH_1):GND
  G1    GND     G1 @S9S_MB_2U_LIB.S9S_MB_2U(SCH_1):GND
  G2    GND     G2 @S9S_MB_2U_LIB.S9S_MB_2U(SCH_1):GND
  G3    GND     G3 @S9S_MB_2U_LIB.S9S_MB_2U(SCH_1):GND

SCONN288_ADR50017P130CC-SCONN2A  I178  J9
  93 M_E_CPU0_SB_DQS_DP<9> DQS9_B_T||TDQS9_B_T||DBI4_B_N @S9S_MB_2U_LIB.S9S_MB_2U(SCH_1):M_E_CPU0_SB_DQS_DP(9)
  94 M_E_CPU0_SB_DQS_DN<9> DQS9_B_C||TDQS9_B_C @S9S_MB_2U_LIB.S9S_MB_2U(SCH_1):M_E_CPU0_SB_DQS_DN(9)
 201 M_E_CPU0_SA_DQS_DP<9> DQS9_A_T||TDQS9_A_T @S9S_MB_2U_LIB.S9S_MB_2U(SCH_1):M_E_CPU0_SA_DQS_DP(9)
 200 M_E_CPU0_SA_DQS_DN<9> DQS9_A_C||TDQS9_A_C @S9S_MB_2U_LIB.S9S_MB_2U(SCH_1):M_E_CPU0_SA_DQS_DN(9)
 190 M_E_CPU0_SA_DQS_DP<8> DQS8_A_T||TDQS8_A_T @S9S_MB_2U_LIB.S9S_MB_2U(SCH_1):M_E_CPU0_SA_DQS_DP(8)
 189 M_E_CPU0_SA_DQS_DN<8> DQS8_A_C||TDQS8_A_C @S9S_MB_2U_LIB.S9S_MB_2U(SCH_1):M_E_CPU0_SA_DQS_DN(8)
 271 M_E_CPU0_SB_DQS_DN<7> DQS7_B_C||TDQS7_B_C @S9S_MB_2U_LIB.S9S_MB_2U(SCH_1):M_E_CPU0_SB_DQS_DN(7)
 179 M_E_CPU0_SA_DQS_DP<7> DQS7_A_T||TDQS7_A_T @S9S_MB_2U_LIB.S9S_MB_2U(SCH_1):M_E_CPU0_SA_DQS_DP(7)
 261 M_E_CPU0_SB_DQS_DP<6> DQS6_B_T||TDQS6_B_T @S9S_MB_2U_LIB.S9S_MB_2U(SCH_1):M_E_CPU0_SB_DQS_DP(6)
 260 M_E_CPU0_SB_DQS_DN<6> DQS6_B_C||TDQS6_B_C @S9S_MB_2U_LIB.S9S_MB_2U(SCH_1):M_E_CPU0_SB_DQS_DN(6)
 167 M_E_CPU0_SA_DQS_DN<6> DQS6_A_C||TDQS6_A_C||DQS6_A_T||TDQS6_A_T @S9S_MB_2U_LIB.S9S_MB_2U(SCH_1):M_E_CPU0_SA_DQS_DN(6)
 250 M_E_CPU0_SB_DQS_DP<5> DQS5_B_T||TDQS5_B_T @S9S_MB_2U_LIB.S9S_MB_2U(SCH_1):M_E_CPU0_SB_DQS_DP(5)
 249 M_E_CPU0_SB_DQS_DN<5> DQS5_B_C||TDQS5_B_C @S9S_MB_2U_LIB.S9S_MB_2U(SCH_1):M_E_CPU0_SB_DQS_DN(5)
 157 M_E_CPU0_SA_DQS_DP<5> DQS5_A_T||TDQS5_A_T @S9S_MB_2U_LIB.S9S_MB_2U(SCH_1):M_E_CPU0_SA_DQS_DP(5)
 156 M_E_CPU0_SA_DQS_DN<5> DQS5_A_C||TDQS5_A_C||DQS5_A_T||TDQS5_A_T @S9S_MB_2U_LIB.S9S_MB_2U(SCH_1):M_E_CPU0_SA_DQS_DN(5)
 239 M_E_CPU0_SB_DQS_DP<4> DQS4_B_T @S9S_MB_2U_LIB.S9S_MB_2U(SCH_1):M_E_CPU0_SB_DQS_DP(4)
 238 M_E_CPU0_SB_DQS_DN<4> DQS4_B_C @S9S_MB_2U_LIB.S9S_MB_2U(SCH_1):M_E_CPU0_SB_DQS_DN(4)
  55 M_E_CPU0_SA_DQS_DP<4> DQS4_A_T @S9S_MB_2U_LIB.S9S_MB_2U(SCH_1):M_E_CPU0_SA_DQS_DP(4)
  56 M_E_CPU0_SA_DQS_DN<4> DQS4_A_C @S9S_MB_2U_LIB.S9S_MB_2U(SCH_1):M_E_CPU0_SA_DQS_DN(4)
 137 M_E_CPU0_SB_DQS_DP<3> DQS3_B_T @S9S_MB_2U_LIB.S9S_MB_2U(SCH_1):M_E_CPU0_SB_DQS_DP(3)
 138 M_E_CPU0_SB_DQS_DN<3> DQS3_B_C @S9S_MB_2U_LIB.S9S_MB_2U(SCH_1):M_E_CPU0_SB_DQS_DN(3)
  44 M_E_CPU0_SA_DQS_DP<3> DQS3_A_T @S9S_MB_2U_LIB.S9S_MB_2U(SCH_1):M_E_CPU0_SA_DQS_DP(3)
  45 M_E_CPU0_SA_DQS_DN<3> DQS3_A_C @S9S_MB_2U_LIB.S9S_MB_2U(SCH_1):M_E_CPU0_SA_DQS_DN(3)
 126 M_E_CPU0_SB_DQS_DP<2> DQS2_B_T @S9S_MB_2U_LIB.S9S_MB_2U(SCH_1):M_E_CPU0_SB_DQS_DP(2)
 127 M_E_CPU0_SB_DQS_DN<2> DQS2_B_C @S9S_MB_2U_LIB.S9S_MB_2U(SCH_1):M_E_CPU0_SB_DQS_DN(2)
  33 M_E_CPU0_SA_DQS_DP<2> DQS2_A_T @S9S_MB_2U_LIB.S9S_MB_2U(SCH_1):M_E_CPU0_SA_DQS_DP(2)
  34 M_E_CPU0_SA_DQS_DN<2> DQS2_A_C @S9S_MB_2U_LIB.S9S_MB_2U(SCH_1):M_E_CPU0_SA_DQS_DN(2)
 115 M_E_CPU0_SB_DQS_DP<1> DQS1_B_T @S9S_MB_2U_LIB.S9S_MB_2U(SCH_1):M_E_CPU0_SB_DQS_DP(1)
 116 M_E_CPU0_SB_DQS_DN<1> DQS1_B_C @S9S_MB_2U_LIB.S9S_MB_2U(SCH_1):M_E_CPU0_SB_DQS_DN(1)
  22 M_E_CPU0_SA_DQS_DP<1> DQS1_A_T @S9S_MB_2U_LIB.S9S_MB_2U(SCH_1):M_E_CPU0_SA_DQS_DP(1)
  23 M_E_CPU0_SA_DQS_DN<1> DQS1_A_C @S9S_MB_2U_LIB.S9S_MB_2U(SCH_1):M_E_CPU0_SA_DQS_DN(1)
 104 M_E_CPU0_SB_DQS_DP<0> DQS0_B_T @S9S_MB_2U_LIB.S9S_MB_2U(SCH_1):M_E_CPU0_SB_DQS_DP(0)
 105 M_E_CPU0_SB_DQS_DN<0> DQS0_B_C @S9S_MB_2U_LIB.S9S_MB_2U(SCH_1):M_E_CPU0_SB_DQS_DN(0)
  11 M_E_CPU0_SA_DQS_DP<0> DQS0_A_T @S9S_MB_2U_LIB.S9S_MB_2U(SCH_1):M_E_CPU0_SA_DQS_DP(0)
  12 M_E_CPU0_SA_DQS_DN<0> DQS0_A_C @S9S_MB_2U_LIB.S9S_MB_2U(SCH_1):M_E_CPU0_SA_DQS_DN(0)
 272 M_E_CPU0_SB_DQS_DP<7> DQS7_B_T||TDQS7_B_T @S9S_MB_2U_LIB.S9S_MB_2U(SCH_1):M_E_CPU0_SB_DQS_DP(7)
 282 M_E_CPU0_SB_DQS_DN<8> DQS8_B_C||TDQS8_B_C @S9S_MB_2U_LIB.S9S_MB_2U(SCH_1):M_E_CPU0_SB_DQS_DN(8)
 283 M_E_CPU0_SB_DQS_DP<8> DQS8_B_T||TDQS8_B_T @S9S_MB_2U_LIB.S9S_MB_2U(SCH_1):M_E_CPU0_SB_DQS_DP(8)
 168 M_E_CPU0_SA_DQS_DP<6> DQS6_A_T||TDQS6_A_T @S9S_MB_2U_LIB.S9S_MB_2U(SCH_1):M_E_CPU0_SA_DQS_DP(6)
 178 M_E_CPU0_SA_DQS_DN<7> DQS7_A_C||TDQS7_A_C @S9S_MB_2U_LIB.S9S_MB_2U(SCH_1):M_E_CPU0_SA_DQS_DN(7)

Q_RES_0402LF-49.9,1%,1/16W,CHIA  I179  R3883
   1 I3C_SPD_DDREFGH_CPU0_LVC1_SCL_R      A @S9S_MB_2U_LIB.S9S_MB_2U(SCH_1):I3C_SPD_DDREFGH_CPU0_LVC1_SCL_R1
   2 I3C_SPD_DDREFGH_CPU0_LVC1_SCL      B @S9S_MB_2U_LIB.S9S_MB_2U(SCH_1):I3C_SPD_DDREFGH_CPU0_LVC1_SCL


DRAWING: @S9S_MB_2U_LIB.S9S_MB_2U(SCH_1):PAGE91 

Q_RES_0402LF-15.4K,1%,1/16W,CHA  I2  R35
   1 PD_CHE_CPU0_DIMM2_SAA      A @S9S_MB_2U_LIB.S9S_MB_2U(SCH_1):PD_CHE_CPU0_DIMM2_SAA
   2    GND      B @S9S_MB_2U_LIB.S9S_MB_2U(SCH_1):GND

SCONN288_ADR50017P087CC-SCONN2A  I13  J10
   3 P3V3_AUX VIN_MGMT @S9S_MB_2U_LIB.S9S_MB_2U(SCH_1):P3V3_AUX
   2 TP_CHE_CPU0_DIMM2_FRU_0   RFU0 @S9S_MB_2U_LIB.S9S_MB_2U(SCH_1):TP_CHE_CPU0_DIMM2_FRU_0
 144 TP_CHE_CPU0_DIMM2_FRU_1   RFU1 @S9S_MB_2U_LIB.S9S_MB_2U(SCH_1):TP_CHE_CPU0_DIMM2_FRU_1
 149 TP_CHE_CPU0_DIMM2_FRU_2   RFU2 @S9S_MB_2U_LIB.S9S_MB_2U(SCH_1):TP_CHE_CPU0_DIMM2_FRU_2
 150 TP_CHE_CPU0_DIMM2_FRU_3   RFU3 @S9S_MB_2U_LIB.S9S_MB_2U(SCH_1):TP_CHE_CPU0_DIMM2_FRU_3
 220 TP_CHE_CPU0_DIMM2_FRU_4   RFU4 @S9S_MB_2U_LIB.S9S_MB_2U(SCH_1):TP_CHE_CPU0_DIMM2_FRU_4
 231 TP_CHE_CPU0_DIMM2_FRU_5   RFU5 @S9S_MB_2U_LIB.S9S_MB_2U(SCH_1):TP_CHE_CPU0_DIMM2_FRU_5
 232 TP_CHE_CPU0_DIMM2_FRU_6   RFU6 @S9S_MB_2U_LIB.S9S_MB_2U(SCH_1):TP_CHE_CPU0_DIMM2_FRU_6
 207 RST_M_EF_CPU0_FPGA_N RESET_N @S9S_MB_2U_LIB.S9S_MB_2U(SCH_1):RST_M_EF_CPU0_FPGA_N
 147 PWRGD_CHE_CPU0_DIMM2 PWR_GOOD||FAIL_N @S9S_MB_2U_LIB.S9S_MB_2U(SCH_1):PWRGD_CHE_CPU0_DIMM2
 227 M_E_CPU0_SB_PAR  PAR_B @S9S_MB_2U_LIB.S9S_MB_2U(SCH_1):M_E_CPU0_SB_PAR
  74 M_E_CPU0_SA_PAR  PAR_A @S9S_MB_2U_LIB.S9S_MB_2U(SCH_1):M_E_CPU0_SA_PAR
  87 M_E_CPU0_SB_RSP<1> LBS||RSP_B_N @S9S_MB_2U_LIB.S9S_MB_2U(SCH_1):M_E_CPU0_SB_RSP(1)
  86 M_E_CPU0_SA_RSP<1> LBD||RSP_A_N @S9S_MB_2U_LIB.S9S_MB_2U(SCH_1):M_E_CPU0_SA_RSP(1)
   5 I3C_SPD_DDREFGH_CPU0_LVC1_SDA   HSDA @S9S_MB_2U_LIB.S9S_MB_2U(SCH_1):I3C_SPD_DDREFGH_CPU0_LVC1_SDA
   4 I3C_SPD_DDREFGH_CPU0_LVC1_SCL_1   HSCL @S9S_MB_2U_LIB.S9S_MB_2U(SCH_1):I3C_SPD_DDREFGH_CPU0_LVC1_SCL_R2
 148 PD_CHE_CPU0_DIMM2_SAA    HSA @S9S_MB_2U_LIB.S9S_MB_2U(SCH_1):PD_CHE_CPU0_DIMM2_SAA
 100 M_E_CPU0_SB_DQ<0>  DQ0_B @S9S_MB_2U_LIB.S9S_MB_2U(SCH_1):M_E_CPU0_SB_DQ(0)
 102 M_E_CPU0_SB_DQ<1>  DQ1_B @S9S_MB_2U_LIB.S9S_MB_2U(SCH_1):M_E_CPU0_SB_DQ(1)
 245 M_E_CPU0_SB_DQ<2>  DQ2_B @S9S_MB_2U_LIB.S9S_MB_2U(SCH_1):M_E_CPU0_SB_DQ(2)
 247 M_E_CPU0_SB_DQ<3>  DQ3_B @S9S_MB_2U_LIB.S9S_MB_2U(SCH_1):M_E_CPU0_SB_DQ(3)
 107 M_E_CPU0_SB_DQ<4>  DQ4_B @S9S_MB_2U_LIB.S9S_MB_2U(SCH_1):M_E_CPU0_SB_DQ(4)
 109 M_E_CPU0_SB_DQ<5>  DQ5_B @S9S_MB_2U_LIB.S9S_MB_2U(SCH_1):M_E_CPU0_SB_DQ(5)
 252 M_E_CPU0_SB_DQ<6>  DQ6_B @S9S_MB_2U_LIB.S9S_MB_2U(SCH_1):M_E_CPU0_SB_DQ(6)
 254 M_E_CPU0_SB_DQ<7>  DQ7_B @S9S_MB_2U_LIB.S9S_MB_2U(SCH_1):M_E_CPU0_SB_DQ(7)
 111 M_E_CPU0_SB_DQ<8>  DQ8_B @S9S_MB_2U_LIB.S9S_MB_2U(SCH_1):M_E_CPU0_SB_DQ(8)
 113 M_E_CPU0_SB_DQ<9>  DQ9_B @S9S_MB_2U_LIB.S9S_MB_2U(SCH_1):M_E_CPU0_SB_DQ(9)
 256 M_E_CPU0_SB_DQ<10> DQ10_B @S9S_MB_2U_LIB.S9S_MB_2U(SCH_1):M_E_CPU0_SB_DQ(10)
 258 M_E_CPU0_SB_DQ<11> DQ11_B @S9S_MB_2U_LIB.S9S_MB_2U(SCH_1):M_E_CPU0_SB_DQ(11)
 118 M_E_CPU0_SB_DQ<12> DQ12_B @S9S_MB_2U_LIB.S9S_MB_2U(SCH_1):M_E_CPU0_SB_DQ(12)
 120 M_E_CPU0_SB_DQ<13> DQ13_B @S9S_MB_2U_LIB.S9S_MB_2U(SCH_1):M_E_CPU0_SB_DQ(13)
 263 M_E_CPU0_SB_DQ<14> DQ14_B @S9S_MB_2U_LIB.S9S_MB_2U(SCH_1):M_E_CPU0_SB_DQ(14)
 265 M_E_CPU0_SB_DQ<15> DQ15_B @S9S_MB_2U_LIB.S9S_MB_2U(SCH_1):M_E_CPU0_SB_DQ(15)
 122 M_E_CPU0_SB_DQ<16> DQ16_B @S9S_MB_2U_LIB.S9S_MB_2U(SCH_1):M_E_CPU0_SB_DQ(16)
 124 M_E_CPU0_SB_DQ<17> DQ17_B @S9S_MB_2U_LIB.S9S_MB_2U(SCH_1):M_E_CPU0_SB_DQ(17)
 267 M_E_CPU0_SB_DQ<18> DQ18_B @S9S_MB_2U_LIB.S9S_MB_2U(SCH_1):M_E_CPU0_SB_DQ(18)
 269 M_E_CPU0_SB_DQ<19> DQ19_B @S9S_MB_2U_LIB.S9S_MB_2U(SCH_1):M_E_CPU0_SB_DQ(19)
 129 M_E_CPU0_SB_DQ<20> DQ20_B @S9S_MB_2U_LIB.S9S_MB_2U(SCH_1):M_E_CPU0_SB_DQ(20)
 131 M_E_CPU0_SB_DQ<21> DQ21_B @S9S_MB_2U_LIB.S9S_MB_2U(SCH_1):M_E_CPU0_SB_DQ(21)
 274 M_E_CPU0_SB_DQ<22> DQ22_B @S9S_MB_2U_LIB.S9S_MB_2U(SCH_1):M_E_CPU0_SB_DQ(22)
 276 M_E_CPU0_SB_DQ<23> DQ23_B @S9S_MB_2U_LIB.S9S_MB_2U(SCH_1):M_E_CPU0_SB_DQ(23)
 133 M_E_CPU0_SB_DQ<24> DQ24_B @S9S_MB_2U_LIB.S9S_MB_2U(SCH_1):M_E_CPU0_SB_DQ(24)
 135 M_E_CPU0_SB_DQ<25> DQ25_B @S9S_MB_2U_LIB.S9S_MB_2U(SCH_1):M_E_CPU0_SB_DQ(25)
 278 M_E_CPU0_SB_DQ<26> DQ26_B @S9S_MB_2U_LIB.S9S_MB_2U(SCH_1):M_E_CPU0_SB_DQ(26)
 280 M_E_CPU0_SB_DQ<27> DQ27_B @S9S_MB_2U_LIB.S9S_MB_2U(SCH_1):M_E_CPU0_SB_DQ(27)
 140 M_E_CPU0_SB_DQ<28> DQ28_B @S9S_MB_2U_LIB.S9S_MB_2U(SCH_1):M_E_CPU0_SB_DQ(28)
 142 M_E_CPU0_SB_DQ<29> DQ29_B @S9S_MB_2U_LIB.S9S_MB_2U(SCH_1):M_E_CPU0_SB_DQ(29)
 285 M_E_CPU0_SB_DQ<30> DQ30_B @S9S_MB_2U_LIB.S9S_MB_2U(SCH_1):M_E_CPU0_SB_DQ(30)
 287 M_E_CPU0_SB_DQ<31> DQ31_B @S9S_MB_2U_LIB.S9S_MB_2U(SCH_1):M_E_CPU0_SB_DQ(31)
   7 M_E_CPU0_SA_DQ<0>  DQ0_A @S9S_MB_2U_LIB.S9S_MB_2U(SCH_1):M_E_CPU0_SA_DQ(0)
   9 M_E_CPU0_SA_DQ<1>  DQ1_A @S9S_MB_2U_LIB.S9S_MB_2U(SCH_1):M_E_CPU0_SA_DQ(1)
 152 M_E_CPU0_SA_DQ<2>  DQ2_A @S9S_MB_2U_LIB.S9S_MB_2U(SCH_1):M_E_CPU0_SA_DQ(2)
 154 M_E_CPU0_SA_DQ<3>  DQ3_A @S9S_MB_2U_LIB.S9S_MB_2U(SCH_1):M_E_CPU0_SA_DQ(3)
  14 M_E_CPU0_SA_DQ<4>  DQ4_A @S9S_MB_2U_LIB.S9S_MB_2U(SCH_1):M_E_CPU0_SA_DQ(4)
  16 M_E_CPU0_SA_DQ<5>  DQ5_A @S9S_MB_2U_LIB.S9S_MB_2U(SCH_1):M_E_CPU0_SA_DQ(5)
 159 M_E_CPU0_SA_DQ<6>  DQ6_A @S9S_MB_2U_LIB.S9S_MB_2U(SCH_1):M_E_CPU0_SA_DQ(6)
 161 M_E_CPU0_SA_DQ<7>  DQ7_A @S9S_MB_2U_LIB.S9S_MB_2U(SCH_1):M_E_CPU0_SA_DQ(7)
  18 M_E_CPU0_SA_DQ<8>  DQ8_A @S9S_MB_2U_LIB.S9S_MB_2U(SCH_1):M_E_CPU0_SA_DQ(8)
  20 M_E_CPU0_SA_DQ<9>  DQ9_A @S9S_MB_2U_LIB.S9S_MB_2U(SCH_1):M_E_CPU0_SA_DQ(9)
 163 M_E_CPU0_SA_DQ<10> DQ10_A @S9S_MB_2U_LIB.S9S_MB_2U(SCH_1):M_E_CPU0_SA_DQ(10)
 165 M_E_CPU0_SA_DQ<11> DQ11_A @S9S_MB_2U_LIB.S9S_MB_2U(SCH_1):M_E_CPU0_SA_DQ(11)
  25 M_E_CPU0_SA_DQ<12> DQ12_A @S9S_MB_2U_LIB.S9S_MB_2U(SCH_1):M_E_CPU0_SA_DQ(12)
  27 M_E_CPU0_SA_DQ<13> DQ13_A @S9S_MB_2U_LIB.S9S_MB_2U(SCH_1):M_E_CPU0_SA_DQ(13)
 170 M_E_CPU0_SA_DQ<14> DQ14_A @S9S_MB_2U_LIB.S9S_MB_2U(SCH_1):M_E_CPU0_SA_DQ(14)
 172 M_E_CPU0_SA_DQ<15> DQ15_A @S9S_MB_2U_LIB.S9S_MB_2U(SCH_1):M_E_CPU0_SA_DQ(15)
  29 M_E_CPU0_SA_DQ<16> DQ16_A @S9S_MB_2U_LIB.S9S_MB_2U(SCH_1):M_E_CPU0_SA_DQ(16)
  31 M_E_CPU0_SA_DQ<17> DQ17_A @S9S_MB_2U_LIB.S9S_MB_2U(SCH_1):M_E_CPU0_SA_DQ(17)
 174 M_E_CPU0_SA_DQ<18> DQ18_A @S9S_MB_2U_LIB.S9S_MB_2U(SCH_1):M_E_CPU0_SA_DQ(18)
 176 M_E_CPU0_SA_DQ<19> DQ19_A @S9S_MB_2U_LIB.S9S_MB_2U(SCH_1):M_E_CPU0_SA_DQ(19)
  36 M_E_CPU0_SA_DQ<20> DQ20_A @S9S_MB_2U_LIB.S9S_MB_2U(SCH_1):M_E_CPU0_SA_DQ(20)
  38 M_E_CPU0_SA_DQ<21> DQ21_A @S9S_MB_2U_LIB.S9S_MB_2U(SCH_1):M_E_CPU0_SA_DQ(21)
 181 M_E_CPU0_SA_DQ<22> DQ22_A @S9S_MB_2U_LIB.S9S_MB_2U(SCH_1):M_E_CPU0_SA_DQ(22)
 183 M_E_CPU0_SA_DQ<23> DQ23_A @S9S_MB_2U_LIB.S9S_MB_2U(SCH_1):M_E_CPU0_SA_DQ(23)
  40 M_E_CPU0_SA_DQ<24> DQ24_A @S9S_MB_2U_LIB.S9S_MB_2U(SCH_1):M_E_CPU0_SA_DQ(24)
  42 M_E_CPU0_SA_DQ<25> DQ25_A @S9S_MB_2U_LIB.S9S_MB_2U(SCH_1):M_E_CPU0_SA_DQ(25)
 185 M_E_CPU0_SA_DQ<26> DQ26_A @S9S_MB_2U_LIB.S9S_MB_2U(SCH_1):M_E_CPU0_SA_DQ(26)
 187 M_E_CPU0_SA_DQ<27> DQ27_A @S9S_MB_2U_LIB.S9S_MB_2U(SCH_1):M_E_CPU0_SA_DQ(27)
  47 M_E_CPU0_SA_DQ<28> DQ28_A @S9S_MB_2U_LIB.S9S_MB_2U(SCH_1):M_E_CPU0_SA_DQ(28)
  49 M_E_CPU0_SA_DQ<29> DQ29_A @S9S_MB_2U_LIB.S9S_MB_2U(SCH_1):M_E_CPU0_SA_DQ(29)
 192 M_E_CPU0_SA_DQ<30> DQ30_A @S9S_MB_2U_LIB.S9S_MB_2U(SCH_1):M_E_CPU0_SA_DQ(30)
 229 M_E_CPU0_SB_CS_N<3> CS1_B_N @S9S_MB_2U_LIB.S9S_MB_2U(SCH_1):M_E_CPU0_SB_CS_N(3)
 209 M_E_CPU0_SA_CS_N<3> CS1_A_N @S9S_MB_2U_LIB.S9S_MB_2U(SCH_1):M_E_CPU0_SA_CS_N(3)
  84 M_E_CPU0_SB_CS_N<2> CS0_B_N @S9S_MB_2U_LIB.S9S_MB_2U(SCH_1):M_E_CPU0_SB_CS_N(2)
  64 M_E_CPU0_SA_CS_N<2> CS0_A_N @S9S_MB_2U_LIB.S9S_MB_2U(SCH_1):M_E_CPU0_SA_CS_N(2)
 217 M_E_CPU0_CLK_DP<1>   CK_T @S9S_MB_2U_LIB.S9S_MB_2U(SCH_1):M_E_CPU0_CLK_DP(1)
 218 M_E_CPU0_CLK_DN<1>   CK_C @S9S_MB_2U_LIB.S9S_MB_2U(SCH_1):M_E_CPU0_CLK_DN(1)
  96 M_E_CPU0_SB_CB<0>  CB0_B @S9S_MB_2U_LIB.S9S_MB_2U(SCH_1):M_E_CPU0_SB_CB(0)
  98 M_E_CPU0_SB_CB<1>  CB1_B @S9S_MB_2U_LIB.S9S_MB_2U(SCH_1):M_E_CPU0_SB_CB(1)
 241 M_E_CPU0_SB_CB<2>  CB2_B @S9S_MB_2U_LIB.S9S_MB_2U(SCH_1):M_E_CPU0_SB_CB(2)
 243 M_E_CPU0_SB_CB<3>  CB3_B @S9S_MB_2U_LIB.S9S_MB_2U(SCH_1):M_E_CPU0_SB_CB(3)
  89 M_E_CPU0_SB_CB<4>  CB4_B @S9S_MB_2U_LIB.S9S_MB_2U(SCH_1):M_E_CPU0_SB_CB(4)
  91 M_E_CPU0_SB_CB<5>  CB5_B @S9S_MB_2U_LIB.S9S_MB_2U(SCH_1):M_E_CPU0_SB_CB(5)
 234 M_E_CPU0_SB_CB<6>  CB6_B @S9S_MB_2U_LIB.S9S_MB_2U(SCH_1):M_E_CPU0_SB_CB(6)
  51 M_E_CPU0_SA_CB<0>  CB0_A @S9S_MB_2U_LIB.S9S_MB_2U(SCH_1):M_E_CPU0_SA_CB(0)
 196 M_E_CPU0_SA_CB<2>  CB2_A @S9S_MB_2U_LIB.S9S_MB_2U(SCH_1):M_E_CPU0_SA_CB(2)
 198 M_E_CPU0_SA_CB<3>  CB3_A @S9S_MB_2U_LIB.S9S_MB_2U(SCH_1):M_E_CPU0_SA_CB(3)
  60 M_E_CPU0_SA_CB<5>  CB5_A @S9S_MB_2U_LIB.S9S_MB_2U(SCH_1):M_E_CPU0_SA_CB(5)
 203 M_E_CPU0_SA_CB<6>  CB6_A @S9S_MB_2U_LIB.S9S_MB_2U(SCH_1):M_E_CPU0_SA_CB(6)
  82 M_E_CPU0_SB_CA<6>  CA6_B @S9S_MB_2U_LIB.S9S_MB_2U(SCH_1):M_E_CPU0_SB_CA(6)
  72 M_E_CPU0_SA_CA<6>  CA6_A @S9S_MB_2U_LIB.S9S_MB_2U(SCH_1):M_E_CPU0_SA_CA(6)
 225 M_E_CPU0_SB_CA<5>  CA5_B @S9S_MB_2U_LIB.S9S_MB_2U(SCH_1):M_E_CPU0_SB_CA(5)
 215 M_E_CPU0_SA_CA<5>  CA5_A @S9S_MB_2U_LIB.S9S_MB_2U(SCH_1):M_E_CPU0_SA_CA(5)
  80 M_E_CPU0_SB_CA<4>  CA4_B @S9S_MB_2U_LIB.S9S_MB_2U(SCH_1):M_E_CPU0_SB_CA(4)
  70 M_E_CPU0_SA_CA<4>  CA4_A @S9S_MB_2U_LIB.S9S_MB_2U(SCH_1):M_E_CPU0_SA_CA(4)
 223 M_E_CPU0_SB_CA<3>  CA3_B @S9S_MB_2U_LIB.S9S_MB_2U(SCH_1):M_E_CPU0_SB_CA(3)
 213 M_E_CPU0_SA_CA<3>  CA3_A @S9S_MB_2U_LIB.S9S_MB_2U(SCH_1):M_E_CPU0_SA_CA(3)
  78 M_E_CPU0_SB_CA<2>  CA2_B @S9S_MB_2U_LIB.S9S_MB_2U(SCH_1):M_E_CPU0_SB_CA(2)
  68 M_E_CPU0_SA_CA<2>  CA2_A @S9S_MB_2U_LIB.S9S_MB_2U(SCH_1):M_E_CPU0_SA_CA(2)
 221 M_E_CPU0_SB_CA<1>  CA1_B @S9S_MB_2U_LIB.S9S_MB_2U(SCH_1):M_E_CPU0_SB_CA(1)
 211 M_E_CPU0_SA_CA<1>  CA1_A @S9S_MB_2U_LIB.S9S_MB_2U(SCH_1):M_E_CPU0_SA_CA(1)
  76 M_E_CPU0_SB_CA<0>  CA0_B @S9S_MB_2U_LIB.S9S_MB_2U(SCH_1):M_E_CPU0_SB_CA(0)
  66 M_E_CPU0_SA_CA<0>  CA0_A @S9S_MB_2U_LIB.S9S_MB_2U(SCH_1):M_E_CPU0_SA_CA(0)
  62 M_E_CPU0_ALERT_N ALERT_N @S9S_MB_2U_LIB.S9S_MB_2U(SCH_1):M_E_CPU0_ALERT_N
 236 M_E_CPU0_SB_CB<7>  CB7_B @S9S_MB_2U_LIB.S9S_MB_2U(SCH_1):M_E_CPU0_SB_CB(7)
  53 M_E_CPU0_SA_CB<1>  CB1_A @S9S_MB_2U_LIB.S9S_MB_2U(SCH_1):M_E_CPU0_SA_CB(1)
  58 M_E_CPU0_SA_CB<4>  CB4_A @S9S_MB_2U_LIB.S9S_MB_2U(SCH_1):M_E_CPU0_SA_CB(4)
 205 M_E_CPU0_SA_CB<7>  CB7_A @S9S_MB_2U_LIB.S9S_MB_2U(SCH_1):M_E_CPU0_SA_CB(7)
 194 M_E_CPU0_SA_DQ<31> DQ31_A @S9S_MB_2U_LIB.S9S_MB_2U(SCH_1):M_E_CPU0_SA_DQ(31)

Q_CAP_C0402-2.2UF,6.3V,20%,X6SA  I123  C29
   1 P3V3_AUX      A @S9S_MB_2U_LIB.S9S_MB_2U(SCH_1):P3V3_AUX
   2    GND      B @S9S_MB_2U_LIB.S9S_MB_2U(SCH_1):GND

Q_CAP_C0805-10UF,16V,10%,X6S,CA  I124  C30
   1 P12V_S3_AUX_CPU0_NVDIMM      A @S9S_MB_2U_LIB.S9S_MB_2U(SCH_1):P12V_S3_AUX_CPU0_NVDIMM
   2    GND      B @S9S_MB_2U_LIB.S9S_MB_2U(SCH_1):GND

Q_CAP_C0805-10UF,16V,10%,X6S,CA  I146  C31
   1 P12V_S3_AUX_CPU0_NVDIMM      A @S9S_MB_2U_LIB.S9S_MB_2U(SCH_1):P12V_S3_AUX_CPU0_NVDIMM
   2    GND      B @S9S_MB_2U_LIB.S9S_MB_2U(SCH_1):GND

SCONN288_ADR50017P087CC-SCONN2A  I148  J10
   6    GND   VSS0 @S9S_MB_2U_LIB.S9S_MB_2U(SCH_1):GND
   8    GND   VSS1 @S9S_MB_2U_LIB.S9S_MB_2U(SCH_1):GND
  10    GND   VSS2 @S9S_MB_2U_LIB.S9S_MB_2U(SCH_1):GND
  13    GND   VSS3 @S9S_MB_2U_LIB.S9S_MB_2U(SCH_1):GND
  15    GND   VSS4 @S9S_MB_2U_LIB.S9S_MB_2U(SCH_1):GND
  17    GND   VSS5 @S9S_MB_2U_LIB.S9S_MB_2U(SCH_1):GND
  19    GND   VSS6 @S9S_MB_2U_LIB.S9S_MB_2U(SCH_1):GND
  21    GND   VSS7 @S9S_MB_2U_LIB.S9S_MB_2U(SCH_1):GND
  24    GND   VSS8 @S9S_MB_2U_LIB.S9S_MB_2U(SCH_1):GND
  26    GND   VSS9 @S9S_MB_2U_LIB.S9S_MB_2U(SCH_1):GND
  28    GND  VSS10 @S9S_MB_2U_LIB.S9S_MB_2U(SCH_1):GND
  30    GND  VSS11 @S9S_MB_2U_LIB.S9S_MB_2U(SCH_1):GND
  32    GND  VSS12 @S9S_MB_2U_LIB.S9S_MB_2U(SCH_1):GND
  35    GND  VSS13 @S9S_MB_2U_LIB.S9S_MB_2U(SCH_1):GND
  37    GND  VSS14 @S9S_MB_2U_LIB.S9S_MB_2U(SCH_1):GND
  39    GND  VSS15 @S9S_MB_2U_LIB.S9S_MB_2U(SCH_1):GND
  41    GND  VSS16 @S9S_MB_2U_LIB.S9S_MB_2U(SCH_1):GND
  43    GND  VSS17 @S9S_MB_2U_LIB.S9S_MB_2U(SCH_1):GND
  46    GND  VSS18 @S9S_MB_2U_LIB.S9S_MB_2U(SCH_1):GND
  48    GND  VSS19 @S9S_MB_2U_LIB.S9S_MB_2U(SCH_1):GND
  50    GND  VSS20 @S9S_MB_2U_LIB.S9S_MB_2U(SCH_1):GND
  52    GND  VSS21 @S9S_MB_2U_LIB.S9S_MB_2U(SCH_1):GND
  54    GND  VSS22 @S9S_MB_2U_LIB.S9S_MB_2U(SCH_1):GND
  57    GND  VSS23 @S9S_MB_2U_LIB.S9S_MB_2U(SCH_1):GND
  59    GND  VSS24 @S9S_MB_2U_LIB.S9S_MB_2U(SCH_1):GND
  61    GND  VSS25 @S9S_MB_2U_LIB.S9S_MB_2U(SCH_1):GND
  63    GND  VSS26 @S9S_MB_2U_LIB.S9S_MB_2U(SCH_1):GND
  65    GND  VSS27 @S9S_MB_2U_LIB.S9S_MB_2U(SCH_1):GND
  67    GND  VSS28 @S9S_MB_2U_LIB.S9S_MB_2U(SCH_1):GND
  69    GND  VSS29 @S9S_MB_2U_LIB.S9S_MB_2U(SCH_1):GND
  71    GND  VSS30 @S9S_MB_2U_LIB.S9S_MB_2U(SCH_1):GND
  73    GND  VSS31 @S9S_MB_2U_LIB.S9S_MB_2U(SCH_1):GND
  75    GND  VSS32 @S9S_MB_2U_LIB.S9S_MB_2U(SCH_1):GND
  77    GND  VSS33 @S9S_MB_2U_LIB.S9S_MB_2U(SCH_1):GND
  79    GND  VSS34 @S9S_MB_2U_LIB.S9S_MB_2U(SCH_1):GND
  81    GND  VSS35 @S9S_MB_2U_LIB.S9S_MB_2U(SCH_1):GND
  83    GND  VSS36 @S9S_MB_2U_LIB.S9S_MB_2U(SCH_1):GND
  85    GND  VSS37 @S9S_MB_2U_LIB.S9S_MB_2U(SCH_1):GND
  88    GND  VSS38 @S9S_MB_2U_LIB.S9S_MB_2U(SCH_1):GND
  90    GND  VSS39 @S9S_MB_2U_LIB.S9S_MB_2U(SCH_1):GND
  92    GND  VSS40 @S9S_MB_2U_LIB.S9S_MB_2U(SCH_1):GND
  95    GND  VSS41 @S9S_MB_2U_LIB.S9S_MB_2U(SCH_1):GND
  97    GND  VSS42 @S9S_MB_2U_LIB.S9S_MB_2U(SCH_1):GND
  99    GND  VSS43 @S9S_MB_2U_LIB.S9S_MB_2U(SCH_1):GND
 101    GND  VSS44 @S9S_MB_2U_LIB.S9S_MB_2U(SCH_1):GND
 103    GND  VSS45 @S9S_MB_2U_LIB.S9S_MB_2U(SCH_1):GND
 106    GND  VSS46 @S9S_MB_2U_LIB.S9S_MB_2U(SCH_1):GND
 108    GND  VSS47 @S9S_MB_2U_LIB.S9S_MB_2U(SCH_1):GND
 110    GND  VSS48 @S9S_MB_2U_LIB.S9S_MB_2U(SCH_1):GND
 112    GND  VSS49 @S9S_MB_2U_LIB.S9S_MB_2U(SCH_1):GND
 114    GND  VSS50 @S9S_MB_2U_LIB.S9S_MB_2U(SCH_1):GND
 117    GND  VSS51 @S9S_MB_2U_LIB.S9S_MB_2U(SCH_1):GND
 119    GND  VSS52 @S9S_MB_2U_LIB.S9S_MB_2U(SCH_1):GND
 121    GND  VSS53 @S9S_MB_2U_LIB.S9S_MB_2U(SCH_1):GND
 123    GND  VSS54 @S9S_MB_2U_LIB.S9S_MB_2U(SCH_1):GND
 125    GND  VSS55 @S9S_MB_2U_LIB.S9S_MB_2U(SCH_1):GND
 128    GND  VSS56 @S9S_MB_2U_LIB.S9S_MB_2U(SCH_1):GND
 130    GND  VSS57 @S9S_MB_2U_LIB.S9S_MB_2U(SCH_1):GND
 134    GND  VSS59 @S9S_MB_2U_LIB.S9S_MB_2U(SCH_1):GND
 143    GND  VSS63 @S9S_MB_2U_LIB.S9S_MB_2U(SCH_1):GND
 151    GND  VSS64 @S9S_MB_2U_LIB.S9S_MB_2U(SCH_1):GND
 153    GND  VSS65 @S9S_MB_2U_LIB.S9S_MB_2U(SCH_1):GND
 155    GND  VSS66 @S9S_MB_2U_LIB.S9S_MB_2U(SCH_1):GND
 158    GND  VSS67 @S9S_MB_2U_LIB.S9S_MB_2U(SCH_1):GND
 160    GND  VSS68 @S9S_MB_2U_LIB.S9S_MB_2U(SCH_1):GND
 162    GND  VSS69 @S9S_MB_2U_LIB.S9S_MB_2U(SCH_1):GND
 164    GND  VSS70 @S9S_MB_2U_LIB.S9S_MB_2U(SCH_1):GND
 166    GND  VSS71 @S9S_MB_2U_LIB.S9S_MB_2U(SCH_1):GND
 169    GND  VSS72 @S9S_MB_2U_LIB.S9S_MB_2U(SCH_1):GND
 171    GND  VSS73 @S9S_MB_2U_LIB.S9S_MB_2U(SCH_1):GND
 173    GND  VSS74 @S9S_MB_2U_LIB.S9S_MB_2U(SCH_1):GND
 175    GND  VSS75 @S9S_MB_2U_LIB.S9S_MB_2U(SCH_1):GND
 177    GND  VSS76 @S9S_MB_2U_LIB.S9S_MB_2U(SCH_1):GND
 180    GND  VSS77 @S9S_MB_2U_LIB.S9S_MB_2U(SCH_1):GND
 182    GND  VSS78 @S9S_MB_2U_LIB.S9S_MB_2U(SCH_1):GND
 184    GND  VSS79 @S9S_MB_2U_LIB.S9S_MB_2U(SCH_1):GND
 186    GND  VSS80 @S9S_MB_2U_LIB.S9S_MB_2U(SCH_1):GND
 188    GND  VSS81 @S9S_MB_2U_LIB.S9S_MB_2U(SCH_1):GND
 191    GND  VSS82 @S9S_MB_2U_LIB.S9S_MB_2U(SCH_1):GND
 193    GND  VSS83 @S9S_MB_2U_LIB.S9S_MB_2U(SCH_1):GND
 195    GND  VSS84 @S9S_MB_2U_LIB.S9S_MB_2U(SCH_1):GND
 197    GND  VSS85 @S9S_MB_2U_LIB.S9S_MB_2U(SCH_1):GND
 199    GND  VSS86 @S9S_MB_2U_LIB.S9S_MB_2U(SCH_1):GND
 202    GND  VSS87 @S9S_MB_2U_LIB.S9S_MB_2U(SCH_1):GND
 204    GND  VSS88 @S9S_MB_2U_LIB.S9S_MB_2U(SCH_1):GND
 206    GND  VSS89 @S9S_MB_2U_LIB.S9S_MB_2U(SCH_1):GND
 208    GND  VSS90 @S9S_MB_2U_LIB.S9S_MB_2U(SCH_1):GND
 210    GND  VSS91 @S9S_MB_2U_LIB.S9S_MB_2U(SCH_1):GND
 212    GND  VSS92 @S9S_MB_2U_LIB.S9S_MB_2U(SCH_1):GND
 214    GND  VSS93 @S9S_MB_2U_LIB.S9S_MB_2U(SCH_1):GND
 216    GND  VSS94 @S9S_MB_2U_LIB.S9S_MB_2U(SCH_1):GND
 219    GND  VSS95 @S9S_MB_2U_LIB.S9S_MB_2U(SCH_1):GND
 222    GND  VSS96 @S9S_MB_2U_LIB.S9S_MB_2U(SCH_1):GND
 224    GND  VSS97 @S9S_MB_2U_LIB.S9S_MB_2U(SCH_1):GND
 226    GND  VSS98 @S9S_MB_2U_LIB.S9S_MB_2U(SCH_1):GND
 228    GND  VSS99 @S9S_MB_2U_LIB.S9S_MB_2U(SCH_1):GND
 233    GND VSS101 @S9S_MB_2U_LIB.S9S_MB_2U(SCH_1):GND
 237    GND VSS103 @S9S_MB_2U_LIB.S9S_MB_2U(SCH_1):GND
 242    GND VSS105 @S9S_MB_2U_LIB.S9S_MB_2U(SCH_1):GND
 244    GND VSS106 @S9S_MB_2U_LIB.S9S_MB_2U(SCH_1):GND
 246    GND VSS107 @S9S_MB_2U_LIB.S9S_MB_2U(SCH_1):GND
 248    GND VSS108 @S9S_MB_2U_LIB.S9S_MB_2U(SCH_1):GND
 251    GND VSS109 @S9S_MB_2U_LIB.S9S_MB_2U(SCH_1):GND
 253    GND VSS110 @S9S_MB_2U_LIB.S9S_MB_2U(SCH_1):GND
 255    GND VSS111 @S9S_MB_2U_LIB.S9S_MB_2U(SCH_1):GND
 257    GND VSS112 @S9S_MB_2U_LIB.S9S_MB_2U(SCH_1):GND
 259    GND VSS113 @S9S_MB_2U_LIB.S9S_MB_2U(SCH_1):GND
 262    GND VSS114 @S9S_MB_2U_LIB.S9S_MB_2U(SCH_1):GND
 264    GND VSS115 @S9S_MB_2U_LIB.S9S_MB_2U(SCH_1):GND
 266    GND VSS116 @S9S_MB_2U_LIB.S9S_MB_2U(SCH_1):GND
 268    GND VSS117 @S9S_MB_2U_LIB.S9S_MB_2U(SCH_1):GND
 270    GND VSS118 @S9S_MB_2U_LIB.S9S_MB_2U(SCH_1):GND
 273    GND VSS119 @S9S_MB_2U_LIB.S9S_MB_2U(SCH_1):GND
 275    GND VSS120 @S9S_MB_2U_LIB.S9S_MB_2U(SCH_1):GND
 277    GND VSS121 @S9S_MB_2U_LIB.S9S_MB_2U(SCH_1):GND
 279    GND VSS122 @S9S_MB_2U_LIB.S9S_MB_2U(SCH_1):GND
 281    GND VSS123 @S9S_MB_2U_LIB.S9S_MB_2U(SCH_1):GND
 284    GND VSS124 @S9S_MB_2U_LIB.S9S_MB_2U(SCH_1):GND
 286    GND VSS125 @S9S_MB_2U_LIB.S9S_MB_2U(SCH_1):GND
 288    GND VSS126 @S9S_MB_2U_LIB.S9S_MB_2U(SCH_1):GND
   1 P12V_S3_AUX_CPU0_NVDIMM VIN_BULK0 @S9S_MB_2U_LIB.S9S_MB_2U(SCH_1):P12V_S3_AUX_CPU0_NVDIMM
 145 P12V_S3_AUX_CPU0_NVDIMM VIN_BULK1 @S9S_MB_2U_LIB.S9S_MB_2U(SCH_1):P12V_S3_AUX_CPU0_NVDIMM
 146 P12V_S3_AUX_CPU0_NVDIMM VIN_BULK2 @S9S_MB_2U_LIB.S9S_MB_2U(SCH_1):P12V_S3_AUX_CPU0_NVDIMM
 230    GND VSS100 @S9S_MB_2U_LIB.S9S_MB_2U(SCH_1):GND
 235    GND VSS102 @S9S_MB_2U_LIB.S9S_MB_2U(SCH_1):GND
 240    GND VSS104 @S9S_MB_2U_LIB.S9S_MB_2U(SCH_1):GND
 132    GND  VSS58 @S9S_MB_2U_LIB.S9S_MB_2U(SCH_1):GND
 136    GND  VSS60 @S9S_MB_2U_LIB.S9S_MB_2U(SCH_1):GND
 139    GND  VSS61 @S9S_MB_2U_LIB.S9S_MB_2U(SCH_1):GND
 141    GND  VSS62 @S9S_MB_2U_LIB.S9S_MB_2U(SCH_1):GND
  G1    GND     G1 @S9S_MB_2U_LIB.S9S_MB_2U(SCH_1):GND
  G2    GND     G2 @S9S_MB_2U_LIB.S9S_MB_2U(SCH_1):GND
  G3    GND     G3 @S9S_MB_2U_LIB.S9S_MB_2U(SCH_1):GND

SCONN288_ADR50017P087CC-SCONN2A  I178  J10
  93 M_E_CPU0_SB_DQS_DP<9> DQS9_B_T||TDQS9_B_T||DBI4_B_N @S9S_MB_2U_LIB.S9S_MB_2U(SCH_1):M_E_CPU0_SB_DQS_DP(9)
  94 M_E_CPU0_SB_DQS_DN<9> DQS9_B_C||TDQS9_B_C @S9S_MB_2U_LIB.S9S_MB_2U(SCH_1):M_E_CPU0_SB_DQS_DN(9)
 201 M_E_CPU0_SA_DQS_DP<9> DQS9_A_T||TDQS9_A_T @S9S_MB_2U_LIB.S9S_MB_2U(SCH_1):M_E_CPU0_SA_DQS_DP(9)
 200 M_E_CPU0_SA_DQS_DN<9> DQS9_A_C||TDQS9_A_C @S9S_MB_2U_LIB.S9S_MB_2U(SCH_1):M_E_CPU0_SA_DQS_DN(9)
 190 M_E_CPU0_SA_DQS_DP<8> DQS8_A_T||TDQS8_A_T @S9S_MB_2U_LIB.S9S_MB_2U(SCH_1):M_E_CPU0_SA_DQS_DP(8)
 189 M_E_CPU0_SA_DQS_DN<8> DQS8_A_C||TDQS8_A_C @S9S_MB_2U_LIB.S9S_MB_2U(SCH_1):M_E_CPU0_SA_DQS_DN(8)
 271 M_E_CPU0_SB_DQS_DN<7> DQS7_B_C||TDQS7_B_C @S9S_MB_2U_LIB.S9S_MB_2U(SCH_1):M_E_CPU0_SB_DQS_DN(7)
 179 M_E_CPU0_SA_DQS_DP<7> DQS7_A_T||TDQS7_A_T @S9S_MB_2U_LIB.S9S_MB_2U(SCH_1):M_E_CPU0_SA_DQS_DP(7)
 261 M_E_CPU0_SB_DQS_DP<6> DQS6_B_T||TDQS6_B_T @S9S_MB_2U_LIB.S9S_MB_2U(SCH_1):M_E_CPU0_SB_DQS_DP(6)
 260 M_E_CPU0_SB_DQS_DN<6> DQS6_B_C||TDQS6_B_C @S9S_MB_2U_LIB.S9S_MB_2U(SCH_1):M_E_CPU0_SB_DQS_DN(6)
 167 M_E_CPU0_SA_DQS_DN<6> DQS6_A_C||TDQS6_A_C||DQS6_A_T||TDQS6_A_T @S9S_MB_2U_LIB.S9S_MB_2U(SCH_1):M_E_CPU0_SA_DQS_DN(6)
 250 M_E_CPU0_SB_DQS_DP<5> DQS5_B_T||TDQS5_B_T @S9S_MB_2U_LIB.S9S_MB_2U(SCH_1):M_E_CPU0_SB_DQS_DP(5)
 249 M_E_CPU0_SB_DQS_DN<5> DQS5_B_C||TDQS5_B_C @S9S_MB_2U_LIB.S9S_MB_2U(SCH_1):M_E_CPU0_SB_DQS_DN(5)
 157 M_E_CPU0_SA_DQS_DP<5> DQS5_A_T||TDQS5_A_T @S9S_MB_2U_LIB.S9S_MB_2U(SCH_1):M_E_CPU0_SA_DQS_DP(5)
 156 M_E_CPU0_SA_DQS_DN<5> DQS5_A_C||TDQS5_A_C||DQS5_A_T||TDQS5_A_T @S9S_MB_2U_LIB.S9S_MB_2U(SCH_1):M_E_CPU0_SA_DQS_DN(5)
 239 M_E_CPU0_SB_DQS_DP<4> DQS4_B_T @S9S_MB_2U_LIB.S9S_MB_2U(SCH_1):M_E_CPU0_SB_DQS_DP(4)
 238 M_E_CPU0_SB_DQS_DN<4> DQS4_B_C @S9S_MB_2U_LIB.S9S_MB_2U(SCH_1):M_E_CPU0_SB_DQS_DN(4)
  55 M_E_CPU0_SA_DQS_DP<4> DQS4_A_T @S9S_MB_2U_LIB.S9S_MB_2U(SCH_1):M_E_CPU0_SA_DQS_DP(4)
  56 M_E_CPU0_SA_DQS_DN<4> DQS4_A_C @S9S_MB_2U_LIB.S9S_MB_2U(SCH_1):M_E_CPU0_SA_DQS_DN(4)
 137 M_E_CPU0_SB_DQS_DP<3> DQS3_B_T @S9S_MB_2U_LIB.S9S_MB_2U(SCH_1):M_E_CPU0_SB_DQS_DP(3)
 138 M_E_CPU0_SB_DQS_DN<3> DQS3_B_C @S9S_MB_2U_LIB.S9S_MB_2U(SCH_1):M_E_CPU0_SB_DQS_DN(3)
  44 M_E_CPU0_SA_DQS_DP<3> DQS3_A_T @S9S_MB_2U_LIB.S9S_MB_2U(SCH_1):M_E_CPU0_SA_DQS_DP(3)
  45 M_E_CPU0_SA_DQS_DN<3> DQS3_A_C @S9S_MB_2U_LIB.S9S_MB_2U(SCH_1):M_E_CPU0_SA_DQS_DN(3)
 126 M_E_CPU0_SB_DQS_DP<2> DQS2_B_T @S9S_MB_2U_LIB.S9S_MB_2U(SCH_1):M_E_CPU0_SB_DQS_DP(2)
 127 M_E_CPU0_SB_DQS_DN<2> DQS2_B_C @S9S_MB_2U_LIB.S9S_MB_2U(SCH_1):M_E_CPU0_SB_DQS_DN(2)
  33 M_E_CPU0_SA_DQS_DP<2> DQS2_A_T @S9S_MB_2U_LIB.S9S_MB_2U(SCH_1):M_E_CPU0_SA_DQS_DP(2)
  34 M_E_CPU0_SA_DQS_DN<2> DQS2_A_C @S9S_MB_2U_LIB.S9S_MB_2U(SCH_1):M_E_CPU0_SA_DQS_DN(2)
 115 M_E_CPU0_SB_DQS_DP<1> DQS1_B_T @S9S_MB_2U_LIB.S9S_MB_2U(SCH_1):M_E_CPU0_SB_DQS_DP(1)
 116 M_E_CPU0_SB_DQS_DN<1> DQS1_B_C @S9S_MB_2U_LIB.S9S_MB_2U(SCH_1):M_E_CPU0_SB_DQS_DN(1)
  22 M_E_CPU0_SA_DQS_DP<1> DQS1_A_T @S9S_MB_2U_LIB.S9S_MB_2U(SCH_1):M_E_CPU0_SA_DQS_DP(1)
  23 M_E_CPU0_SA_DQS_DN<1> DQS1_A_C @S9S_MB_2U_LIB.S9S_MB_2U(SCH_1):M_E_CPU0_SA_DQS_DN(1)
 104 M_E_CPU0_SB_DQS_DP<0> DQS0_B_T @S9S_MB_2U_LIB.S9S_MB_2U(SCH_1):M_E_CPU0_SB_DQS_DP(0)
 105 M_E_CPU0_SB_DQS_DN<0> DQS0_B_C @S9S_MB_2U_LIB.S9S_MB_2U(SCH_1):M_E_CPU0_SB_DQS_DN(0)
  11 M_E_CPU0_SA_DQS_DP<0> DQS0_A_T @S9S_MB_2U_LIB.S9S_MB_2U(SCH_1):M_E_CPU0_SA_DQS_DP(0)
  12 M_E_CPU0_SA_DQS_DN<0> DQS0_A_C @S9S_MB_2U_LIB.S9S_MB_2U(SCH_1):M_E_CPU0_SA_DQS_DN(0)
 272 M_E_CPU0_SB_DQS_DP<7> DQS7_B_T||TDQS7_B_T @S9S_MB_2U_LIB.S9S_MB_2U(SCH_1):M_E_CPU0_SB_DQS_DP(7)
 282 M_E_CPU0_SB_DQS_DN<8> DQS8_B_C||TDQS8_B_C @S9S_MB_2U_LIB.S9S_MB_2U(SCH_1):M_E_CPU0_SB_DQS_DN(8)
 283 M_E_CPU0_SB_DQS_DP<8> DQS8_B_T||TDQS8_B_T @S9S_MB_2U_LIB.S9S_MB_2U(SCH_1):M_E_CPU0_SB_DQS_DP(8)
 168 M_E_CPU0_SA_DQS_DP<6> DQS6_A_T||TDQS6_A_T @S9S_MB_2U_LIB.S9S_MB_2U(SCH_1):M_E_CPU0_SA_DQS_DP(6)
 178 M_E_CPU0_SA_DQS_DN<7> DQS7_A_C||TDQS7_A_C @S9S_MB_2U_LIB.S9S_MB_2U(SCH_1):M_E_CPU0_SA_DQS_DN(7)

Q_RES_0402LF-49.9,1%,1/16W,CHIA  I179  R3884
   1 I3C_SPD_DDREFGH_CPU0_LVC1_SCL_1      A @S9S_MB_2U_LIB.S9S_MB_2U(SCH_1):I3C_SPD_DDREFGH_CPU0_LVC1_SCL_R2
   2 I3C_SPD_DDREFGH_CPU0_LVC1_SCL      B @S9S_MB_2U_LIB.S9S_MB_2U(SCH_1):I3C_SPD_DDREFGH_CPU0_LVC1_SCL


DRAWING: @S9S_MB_2U_LIB.S9S_MB_2U(SCH_1):PAGE92 

Q_RES_0402LF-23.2K,1%,1/16W,CHA  I2  R36
   1 PD_CHF_CPU0_DIMM1_SAA      A @S9S_MB_2U_LIB.S9S_MB_2U(SCH_1):PD_CHF_CPU0_DIMM1_SAA
   2    GND      B @S9S_MB_2U_LIB.S9S_MB_2U(SCH_1):GND

SCONN288_ADR50017P130CC-SCONN2A  I25  J11
   3 P3V3_AUX VIN_MGMT @S9S_MB_2U_LIB.S9S_MB_2U(SCH_1):P3V3_AUX
   2 TP_CHF_CPU0_DIMM1_FRU_0   RFU0 @S9S_MB_2U_LIB.S9S_MB_2U(SCH_1):TP_CHF_CPU0_DIMM1_FRU_0
 144 TP_CHF_CPU0_DIMM1_FRU_1   RFU1 @S9S_MB_2U_LIB.S9S_MB_2U(SCH_1):TP_CHF_CPU0_DIMM1_FRU_1
 149 TP_CHF_CPU0_DIMM1_FRU_2   RFU2 @S9S_MB_2U_LIB.S9S_MB_2U(SCH_1):TP_CHF_CPU0_DIMM1_FRU_2
 150 TP_CHF_CPU0_DIMM1_FRU_3   RFU3 @S9S_MB_2U_LIB.S9S_MB_2U(SCH_1):TP_CHF_CPU0_DIMM1_FRU_3
 220 TP_CHF_CPU0_DIMM1_FRU_4   RFU4 @S9S_MB_2U_LIB.S9S_MB_2U(SCH_1):TP_CHF_CPU0_DIMM1_FRU_4
 231 TP_CHF_CPU0_DIMM1_FRU_5   RFU5 @S9S_MB_2U_LIB.S9S_MB_2U(SCH_1):TP_CHF_CPU0_DIMM1_FRU_5
 232 TP_CHF_CPU0_DIMM1_FRU_6   RFU6 @S9S_MB_2U_LIB.S9S_MB_2U(SCH_1):TP_CHF_CPU0_DIMM1_FRU_6
 207 RST_M_EF_CPU0_FPGA_N RESET_N @S9S_MB_2U_LIB.S9S_MB_2U(SCH_1):RST_M_EF_CPU0_FPGA_N
 147 PWRGD_CHF_CPU0_DIMM1 PWR_GOOD||FAIL_N @S9S_MB_2U_LIB.S9S_MB_2U(SCH_1):PWRGD_CHF_CPU0_DIMM1
 227 M_F_CPU0_SB_PAR  PAR_B @S9S_MB_2U_LIB.S9S_MB_2U(SCH_1):M_F_CPU0_SB_PAR
  74 M_F_CPU0_SA_PAR  PAR_A @S9S_MB_2U_LIB.S9S_MB_2U(SCH_1):M_F_CPU0_SA_PAR
  87 M_F_CPU0_SB_RSP<0> LBS||RSP_B_N @S9S_MB_2U_LIB.S9S_MB_2U(SCH_1):M_F_CPU0_SB_RSP(0)
  86 M_F_CPU0_SA_RSP<0> LBD||RSP_A_N @S9S_MB_2U_LIB.S9S_MB_2U(SCH_1):M_F_CPU0_SA_RSP(0)
   5 I3C_SPD_DDREFGH_CPU0_LVC1_SDA   HSDA @S9S_MB_2U_LIB.S9S_MB_2U(SCH_1):I3C_SPD_DDREFGH_CPU0_LVC1_SDA
   4 I3C_SPD_DDREFGH_CPU0_LVC1_SCL_2   HSCL @S9S_MB_2U_LIB.S9S_MB_2U(SCH_1):I3C_SPD_DDREFGH_CPU0_LVC1_SCL_R3
 148 PD_CHF_CPU0_DIMM1_SAA    HSA @S9S_MB_2U_LIB.S9S_MB_2U(SCH_1):PD_CHF_CPU0_DIMM1_SAA
 100 M_F_CPU0_SB_DQ<0>  DQ0_B @S9S_MB_2U_LIB.S9S_MB_2U(SCH_1):M_F_CPU0_SB_DQ(0)
 102 M_F_CPU0_SB_DQ<1>  DQ1_B @S9S_MB_2U_LIB.S9S_MB_2U(SCH_1):M_F_CPU0_SB_DQ(1)
 245 M_F_CPU0_SB_DQ<2>  DQ2_B @S9S_MB_2U_LIB.S9S_MB_2U(SCH_1):M_F_CPU0_SB_DQ(2)
 247 M_F_CPU0_SB_DQ<3>  DQ3_B @S9S_MB_2U_LIB.S9S_MB_2U(SCH_1):M_F_CPU0_SB_DQ(3)
 107 M_F_CPU0_SB_DQ<4>  DQ4_B @S9S_MB_2U_LIB.S9S_MB_2U(SCH_1):M_F_CPU0_SB_DQ(4)
 109 M_F_CPU0_SB_DQ<5>  DQ5_B @S9S_MB_2U_LIB.S9S_MB_2U(SCH_1):M_F_CPU0_SB_DQ(5)
 252 M_F_CPU0_SB_DQ<6>  DQ6_B @S9S_MB_2U_LIB.S9S_MB_2U(SCH_1):M_F_CPU0_SB_DQ(6)
 254 M_F_CPU0_SB_DQ<7>  DQ7_B @S9S_MB_2U_LIB.S9S_MB_2U(SCH_1):M_F_CPU0_SB_DQ(7)
 111 M_F_CPU0_SB_DQ<8>  DQ8_B @S9S_MB_2U_LIB.S9S_MB_2U(SCH_1):M_F_CPU0_SB_DQ(8)
 113 M_F_CPU0_SB_DQ<9>  DQ9_B @S9S_MB_2U_LIB.S9S_MB_2U(SCH_1):M_F_CPU0_SB_DQ(9)
 256 M_F_CPU0_SB_DQ<10> DQ10_B @S9S_MB_2U_LIB.S9S_MB_2U(SCH_1):M_F_CPU0_SB_DQ(10)
 258 M_F_CPU0_SB_DQ<11> DQ11_B @S9S_MB_2U_LIB.S9S_MB_2U(SCH_1):M_F_CPU0_SB_DQ(11)
 118 M_F_CPU0_SB_DQ<12> DQ12_B @S9S_MB_2U_LIB.S9S_MB_2U(SCH_1):M_F_CPU0_SB_DQ(12)
 120 M_F_CPU0_SB_DQ<13> DQ13_B @S9S_MB_2U_LIB.S9S_MB_2U(SCH_1):M_F_CPU0_SB_DQ(13)
 263 M_F_CPU0_SB_DQ<14> DQ14_B @S9S_MB_2U_LIB.S9S_MB_2U(SCH_1):M_F_CPU0_SB_DQ(14)
 265 M_F_CPU0_SB_DQ<15> DQ15_B @S9S_MB_2U_LIB.S9S_MB_2U(SCH_1):M_F_CPU0_SB_DQ(15)
 122 M_F_CPU0_SB_DQ<16> DQ16_B @S9S_MB_2U_LIB.S9S_MB_2U(SCH_1):M_F_CPU0_SB_DQ(16)
 124 M_F_CPU0_SB_DQ<17> DQ17_B @S9S_MB_2U_LIB.S9S_MB_2U(SCH_1):M_F_CPU0_SB_DQ(17)
 267 M_F_CPU0_SB_DQ<18> DQ18_B @S9S_MB_2U_LIB.S9S_MB_2U(SCH_1):M_F_CPU0_SB_DQ(18)
 269 M_F_CPU0_SB_DQ<19> DQ19_B @S9S_MB_2U_LIB.S9S_MB_2U(SCH_1):M_F_CPU0_SB_DQ(19)
 129 M_F_CPU0_SB_DQ<20> DQ20_B @S9S_MB_2U_LIB.S9S_MB_2U(SCH_1):M_F_CPU0_SB_DQ(20)
 131 M_F_CPU0_SB_DQ<21> DQ21_B @S9S_MB_2U_LIB.S9S_MB_2U(SCH_1):M_F_CPU0_SB_DQ(21)
 274 M_F_CPU0_SB_DQ<22> DQ22_B @S9S_MB_2U_LIB.S9S_MB_2U(SCH_1):M_F_CPU0_SB_DQ(22)
 276 M_F_CPU0_SB_DQ<23> DQ23_B @S9S_MB_2U_LIB.S9S_MB_2U(SCH_1):M_F_CPU0_SB_DQ(23)
 133 M_F_CPU0_SB_DQ<24> DQ24_B @S9S_MB_2U_LIB.S9S_MB_2U(SCH_1):M_F_CPU0_SB_DQ(24)
 135 M_F_CPU0_SB_DQ<25> DQ25_B @S9S_MB_2U_LIB.S9S_MB_2U(SCH_1):M_F_CPU0_SB_DQ(25)
 278 M_F_CPU0_SB_DQ<26> DQ26_B @S9S_MB_2U_LIB.S9S_MB_2U(SCH_1):M_F_CPU0_SB_DQ(26)
 280 M_F_CPU0_SB_DQ<27> DQ27_B @S9S_MB_2U_LIB.S9S_MB_2U(SCH_1):M_F_CPU0_SB_DQ(27)
 140 M_F_CPU0_SB_DQ<28> DQ28_B @S9S_MB_2U_LIB.S9S_MB_2U(SCH_1):M_F_CPU0_SB_DQ(28)
 142 M_F_CPU0_SB_DQ<29> DQ29_B @S9S_MB_2U_LIB.S9S_MB_2U(SCH_1):M_F_CPU0_SB_DQ(29)
 285 M_F_CPU0_SB_DQ<30> DQ30_B @S9S_MB_2U_LIB.S9S_MB_2U(SCH_1):M_F_CPU0_SB_DQ(30)
 287 M_F_CPU0_SB_DQ<31> DQ31_B @S9S_MB_2U_LIB.S9S_MB_2U(SCH_1):M_F_CPU0_SB_DQ(31)
   7 M_F_CPU0_SA_DQ<0>  DQ0_A @S9S_MB_2U_LIB.S9S_MB_2U(SCH_1):M_F_CPU0_SA_DQ(0)
   9 M_F_CPU0_SA_DQ<1>  DQ1_A @S9S_MB_2U_LIB.S9S_MB_2U(SCH_1):M_F_CPU0_SA_DQ(1)
 152 M_F_CPU0_SA_DQ<2>  DQ2_A @S9S_MB_2U_LIB.S9S_MB_2U(SCH_1):M_F_CPU0_SA_DQ(2)
 154 M_F_CPU0_SA_DQ<3>  DQ3_A @S9S_MB_2U_LIB.S9S_MB_2U(SCH_1):M_F_CPU0_SA_DQ(3)
  14 M_F_CPU0_SA_DQ<4>  DQ4_A @S9S_MB_2U_LIB.S9S_MB_2U(SCH_1):M_F_CPU0_SA_DQ(4)
  16 M_F_CPU0_SA_DQ<5>  DQ5_A @S9S_MB_2U_LIB.S9S_MB_2U(SCH_1):M_F_CPU0_SA_DQ(5)
 159 M_F_CPU0_SA_DQ<6>  DQ6_A @S9S_MB_2U_LIB.S9S_MB_2U(SCH_1):M_F_CPU0_SA_DQ(6)
 161 M_F_CPU0_SA_DQ<7>  DQ7_A @S9S_MB_2U_LIB.S9S_MB_2U(SCH_1):M_F_CPU0_SA_DQ(7)
  18 M_F_CPU0_SA_DQ<8>  DQ8_A @S9S_MB_2U_LIB.S9S_MB_2U(SCH_1):M_F_CPU0_SA_DQ(8)
  20 M_F_CPU0_SA_DQ<9>  DQ9_A @S9S_MB_2U_LIB.S9S_MB_2U(SCH_1):M_F_CPU0_SA_DQ(9)
 163 M_F_CPU0_SA_DQ<10> DQ10_A @S9S_MB_2U_LIB.S9S_MB_2U(SCH_1):M_F_CPU0_SA_DQ(10)
 165 M_F_CPU0_SA_DQ<11> DQ11_A @S9S_MB_2U_LIB.S9S_MB_2U(SCH_1):M_F_CPU0_SA_DQ(11)
  25 M_F_CPU0_SA_DQ<12> DQ12_A @S9S_MB_2U_LIB.S9S_MB_2U(SCH_1):M_F_CPU0_SA_DQ(12)
  27 M_F_CPU0_SA_DQ<13> DQ13_A @S9S_MB_2U_LIB.S9S_MB_2U(SCH_1):M_F_CPU0_SA_DQ(13)
 170 M_F_CPU0_SA_DQ<14> DQ14_A @S9S_MB_2U_LIB.S9S_MB_2U(SCH_1):M_F_CPU0_SA_DQ(14)
 172 M_F_CPU0_SA_DQ<15> DQ15_A @S9S_MB_2U_LIB.S9S_MB_2U(SCH_1):M_F_CPU0_SA_DQ(15)
  29 M_F_CPU0_SA_DQ<16> DQ16_A @S9S_MB_2U_LIB.S9S_MB_2U(SCH_1):M_F_CPU0_SA_DQ(16)
  31 M_F_CPU0_SA_DQ<17> DQ17_A @S9S_MB_2U_LIB.S9S_MB_2U(SCH_1):M_F_CPU0_SA_DQ(17)
 174 M_F_CPU0_SA_DQ<18> DQ18_A @S9S_MB_2U_LIB.S9S_MB_2U(SCH_1):M_F_CPU0_SA_DQ(18)
 176 M_F_CPU0_SA_DQ<19> DQ19_A @S9S_MB_2U_LIB.S9S_MB_2U(SCH_1):M_F_CPU0_SA_DQ(19)
  36 M_F_CPU0_SA_DQ<20> DQ20_A @S9S_MB_2U_LIB.S9S_MB_2U(SCH_1):M_F_CPU0_SA_DQ(20)
  38 M_F_CPU0_SA_DQ<21> DQ21_A @S9S_MB_2U_LIB.S9S_MB_2U(SCH_1):M_F_CPU0_SA_DQ(21)
 181 M_F_CPU0_SA_DQ<22> DQ22_A @S9S_MB_2U_LIB.S9S_MB_2U(SCH_1):M_F_CPU0_SA_DQ(22)
 183 M_F_CPU0_SA_DQ<23> DQ23_A @S9S_MB_2U_LIB.S9S_MB_2U(SCH_1):M_F_CPU0_SA_DQ(23)
  40 M_F_CPU0_SA_DQ<24> DQ24_A @S9S_MB_2U_LIB.S9S_MB_2U(SCH_1):M_F_CPU0_SA_DQ(24)
  42 M_F_CPU0_SA_DQ<25> DQ25_A @S9S_MB_2U_LIB.S9S_MB_2U(SCH_1):M_F_CPU0_SA_DQ(25)
 185 M_F_CPU0_SA_DQ<26> DQ26_A @S9S_MB_2U_LIB.S9S_MB_2U(SCH_1):M_F_CPU0_SA_DQ(26)
 187 M_F_CPU0_SA_DQ<27> DQ27_A @S9S_MB_2U_LIB.S9S_MB_2U(SCH_1):M_F_CPU0_SA_DQ(27)
  47 M_F_CPU0_SA_DQ<28> DQ28_A @S9S_MB_2U_LIB.S9S_MB_2U(SCH_1):M_F_CPU0_SA_DQ(28)
  49 M_F_CPU0_SA_DQ<29> DQ29_A @S9S_MB_2U_LIB.S9S_MB_2U(SCH_1):M_F_CPU0_SA_DQ(29)
 192 M_F_CPU0_SA_DQ<30> DQ30_A @S9S_MB_2U_LIB.S9S_MB_2U(SCH_1):M_F_CPU0_SA_DQ(30)
 229 M_F_CPU0_SB_CS_N<1> CS1_B_N @S9S_MB_2U_LIB.S9S_MB_2U(SCH_1):M_F_CPU0_SB_CS_N(1)
 209 M_F_CPU0_SA_CS_N<1> CS1_A_N @S9S_MB_2U_LIB.S9S_MB_2U(SCH_1):M_F_CPU0_SA_CS_N(1)
  84 M_F_CPU0_SB_CS_N<0> CS0_B_N @S9S_MB_2U_LIB.S9S_MB_2U(SCH_1):M_F_CPU0_SB_CS_N(0)
  64 M_F_CPU0_SA_CS_N<0> CS0_A_N @S9S_MB_2U_LIB.S9S_MB_2U(SCH_1):M_F_CPU0_SA_CS_N(0)
 217 M_F_CPU0_CLK_DP<0>   CK_T @S9S_MB_2U_LIB.S9S_MB_2U(SCH_1):M_F_CPU0_CLK_DP(0)
 218 M_F_CPU0_CLK_DN<0>   CK_C @S9S_MB_2U_LIB.S9S_MB_2U(SCH_1):M_F_CPU0_CLK_DN(0)
  96 M_F_CPU0_SB_CB<0>  CB0_B @S9S_MB_2U_LIB.S9S_MB_2U(SCH_1):M_F_CPU0_SB_CB(0)
  98 M_F_CPU0_SB_CB<1>  CB1_B @S9S_MB_2U_LIB.S9S_MB_2U(SCH_1):M_F_CPU0_SB_CB(1)
 241 M_F_CPU0_SB_CB<2>  CB2_B @S9S_MB_2U_LIB.S9S_MB_2U(SCH_1):M_F_CPU0_SB_CB(2)
 243 M_F_CPU0_SB_CB<3>  CB3_B @S9S_MB_2U_LIB.S9S_MB_2U(SCH_1):M_F_CPU0_SB_CB(3)
  89 M_F_CPU0_SB_CB<4>  CB4_B @S9S_MB_2U_LIB.S9S_MB_2U(SCH_1):M_F_CPU0_SB_CB(4)
  91 M_F_CPU0_SB_CB<5>  CB5_B @S9S_MB_2U_LIB.S9S_MB_2U(SCH_1):M_F_CPU0_SB_CB(5)
 234 M_F_CPU0_SB_CB<6>  CB6_B @S9S_MB_2U_LIB.S9S_MB_2U(SCH_1):M_F_CPU0_SB_CB(6)
  51 M_F_CPU0_SA_CB<0>  CB0_A @S9S_MB_2U_LIB.S9S_MB_2U(SCH_1):M_F_CPU0_SA_CB(0)
 196 M_F_CPU0_SA_CB<2>  CB2_A @S9S_MB_2U_LIB.S9S_MB_2U(SCH_1):M_F_CPU0_SA_CB(2)
 198 M_F_CPU0_SA_CB<3>  CB3_A @S9S_MB_2U_LIB.S9S_MB_2U(SCH_1):M_F_CPU0_SA_CB(3)
  60 M_F_CPU0_SA_CB<5>  CB5_A @S9S_MB_2U_LIB.S9S_MB_2U(SCH_1):M_F_CPU0_SA_CB(5)
 203 M_F_CPU0_SA_CB<6>  CB6_A @S9S_MB_2U_LIB.S9S_MB_2U(SCH_1):M_F_CPU0_SA_CB(6)
  82 M_F_CPU0_SB_CA<6>  CA6_B @S9S_MB_2U_LIB.S9S_MB_2U(SCH_1):M_F_CPU0_SB_CA(6)
  72 M_F_CPU0_SA_CA<6>  CA6_A @S9S_MB_2U_LIB.S9S_MB_2U(SCH_1):M_F_CPU0_SA_CA(6)
 225 M_F_CPU0_SB_CA<5>  CA5_B @S9S_MB_2U_LIB.S9S_MB_2U(SCH_1):M_F_CPU0_SB_CA(5)
 215 M_F_CPU0_SA_CA<5>  CA5_A @S9S_MB_2U_LIB.S9S_MB_2U(SCH_1):M_F_CPU0_SA_CA(5)
  80 M_F_CPU0_SB_CA<4>  CA4_B @S9S_MB_2U_LIB.S9S_MB_2U(SCH_1):M_F_CPU0_SB_CA(4)
  70 M_F_CPU0_SA_CA<4>  CA4_A @S9S_MB_2U_LIB.S9S_MB_2U(SCH_1):M_F_CPU0_SA_CA(4)
 223 M_F_CPU0_SB_CA<3>  CA3_B @S9S_MB_2U_LIB.S9S_MB_2U(SCH_1):M_F_CPU0_SB_CA(3)
 213 M_F_CPU0_SA_CA<3>  CA3_A @S9S_MB_2U_LIB.S9S_MB_2U(SCH_1):M_F_CPU0_SA_CA(3)
  78 M_F_CPU0_SB_CA<2>  CA2_B @S9S_MB_2U_LIB.S9S_MB_2U(SCH_1):M_F_CPU0_SB_CA(2)
  68 M_F_CPU0_SA_CA<2>  CA2_A @S9S_MB_2U_LIB.S9S_MB_2U(SCH_1):M_F_CPU0_SA_CA(2)
 221 M_F_CPU0_SB_CA<1>  CA1_B @S9S_MB_2U_LIB.S9S_MB_2U(SCH_1):M_F_CPU0_SB_CA(1)
 211 M_F_CPU0_SA_CA<1>  CA1_A @S9S_MB_2U_LIB.S9S_MB_2U(SCH_1):M_F_CPU0_SA_CA(1)
  76 M_F_CPU0_SB_CA<0>  CA0_B @S9S_MB_2U_LIB.S9S_MB_2U(SCH_1):M_F_CPU0_SB_CA(0)
  66 M_F_CPU0_SA_CA<0>  CA0_A @S9S_MB_2U_LIB.S9S_MB_2U(SCH_1):M_F_CPU0_SA_CA(0)
  62 M_F_CPU0_ALERT_N ALERT_N @S9S_MB_2U_LIB.S9S_MB_2U(SCH_1):M_F_CPU0_ALERT_N
 236 M_F_CPU0_SB_CB<7>  CB7_B @S9S_MB_2U_LIB.S9S_MB_2U(SCH_1):M_F_CPU0_SB_CB(7)
  53 M_F_CPU0_SA_CB<1>  CB1_A @S9S_MB_2U_LIB.S9S_MB_2U(SCH_1):M_F_CPU0_SA_CB(1)
  58 M_F_CPU0_SA_CB<4>  CB4_A @S9S_MB_2U_LIB.S9S_MB_2U(SCH_1):M_F_CPU0_SA_CB(4)
 205 M_F_CPU0_SA_CB<7>  CB7_A @S9S_MB_2U_LIB.S9S_MB_2U(SCH_1):M_F_CPU0_SA_CB(7)
 194 M_F_CPU0_SA_DQ<31> DQ31_A @S9S_MB_2U_LIB.S9S_MB_2U(SCH_1):M_F_CPU0_SA_DQ(31)

Q_CAP_C0402-2.2UF,6.3V,20%,X6SA  I122  C32
   1 P3V3_AUX      A @S9S_MB_2U_LIB.S9S_MB_2U(SCH_1):P3V3_AUX
   2    GND      B @S9S_MB_2U_LIB.S9S_MB_2U(SCH_1):GND

Q_CAP_C0805-10UF,16V,10%,X6S,CA  I127  C33
   1 P12V_S3_AUX_CPU0_NVDIMM      A @S9S_MB_2U_LIB.S9S_MB_2U(SCH_1):P12V_S3_AUX_CPU0_NVDIMM
   2    GND      B @S9S_MB_2U_LIB.S9S_MB_2U(SCH_1):GND

Q_CAP_C0805-10UF,16V,10%,X6S,CA  I130  C34
   1 P12V_S3_AUX_CPU0_NVDIMM      A @S9S_MB_2U_LIB.S9S_MB_2U(SCH_1):P12V_S3_AUX_CPU0_NVDIMM
   2    GND      B @S9S_MB_2U_LIB.S9S_MB_2U(SCH_1):GND

SCONN288_ADR50017P130CC-SCONN2A  I175  J11
   6    GND   VSS0 @S9S_MB_2U_LIB.S9S_MB_2U(SCH_1):GND
   8    GND   VSS1 @S9S_MB_2U_LIB.S9S_MB_2U(SCH_1):GND
  10    GND   VSS2 @S9S_MB_2U_LIB.S9S_MB_2U(SCH_1):GND
  13    GND   VSS3 @S9S_MB_2U_LIB.S9S_MB_2U(SCH_1):GND
  15    GND   VSS4 @S9S_MB_2U_LIB.S9S_MB_2U(SCH_1):GND
  17    GND   VSS5 @S9S_MB_2U_LIB.S9S_MB_2U(SCH_1):GND
  19    GND   VSS6 @S9S_MB_2U_LIB.S9S_MB_2U(SCH_1):GND
  21    GND   VSS7 @S9S_MB_2U_LIB.S9S_MB_2U(SCH_1):GND
  24    GND   VSS8 @S9S_MB_2U_LIB.S9S_MB_2U(SCH_1):GND
  26    GND   VSS9 @S9S_MB_2U_LIB.S9S_MB_2U(SCH_1):GND
  28    GND  VSS10 @S9S_MB_2U_LIB.S9S_MB_2U(SCH_1):GND
  30    GND  VSS11 @S9S_MB_2U_LIB.S9S_MB_2U(SCH_1):GND
  32    GND  VSS12 @S9S_MB_2U_LIB.S9S_MB_2U(SCH_1):GND
  35    GND  VSS13 @S9S_MB_2U_LIB.S9S_MB_2U(SCH_1):GND
  37    GND  VSS14 @S9S_MB_2U_LIB.S9S_MB_2U(SCH_1):GND
  39    GND  VSS15 @S9S_MB_2U_LIB.S9S_MB_2U(SCH_1):GND
  41    GND  VSS16 @S9S_MB_2U_LIB.S9S_MB_2U(SCH_1):GND
  43    GND  VSS17 @S9S_MB_2U_LIB.S9S_MB_2U(SCH_1):GND
  46    GND  VSS18 @S9S_MB_2U_LIB.S9S_MB_2U(SCH_1):GND
  48    GND  VSS19 @S9S_MB_2U_LIB.S9S_MB_2U(SCH_1):GND
  50    GND  VSS20 @S9S_MB_2U_LIB.S9S_MB_2U(SCH_1):GND
  52    GND  VSS21 @S9S_MB_2U_LIB.S9S_MB_2U(SCH_1):GND
  54    GND  VSS22 @S9S_MB_2U_LIB.S9S_MB_2U(SCH_1):GND
  57    GND  VSS23 @S9S_MB_2U_LIB.S9S_MB_2U(SCH_1):GND
  59    GND  VSS24 @S9S_MB_2U_LIB.S9S_MB_2U(SCH_1):GND
  61    GND  VSS25 @S9S_MB_2U_LIB.S9S_MB_2U(SCH_1):GND
  63    GND  VSS26 @S9S_MB_2U_LIB.S9S_MB_2U(SCH_1):GND
  65    GND  VSS27 @S9S_MB_2U_LIB.S9S_MB_2U(SCH_1):GND
  67    GND  VSS28 @S9S_MB_2U_LIB.S9S_MB_2U(SCH_1):GND
  69    GND  VSS29 @S9S_MB_2U_LIB.S9S_MB_2U(SCH_1):GND
  71    GND  VSS30 @S9S_MB_2U_LIB.S9S_MB_2U(SCH_1):GND
  73    GND  VSS31 @S9S_MB_2U_LIB.S9S_MB_2U(SCH_1):GND
  75    GND  VSS32 @S9S_MB_2U_LIB.S9S_MB_2U(SCH_1):GND
  77    GND  VSS33 @S9S_MB_2U_LIB.S9S_MB_2U(SCH_1):GND
  79    GND  VSS34 @S9S_MB_2U_LIB.S9S_MB_2U(SCH_1):GND
  81    GND  VSS35 @S9S_MB_2U_LIB.S9S_MB_2U(SCH_1):GND
  83    GND  VSS36 @S9S_MB_2U_LIB.S9S_MB_2U(SCH_1):GND
  85    GND  VSS37 @S9S_MB_2U_LIB.S9S_MB_2U(SCH_1):GND
  88    GND  VSS38 @S9S_MB_2U_LIB.S9S_MB_2U(SCH_1):GND
  90    GND  VSS39 @S9S_MB_2U_LIB.S9S_MB_2U(SCH_1):GND
  92    GND  VSS40 @S9S_MB_2U_LIB.S9S_MB_2U(SCH_1):GND
  95    GND  VSS41 @S9S_MB_2U_LIB.S9S_MB_2U(SCH_1):GND
  97    GND  VSS42 @S9S_MB_2U_LIB.S9S_MB_2U(SCH_1):GND
  99    GND  VSS43 @S9S_MB_2U_LIB.S9S_MB_2U(SCH_1):GND
 101    GND  VSS44 @S9S_MB_2U_LIB.S9S_MB_2U(SCH_1):GND
 103    GND  VSS45 @S9S_MB_2U_LIB.S9S_MB_2U(SCH_1):GND
 106    GND  VSS46 @S9S_MB_2U_LIB.S9S_MB_2U(SCH_1):GND
 108    GND  VSS47 @S9S_MB_2U_LIB.S9S_MB_2U(SCH_1):GND
 110    GND  VSS48 @S9S_MB_2U_LIB.S9S_MB_2U(SCH_1):GND
 112    GND  VSS49 @S9S_MB_2U_LIB.S9S_MB_2U(SCH_1):GND
 114    GND  VSS50 @S9S_MB_2U_LIB.S9S_MB_2U(SCH_1):GND
 117    GND  VSS51 @S9S_MB_2U_LIB.S9S_MB_2U(SCH_1):GND
 119    GND  VSS52 @S9S_MB_2U_LIB.S9S_MB_2U(SCH_1):GND
 121    GND  VSS53 @S9S_MB_2U_LIB.S9S_MB_2U(SCH_1):GND
 123    GND  VSS54 @S9S_MB_2U_LIB.S9S_MB_2U(SCH_1):GND
 125    GND  VSS55 @S9S_MB_2U_LIB.S9S_MB_2U(SCH_1):GND
 128    GND  VSS56 @S9S_MB_2U_LIB.S9S_MB_2U(SCH_1):GND
 130    GND  VSS57 @S9S_MB_2U_LIB.S9S_MB_2U(SCH_1):GND
 134    GND  VSS59 @S9S_MB_2U_LIB.S9S_MB_2U(SCH_1):GND
 143    GND  VSS63 @S9S_MB_2U_LIB.S9S_MB_2U(SCH_1):GND
 151    GND  VSS64 @S9S_MB_2U_LIB.S9S_MB_2U(SCH_1):GND
 153    GND  VSS65 @S9S_MB_2U_LIB.S9S_MB_2U(SCH_1):GND
 155    GND  VSS66 @S9S_MB_2U_LIB.S9S_MB_2U(SCH_1):GND
 158    GND  VSS67 @S9S_MB_2U_LIB.S9S_MB_2U(SCH_1):GND
 160    GND  VSS68 @S9S_MB_2U_LIB.S9S_MB_2U(SCH_1):GND
 162    GND  VSS69 @S9S_MB_2U_LIB.S9S_MB_2U(SCH_1):GND
 164    GND  VSS70 @S9S_MB_2U_LIB.S9S_MB_2U(SCH_1):GND
 166    GND  VSS71 @S9S_MB_2U_LIB.S9S_MB_2U(SCH_1):GND
 169    GND  VSS72 @S9S_MB_2U_LIB.S9S_MB_2U(SCH_1):GND
 171    GND  VSS73 @S9S_MB_2U_LIB.S9S_MB_2U(SCH_1):GND
 173    GND  VSS74 @S9S_MB_2U_LIB.S9S_MB_2U(SCH_1):GND
 175    GND  VSS75 @S9S_MB_2U_LIB.S9S_MB_2U(SCH_1):GND
 177    GND  VSS76 @S9S_MB_2U_LIB.S9S_MB_2U(SCH_1):GND
 180    GND  VSS77 @S9S_MB_2U_LIB.S9S_MB_2U(SCH_1):GND
 182    GND  VSS78 @S9S_MB_2U_LIB.S9S_MB_2U(SCH_1):GND
 184    GND  VSS79 @S9S_MB_2U_LIB.S9S_MB_2U(SCH_1):GND
 186    GND  VSS80 @S9S_MB_2U_LIB.S9S_MB_2U(SCH_1):GND
 188    GND  VSS81 @S9S_MB_2U_LIB.S9S_MB_2U(SCH_1):GND
 191    GND  VSS82 @S9S_MB_2U_LIB.S9S_MB_2U(SCH_1):GND
 193    GND  VSS83 @S9S_MB_2U_LIB.S9S_MB_2U(SCH_1):GND
 195    GND  VSS84 @S9S_MB_2U_LIB.S9S_MB_2U(SCH_1):GND
 197    GND  VSS85 @S9S_MB_2U_LIB.S9S_MB_2U(SCH_1):GND
 199    GND  VSS86 @S9S_MB_2U_LIB.S9S_MB_2U(SCH_1):GND
 202    GND  VSS87 @S9S_MB_2U_LIB.S9S_MB_2U(SCH_1):GND
 204    GND  VSS88 @S9S_MB_2U_LIB.S9S_MB_2U(SCH_1):GND
 206    GND  VSS89 @S9S_MB_2U_LIB.S9S_MB_2U(SCH_1):GND
 208    GND  VSS90 @S9S_MB_2U_LIB.S9S_MB_2U(SCH_1):GND
 210    GND  VSS91 @S9S_MB_2U_LIB.S9S_MB_2U(SCH_1):GND
 212    GND  VSS92 @S9S_MB_2U_LIB.S9S_MB_2U(SCH_1):GND
 214    GND  VSS93 @S9S_MB_2U_LIB.S9S_MB_2U(SCH_1):GND
 216    GND  VSS94 @S9S_MB_2U_LIB.S9S_MB_2U(SCH_1):GND
 219    GND  VSS95 @S9S_MB_2U_LIB.S9S_MB_2U(SCH_1):GND
 222    GND  VSS96 @S9S_MB_2U_LIB.S9S_MB_2U(SCH_1):GND
 224    GND  VSS97 @S9S_MB_2U_LIB.S9S_MB_2U(SCH_1):GND
 226    GND  VSS98 @S9S_MB_2U_LIB.S9S_MB_2U(SCH_1):GND
 228    GND  VSS99 @S9S_MB_2U_LIB.S9S_MB_2U(SCH_1):GND
 233    GND VSS101 @S9S_MB_2U_LIB.S9S_MB_2U(SCH_1):GND
 237    GND VSS103 @S9S_MB_2U_LIB.S9S_MB_2U(SCH_1):GND
 242    GND VSS105 @S9S_MB_2U_LIB.S9S_MB_2U(SCH_1):GND
 244    GND VSS106 @S9S_MB_2U_LIB.S9S_MB_2U(SCH_1):GND
 246    GND VSS107 @S9S_MB_2U_LIB.S9S_MB_2U(SCH_1):GND
 248    GND VSS108 @S9S_MB_2U_LIB.S9S_MB_2U(SCH_1):GND
 251    GND VSS109 @S9S_MB_2U_LIB.S9S_MB_2U(SCH_1):GND
 253    GND VSS110 @S9S_MB_2U_LIB.S9S_MB_2U(SCH_1):GND
 255    GND VSS111 @S9S_MB_2U_LIB.S9S_MB_2U(SCH_1):GND
 257    GND VSS112 @S9S_MB_2U_LIB.S9S_MB_2U(SCH_1):GND
 259    GND VSS113 @S9S_MB_2U_LIB.S9S_MB_2U(SCH_1):GND
 262    GND VSS114 @S9S_MB_2U_LIB.S9S_MB_2U(SCH_1):GND
 264    GND VSS115 @S9S_MB_2U_LIB.S9S_MB_2U(SCH_1):GND
 266    GND VSS116 @S9S_MB_2U_LIB.S9S_MB_2U(SCH_1):GND
 268    GND VSS117 @S9S_MB_2U_LIB.S9S_MB_2U(SCH_1):GND
 270    GND VSS118 @S9S_MB_2U_LIB.S9S_MB_2U(SCH_1):GND
 273    GND VSS119 @S9S_MB_2U_LIB.S9S_MB_2U(SCH_1):GND
 275    GND VSS120 @S9S_MB_2U_LIB.S9S_MB_2U(SCH_1):GND
 277    GND VSS121 @S9S_MB_2U_LIB.S9S_MB_2U(SCH_1):GND
 279    GND VSS122 @S9S_MB_2U_LIB.S9S_MB_2U(SCH_1):GND
 281    GND VSS123 @S9S_MB_2U_LIB.S9S_MB_2U(SCH_1):GND
 284    GND VSS124 @S9S_MB_2U_LIB.S9S_MB_2U(SCH_1):GND
 286    GND VSS125 @S9S_MB_2U_LIB.S9S_MB_2U(SCH_1):GND
 288    GND VSS126 @S9S_MB_2U_LIB.S9S_MB_2U(SCH_1):GND
   1 P12V_S3_AUX_CPU0_NVDIMM VIN_BULK0 @S9S_MB_2U_LIB.S9S_MB_2U(SCH_1):P12V_S3_AUX_CPU0_NVDIMM
 145 P12V_S3_AUX_CPU0_NVDIMM VIN_BULK1 @S9S_MB_2U_LIB.S9S_MB_2U(SCH_1):P12V_S3_AUX_CPU0_NVDIMM
 146 P12V_S3_AUX_CPU0_NVDIMM VIN_BULK2 @S9S_MB_2U_LIB.S9S_MB_2U(SCH_1):P12V_S3_AUX_CPU0_NVDIMM
 230    GND VSS100 @S9S_MB_2U_LIB.S9S_MB_2U(SCH_1):GND
 235    GND VSS102 @S9S_MB_2U_LIB.S9S_MB_2U(SCH_1):GND
 240    GND VSS104 @S9S_MB_2U_LIB.S9S_MB_2U(SCH_1):GND
 132    GND  VSS58 @S9S_MB_2U_LIB.S9S_MB_2U(SCH_1):GND
 136    GND  VSS60 @S9S_MB_2U_LIB.S9S_MB_2U(SCH_1):GND
 139    GND  VSS61 @S9S_MB_2U_LIB.S9S_MB_2U(SCH_1):GND
 141    GND  VSS62 @S9S_MB_2U_LIB.S9S_MB_2U(SCH_1):GND
  G1    GND     G1 @S9S_MB_2U_LIB.S9S_MB_2U(SCH_1):GND
  G2    GND     G2 @S9S_MB_2U_LIB.S9S_MB_2U(SCH_1):GND
  G3    GND     G3 @S9S_MB_2U_LIB.S9S_MB_2U(SCH_1):GND

SCONN288_ADR50017P130CC-SCONN2A  I178  J11
  93 M_F_CPU0_SB_DQS_DP<9> DQS9_B_T||TDQS9_B_T||DBI4_B_N @S9S_MB_2U_LIB.S9S_MB_2U(SCH_1):M_F_CPU0_SB_DQS_DP(9)
  94 M_F_CPU0_SB_DQS_DN<9> DQS9_B_C||TDQS9_B_C @S9S_MB_2U_LIB.S9S_MB_2U(SCH_1):M_F_CPU0_SB_DQS_DN(9)
 201 M_F_CPU0_SA_DQS_DP<9> DQS9_A_T||TDQS9_A_T @S9S_MB_2U_LIB.S9S_MB_2U(SCH_1):M_F_CPU0_SA_DQS_DP(9)
 200 M_F_CPU0_SA_DQS_DN<9> DQS9_A_C||TDQS9_A_C @S9S_MB_2U_LIB.S9S_MB_2U(SCH_1):M_F_CPU0_SA_DQS_DN(9)
 190 M_F_CPU0_SA_DQS_DP<8> DQS8_A_T||TDQS8_A_T @S9S_MB_2U_LIB.S9S_MB_2U(SCH_1):M_F_CPU0_SA_DQS_DP(8)
 189 M_F_CPU0_SA_DQS_DN<8> DQS8_A_C||TDQS8_A_C @S9S_MB_2U_LIB.S9S_MB_2U(SCH_1):M_F_CPU0_SA_DQS_DN(8)
 271 M_F_CPU0_SB_DQS_DN<7> DQS7_B_C||TDQS7_B_C @S9S_MB_2U_LIB.S9S_MB_2U(SCH_1):M_F_CPU0_SB_DQS_DN(7)
 179 M_F_CPU0_SA_DQS_DP<7> DQS7_A_T||TDQS7_A_T @S9S_MB_2U_LIB.S9S_MB_2U(SCH_1):M_F_CPU0_SA_DQS_DP(7)
 261 M_F_CPU0_SB_DQS_DP<6> DQS6_B_T||TDQS6_B_T @S9S_MB_2U_LIB.S9S_MB_2U(SCH_1):M_F_CPU0_SB_DQS_DP(6)
 260 M_F_CPU0_SB_DQS_DN<6> DQS6_B_C||TDQS6_B_C @S9S_MB_2U_LIB.S9S_MB_2U(SCH_1):M_F_CPU0_SB_DQS_DN(6)
 167 M_F_CPU0_SA_DQS_DN<6> DQS6_A_C||TDQS6_A_C||DQS6_A_T||TDQS6_A_T @S9S_MB_2U_LIB.S9S_MB_2U(SCH_1):M_F_CPU0_SA_DQS_DN(6)
 250 M_F_CPU0_SB_DQS_DP<5> DQS5_B_T||TDQS5_B_T @S9S_MB_2U_LIB.S9S_MB_2U(SCH_1):M_F_CPU0_SB_DQS_DP(5)
 249 M_F_CPU0_SB_DQS_DN<5> DQS5_B_C||TDQS5_B_C @S9S_MB_2U_LIB.S9S_MB_2U(SCH_1):M_F_CPU0_SB_DQS_DN(5)
 157 M_F_CPU0_SA_DQS_DP<5> DQS5_A_T||TDQS5_A_T @S9S_MB_2U_LIB.S9S_MB_2U(SCH_1):M_F_CPU0_SA_DQS_DP(5)
 156 M_F_CPU0_SA_DQS_DN<5> DQS5_A_C||TDQS5_A_C||DQS5_A_T||TDQS5_A_T @S9S_MB_2U_LIB.S9S_MB_2U(SCH_1):M_F_CPU0_SA_DQS_DN(5)
 239 M_F_CPU0_SB_DQS_DP<4> DQS4_B_T @S9S_MB_2U_LIB.S9S_MB_2U(SCH_1):M_F_CPU0_SB_DQS_DP(4)
 238 M_F_CPU0_SB_DQS_DN<4> DQS4_B_C @S9S_MB_2U_LIB.S9S_MB_2U(SCH_1):M_F_CPU0_SB_DQS_DN(4)
  55 M_F_CPU0_SA_DQS_DP<4> DQS4_A_T @S9S_MB_2U_LIB.S9S_MB_2U(SCH_1):M_F_CPU0_SA_DQS_DP(4)
  56 M_F_CPU0_SA_DQS_DN<4> DQS4_A_C @S9S_MB_2U_LIB.S9S_MB_2U(SCH_1):M_F_CPU0_SA_DQS_DN(4)
 137 M_F_CPU0_SB_DQS_DP<3> DQS3_B_T @S9S_MB_2U_LIB.S9S_MB_2U(SCH_1):M_F_CPU0_SB_DQS_DP(3)
 138 M_F_CPU0_SB_DQS_DN<3> DQS3_B_C @S9S_MB_2U_LIB.S9S_MB_2U(SCH_1):M_F_CPU0_SB_DQS_DN(3)
  44 M_F_CPU0_SA_DQS_DP<3> DQS3_A_T @S9S_MB_2U_LIB.S9S_MB_2U(SCH_1):M_F_CPU0_SA_DQS_DP(3)
  45 M_F_CPU0_SA_DQS_DN<3> DQS3_A_C @S9S_MB_2U_LIB.S9S_MB_2U(SCH_1):M_F_CPU0_SA_DQS_DN(3)
 126 M_F_CPU0_SB_DQS_DP<2> DQS2_B_T @S9S_MB_2U_LIB.S9S_MB_2U(SCH_1):M_F_CPU0_SB_DQS_DP(2)
 127 M_F_CPU0_SB_DQS_DN<2> DQS2_B_C @S9S_MB_2U_LIB.S9S_MB_2U(SCH_1):M_F_CPU0_SB_DQS_DN(2)
  33 M_F_CPU0_SA_DQS_DP<2> DQS2_A_T @S9S_MB_2U_LIB.S9S_MB_2U(SCH_1):M_F_CPU0_SA_DQS_DP(2)
  34 M_F_CPU0_SA_DQS_DN<2> DQS2_A_C @S9S_MB_2U_LIB.S9S_MB_2U(SCH_1):M_F_CPU0_SA_DQS_DN(2)
 115 M_F_CPU0_SB_DQS_DP<1> DQS1_B_T @S9S_MB_2U_LIB.S9S_MB_2U(SCH_1):M_F_CPU0_SB_DQS_DP(1)
 116 M_F_CPU0_SB_DQS_DN<1> DQS1_B_C @S9S_MB_2U_LIB.S9S_MB_2U(SCH_1):M_F_CPU0_SB_DQS_DN(1)
  22 M_F_CPU0_SA_DQS_DP<1> DQS1_A_T @S9S_MB_2U_LIB.S9S_MB_2U(SCH_1):M_F_CPU0_SA_DQS_DP(1)
  23 M_F_CPU0_SA_DQS_DN<1> DQS1_A_C @S9S_MB_2U_LIB.S9S_MB_2U(SCH_1):M_F_CPU0_SA_DQS_DN(1)
 104 M_F_CPU0_SB_DQS_DP<0> DQS0_B_T @S9S_MB_2U_LIB.S9S_MB_2U(SCH_1):M_F_CPU0_SB_DQS_DP(0)
 105 M_F_CPU0_SB_DQS_DN<0> DQS0_B_C @S9S_MB_2U_LIB.S9S_MB_2U(SCH_1):M_F_CPU0_SB_DQS_DN(0)
  11 M_F_CPU0_SA_DQS_DP<0> DQS0_A_T @S9S_MB_2U_LIB.S9S_MB_2U(SCH_1):M_F_CPU0_SA_DQS_DP(0)
  12 M_F_CPU0_SA_DQS_DN<0> DQS0_A_C @S9S_MB_2U_LIB.S9S_MB_2U(SCH_1):M_F_CPU0_SA_DQS_DN(0)
 272 M_F_CPU0_SB_DQS_DP<7> DQS7_B_T||TDQS7_B_T @S9S_MB_2U_LIB.S9S_MB_2U(SCH_1):M_F_CPU0_SB_DQS_DP(7)
 282 M_F_CPU0_SB_DQS_DN<8> DQS8_B_C||TDQS8_B_C @S9S_MB_2U_LIB.S9S_MB_2U(SCH_1):M_F_CPU0_SB_DQS_DN(8)
 283 M_F_CPU0_SB_DQS_DP<8> DQS8_B_T||TDQS8_B_T @S9S_MB_2U_LIB.S9S_MB_2U(SCH_1):M_F_CPU0_SB_DQS_DP(8)
 168 M_F_CPU0_SA_DQS_DP<6> DQS6_A_T||TDQS6_A_T @S9S_MB_2U_LIB.S9S_MB_2U(SCH_1):M_F_CPU0_SA_DQS_DP(6)
 178 M_F_CPU0_SA_DQS_DN<7> DQS7_A_C||TDQS7_A_C @S9S_MB_2U_LIB.S9S_MB_2U(SCH_1):M_F_CPU0_SA_DQS_DN(7)

Q_RES_0402LF-49.9,1%,1/16W,CHIA  I179  R3885
   1 I3C_SPD_DDREFGH_CPU0_LVC1_SCL_2      A @S9S_MB_2U_LIB.S9S_MB_2U(SCH_1):I3C_SPD_DDREFGH_CPU0_LVC1_SCL_R3
   2 I3C_SPD_DDREFGH_CPU0_LVC1_SCL      B @S9S_MB_2U_LIB.S9S_MB_2U(SCH_1):I3C_SPD_DDREFGH_CPU0_LVC1_SCL


DRAWING: @S9S_MB_2U_LIB.S9S_MB_2U(SCH_1):PAGE93 

Q_RES_0402LF-35.7K,1%,1/16W,CHA  I2  R37
   1 PD_CHF_CPU0_DIMM2_SAA      A @S9S_MB_2U_LIB.S9S_MB_2U(SCH_1):PD_CHF_CPU0_DIMM2_SAA
   2    GND      B @S9S_MB_2U_LIB.S9S_MB_2U(SCH_1):GND

SCONN288_ADR50017P087CC-SCONN2A  I24  J12
   3 P3V3_AUX VIN_MGMT @S9S_MB_2U_LIB.S9S_MB_2U(SCH_1):P3V3_AUX
   2 TP_CHF_CPU0_DIMM2_FRU_0   RFU0 @S9S_MB_2U_LIB.S9S_MB_2U(SCH_1):TP_CHF_CPU0_DIMM2_FRU_0
 144 TP_CHF_CPU0_DIMM2_FRU_1   RFU1 @S9S_MB_2U_LIB.S9S_MB_2U(SCH_1):TP_CHF_CPU0_DIMM2_FRU_1
 149 TP_CHF_CPU0_DIMM2_FRU_2   RFU2 @S9S_MB_2U_LIB.S9S_MB_2U(SCH_1):TP_CHF_CPU0_DIMM2_FRU_2
 150 TP_CHF_CPU0_DIMM2_FRU_3   RFU3 @S9S_MB_2U_LIB.S9S_MB_2U(SCH_1):TP_CHF_CPU0_DIMM2_FRU_3
 220 TP_CHF_CPU0_DIMM2_FRU_4   RFU4 @S9S_MB_2U_LIB.S9S_MB_2U(SCH_1):TP_CHF_CPU0_DIMM2_FRU_4
 231 TP_CHF_CPU0_DIMM2_FRU_5   RFU5 @S9S_MB_2U_LIB.S9S_MB_2U(SCH_1):TP_CHF_CPU0_DIMM2_FRU_5
 232 TP_CHF_CPU0_DIMM2_FRU_6   RFU6 @S9S_MB_2U_LIB.S9S_MB_2U(SCH_1):TP_CHF_CPU0_DIMM2_FRU_6
 207 RST_M_EF_CPU0_FPGA_N RESET_N @S9S_MB_2U_LIB.S9S_MB_2U(SCH_1):RST_M_EF_CPU0_FPGA_N
 147 PWRGD_CHF_CPU0_DIMM2 PWR_GOOD||FAIL_N @S9S_MB_2U_LIB.S9S_MB_2U(SCH_1):PWRGD_CHF_CPU0_DIMM2
 227 M_F_CPU0_SB_PAR  PAR_B @S9S_MB_2U_LIB.S9S_MB_2U(SCH_1):M_F_CPU0_SB_PAR
  74 M_F_CPU0_SA_PAR  PAR_A @S9S_MB_2U_LIB.S9S_MB_2U(SCH_1):M_F_CPU0_SA_PAR
  87 M_F_CPU0_SB_RSP<1> LBS||RSP_B_N @S9S_MB_2U_LIB.S9S_MB_2U(SCH_1):M_F_CPU0_SB_RSP(1)
  86 M_F_CPU0_SA_RSP<1> LBD||RSP_A_N @S9S_MB_2U_LIB.S9S_MB_2U(SCH_1):M_F_CPU0_SA_RSP(1)
   5 I3C_SPD_DDREFGH_CPU0_LVC1_SDA   HSDA @S9S_MB_2U_LIB.S9S_MB_2U(SCH_1):I3C_SPD_DDREFGH_CPU0_LVC1_SDA
   4 I3C_SPD_DDREFGH_CPU0_LVC1_SCL_3   HSCL @S9S_MB_2U_LIB.S9S_MB_2U(SCH_1):I3C_SPD_DDREFGH_CPU0_LVC1_SCL_R4
 148 PD_CHF_CPU0_DIMM2_SAA    HSA @S9S_MB_2U_LIB.S9S_MB_2U(SCH_1):PD_CHF_CPU0_DIMM2_SAA
 100 M_F_CPU0_SB_DQ<0>  DQ0_B @S9S_MB_2U_LIB.S9S_MB_2U(SCH_1):M_F_CPU0_SB_DQ(0)
 102 M_F_CPU0_SB_DQ<1>  DQ1_B @S9S_MB_2U_LIB.S9S_MB_2U(SCH_1):M_F_CPU0_SB_DQ(1)
 245 M_F_CPU0_SB_DQ<2>  DQ2_B @S9S_MB_2U_LIB.S9S_MB_2U(SCH_1):M_F_CPU0_SB_DQ(2)
 247 M_F_CPU0_SB_DQ<3>  DQ3_B @S9S_MB_2U_LIB.S9S_MB_2U(SCH_1):M_F_CPU0_SB_DQ(3)
 107 M_F_CPU0_SB_DQ<4>  DQ4_B @S9S_MB_2U_LIB.S9S_MB_2U(SCH_1):M_F_CPU0_SB_DQ(4)
 109 M_F_CPU0_SB_DQ<5>  DQ5_B @S9S_MB_2U_LIB.S9S_MB_2U(SCH_1):M_F_CPU0_SB_DQ(5)
 252 M_F_CPU0_SB_DQ<6>  DQ6_B @S9S_MB_2U_LIB.S9S_MB_2U(SCH_1):M_F_CPU0_SB_DQ(6)
 254 M_F_CPU0_SB_DQ<7>  DQ7_B @S9S_MB_2U_LIB.S9S_MB_2U(SCH_1):M_F_CPU0_SB_DQ(7)
 111 M_F_CPU0_SB_DQ<8>  DQ8_B @S9S_MB_2U_LIB.S9S_MB_2U(SCH_1):M_F_CPU0_SB_DQ(8)
 113 M_F_CPU0_SB_DQ<9>  DQ9_B @S9S_MB_2U_LIB.S9S_MB_2U(SCH_1):M_F_CPU0_SB_DQ(9)
 256 M_F_CPU0_SB_DQ<10> DQ10_B @S9S_MB_2U_LIB.S9S_MB_2U(SCH_1):M_F_CPU0_SB_DQ(10)
 258 M_F_CPU0_SB_DQ<11> DQ11_B @S9S_MB_2U_LIB.S9S_MB_2U(SCH_1):M_F_CPU0_SB_DQ(11)
 118 M_F_CPU0_SB_DQ<12> DQ12_B @S9S_MB_2U_LIB.S9S_MB_2U(SCH_1):M_F_CPU0_SB_DQ(12)
 120 M_F_CPU0_SB_DQ<13> DQ13_B @S9S_MB_2U_LIB.S9S_MB_2U(SCH_1):M_F_CPU0_SB_DQ(13)
 263 M_F_CPU0_SB_DQ<14> DQ14_B @S9S_MB_2U_LIB.S9S_MB_2U(SCH_1):M_F_CPU0_SB_DQ(14)
 265 M_F_CPU0_SB_DQ<15> DQ15_B @S9S_MB_2U_LIB.S9S_MB_2U(SCH_1):M_F_CPU0_SB_DQ(15)
 122 M_F_CPU0_SB_DQ<16> DQ16_B @S9S_MB_2U_LIB.S9S_MB_2U(SCH_1):M_F_CPU0_SB_DQ(16)
 124 M_F_CPU0_SB_DQ<17> DQ17_B @S9S_MB_2U_LIB.S9S_MB_2U(SCH_1):M_F_CPU0_SB_DQ(17)
 267 M_F_CPU0_SB_DQ<18> DQ18_B @S9S_MB_2U_LIB.S9S_MB_2U(SCH_1):M_F_CPU0_SB_DQ(18)
 269 M_F_CPU0_SB_DQ<19> DQ19_B @S9S_MB_2U_LIB.S9S_MB_2U(SCH_1):M_F_CPU0_SB_DQ(19)
 129 M_F_CPU0_SB_DQ<20> DQ20_B @S9S_MB_2U_LIB.S9S_MB_2U(SCH_1):M_F_CPU0_SB_DQ(20)
 131 M_F_CPU0_SB_DQ<21> DQ21_B @S9S_MB_2U_LIB.S9S_MB_2U(SCH_1):M_F_CPU0_SB_DQ(21)
 274 M_F_CPU0_SB_DQ<22> DQ22_B @S9S_MB_2U_LIB.S9S_MB_2U(SCH_1):M_F_CPU0_SB_DQ(22)
 276 M_F_CPU0_SB_DQ<23> DQ23_B @S9S_MB_2U_LIB.S9S_MB_2U(SCH_1):M_F_CPU0_SB_DQ(23)
 133 M_F_CPU0_SB_DQ<24> DQ24_B @S9S_MB_2U_LIB.S9S_MB_2U(SCH_1):M_F_CPU0_SB_DQ(24)
 135 M_F_CPU0_SB_DQ<25> DQ25_B @S9S_MB_2U_LIB.S9S_MB_2U(SCH_1):M_F_CPU0_SB_DQ(25)
 278 M_F_CPU0_SB_DQ<26> DQ26_B @S9S_MB_2U_LIB.S9S_MB_2U(SCH_1):M_F_CPU0_SB_DQ(26)
 280 M_F_CPU0_SB_DQ<27> DQ27_B @S9S_MB_2U_LIB.S9S_MB_2U(SCH_1):M_F_CPU0_SB_DQ(27)
 140 M_F_CPU0_SB_DQ<28> DQ28_B @S9S_MB_2U_LIB.S9S_MB_2U(SCH_1):M_F_CPU0_SB_DQ(28)
 142 M_F_CPU0_SB_DQ<29> DQ29_B @S9S_MB_2U_LIB.S9S_MB_2U(SCH_1):M_F_CPU0_SB_DQ(29)
 285 M_F_CPU0_SB_DQ<30> DQ30_B @S9S_MB_2U_LIB.S9S_MB_2U(SCH_1):M_F_CPU0_SB_DQ(30)
 287 M_F_CPU0_SB_DQ<31> DQ31_B @S9S_MB_2U_LIB.S9S_MB_2U(SCH_1):M_F_CPU0_SB_DQ(31)
   7 M_F_CPU0_SA_DQ<0>  DQ0_A @S9S_MB_2U_LIB.S9S_MB_2U(SCH_1):M_F_CPU0_SA_DQ(0)
   9 M_F_CPU0_SA_DQ<1>  DQ1_A @S9S_MB_2U_LIB.S9S_MB_2U(SCH_1):M_F_CPU0_SA_DQ(1)
 152 M_F_CPU0_SA_DQ<2>  DQ2_A @S9S_MB_2U_LIB.S9S_MB_2U(SCH_1):M_F_CPU0_SA_DQ(2)
 154 M_F_CPU0_SA_DQ<3>  DQ3_A @S9S_MB_2U_LIB.S9S_MB_2U(SCH_1):M_F_CPU0_SA_DQ(3)
  14 M_F_CPU0_SA_DQ<4>  DQ4_A @S9S_MB_2U_LIB.S9S_MB_2U(SCH_1):M_F_CPU0_SA_DQ(4)
  16 M_F_CPU0_SA_DQ<5>  DQ5_A @S9S_MB_2U_LIB.S9S_MB_2U(SCH_1):M_F_CPU0_SA_DQ(5)
 159 M_F_CPU0_SA_DQ<6>  DQ6_A @S9S_MB_2U_LIB.S9S_MB_2U(SCH_1):M_F_CPU0_SA_DQ(6)
 161 M_F_CPU0_SA_DQ<7>  DQ7_A @S9S_MB_2U_LIB.S9S_MB_2U(SCH_1):M_F_CPU0_SA_DQ(7)
  18 M_F_CPU0_SA_DQ<8>  DQ8_A @S9S_MB_2U_LIB.S9S_MB_2U(SCH_1):M_F_CPU0_SA_DQ(8)
  20 M_F_CPU0_SA_DQ<9>  DQ9_A @S9S_MB_2U_LIB.S9S_MB_2U(SCH_1):M_F_CPU0_SA_DQ(9)
 163 M_F_CPU0_SA_DQ<10> DQ10_A @S9S_MB_2U_LIB.S9S_MB_2U(SCH_1):M_F_CPU0_SA_DQ(10)
 165 M_F_CPU0_SA_DQ<11> DQ11_A @S9S_MB_2U_LIB.S9S_MB_2U(SCH_1):M_F_CPU0_SA_DQ(11)
  25 M_F_CPU0_SA_DQ<12> DQ12_A @S9S_MB_2U_LIB.S9S_MB_2U(SCH_1):M_F_CPU0_SA_DQ(12)
  27 M_F_CPU0_SA_DQ<13> DQ13_A @S9S_MB_2U_LIB.S9S_MB_2U(SCH_1):M_F_CPU0_SA_DQ(13)
 170 M_F_CPU0_SA_DQ<14> DQ14_A @S9S_MB_2U_LIB.S9S_MB_2U(SCH_1):M_F_CPU0_SA_DQ(14)
 172 M_F_CPU0_SA_DQ<15> DQ15_A @S9S_MB_2U_LIB.S9S_MB_2U(SCH_1):M_F_CPU0_SA_DQ(15)
  29 M_F_CPU0_SA_DQ<16> DQ16_A @S9S_MB_2U_LIB.S9S_MB_2U(SCH_1):M_F_CPU0_SA_DQ(16)
  31 M_F_CPU0_SA_DQ<17> DQ17_A @S9S_MB_2U_LIB.S9S_MB_2U(SCH_1):M_F_CPU0_SA_DQ(17)
 174 M_F_CPU0_SA_DQ<18> DQ18_A @S9S_MB_2U_LIB.S9S_MB_2U(SCH_1):M_F_CPU0_SA_DQ(18)
 176 M_F_CPU0_SA_DQ<19> DQ19_A @S9S_MB_2U_LIB.S9S_MB_2U(SCH_1):M_F_CPU0_SA_DQ(19)
  36 M_F_CPU0_SA_DQ<20> DQ20_A @S9S_MB_2U_LIB.S9S_MB_2U(SCH_1):M_F_CPU0_SA_DQ(20)
  38 M_F_CPU0_SA_DQ<21> DQ21_A @S9S_MB_2U_LIB.S9S_MB_2U(SCH_1):M_F_CPU0_SA_DQ(21)
 181 M_F_CPU0_SA_DQ<22> DQ22_A @S9S_MB_2U_LIB.S9S_MB_2U(SCH_1):M_F_CPU0_SA_DQ(22)
 183 M_F_CPU0_SA_DQ<23> DQ23_A @S9S_MB_2U_LIB.S9S_MB_2U(SCH_1):M_F_CPU0_SA_DQ(23)
  40 M_F_CPU0_SA_DQ<24> DQ24_A @S9S_MB_2U_LIB.S9S_MB_2U(SCH_1):M_F_CPU0_SA_DQ(24)
  42 M_F_CPU0_SA_DQ<25> DQ25_A @S9S_MB_2U_LIB.S9S_MB_2U(SCH_1):M_F_CPU0_SA_DQ(25)
 185 M_F_CPU0_SA_DQ<26> DQ26_A @S9S_MB_2U_LIB.S9S_MB_2U(SCH_1):M_F_CPU0_SA_DQ(26)
 187 M_F_CPU0_SA_DQ<27> DQ27_A @S9S_MB_2U_LIB.S9S_MB_2U(SCH_1):M_F_CPU0_SA_DQ(27)
  47 M_F_CPU0_SA_DQ<28> DQ28_A @S9S_MB_2U_LIB.S9S_MB_2U(SCH_1):M_F_CPU0_SA_DQ(28)
  49 M_F_CPU0_SA_DQ<29> DQ29_A @S9S_MB_2U_LIB.S9S_MB_2U(SCH_1):M_F_CPU0_SA_DQ(29)
 192 M_F_CPU0_SA_DQ<30> DQ30_A @S9S_MB_2U_LIB.S9S_MB_2U(SCH_1):M_F_CPU0_SA_DQ(30)
 229 M_F_CPU0_SB_CS_N<3> CS1_B_N @S9S_MB_2U_LIB.S9S_MB_2U(SCH_1):M_F_CPU0_SB_CS_N(3)
 209 M_F_CPU0_SA_CS_N<3> CS1_A_N @S9S_MB_2U_LIB.S9S_MB_2U(SCH_1):M_F_CPU0_SA_CS_N(3)
  84 M_F_CPU0_SB_CS_N<2> CS0_B_N @S9S_MB_2U_LIB.S9S_MB_2U(SCH_1):M_F_CPU0_SB_CS_N(2)
  64 M_F_CPU0_SA_CS_N<2> CS0_A_N @S9S_MB_2U_LIB.S9S_MB_2U(SCH_1):M_F_CPU0_SA_CS_N(2)
 217 M_F_CPU0_CLK_DP<1>   CK_T @S9S_MB_2U_LIB.S9S_MB_2U(SCH_1):M_F_CPU0_CLK_DP(1)
 218 M_F_CPU0_CLK_DN<1>   CK_C @S9S_MB_2U_LIB.S9S_MB_2U(SCH_1):M_F_CPU0_CLK_DN(1)
  96 M_F_CPU0_SB_CB<0>  CB0_B @S9S_MB_2U_LIB.S9S_MB_2U(SCH_1):M_F_CPU0_SB_CB(0)
  98 M_F_CPU0_SB_CB<1>  CB1_B @S9S_MB_2U_LIB.S9S_MB_2U(SCH_1):M_F_CPU0_SB_CB(1)
 241 M_F_CPU0_SB_CB<2>  CB2_B @S9S_MB_2U_LIB.S9S_MB_2U(SCH_1):M_F_CPU0_SB_CB(2)
 243 M_F_CPU0_SB_CB<3>  CB3_B @S9S_MB_2U_LIB.S9S_MB_2U(SCH_1):M_F_CPU0_SB_CB(3)
  89 M_F_CPU0_SB_CB<4>  CB4_B @S9S_MB_2U_LIB.S9S_MB_2U(SCH_1):M_F_CPU0_SB_CB(4)
  91 M_F_CPU0_SB_CB<5>  CB5_B @S9S_MB_2U_LIB.S9S_MB_2U(SCH_1):M_F_CPU0_SB_CB(5)
 234 M_F_CPU0_SB_CB<6>  CB6_B @S9S_MB_2U_LIB.S9S_MB_2U(SCH_1):M_F_CPU0_SB_CB(6)
  51 M_F_CPU0_SA_CB<0>  CB0_A @S9S_MB_2U_LIB.S9S_MB_2U(SCH_1):M_F_CPU0_SA_CB(0)
 196 M_F_CPU0_SA_CB<2>  CB2_A @S9S_MB_2U_LIB.S9S_MB_2U(SCH_1):M_F_CPU0_SA_CB(2)
 198 M_F_CPU0_SA_CB<3>  CB3_A @S9S_MB_2U_LIB.S9S_MB_2U(SCH_1):M_F_CPU0_SA_CB(3)
  60 M_F_CPU0_SA_CB<5>  CB5_A @S9S_MB_2U_LIB.S9S_MB_2U(SCH_1):M_F_CPU0_SA_CB(5)
 203 M_F_CPU0_SA_CB<6>  CB6_A @S9S_MB_2U_LIB.S9S_MB_2U(SCH_1):M_F_CPU0_SA_CB(6)
  82 M_F_CPU0_SB_CA<6>  CA6_B @S9S_MB_2U_LIB.S9S_MB_2U(SCH_1):M_F_CPU0_SB_CA(6)
  72 M_F_CPU0_SA_CA<6>  CA6_A @S9S_MB_2U_LIB.S9S_MB_2U(SCH_1):M_F_CPU0_SA_CA(6)
 225 M_F_CPU0_SB_CA<5>  CA5_B @S9S_MB_2U_LIB.S9S_MB_2U(SCH_1):M_F_CPU0_SB_CA(5)
 215 M_F_CPU0_SA_CA<5>  CA5_A @S9S_MB_2U_LIB.S9S_MB_2U(SCH_1):M_F_CPU0_SA_CA(5)
  80 M_F_CPU0_SB_CA<4>  CA4_B @S9S_MB_2U_LIB.S9S_MB_2U(SCH_1):M_F_CPU0_SB_CA(4)
  70 M_F_CPU0_SA_CA<4>  CA4_A @S9S_MB_2U_LIB.S9S_MB_2U(SCH_1):M_F_CPU0_SA_CA(4)
 223 M_F_CPU0_SB_CA<3>  CA3_B @S9S_MB_2U_LIB.S9S_MB_2U(SCH_1):M_F_CPU0_SB_CA(3)
 213 M_F_CPU0_SA_CA<3>  CA3_A @S9S_MB_2U_LIB.S9S_MB_2U(SCH_1):M_F_CPU0_SA_CA(3)
  78 M_F_CPU0_SB_CA<2>  CA2_B @S9S_MB_2U_LIB.S9S_MB_2U(SCH_1):M_F_CPU0_SB_CA(2)
  68 M_F_CPU0_SA_CA<2>  CA2_A @S9S_MB_2U_LIB.S9S_MB_2U(SCH_1):M_F_CPU0_SA_CA(2)
 221 M_F_CPU0_SB_CA<1>  CA1_B @S9S_MB_2U_LIB.S9S_MB_2U(SCH_1):M_F_CPU0_SB_CA(1)
 211 M_F_CPU0_SA_CA<1>  CA1_A @S9S_MB_2U_LIB.S9S_MB_2U(SCH_1):M_F_CPU0_SA_CA(1)
  76 M_F_CPU0_SB_CA<0>  CA0_B @S9S_MB_2U_LIB.S9S_MB_2U(SCH_1):M_F_CPU0_SB_CA(0)
  66 M_F_CPU0_SA_CA<0>  CA0_A @S9S_MB_2U_LIB.S9S_MB_2U(SCH_1):M_F_CPU0_SA_CA(0)
  62 M_F_CPU0_ALERT_N ALERT_N @S9S_MB_2U_LIB.S9S_MB_2U(SCH_1):M_F_CPU0_ALERT_N
 236 M_F_CPU0_SB_CB<7>  CB7_B @S9S_MB_2U_LIB.S9S_MB_2U(SCH_1):M_F_CPU0_SB_CB(7)
  53 M_F_CPU0_SA_CB<1>  CB1_A @S9S_MB_2U_LIB.S9S_MB_2U(SCH_1):M_F_CPU0_SA_CB(1)
  58 M_F_CPU0_SA_CB<4>  CB4_A @S9S_MB_2U_LIB.S9S_MB_2U(SCH_1):M_F_CPU0_SA_CB(4)
 205 M_F_CPU0_SA_CB<7>  CB7_A @S9S_MB_2U_LIB.S9S_MB_2U(SCH_1):M_F_CPU0_SA_CB(7)
 194 M_F_CPU0_SA_DQ<31> DQ31_A @S9S_MB_2U_LIB.S9S_MB_2U(SCH_1):M_F_CPU0_SA_DQ(31)

Q_CAP_C0402-2.2UF,6.3V,20%,X6SA  I122  C35
   1 P3V3_AUX      A @S9S_MB_2U_LIB.S9S_MB_2U(SCH_1):P3V3_AUX
   2    GND      B @S9S_MB_2U_LIB.S9S_MB_2U(SCH_1):GND

Q_CAP_C0805-10UF,16V,10%,X6S,CA  I126  C36
   1 P12V_S3_AUX_CPU0_NVDIMM      A @S9S_MB_2U_LIB.S9S_MB_2U(SCH_1):P12V_S3_AUX_CPU0_NVDIMM
   2    GND      B @S9S_MB_2U_LIB.S9S_MB_2U(SCH_1):GND

Q_CAP_C0805-10UF,16V,10%,X6S,CA  I128  C37
   1 P12V_S3_AUX_CPU0_NVDIMM      A @S9S_MB_2U_LIB.S9S_MB_2U(SCH_1):P12V_S3_AUX_CPU0_NVDIMM
   2    GND      B @S9S_MB_2U_LIB.S9S_MB_2U(SCH_1):GND

SCONN288_ADR50017P087CC-SCONN2A  I175  J12
   6    GND   VSS0 @S9S_MB_2U_LIB.S9S_MB_2U(SCH_1):GND
   8    GND   VSS1 @S9S_MB_2U_LIB.S9S_MB_2U(SCH_1):GND
  10    GND   VSS2 @S9S_MB_2U_LIB.S9S_MB_2U(SCH_1):GND
  13    GND   VSS3 @S9S_MB_2U_LIB.S9S_MB_2U(SCH_1):GND
  15    GND   VSS4 @S9S_MB_2U_LIB.S9S_MB_2U(SCH_1):GND
  17    GND   VSS5 @S9S_MB_2U_LIB.S9S_MB_2U(SCH_1):GND
  19    GND   VSS6 @S9S_MB_2U_LIB.S9S_MB_2U(SCH_1):GND
  21    GND   VSS7 @S9S_MB_2U_LIB.S9S_MB_2U(SCH_1):GND
  24    GND   VSS8 @S9S_MB_2U_LIB.S9S_MB_2U(SCH_1):GND
  26    GND   VSS9 @S9S_MB_2U_LIB.S9S_MB_2U(SCH_1):GND
  28    GND  VSS10 @S9S_MB_2U_LIB.S9S_MB_2U(SCH_1):GND
  30    GND  VSS11 @S9S_MB_2U_LIB.S9S_MB_2U(SCH_1):GND
  32    GND  VSS12 @S9S_MB_2U_LIB.S9S_MB_2U(SCH_1):GND
  35    GND  VSS13 @S9S_MB_2U_LIB.S9S_MB_2U(SCH_1):GND
  37    GND  VSS14 @S9S_MB_2U_LIB.S9S_MB_2U(SCH_1):GND
  39    GND  VSS15 @S9S_MB_2U_LIB.S9S_MB_2U(SCH_1):GND
  41    GND  VSS16 @S9S_MB_2U_LIB.S9S_MB_2U(SCH_1):GND
  43    GND  VSS17 @S9S_MB_2U_LIB.S9S_MB_2U(SCH_1):GND
  46    GND  VSS18 @S9S_MB_2U_LIB.S9S_MB_2U(SCH_1):GND
  48    GND  VSS19 @S9S_MB_2U_LIB.S9S_MB_2U(SCH_1):GND
  50    GND  VSS20 @S9S_MB_2U_LIB.S9S_MB_2U(SCH_1):GND
  52    GND  VSS21 @S9S_MB_2U_LIB.S9S_MB_2U(SCH_1):GND
  54    GND  VSS22 @S9S_MB_2U_LIB.S9S_MB_2U(SCH_1):GND
  57    GND  VSS23 @S9S_MB_2U_LIB.S9S_MB_2U(SCH_1):GND
  59    GND  VSS24 @S9S_MB_2U_LIB.S9S_MB_2U(SCH_1):GND
  61    GND  VSS25 @S9S_MB_2U_LIB.S9S_MB_2U(SCH_1):GND
  63    GND  VSS26 @S9S_MB_2U_LIB.S9S_MB_2U(SCH_1):GND
  65    GND  VSS27 @S9S_MB_2U_LIB.S9S_MB_2U(SCH_1):GND
  67    GND  VSS28 @S9S_MB_2U_LIB.S9S_MB_2U(SCH_1):GND
  69    GND  VSS29 @S9S_MB_2U_LIB.S9S_MB_2U(SCH_1):GND
  71    GND  VSS30 @S9S_MB_2U_LIB.S9S_MB_2U(SCH_1):GND
  73    GND  VSS31 @S9S_MB_2U_LIB.S9S_MB_2U(SCH_1):GND
  75    GND  VSS32 @S9S_MB_2U_LIB.S9S_MB_2U(SCH_1):GND
  77    GND  VSS33 @S9S_MB_2U_LIB.S9S_MB_2U(SCH_1):GND
  79    GND  VSS34 @S9S_MB_2U_LIB.S9S_MB_2U(SCH_1):GND
  81    GND  VSS35 @S9S_MB_2U_LIB.S9S_MB_2U(SCH_1):GND
  83    GND  VSS36 @S9S_MB_2U_LIB.S9S_MB_2U(SCH_1):GND
  85    GND  VSS37 @S9S_MB_2U_LIB.S9S_MB_2U(SCH_1):GND
  88    GND  VSS38 @S9S_MB_2U_LIB.S9S_MB_2U(SCH_1):GND
  90    GND  VSS39 @S9S_MB_2U_LIB.S9S_MB_2U(SCH_1):GND
  92    GND  VSS40 @S9S_MB_2U_LIB.S9S_MB_2U(SCH_1):GND
  95    GND  VSS41 @S9S_MB_2U_LIB.S9S_MB_2U(SCH_1):GND
  97    GND  VSS42 @S9S_MB_2U_LIB.S9S_MB_2U(SCH_1):GND
  99    GND  VSS43 @S9S_MB_2U_LIB.S9S_MB_2U(SCH_1):GND
 101    GND  VSS44 @S9S_MB_2U_LIB.S9S_MB_2U(SCH_1):GND
 103    GND  VSS45 @S9S_MB_2U_LIB.S9S_MB_2U(SCH_1):GND
 106    GND  VSS46 @S9S_MB_2U_LIB.S9S_MB_2U(SCH_1):GND
 108    GND  VSS47 @S9S_MB_2U_LIB.S9S_MB_2U(SCH_1):GND
 110    GND  VSS48 @S9S_MB_2U_LIB.S9S_MB_2U(SCH_1):GND
 112    GND  VSS49 @S9S_MB_2U_LIB.S9S_MB_2U(SCH_1):GND
 114    GND  VSS50 @S9S_MB_2U_LIB.S9S_MB_2U(SCH_1):GND
 117    GND  VSS51 @S9S_MB_2U_LIB.S9S_MB_2U(SCH_1):GND
 119    GND  VSS52 @S9S_MB_2U_LIB.S9S_MB_2U(SCH_1):GND
 121    GND  VSS53 @S9S_MB_2U_LIB.S9S_MB_2U(SCH_1):GND
 123    GND  VSS54 @S9S_MB_2U_LIB.S9S_MB_2U(SCH_1):GND
 125    GND  VSS55 @S9S_MB_2U_LIB.S9S_MB_2U(SCH_1):GND
 128    GND  VSS56 @S9S_MB_2U_LIB.S9S_MB_2U(SCH_1):GND
 130    GND  VSS57 @S9S_MB_2U_LIB.S9S_MB_2U(SCH_1):GND
 134    GND  VSS59 @S9S_MB_2U_LIB.S9S_MB_2U(SCH_1):GND
 143    GND  VSS63 @S9S_MB_2U_LIB.S9S_MB_2U(SCH_1):GND
 151    GND  VSS64 @S9S_MB_2U_LIB.S9S_MB_2U(SCH_1):GND
 153    GND  VSS65 @S9S_MB_2U_LIB.S9S_MB_2U(SCH_1):GND
 155    GND  VSS66 @S9S_MB_2U_LIB.S9S_MB_2U(SCH_1):GND
 158    GND  VSS67 @S9S_MB_2U_LIB.S9S_MB_2U(SCH_1):GND
 160    GND  VSS68 @S9S_MB_2U_LIB.S9S_MB_2U(SCH_1):GND
 162    GND  VSS69 @S9S_MB_2U_LIB.S9S_MB_2U(SCH_1):GND
 164    GND  VSS70 @S9S_MB_2U_LIB.S9S_MB_2U(SCH_1):GND
 166    GND  VSS71 @S9S_MB_2U_LIB.S9S_MB_2U(SCH_1):GND
 169    GND  VSS72 @S9S_MB_2U_LIB.S9S_MB_2U(SCH_1):GND
 171    GND  VSS73 @S9S_MB_2U_LIB.S9S_MB_2U(SCH_1):GND
 173    GND  VSS74 @S9S_MB_2U_LIB.S9S_MB_2U(SCH_1):GND
 175    GND  VSS75 @S9S_MB_2U_LIB.S9S_MB_2U(SCH_1):GND
 177    GND  VSS76 @S9S_MB_2U_LIB.S9S_MB_2U(SCH_1):GND
 180    GND  VSS77 @S9S_MB_2U_LIB.S9S_MB_2U(SCH_1):GND
 182    GND  VSS78 @S9S_MB_2U_LIB.S9S_MB_2U(SCH_1):GND
 184    GND  VSS79 @S9S_MB_2U_LIB.S9S_MB_2U(SCH_1):GND
 186    GND  VSS80 @S9S_MB_2U_LIB.S9S_MB_2U(SCH_1):GND
 188    GND  VSS81 @S9S_MB_2U_LIB.S9S_MB_2U(SCH_1):GND
 191    GND  VSS82 @S9S_MB_2U_LIB.S9S_MB_2U(SCH_1):GND
 193    GND  VSS83 @S9S_MB_2U_LIB.S9S_MB_2U(SCH_1):GND
 195    GND  VSS84 @S9S_MB_2U_LIB.S9S_MB_2U(SCH_1):GND
 197    GND  VSS85 @S9S_MB_2U_LIB.S9S_MB_2U(SCH_1):GND
 199    GND  VSS86 @S9S_MB_2U_LIB.S9S_MB_2U(SCH_1):GND
 202    GND  VSS87 @S9S_MB_2U_LIB.S9S_MB_2U(SCH_1):GND
 204    GND  VSS88 @S9S_MB_2U_LIB.S9S_MB_2U(SCH_1):GND
 206    GND  VSS89 @S9S_MB_2U_LIB.S9S_MB_2U(SCH_1):GND
 208    GND  VSS90 @S9S_MB_2U_LIB.S9S_MB_2U(SCH_1):GND
 210    GND  VSS91 @S9S_MB_2U_LIB.S9S_MB_2U(SCH_1):GND
 212    GND  VSS92 @S9S_MB_2U_LIB.S9S_MB_2U(SCH_1):GND
 214    GND  VSS93 @S9S_MB_2U_LIB.S9S_MB_2U(SCH_1):GND
 216    GND  VSS94 @S9S_MB_2U_LIB.S9S_MB_2U(SCH_1):GND
 219    GND  VSS95 @S9S_MB_2U_LIB.S9S_MB_2U(SCH_1):GND
 222    GND  VSS96 @S9S_MB_2U_LIB.S9S_MB_2U(SCH_1):GND
 224    GND  VSS97 @S9S_MB_2U_LIB.S9S_MB_2U(SCH_1):GND
 226    GND  VSS98 @S9S_MB_2U_LIB.S9S_MB_2U(SCH_1):GND
 228    GND  VSS99 @S9S_MB_2U_LIB.S9S_MB_2U(SCH_1):GND
 233    GND VSS101 @S9S_MB_2U_LIB.S9S_MB_2U(SCH_1):GND
 237    GND VSS103 @S9S_MB_2U_LIB.S9S_MB_2U(SCH_1):GND
 242    GND VSS105 @S9S_MB_2U_LIB.S9S_MB_2U(SCH_1):GND
 244    GND VSS106 @S9S_MB_2U_LIB.S9S_MB_2U(SCH_1):GND
 246    GND VSS107 @S9S_MB_2U_LIB.S9S_MB_2U(SCH_1):GND
 248    GND VSS108 @S9S_MB_2U_LIB.S9S_MB_2U(SCH_1):GND
 251    GND VSS109 @S9S_MB_2U_LIB.S9S_MB_2U(SCH_1):GND
 253    GND VSS110 @S9S_MB_2U_LIB.S9S_MB_2U(SCH_1):GND
 255    GND VSS111 @S9S_MB_2U_LIB.S9S_MB_2U(SCH_1):GND
 257    GND VSS112 @S9S_MB_2U_LIB.S9S_MB_2U(SCH_1):GND
 259    GND VSS113 @S9S_MB_2U_LIB.S9S_MB_2U(SCH_1):GND
 262    GND VSS114 @S9S_MB_2U_LIB.S9S_MB_2U(SCH_1):GND
 264    GND VSS115 @S9S_MB_2U_LIB.S9S_MB_2U(SCH_1):GND
 266    GND VSS116 @S9S_MB_2U_LIB.S9S_MB_2U(SCH_1):GND
 268    GND VSS117 @S9S_MB_2U_LIB.S9S_MB_2U(SCH_1):GND
 270    GND VSS118 @S9S_MB_2U_LIB.S9S_MB_2U(SCH_1):GND
 273    GND VSS119 @S9S_MB_2U_LIB.S9S_MB_2U(SCH_1):GND
 275    GND VSS120 @S9S_MB_2U_LIB.S9S_MB_2U(SCH_1):GND
 277    GND VSS121 @S9S_MB_2U_LIB.S9S_MB_2U(SCH_1):GND
 279    GND VSS122 @S9S_MB_2U_LIB.S9S_MB_2U(SCH_1):GND
 281    GND VSS123 @S9S_MB_2U_LIB.S9S_MB_2U(SCH_1):GND
 284    GND VSS124 @S9S_MB_2U_LIB.S9S_MB_2U(SCH_1):GND
 286    GND VSS125 @S9S_MB_2U_LIB.S9S_MB_2U(SCH_1):GND
 288    GND VSS126 @S9S_MB_2U_LIB.S9S_MB_2U(SCH_1):GND
   1 P12V_S3_AUX_CPU0_NVDIMM VIN_BULK0 @S9S_MB_2U_LIB.S9S_MB_2U(SCH_1):P12V_S3_AUX_CPU0_NVDIMM
 145 P12V_S3_AUX_CPU0_NVDIMM VIN_BULK1 @S9S_MB_2U_LIB.S9S_MB_2U(SCH_1):P12V_S3_AUX_CPU0_NVDIMM
 146 P12V_S3_AUX_CPU0_NVDIMM VIN_BULK2 @S9S_MB_2U_LIB.S9S_MB_2U(SCH_1):P12V_S3_AUX_CPU0_NVDIMM
 230    GND VSS100 @S9S_MB_2U_LIB.S9S_MB_2U(SCH_1):GND
 235    GND VSS102 @S9S_MB_2U_LIB.S9S_MB_2U(SCH_1):GND
 240    GND VSS104 @S9S_MB_2U_LIB.S9S_MB_2U(SCH_1):GND
 132    GND  VSS58 @S9S_MB_2U_LIB.S9S_MB_2U(SCH_1):GND
 136    GND  VSS60 @S9S_MB_2U_LIB.S9S_MB_2U(SCH_1):GND
 139    GND  VSS61 @S9S_MB_2U_LIB.S9S_MB_2U(SCH_1):GND
 141    GND  VSS62 @S9S_MB_2U_LIB.S9S_MB_2U(SCH_1):GND
  G1    GND     G1 @S9S_MB_2U_LIB.S9S_MB_2U(SCH_1):GND
  G2    GND     G2 @S9S_MB_2U_LIB.S9S_MB_2U(SCH_1):GND
  G3    GND     G3 @S9S_MB_2U_LIB.S9S_MB_2U(SCH_1):GND

SCONN288_ADR50017P087CC-SCONN2A  I178  J12
  93 M_F_CPU0_SB_DQS_DP<9> DQS9_B_T||TDQS9_B_T||DBI4_B_N @S9S_MB_2U_LIB.S9S_MB_2U(SCH_1):M_F_CPU0_SB_DQS_DP(9)
  94 M_F_CPU0_SB_DQS_DN<9> DQS9_B_C||TDQS9_B_C @S9S_MB_2U_LIB.S9S_MB_2U(SCH_1):M_F_CPU0_SB_DQS_DN(9)
 201 M_F_CPU0_SA_DQS_DP<9> DQS9_A_T||TDQS9_A_T @S9S_MB_2U_LIB.S9S_MB_2U(SCH_1):M_F_CPU0_SA_DQS_DP(9)
 200 M_F_CPU0_SA_DQS_DN<9> DQS9_A_C||TDQS9_A_C @S9S_MB_2U_LIB.S9S_MB_2U(SCH_1):M_F_CPU0_SA_DQS_DN(9)
 190 M_F_CPU0_SA_DQS_DP<8> DQS8_A_T||TDQS8_A_T @S9S_MB_2U_LIB.S9S_MB_2U(SCH_1):M_F_CPU0_SA_DQS_DP(8)
 189 M_F_CPU0_SA_DQS_DN<8> DQS8_A_C||TDQS8_A_C @S9S_MB_2U_LIB.S9S_MB_2U(SCH_1):M_F_CPU0_SA_DQS_DN(8)
 271 M_F_CPU0_SB_DQS_DN<7> DQS7_B_C||TDQS7_B_C @S9S_MB_2U_LIB.S9S_MB_2U(SCH_1):M_F_CPU0_SB_DQS_DN(7)
 179 M_F_CPU0_SA_DQS_DP<7> DQS7_A_T||TDQS7_A_T @S9S_MB_2U_LIB.S9S_MB_2U(SCH_1):M_F_CPU0_SA_DQS_DP(7)
 261 M_F_CPU0_SB_DQS_DP<6> DQS6_B_T||TDQS6_B_T @S9S_MB_2U_LIB.S9S_MB_2U(SCH_1):M_F_CPU0_SB_DQS_DP(6)
 260 M_F_CPU0_SB_DQS_DN<6> DQS6_B_C||TDQS6_B_C @S9S_MB_2U_LIB.S9S_MB_2U(SCH_1):M_F_CPU0_SB_DQS_DN(6)
 167 M_F_CPU0_SA_DQS_DN<6> DQS6_A_C||TDQS6_A_C||DQS6_A_T||TDQS6_A_T @S9S_MB_2U_LIB.S9S_MB_2U(SCH_1):M_F_CPU0_SA_DQS_DN(6)
 250 M_F_CPU0_SB_DQS_DP<5> DQS5_B_T||TDQS5_B_T @S9S_MB_2U_LIB.S9S_MB_2U(SCH_1):M_F_CPU0_SB_DQS_DP(5)
 249 M_F_CPU0_SB_DQS_DN<5> DQS5_B_C||TDQS5_B_C @S9S_MB_2U_LIB.S9S_MB_2U(SCH_1):M_F_CPU0_SB_DQS_DN(5)
 157 M_F_CPU0_SA_DQS_DP<5> DQS5_A_T||TDQS5_A_T @S9S_MB_2U_LIB.S9S_MB_2U(SCH_1):M_F_CPU0_SA_DQS_DP(5)
 156 M_F_CPU0_SA_DQS_DN<5> DQS5_A_C||TDQS5_A_C||DQS5_A_T||TDQS5_A_T @S9S_MB_2U_LIB.S9S_MB_2U(SCH_1):M_F_CPU0_SA_DQS_DN(5)
 239 M_F_CPU0_SB_DQS_DP<4> DQS4_B_T @S9S_MB_2U_LIB.S9S_MB_2U(SCH_1):M_F_CPU0_SB_DQS_DP(4)
 238 M_F_CPU0_SB_DQS_DN<4> DQS4_B_C @S9S_MB_2U_LIB.S9S_MB_2U(SCH_1):M_F_CPU0_SB_DQS_DN(4)
  55 M_F_CPU0_SA_DQS_DP<4> DQS4_A_T @S9S_MB_2U_LIB.S9S_MB_2U(SCH_1):M_F_CPU0_SA_DQS_DP(4)
  56 M_F_CPU0_SA_DQS_DN<4> DQS4_A_C @S9S_MB_2U_LIB.S9S_MB_2U(SCH_1):M_F_CPU0_SA_DQS_DN(4)
 137 M_F_CPU0_SB_DQS_DP<3> DQS3_B_T @S9S_MB_2U_LIB.S9S_MB_2U(SCH_1):M_F_CPU0_SB_DQS_DP(3)
 138 M_F_CPU0_SB_DQS_DN<3> DQS3_B_C @S9S_MB_2U_LIB.S9S_MB_2U(SCH_1):M_F_CPU0_SB_DQS_DN(3)
  44 M_F_CPU0_SA_DQS_DP<3> DQS3_A_T @S9S_MB_2U_LIB.S9S_MB_2U(SCH_1):M_F_CPU0_SA_DQS_DP(3)
  45 M_F_CPU0_SA_DQS_DN<3> DQS3_A_C @S9S_MB_2U_LIB.S9S_MB_2U(SCH_1):M_F_CPU0_SA_DQS_DN(3)
 126 M_F_CPU0_SB_DQS_DP<2> DQS2_B_T @S9S_MB_2U_LIB.S9S_MB_2U(SCH_1):M_F_CPU0_SB_DQS_DP(2)
 127 M_F_CPU0_SB_DQS_DN<2> DQS2_B_C @S9S_MB_2U_LIB.S9S_MB_2U(SCH_1):M_F_CPU0_SB_DQS_DN(2)
  33 M_F_CPU0_SA_DQS_DP<2> DQS2_A_T @S9S_MB_2U_LIB.S9S_MB_2U(SCH_1):M_F_CPU0_SA_DQS_DP(2)
  34 M_F_CPU0_SA_DQS_DN<2> DQS2_A_C @S9S_MB_2U_LIB.S9S_MB_2U(SCH_1):M_F_CPU0_SA_DQS_DN(2)
 115 M_F_CPU0_SB_DQS_DP<1> DQS1_B_T @S9S_MB_2U_LIB.S9S_MB_2U(SCH_1):M_F_CPU0_SB_DQS_DP(1)
 116 M_F_CPU0_SB_DQS_DN<1> DQS1_B_C @S9S_MB_2U_LIB.S9S_MB_2U(SCH_1):M_F_CPU0_SB_DQS_DN(1)
  22 M_F_CPU0_SA_DQS_DP<1> DQS1_A_T @S9S_MB_2U_LIB.S9S_MB_2U(SCH_1):M_F_CPU0_SA_DQS_DP(1)
  23 M_F_CPU0_SA_DQS_DN<1> DQS1_A_C @S9S_MB_2U_LIB.S9S_MB_2U(SCH_1):M_F_CPU0_SA_DQS_DN(1)
 104 M_F_CPU0_SB_DQS_DP<0> DQS0_B_T @S9S_MB_2U_LIB.S9S_MB_2U(SCH_1):M_F_CPU0_SB_DQS_DP(0)
 105 M_F_CPU0_SB_DQS_DN<0> DQS0_B_C @S9S_MB_2U_LIB.S9S_MB_2U(SCH_1):M_F_CPU0_SB_DQS_DN(0)
  11 M_F_CPU0_SA_DQS_DP<0> DQS0_A_T @S9S_MB_2U_LIB.S9S_MB_2U(SCH_1):M_F_CPU0_SA_DQS_DP(0)
  12 M_F_CPU0_SA_DQS_DN<0> DQS0_A_C @S9S_MB_2U_LIB.S9S_MB_2U(SCH_1):M_F_CPU0_SA_DQS_DN(0)
 272 M_F_CPU0_SB_DQS_DP<7> DQS7_B_T||TDQS7_B_T @S9S_MB_2U_LIB.S9S_MB_2U(SCH_1):M_F_CPU0_SB_DQS_DP(7)
 282 M_F_CPU0_SB_DQS_DN<8> DQS8_B_C||TDQS8_B_C @S9S_MB_2U_LIB.S9S_MB_2U(SCH_1):M_F_CPU0_SB_DQS_DN(8)
 283 M_F_CPU0_SB_DQS_DP<8> DQS8_B_T||TDQS8_B_T @S9S_MB_2U_LIB.S9S_MB_2U(SCH_1):M_F_CPU0_SB_DQS_DP(8)
 168 M_F_CPU0_SA_DQS_DP<6> DQS6_A_T||TDQS6_A_T @S9S_MB_2U_LIB.S9S_MB_2U(SCH_1):M_F_CPU0_SA_DQS_DP(6)
 178 M_F_CPU0_SA_DQS_DN<7> DQS7_A_C||TDQS7_A_C @S9S_MB_2U_LIB.S9S_MB_2U(SCH_1):M_F_CPU0_SA_DQS_DN(7)

Q_RES_0402LF-49.9,1%,1/16W,CHIA  I179  R3886
   1 I3C_SPD_DDREFGH_CPU0_LVC1_SCL_3      A @S9S_MB_2U_LIB.S9S_MB_2U(SCH_1):I3C_SPD_DDREFGH_CPU0_LVC1_SCL_R4
   2 I3C_SPD_DDREFGH_CPU0_LVC1_SCL      B @S9S_MB_2U_LIB.S9S_MB_2U(SCH_1):I3C_SPD_DDREFGH_CPU0_LVC1_SCL


DRAWING: @S9S_MB_2U_LIB.S9S_MB_2U(SCH_1):PAGE94 

Q_RES_0402LF-54.9K,1%,1/16W,CHA  I10  R38
   1 PD_CHG_CPU0_DIMM1_SAA      A @S9S_MB_2U_LIB.S9S_MB_2U(SCH_1):PD_CHG_CPU0_DIMM1_SAA
   2    GND      B @S9S_MB_2U_LIB.S9S_MB_2U(SCH_1):GND

SCONN288_ADR50017P130CC-SCONN2A  I11  J13
   3 P3V3_AUX VIN_MGMT @S9S_MB_2U_LIB.S9S_MB_2U(SCH_1):P3V3_AUX
   2 TP_CHG_CPU0_DIMM1_FRU_0   RFU0 @S9S_MB_2U_LIB.S9S_MB_2U(SCH_1):TP_CHG_CPU0_DIMM1_FRU_0
 144 TP_CHG_CPU0_DIMM1_FRU_1   RFU1 @S9S_MB_2U_LIB.S9S_MB_2U(SCH_1):TP_CHG_CPU0_DIMM1_FRU_1
 149 TP_CHG_CPU0_DIMM1_FRU_2   RFU2 @S9S_MB_2U_LIB.S9S_MB_2U(SCH_1):TP_CHG_CPU0_DIMM1_FRU_2
 150 TP_CHG_CPU0_DIMM1_FRU_3   RFU3 @S9S_MB_2U_LIB.S9S_MB_2U(SCH_1):TP_CHG_CPU0_DIMM1_FRU_3
 220 TP_CHG_CPU0_DIMM1_FRU_4   RFU4 @S9S_MB_2U_LIB.S9S_MB_2U(SCH_1):TP_CHG_CPU0_DIMM1_FRU_4
 231 TP_CHG_CPU0_DIMM1_FRU_5   RFU5 @S9S_MB_2U_LIB.S9S_MB_2U(SCH_1):TP_CHG_CPU0_DIMM1_FRU_5
 232 TP_CHG_CPU0_DIMM1_FRU_6   RFU6 @S9S_MB_2U_LIB.S9S_MB_2U(SCH_1):TP_CHG_CPU0_DIMM1_FRU_6
 207 RST_M_GH_CPU0_FPGA_N RESET_N @S9S_MB_2U_LIB.S9S_MB_2U(SCH_1):RST_M_GH_CPU0_FPGA_N
 147 PWRGD_CHG_CPU0_DIMM1 PWR_GOOD||FAIL_N @S9S_MB_2U_LIB.S9S_MB_2U(SCH_1):PWRGD_CHG_CPU0_DIMM1
 227 M_G_CPU0_SB_PAR  PAR_B @S9S_MB_2U_LIB.S9S_MB_2U(SCH_1):M_G_CPU0_SB_PAR
  74 M_G_CPU0_SA_PAR  PAR_A @S9S_MB_2U_LIB.S9S_MB_2U(SCH_1):M_G_CPU0_SA_PAR
  87 M_G_CPU0_SB_RSP<0> LBS||RSP_B_N @S9S_MB_2U_LIB.S9S_MB_2U(SCH_1):M_G_CPU0_SB_RSP(0)
  86 M_G_CPU0_SA_RSP<0> LBD||RSP_A_N @S9S_MB_2U_LIB.S9S_MB_2U(SCH_1):M_G_CPU0_SA_RSP(0)
   5 I3C_SPD_DDREFGH_CPU0_LVC1_SDA   HSDA @S9S_MB_2U_LIB.S9S_MB_2U(SCH_1):I3C_SPD_DDREFGH_CPU0_LVC1_SDA
   4 I3C_SPD_DDREFGH_CPU0_LVC1_SCL_4   HSCL @S9S_MB_2U_LIB.S9S_MB_2U(SCH_1):I3C_SPD_DDREFGH_CPU0_LVC1_SCL_R5
 148 PD_CHG_CPU0_DIMM1_SAA    HSA @S9S_MB_2U_LIB.S9S_MB_2U(SCH_1):PD_CHG_CPU0_DIMM1_SAA
 100 M_G_CPU0_SB_DQ<0>  DQ0_B @S9S_MB_2U_LIB.S9S_MB_2U(SCH_1):M_G_CPU0_SB_DQ(0)
 102 M_G_CPU0_SB_DQ<1>  DQ1_B @S9S_MB_2U_LIB.S9S_MB_2U(SCH_1):M_G_CPU0_SB_DQ(1)
 245 M_G_CPU0_SB_DQ<2>  DQ2_B @S9S_MB_2U_LIB.S9S_MB_2U(SCH_1):M_G_CPU0_SB_DQ(2)
 247 M_G_CPU0_SB_DQ<3>  DQ3_B @S9S_MB_2U_LIB.S9S_MB_2U(SCH_1):M_G_CPU0_SB_DQ(3)
 107 M_G_CPU0_SB_DQ<4>  DQ4_B @S9S_MB_2U_LIB.S9S_MB_2U(SCH_1):M_G_CPU0_SB_DQ(4)
 109 M_G_CPU0_SB_DQ<5>  DQ5_B @S9S_MB_2U_LIB.S9S_MB_2U(SCH_1):M_G_CPU0_SB_DQ(5)
 252 M_G_CPU0_SB_DQ<6>  DQ6_B @S9S_MB_2U_LIB.S9S_MB_2U(SCH_1):M_G_CPU0_SB_DQ(6)
 254 M_G_CPU0_SB_DQ<7>  DQ7_B @S9S_MB_2U_LIB.S9S_MB_2U(SCH_1):M_G_CPU0_SB_DQ(7)
 111 M_G_CPU0_SB_DQ<8>  DQ8_B @S9S_MB_2U_LIB.S9S_MB_2U(SCH_1):M_G_CPU0_SB_DQ(8)
 113 M_G_CPU0_SB_DQ<9>  DQ9_B @S9S_MB_2U_LIB.S9S_MB_2U(SCH_1):M_G_CPU0_SB_DQ(9)
 256 M_G_CPU0_SB_DQ<10> DQ10_B @S9S_MB_2U_LIB.S9S_MB_2U(SCH_1):M_G_CPU0_SB_DQ(10)
 258 M_G_CPU0_SB_DQ<11> DQ11_B @S9S_MB_2U_LIB.S9S_MB_2U(SCH_1):M_G_CPU0_SB_DQ(11)
 118 M_G_CPU0_SB_DQ<12> DQ12_B @S9S_MB_2U_LIB.S9S_MB_2U(SCH_1):M_G_CPU0_SB_DQ(12)
 120 M_G_CPU0_SB_DQ<13> DQ13_B @S9S_MB_2U_LIB.S9S_MB_2U(SCH_1):M_G_CPU0_SB_DQ(13)
 263 M_G_CPU0_SB_DQ<14> DQ14_B @S9S_MB_2U_LIB.S9S_MB_2U(SCH_1):M_G_CPU0_SB_DQ(14)
 265 M_G_CPU0_SB_DQ<15> DQ15_B @S9S_MB_2U_LIB.S9S_MB_2U(SCH_1):M_G_CPU0_SB_DQ(15)
 122 M_G_CPU0_SB_DQ<16> DQ16_B @S9S_MB_2U_LIB.S9S_MB_2U(SCH_1):M_G_CPU0_SB_DQ(16)
 124 M_G_CPU0_SB_DQ<17> DQ17_B @S9S_MB_2U_LIB.S9S_MB_2U(SCH_1):M_G_CPU0_SB_DQ(17)
 267 M_G_CPU0_SB_DQ<18> DQ18_B @S9S_MB_2U_LIB.S9S_MB_2U(SCH_1):M_G_CPU0_SB_DQ(18)
 269 M_G_CPU0_SB_DQ<19> DQ19_B @S9S_MB_2U_LIB.S9S_MB_2U(SCH_1):M_G_CPU0_SB_DQ(19)
 129 M_G_CPU0_SB_DQ<20> DQ20_B @S9S_MB_2U_LIB.S9S_MB_2U(SCH_1):M_G_CPU0_SB_DQ(20)
 131 M_G_CPU0_SB_DQ<21> DQ21_B @S9S_MB_2U_LIB.S9S_MB_2U(SCH_1):M_G_CPU0_SB_DQ(21)
 274 M_G_CPU0_SB_DQ<22> DQ22_B @S9S_MB_2U_LIB.S9S_MB_2U(SCH_1):M_G_CPU0_SB_DQ(22)
 276 M_G_CPU0_SB_DQ<23> DQ23_B @S9S_MB_2U_LIB.S9S_MB_2U(SCH_1):M_G_CPU0_SB_DQ(23)
 133 M_G_CPU0_SB_DQ<24> DQ24_B @S9S_MB_2U_LIB.S9S_MB_2U(SCH_1):M_G_CPU0_SB_DQ(24)
 135 M_G_CPU0_SB_DQ<25> DQ25_B @S9S_MB_2U_LIB.S9S_MB_2U(SCH_1):M_G_CPU0_SB_DQ(25)
 278 M_G_CPU0_SB_DQ<26> DQ26_B @S9S_MB_2U_LIB.S9S_MB_2U(SCH_1):M_G_CPU0_SB_DQ(26)
 280 M_G_CPU0_SB_DQ<27> DQ27_B @S9S_MB_2U_LIB.S9S_MB_2U(SCH_1):M_G_CPU0_SB_DQ(27)
 140 M_G_CPU0_SB_DQ<28> DQ28_B @S9S_MB_2U_LIB.S9S_MB_2U(SCH_1):M_G_CPU0_SB_DQ(28)
 142 M_G_CPU0_SB_DQ<29> DQ29_B @S9S_MB_2U_LIB.S9S_MB_2U(SCH_1):M_G_CPU0_SB_DQ(29)
 285 M_G_CPU0_SB_DQ<30> DQ30_B @S9S_MB_2U_LIB.S9S_MB_2U(SCH_1):M_G_CPU0_SB_DQ(30)
 287 M_G_CPU0_SB_DQ<31> DQ31_B @S9S_MB_2U_LIB.S9S_MB_2U(SCH_1):M_G_CPU0_SB_DQ(31)
   7 M_G_CPU0_SA_DQ<0>  DQ0_A @S9S_MB_2U_LIB.S9S_MB_2U(SCH_1):M_G_CPU0_SA_DQ(0)
   9 M_G_CPU0_SA_DQ<1>  DQ1_A @S9S_MB_2U_LIB.S9S_MB_2U(SCH_1):M_G_CPU0_SA_DQ(1)
 152 M_G_CPU0_SA_DQ<2>  DQ2_A @S9S_MB_2U_LIB.S9S_MB_2U(SCH_1):M_G_CPU0_SA_DQ(2)
 154 M_G_CPU0_SA_DQ<3>  DQ3_A @S9S_MB_2U_LIB.S9S_MB_2U(SCH_1):M_G_CPU0_SA_DQ(3)
  14 M_G_CPU0_SA_DQ<4>  DQ4_A @S9S_MB_2U_LIB.S9S_MB_2U(SCH_1):M_G_CPU0_SA_DQ(4)
  16 M_G_CPU0_SA_DQ<5>  DQ5_A @S9S_MB_2U_LIB.S9S_MB_2U(SCH_1):M_G_CPU0_SA_DQ(5)
 159 M_G_CPU0_SA_DQ<6>  DQ6_A @S9S_MB_2U_LIB.S9S_MB_2U(SCH_1):M_G_CPU0_SA_DQ(6)
 161 M_G_CPU0_SA_DQ<7>  DQ7_A @S9S_MB_2U_LIB.S9S_MB_2U(SCH_1):M_G_CPU0_SA_DQ(7)
  18 M_G_CPU0_SA_DQ<8>  DQ8_A @S9S_MB_2U_LIB.S9S_MB_2U(SCH_1):M_G_CPU0_SA_DQ(8)
  20 M_G_CPU0_SA_DQ<9>  DQ9_A @S9S_MB_2U_LIB.S9S_MB_2U(SCH_1):M_G_CPU0_SA_DQ(9)
 163 M_G_CPU0_SA_DQ<10> DQ10_A @S9S_MB_2U_LIB.S9S_MB_2U(SCH_1):M_G_CPU0_SA_DQ(10)
 165 M_G_CPU0_SA_DQ<11> DQ11_A @S9S_MB_2U_LIB.S9S_MB_2U(SCH_1):M_G_CPU0_SA_DQ(11)
  25 M_G_CPU0_SA_DQ<12> DQ12_A @S9S_MB_2U_LIB.S9S_MB_2U(SCH_1):M_G_CPU0_SA_DQ(12)
  27 M_G_CPU0_SA_DQ<13> DQ13_A @S9S_MB_2U_LIB.S9S_MB_2U(SCH_1):M_G_CPU0_SA_DQ(13)
 170 M_G_CPU0_SA_DQ<14> DQ14_A @S9S_MB_2U_LIB.S9S_MB_2U(SCH_1):M_G_CPU0_SA_DQ(14)
 172 M_G_CPU0_SA_DQ<15> DQ15_A @S9S_MB_2U_LIB.S9S_MB_2U(SCH_1):M_G_CPU0_SA_DQ(15)
  29 M_G_CPU0_SA_DQ<16> DQ16_A @S9S_MB_2U_LIB.S9S_MB_2U(SCH_1):M_G_CPU0_SA_DQ(16)
  31 M_G_CPU0_SA_DQ<17> DQ17_A @S9S_MB_2U_LIB.S9S_MB_2U(SCH_1):M_G_CPU0_SA_DQ(17)
 174 M_G_CPU0_SA_DQ<18> DQ18_A @S9S_MB_2U_LIB.S9S_MB_2U(SCH_1):M_G_CPU0_SA_DQ(18)
 176 M_G_CPU0_SA_DQ<19> DQ19_A @S9S_MB_2U_LIB.S9S_MB_2U(SCH_1):M_G_CPU0_SA_DQ(19)
  36 M_G_CPU0_SA_DQ<20> DQ20_A @S9S_MB_2U_LIB.S9S_MB_2U(SCH_1):M_G_CPU0_SA_DQ(20)
  38 M_G_CPU0_SA_DQ<21> DQ21_A @S9S_MB_2U_LIB.S9S_MB_2U(SCH_1):M_G_CPU0_SA_DQ(21)
 181 M_G_CPU0_SA_DQ<22> DQ22_A @S9S_MB_2U_LIB.S9S_MB_2U(SCH_1):M_G_CPU0_SA_DQ(22)
 183 M_G_CPU0_SA_DQ<23> DQ23_A @S9S_MB_2U_LIB.S9S_MB_2U(SCH_1):M_G_CPU0_SA_DQ(23)
  40 M_G_CPU0_SA_DQ<24> DQ24_A @S9S_MB_2U_LIB.S9S_MB_2U(SCH_1):M_G_CPU0_SA_DQ(24)
  42 M_G_CPU0_SA_DQ<25> DQ25_A @S9S_MB_2U_LIB.S9S_MB_2U(SCH_1):M_G_CPU0_SA_DQ(25)
 185 M_G_CPU0_SA_DQ<26> DQ26_A @S9S_MB_2U_LIB.S9S_MB_2U(SCH_1):M_G_CPU0_SA_DQ(26)
 187 M_G_CPU0_SA_DQ<27> DQ27_A @S9S_MB_2U_LIB.S9S_MB_2U(SCH_1):M_G_CPU0_SA_DQ(27)
  47 M_G_CPU0_SA_DQ<28> DQ28_A @S9S_MB_2U_LIB.S9S_MB_2U(SCH_1):M_G_CPU0_SA_DQ(28)
  49 M_G_CPU0_SA_DQ<29> DQ29_A @S9S_MB_2U_LIB.S9S_MB_2U(SCH_1):M_G_CPU0_SA_DQ(29)
 192 M_G_CPU0_SA_DQ<30> DQ30_A @S9S_MB_2U_LIB.S9S_MB_2U(SCH_1):M_G_CPU0_SA_DQ(30)
 229 M_G_CPU0_SB_CS_N<1> CS1_B_N @S9S_MB_2U_LIB.S9S_MB_2U(SCH_1):M_G_CPU0_SB_CS_N(1)
 209 M_G_CPU0_SA_CS_N<1> CS1_A_N @S9S_MB_2U_LIB.S9S_MB_2U(SCH_1):M_G_CPU0_SA_CS_N(1)
  84 M_G_CPU0_SB_CS_N<0> CS0_B_N @S9S_MB_2U_LIB.S9S_MB_2U(SCH_1):M_G_CPU0_SB_CS_N(0)
  64 M_G_CPU0_SA_CS_N<0> CS0_A_N @S9S_MB_2U_LIB.S9S_MB_2U(SCH_1):M_G_CPU0_SA_CS_N(0)
 217 M_G_CPU0_CLK_DP<0>   CK_T @S9S_MB_2U_LIB.S9S_MB_2U(SCH_1):M_G_CPU0_CLK_DP(0)
 218 M_G_CPU0_CLK_DN<0>   CK_C @S9S_MB_2U_LIB.S9S_MB_2U(SCH_1):M_G_CPU0_CLK_DN(0)
  96 M_G_CPU0_SB_CB<0>  CB0_B @S9S_MB_2U_LIB.S9S_MB_2U(SCH_1):M_G_CPU0_SB_CB(0)
  98 M_G_CPU0_SB_CB<1>  CB1_B @S9S_MB_2U_LIB.S9S_MB_2U(SCH_1):M_G_CPU0_SB_CB(1)
 241 M_G_CPU0_SB_CB<2>  CB2_B @S9S_MB_2U_LIB.S9S_MB_2U(SCH_1):M_G_CPU0_SB_CB(2)
 243 M_G_CPU0_SB_CB<3>  CB3_B @S9S_MB_2U_LIB.S9S_MB_2U(SCH_1):M_G_CPU0_SB_CB(3)
  89 M_G_CPU0_SB_CB<4>  CB4_B @S9S_MB_2U_LIB.S9S_MB_2U(SCH_1):M_G_CPU0_SB_CB(4)
  91 M_G_CPU0_SB_CB<5>  CB5_B @S9S_MB_2U_LIB.S9S_MB_2U(SCH_1):M_G_CPU0_SB_CB(5)
 234 M_G_CPU0_SB_CB<6>  CB6_B @S9S_MB_2U_LIB.S9S_MB_2U(SCH_1):M_G_CPU0_SB_CB(6)
  51 M_G_CPU0_SA_CB<0>  CB0_A @S9S_MB_2U_LIB.S9S_MB_2U(SCH_1):M_G_CPU0_SA_CB(0)
 196 M_G_CPU0_SA_CB<2>  CB2_A @S9S_MB_2U_LIB.S9S_MB_2U(SCH_1):M_G_CPU0_SA_CB(2)
 198 M_G_CPU0_SA_CB<3>  CB3_A @S9S_MB_2U_LIB.S9S_MB_2U(SCH_1):M_G_CPU0_SA_CB(3)
  60 M_G_CPU0_SA_CB<5>  CB5_A @S9S_MB_2U_LIB.S9S_MB_2U(SCH_1):M_G_CPU0_SA_CB(5)
 203 M_G_CPU0_SA_CB<6>  CB6_A @S9S_MB_2U_LIB.S9S_MB_2U(SCH_1):M_G_CPU0_SA_CB(6)
  82 M_G_CPU0_SB_CA<6>  CA6_B @S9S_MB_2U_LIB.S9S_MB_2U(SCH_1):M_G_CPU0_SB_CA(6)
  72 M_G_CPU0_SA_CA<6>  CA6_A @S9S_MB_2U_LIB.S9S_MB_2U(SCH_1):M_G_CPU0_SA_CA(6)
 225 M_G_CPU0_SB_CA<5>  CA5_B @S9S_MB_2U_LIB.S9S_MB_2U(SCH_1):M_G_CPU0_SB_CA(5)
 215 M_G_CPU0_SA_CA<5>  CA5_A @S9S_MB_2U_LIB.S9S_MB_2U(SCH_1):M_G_CPU0_SA_CA(5)
  80 M_G_CPU0_SB_CA<4>  CA4_B @S9S_MB_2U_LIB.S9S_MB_2U(SCH_1):M_G_CPU0_SB_CA(4)
  70 M_G_CPU0_SA_CA<4>  CA4_A @S9S_MB_2U_LIB.S9S_MB_2U(SCH_1):M_G_CPU0_SA_CA(4)
 223 M_G_CPU0_SB_CA<3>  CA3_B @S9S_MB_2U_LIB.S9S_MB_2U(SCH_1):M_G_CPU0_SB_CA(3)
 213 M_G_CPU0_SA_CA<3>  CA3_A @S9S_MB_2U_LIB.S9S_MB_2U(SCH_1):M_G_CPU0_SA_CA(3)
  78 M_G_CPU0_SB_CA<2>  CA2_B @S9S_MB_2U_LIB.S9S_MB_2U(SCH_1):M_G_CPU0_SB_CA(2)
  68 M_G_CPU0_SA_CA<2>  CA2_A @S9S_MB_2U_LIB.S9S_MB_2U(SCH_1):M_G_CPU0_SA_CA(2)
 221 M_G_CPU0_SB_CA<1>  CA1_B @S9S_MB_2U_LIB.S9S_MB_2U(SCH_1):M_G_CPU0_SB_CA(1)
 211 M_G_CPU0_SA_CA<1>  CA1_A @S9S_MB_2U_LIB.S9S_MB_2U(SCH_1):M_G_CPU0_SA_CA(1)
  76 M_G_CPU0_SB_CA<0>  CA0_B @S9S_MB_2U_LIB.S9S_MB_2U(SCH_1):M_G_CPU0_SB_CA(0)
  66 M_G_CPU0_SA_CA<0>  CA0_A @S9S_MB_2U_LIB.S9S_MB_2U(SCH_1):M_G_CPU0_SA_CA(0)
  62 M_G_CPU0_ALERT_N ALERT_N @S9S_MB_2U_LIB.S9S_MB_2U(SCH_1):M_G_CPU0_ALERT_N
 236 M_G_CPU0_SB_CB<7>  CB7_B @S9S_MB_2U_LIB.S9S_MB_2U(SCH_1):M_G_CPU0_SB_CB(7)
  53 M_G_CPU0_SA_CB<1>  CB1_A @S9S_MB_2U_LIB.S9S_MB_2U(SCH_1):M_G_CPU0_SA_CB(1)
  58 M_G_CPU0_SA_CB<4>  CB4_A @S9S_MB_2U_LIB.S9S_MB_2U(SCH_1):M_G_CPU0_SA_CB(4)
 205 M_G_CPU0_SA_CB<7>  CB7_A @S9S_MB_2U_LIB.S9S_MB_2U(SCH_1):M_G_CPU0_SA_CB(7)
 194 M_G_CPU0_SA_DQ<31> DQ31_A @S9S_MB_2U_LIB.S9S_MB_2U(SCH_1):M_G_CPU0_SA_DQ(31)

Q_CAP_C0402-2.2UF,6.3V,20%,X6SA  I123  C38
   1 P3V3_AUX      A @S9S_MB_2U_LIB.S9S_MB_2U(SCH_1):P3V3_AUX
   2    GND      B @S9S_MB_2U_LIB.S9S_MB_2U(SCH_1):GND

Q_CAP_C0805-10UF,16V,10%,X6S,CA  I125  C39
   1 P12V_S3_AUX_CPU0_NVDIMM      A @S9S_MB_2U_LIB.S9S_MB_2U(SCH_1):P12V_S3_AUX_CPU0_NVDIMM
   2    GND      B @S9S_MB_2U_LIB.S9S_MB_2U(SCH_1):GND

Q_CAP_C0805-10UF,16V,10%,X6S,CA  I162  C40
   1 P12V_S3_AUX_CPU0_NVDIMM      A @S9S_MB_2U_LIB.S9S_MB_2U(SCH_1):P12V_S3_AUX_CPU0_NVDIMM
   2    GND      B @S9S_MB_2U_LIB.S9S_MB_2U(SCH_1):GND

SCONN288_ADR50017P130CC-SCONN2A  I164  J13
   6    GND   VSS0 @S9S_MB_2U_LIB.S9S_MB_2U(SCH_1):GND
   8    GND   VSS1 @S9S_MB_2U_LIB.S9S_MB_2U(SCH_1):GND
  10    GND   VSS2 @S9S_MB_2U_LIB.S9S_MB_2U(SCH_1):GND
  13    GND   VSS3 @S9S_MB_2U_LIB.S9S_MB_2U(SCH_1):GND
  15    GND   VSS4 @S9S_MB_2U_LIB.S9S_MB_2U(SCH_1):GND
  17    GND   VSS5 @S9S_MB_2U_LIB.S9S_MB_2U(SCH_1):GND
  19    GND   VSS6 @S9S_MB_2U_LIB.S9S_MB_2U(SCH_1):GND
  21    GND   VSS7 @S9S_MB_2U_LIB.S9S_MB_2U(SCH_1):GND
  24    GND   VSS8 @S9S_MB_2U_LIB.S9S_MB_2U(SCH_1):GND
  26    GND   VSS9 @S9S_MB_2U_LIB.S9S_MB_2U(SCH_1):GND
  28    GND  VSS10 @S9S_MB_2U_LIB.S9S_MB_2U(SCH_1):GND
  30    GND  VSS11 @S9S_MB_2U_LIB.S9S_MB_2U(SCH_1):GND
  32    GND  VSS12 @S9S_MB_2U_LIB.S9S_MB_2U(SCH_1):GND
  35    GND  VSS13 @S9S_MB_2U_LIB.S9S_MB_2U(SCH_1):GND
  37    GND  VSS14 @S9S_MB_2U_LIB.S9S_MB_2U(SCH_1):GND
  39    GND  VSS15 @S9S_MB_2U_LIB.S9S_MB_2U(SCH_1):GND
  41    GND  VSS16 @S9S_MB_2U_LIB.S9S_MB_2U(SCH_1):GND
  43    GND  VSS17 @S9S_MB_2U_LIB.S9S_MB_2U(SCH_1):GND
  46    GND  VSS18 @S9S_MB_2U_LIB.S9S_MB_2U(SCH_1):GND
  48    GND  VSS19 @S9S_MB_2U_LIB.S9S_MB_2U(SCH_1):GND
  50    GND  VSS20 @S9S_MB_2U_LIB.S9S_MB_2U(SCH_1):GND
  52    GND  VSS21 @S9S_MB_2U_LIB.S9S_MB_2U(SCH_1):GND
  54    GND  VSS22 @S9S_MB_2U_LIB.S9S_MB_2U(SCH_1):GND
  57    GND  VSS23 @S9S_MB_2U_LIB.S9S_MB_2U(SCH_1):GND
  59    GND  VSS24 @S9S_MB_2U_LIB.S9S_MB_2U(SCH_1):GND
  61    GND  VSS25 @S9S_MB_2U_LIB.S9S_MB_2U(SCH_1):GND
  63    GND  VSS26 @S9S_MB_2U_LIB.S9S_MB_2U(SCH_1):GND
  65    GND  VSS27 @S9S_MB_2U_LIB.S9S_MB_2U(SCH_1):GND
  67    GND  VSS28 @S9S_MB_2U_LIB.S9S_MB_2U(SCH_1):GND
  69    GND  VSS29 @S9S_MB_2U_LIB.S9S_MB_2U(SCH_1):GND
  71    GND  VSS30 @S9S_MB_2U_LIB.S9S_MB_2U(SCH_1):GND
  73    GND  VSS31 @S9S_MB_2U_LIB.S9S_MB_2U(SCH_1):GND
  75    GND  VSS32 @S9S_MB_2U_LIB.S9S_MB_2U(SCH_1):GND
  77    GND  VSS33 @S9S_MB_2U_LIB.S9S_MB_2U(SCH_1):GND
  79    GND  VSS34 @S9S_MB_2U_LIB.S9S_MB_2U(SCH_1):GND
  81    GND  VSS35 @S9S_MB_2U_LIB.S9S_MB_2U(SCH_1):GND
  83    GND  VSS36 @S9S_MB_2U_LIB.S9S_MB_2U(SCH_1):GND
  85    GND  VSS37 @S9S_MB_2U_LIB.S9S_MB_2U(SCH_1):GND
  88    GND  VSS38 @S9S_MB_2U_LIB.S9S_MB_2U(SCH_1):GND
  90    GND  VSS39 @S9S_MB_2U_LIB.S9S_MB_2U(SCH_1):GND
  92    GND  VSS40 @S9S_MB_2U_LIB.S9S_MB_2U(SCH_1):GND
  95    GND  VSS41 @S9S_MB_2U_LIB.S9S_MB_2U(SCH_1):GND
  97    GND  VSS42 @S9S_MB_2U_LIB.S9S_MB_2U(SCH_1):GND
  99    GND  VSS43 @S9S_MB_2U_LIB.S9S_MB_2U(SCH_1):GND
 101    GND  VSS44 @S9S_MB_2U_LIB.S9S_MB_2U(SCH_1):GND
 103    GND  VSS45 @S9S_MB_2U_LIB.S9S_MB_2U(SCH_1):GND
 106    GND  VSS46 @S9S_MB_2U_LIB.S9S_MB_2U(SCH_1):GND
 108    GND  VSS47 @S9S_MB_2U_LIB.S9S_MB_2U(SCH_1):GND
 110    GND  VSS48 @S9S_MB_2U_LIB.S9S_MB_2U(SCH_1):GND
 112    GND  VSS49 @S9S_MB_2U_LIB.S9S_MB_2U(SCH_1):GND
 114    GND  VSS50 @S9S_MB_2U_LIB.S9S_MB_2U(SCH_1):GND
 117    GND  VSS51 @S9S_MB_2U_LIB.S9S_MB_2U(SCH_1):GND
 119    GND  VSS52 @S9S_MB_2U_LIB.S9S_MB_2U(SCH_1):GND
 121    GND  VSS53 @S9S_MB_2U_LIB.S9S_MB_2U(SCH_1):GND
 123    GND  VSS54 @S9S_MB_2U_LIB.S9S_MB_2U(SCH_1):GND
 125    GND  VSS55 @S9S_MB_2U_LIB.S9S_MB_2U(SCH_1):GND
 128    GND  VSS56 @S9S_MB_2U_LIB.S9S_MB_2U(SCH_1):GND
 130    GND  VSS57 @S9S_MB_2U_LIB.S9S_MB_2U(SCH_1):GND
 134    GND  VSS59 @S9S_MB_2U_LIB.S9S_MB_2U(SCH_1):GND
 143    GND  VSS63 @S9S_MB_2U_LIB.S9S_MB_2U(SCH_1):GND
 151    GND  VSS64 @S9S_MB_2U_LIB.S9S_MB_2U(SCH_1):GND
 153    GND  VSS65 @S9S_MB_2U_LIB.S9S_MB_2U(SCH_1):GND
 155    GND  VSS66 @S9S_MB_2U_LIB.S9S_MB_2U(SCH_1):GND
 158    GND  VSS67 @S9S_MB_2U_LIB.S9S_MB_2U(SCH_1):GND
 160    GND  VSS68 @S9S_MB_2U_LIB.S9S_MB_2U(SCH_1):GND
 162    GND  VSS69 @S9S_MB_2U_LIB.S9S_MB_2U(SCH_1):GND
 164    GND  VSS70 @S9S_MB_2U_LIB.S9S_MB_2U(SCH_1):GND
 166    GND  VSS71 @S9S_MB_2U_LIB.S9S_MB_2U(SCH_1):GND
 169    GND  VSS72 @S9S_MB_2U_LIB.S9S_MB_2U(SCH_1):GND
 171    GND  VSS73 @S9S_MB_2U_LIB.S9S_MB_2U(SCH_1):GND
 173    GND  VSS74 @S9S_MB_2U_LIB.S9S_MB_2U(SCH_1):GND
 175    GND  VSS75 @S9S_MB_2U_LIB.S9S_MB_2U(SCH_1):GND
 177    GND  VSS76 @S9S_MB_2U_LIB.S9S_MB_2U(SCH_1):GND
 180    GND  VSS77 @S9S_MB_2U_LIB.S9S_MB_2U(SCH_1):GND
 182    GND  VSS78 @S9S_MB_2U_LIB.S9S_MB_2U(SCH_1):GND
 184    GND  VSS79 @S9S_MB_2U_LIB.S9S_MB_2U(SCH_1):GND
 186    GND  VSS80 @S9S_MB_2U_LIB.S9S_MB_2U(SCH_1):GND
 188    GND  VSS81 @S9S_MB_2U_LIB.S9S_MB_2U(SCH_1):GND
 191    GND  VSS82 @S9S_MB_2U_LIB.S9S_MB_2U(SCH_1):GND
 193    GND  VSS83 @S9S_MB_2U_LIB.S9S_MB_2U(SCH_1):GND
 195    GND  VSS84 @S9S_MB_2U_LIB.S9S_MB_2U(SCH_1):GND
 197    GND  VSS85 @S9S_MB_2U_LIB.S9S_MB_2U(SCH_1):GND
 199    GND  VSS86 @S9S_MB_2U_LIB.S9S_MB_2U(SCH_1):GND
 202    GND  VSS87 @S9S_MB_2U_LIB.S9S_MB_2U(SCH_1):GND
 204    GND  VSS88 @S9S_MB_2U_LIB.S9S_MB_2U(SCH_1):GND
 206    GND  VSS89 @S9S_MB_2U_LIB.S9S_MB_2U(SCH_1):GND
 208    GND  VSS90 @S9S_MB_2U_LIB.S9S_MB_2U(SCH_1):GND
 210    GND  VSS91 @S9S_MB_2U_LIB.S9S_MB_2U(SCH_1):GND
 212    GND  VSS92 @S9S_MB_2U_LIB.S9S_MB_2U(SCH_1):GND
 214    GND  VSS93 @S9S_MB_2U_LIB.S9S_MB_2U(SCH_1):GND
 216    GND  VSS94 @S9S_MB_2U_LIB.S9S_MB_2U(SCH_1):GND
 219    GND  VSS95 @S9S_MB_2U_LIB.S9S_MB_2U(SCH_1):GND
 222    GND  VSS96 @S9S_MB_2U_LIB.S9S_MB_2U(SCH_1):GND
 224    GND  VSS97 @S9S_MB_2U_LIB.S9S_MB_2U(SCH_1):GND
 226    GND  VSS98 @S9S_MB_2U_LIB.S9S_MB_2U(SCH_1):GND
 228    GND  VSS99 @S9S_MB_2U_LIB.S9S_MB_2U(SCH_1):GND
 233    GND VSS101 @S9S_MB_2U_LIB.S9S_MB_2U(SCH_1):GND
 237    GND VSS103 @S9S_MB_2U_LIB.S9S_MB_2U(SCH_1):GND
 242    GND VSS105 @S9S_MB_2U_LIB.S9S_MB_2U(SCH_1):GND
 244    GND VSS106 @S9S_MB_2U_LIB.S9S_MB_2U(SCH_1):GND
 246    GND VSS107 @S9S_MB_2U_LIB.S9S_MB_2U(SCH_1):GND
 248    GND VSS108 @S9S_MB_2U_LIB.S9S_MB_2U(SCH_1):GND
 251    GND VSS109 @S9S_MB_2U_LIB.S9S_MB_2U(SCH_1):GND
 253    GND VSS110 @S9S_MB_2U_LIB.S9S_MB_2U(SCH_1):GND
 255    GND VSS111 @S9S_MB_2U_LIB.S9S_MB_2U(SCH_1):GND
 257    GND VSS112 @S9S_MB_2U_LIB.S9S_MB_2U(SCH_1):GND
 259    GND VSS113 @S9S_MB_2U_LIB.S9S_MB_2U(SCH_1):GND
 262    GND VSS114 @S9S_MB_2U_LIB.S9S_MB_2U(SCH_1):GND
 264    GND VSS115 @S9S_MB_2U_LIB.S9S_MB_2U(SCH_1):GND
 266    GND VSS116 @S9S_MB_2U_LIB.S9S_MB_2U(SCH_1):GND
 268    GND VSS117 @S9S_MB_2U_LIB.S9S_MB_2U(SCH_1):GND
 270    GND VSS118 @S9S_MB_2U_LIB.S9S_MB_2U(SCH_1):GND
 273    GND VSS119 @S9S_MB_2U_LIB.S9S_MB_2U(SCH_1):GND
 275    GND VSS120 @S9S_MB_2U_LIB.S9S_MB_2U(SCH_1):GND
 277    GND VSS121 @S9S_MB_2U_LIB.S9S_MB_2U(SCH_1):GND
 279    GND VSS122 @S9S_MB_2U_LIB.S9S_MB_2U(SCH_1):GND
 281    GND VSS123 @S9S_MB_2U_LIB.S9S_MB_2U(SCH_1):GND
 284    GND VSS124 @S9S_MB_2U_LIB.S9S_MB_2U(SCH_1):GND
 286    GND VSS125 @S9S_MB_2U_LIB.S9S_MB_2U(SCH_1):GND
 288    GND VSS126 @S9S_MB_2U_LIB.S9S_MB_2U(SCH_1):GND
   1 P12V_S3_AUX_CPU0_NVDIMM VIN_BULK0 @S9S_MB_2U_LIB.S9S_MB_2U(SCH_1):P12V_S3_AUX_CPU0_NVDIMM
 145 P12V_S3_AUX_CPU0_NVDIMM VIN_BULK1 @S9S_MB_2U_LIB.S9S_MB_2U(SCH_1):P12V_S3_AUX_CPU0_NVDIMM
 146 P12V_S3_AUX_CPU0_NVDIMM VIN_BULK2 @S9S_MB_2U_LIB.S9S_MB_2U(SCH_1):P12V_S3_AUX_CPU0_NVDIMM
 230    GND VSS100 @S9S_MB_2U_LIB.S9S_MB_2U(SCH_1):GND
 235    GND VSS102 @S9S_MB_2U_LIB.S9S_MB_2U(SCH_1):GND
 240    GND VSS104 @S9S_MB_2U_LIB.S9S_MB_2U(SCH_1):GND
 132    GND  VSS58 @S9S_MB_2U_LIB.S9S_MB_2U(SCH_1):GND
 136    GND  VSS60 @S9S_MB_2U_LIB.S9S_MB_2U(SCH_1):GND
 139    GND  VSS61 @S9S_MB_2U_LIB.S9S_MB_2U(SCH_1):GND
 141    GND  VSS62 @S9S_MB_2U_LIB.S9S_MB_2U(SCH_1):GND
  G1    GND     G1 @S9S_MB_2U_LIB.S9S_MB_2U(SCH_1):GND
  G2    GND     G2 @S9S_MB_2U_LIB.S9S_MB_2U(SCH_1):GND
  G3    GND     G3 @S9S_MB_2U_LIB.S9S_MB_2U(SCH_1):GND

SCONN288_ADR50017P130CC-SCONN2A  I178  J13
  93 M_G_CPU0_SB_DQS_DP<9> DQS9_B_T||TDQS9_B_T||DBI4_B_N @S9S_MB_2U_LIB.S9S_MB_2U(SCH_1):M_G_CPU0_SB_DQS_DP(9)
  94 M_G_CPU0_SB_DQS_DN<9> DQS9_B_C||TDQS9_B_C @S9S_MB_2U_LIB.S9S_MB_2U(SCH_1):M_G_CPU0_SB_DQS_DN(9)
 201 M_G_CPU0_SA_DQS_DP<9> DQS9_A_T||TDQS9_A_T @S9S_MB_2U_LIB.S9S_MB_2U(SCH_1):M_G_CPU0_SA_DQS_DP(9)
 200 M_G_CPU0_SA_DQS_DN<9> DQS9_A_C||TDQS9_A_C @S9S_MB_2U_LIB.S9S_MB_2U(SCH_1):M_G_CPU0_SA_DQS_DN(9)
 190 M_G_CPU0_SA_DQS_DP<8> DQS8_A_T||TDQS8_A_T @S9S_MB_2U_LIB.S9S_MB_2U(SCH_1):M_G_CPU0_SA_DQS_DP(8)
 189 M_G_CPU0_SA_DQS_DN<8> DQS8_A_C||TDQS8_A_C @S9S_MB_2U_LIB.S9S_MB_2U(SCH_1):M_G_CPU0_SA_DQS_DN(8)
 271 M_G_CPU0_SB_DQS_DN<7> DQS7_B_C||TDQS7_B_C @S9S_MB_2U_LIB.S9S_MB_2U(SCH_1):M_G_CPU0_SB_DQS_DN(7)
 179 M_G_CPU0_SA_DQS_DP<7> DQS7_A_T||TDQS7_A_T @S9S_MB_2U_LIB.S9S_MB_2U(SCH_1):M_G_CPU0_SA_DQS_DP(7)
 261 M_G_CPU0_SB_DQS_DP<6> DQS6_B_T||TDQS6_B_T @S9S_MB_2U_LIB.S9S_MB_2U(SCH_1):M_G_CPU0_SB_DQS_DP(6)
 260 M_G_CPU0_SB_DQS_DN<6> DQS6_B_C||TDQS6_B_C @S9S_MB_2U_LIB.S9S_MB_2U(SCH_1):M_G_CPU0_SB_DQS_DN(6)
 167 M_G_CPU0_SA_DQS_DN<6> DQS6_A_C||TDQS6_A_C||DQS6_A_T||TDQS6_A_T @S9S_MB_2U_LIB.S9S_MB_2U(SCH_1):M_G_CPU0_SA_DQS_DN(6)
 250 M_G_CPU0_SB_DQS_DP<5> DQS5_B_T||TDQS5_B_T @S9S_MB_2U_LIB.S9S_MB_2U(SCH_1):M_G_CPU0_SB_DQS_DP(5)
 249 M_G_CPU0_SB_DQS_DN<5> DQS5_B_C||TDQS5_B_C @S9S_MB_2U_LIB.S9S_MB_2U(SCH_1):M_G_CPU0_SB_DQS_DN(5)
 157 M_G_CPU0_SA_DQS_DP<5> DQS5_A_T||TDQS5_A_T @S9S_MB_2U_LIB.S9S_MB_2U(SCH_1):M_G_CPU0_SA_DQS_DP(5)
 156 M_G_CPU0_SA_DQS_DN<5> DQS5_A_C||TDQS5_A_C||DQS5_A_T||TDQS5_A_T @S9S_MB_2U_LIB.S9S_MB_2U(SCH_1):M_G_CPU0_SA_DQS_DN(5)
 239 M_G_CPU0_SB_DQS_DP<4> DQS4_B_T @S9S_MB_2U_LIB.S9S_MB_2U(SCH_1):M_G_CPU0_SB_DQS_DP(4)
 238 M_G_CPU0_SB_DQS_DN<4> DQS4_B_C @S9S_MB_2U_LIB.S9S_MB_2U(SCH_1):M_G_CPU0_SB_DQS_DN(4)
  55 M_G_CPU0_SA_DQS_DP<4> DQS4_A_T @S9S_MB_2U_LIB.S9S_MB_2U(SCH_1):M_G_CPU0_SA_DQS_DP(4)
  56 M_G_CPU0_SA_DQS_DN<4> DQS4_A_C @S9S_MB_2U_LIB.S9S_MB_2U(SCH_1):M_G_CPU0_SA_DQS_DN(4)
 137 M_G_CPU0_SB_DQS_DP<3> DQS3_B_T @S9S_MB_2U_LIB.S9S_MB_2U(SCH_1):M_G_CPU0_SB_DQS_DP(3)
 138 M_G_CPU0_SB_DQS_DN<3> DQS3_B_C @S9S_MB_2U_LIB.S9S_MB_2U(SCH_1):M_G_CPU0_SB_DQS_DN(3)
  44 M_G_CPU0_SA_DQS_DP<3> DQS3_A_T @S9S_MB_2U_LIB.S9S_MB_2U(SCH_1):M_G_CPU0_SA_DQS_DP(3)
  45 M_G_CPU0_SA_DQS_DN<3> DQS3_A_C @S9S_MB_2U_LIB.S9S_MB_2U(SCH_1):M_G_CPU0_SA_DQS_DN(3)
 126 M_G_CPU0_SB_DQS_DP<2> DQS2_B_T @S9S_MB_2U_LIB.S9S_MB_2U(SCH_1):M_G_CPU0_SB_DQS_DP(2)
 127 M_G_CPU0_SB_DQS_DN<2> DQS2_B_C @S9S_MB_2U_LIB.S9S_MB_2U(SCH_1):M_G_CPU0_SB_DQS_DN(2)
  33 M_G_CPU0_SA_DQS_DP<2> DQS2_A_T @S9S_MB_2U_LIB.S9S_MB_2U(SCH_1):M_G_CPU0_SA_DQS_DP(2)
  34 M_G_CPU0_SA_DQS_DN<2> DQS2_A_C @S9S_MB_2U_LIB.S9S_MB_2U(SCH_1):M_G_CPU0_SA_DQS_DN(2)
 115 M_G_CPU0_SB_DQS_DP<1> DQS1_B_T @S9S_MB_2U_LIB.S9S_MB_2U(SCH_1):M_G_CPU0_SB_DQS_DP(1)
 116 M_G_CPU0_SB_DQS_DN<1> DQS1_B_C @S9S_MB_2U_LIB.S9S_MB_2U(SCH_1):M_G_CPU0_SB_DQS_DN(1)
  22 M_G_CPU0_SA_DQS_DP<1> DQS1_A_T @S9S_MB_2U_LIB.S9S_MB_2U(SCH_1):M_G_CPU0_SA_DQS_DP(1)
  23 M_G_CPU0_SA_DQS_DN<1> DQS1_A_C @S9S_MB_2U_LIB.S9S_MB_2U(SCH_1):M_G_CPU0_SA_DQS_DN(1)
 104 M_G_CPU0_SB_DQS_DP<0> DQS0_B_T @S9S_MB_2U_LIB.S9S_MB_2U(SCH_1):M_G_CPU0_SB_DQS_DP(0)
 105 M_G_CPU0_SB_DQS_DN<0> DQS0_B_C @S9S_MB_2U_LIB.S9S_MB_2U(SCH_1):M_G_CPU0_SB_DQS_DN(0)
  11 M_G_CPU0_SA_DQS_DP<0> DQS0_A_T @S9S_MB_2U_LIB.S9S_MB_2U(SCH_1):M_G_CPU0_SA_DQS_DP(0)
  12 M_G_CPU0_SA_DQS_DN<0> DQS0_A_C @S9S_MB_2U_LIB.S9S_MB_2U(SCH_1):M_G_CPU0_SA_DQS_DN(0)
 272 M_G_CPU0_SB_DQS_DP<7> DQS7_B_T||TDQS7_B_T @S9S_MB_2U_LIB.S9S_MB_2U(SCH_1):M_G_CPU0_SB_DQS_DP(7)
 282 M_G_CPU0_SB_DQS_DN<8> DQS8_B_C||TDQS8_B_C @S9S_MB_2U_LIB.S9S_MB_2U(SCH_1):M_G_CPU0_SB_DQS_DN(8)
 283 M_G_CPU0_SB_DQS_DP<8> DQS8_B_T||TDQS8_B_T @S9S_MB_2U_LIB.S9S_MB_2U(SCH_1):M_G_CPU0_SB_DQS_DP(8)
 168 M_G_CPU0_SA_DQS_DP<6> DQS6_A_T||TDQS6_A_T @S9S_MB_2U_LIB.S9S_MB_2U(SCH_1):M_G_CPU0_SA_DQS_DP(6)
 178 M_G_CPU0_SA_DQS_DN<7> DQS7_A_C||TDQS7_A_C @S9S_MB_2U_LIB.S9S_MB_2U(SCH_1):M_G_CPU0_SA_DQS_DN(7)

Q_RES_0402LF-49.9,1%,1/16W,CHIA  I179  R3887
   1 I3C_SPD_DDREFGH_CPU0_LVC1_SCL_4      A @S9S_MB_2U_LIB.S9S_MB_2U(SCH_1):I3C_SPD_DDREFGH_CPU0_LVC1_SCL_R5
   2 I3C_SPD_DDREFGH_CPU0_LVC1_SCL      B @S9S_MB_2U_LIB.S9S_MB_2U(SCH_1):I3C_SPD_DDREFGH_CPU0_LVC1_SCL


DRAWING: @S9S_MB_2U_LIB.S9S_MB_2U(SCH_1):PAGE95 

Q_RES_0402LF-84.5K,1%,1/16W,CHA  I46  R39
   1 PD_CHG_CPU0_DIMM2_SAA      A @S9S_MB_2U_LIB.S9S_MB_2U(SCH_1):PD_CHG_CPU0_DIMM2_SAA
   2    GND      B @S9S_MB_2U_LIB.S9S_MB_2U(SCH_1):GND

SCONN288_ADR50017P087CC-SCONN2A  I47  J14
   3 P3V3_AUX VIN_MGMT @S9S_MB_2U_LIB.S9S_MB_2U(SCH_1):P3V3_AUX
   2 TP_CHG_CPU0_DIMM2_FRU_0   RFU0 @S9S_MB_2U_LIB.S9S_MB_2U(SCH_1):TP_CHG_CPU0_DIMM2_FRU_0
 144 TP_CHG_CPU0_DIMM2_FRU_1   RFU1 @S9S_MB_2U_LIB.S9S_MB_2U(SCH_1):TP_CHG_CPU0_DIMM2_FRU_1
 149 TP_CHG_CPU0_DIMM2_FRU_2   RFU2 @S9S_MB_2U_LIB.S9S_MB_2U(SCH_1):TP_CHG_CPU0_DIMM2_FRU_2
 150 TP_CHG_CPU0_DIMM2_FRU_3   RFU3 @S9S_MB_2U_LIB.S9S_MB_2U(SCH_1):TP_CHG_CPU0_DIMM2_FRU_3
 220 TP_CHG_CPU0_DIMM2_FRU_4   RFU4 @S9S_MB_2U_LIB.S9S_MB_2U(SCH_1):TP_CHG_CPU0_DIMM2_FRU_4
 231 TP_CHG_CPU0_DIMM2_FRU_5   RFU5 @S9S_MB_2U_LIB.S9S_MB_2U(SCH_1):TP_CHG_CPU0_DIMM2_FRU_5
 232 TP_CHG_CPU0_DIMM2_FRU_6   RFU6 @S9S_MB_2U_LIB.S9S_MB_2U(SCH_1):TP_CHG_CPU0_DIMM2_FRU_6
 207 RST_M_GH_CPU0_FPGA_N RESET_N @S9S_MB_2U_LIB.S9S_MB_2U(SCH_1):RST_M_GH_CPU0_FPGA_N
 147 PWRGD_CHG_CPU0_DIMM2 PWR_GOOD||FAIL_N @S9S_MB_2U_LIB.S9S_MB_2U(SCH_1):PWRGD_CHG_CPU0_DIMM2
 227 M_G_CPU0_SB_PAR  PAR_B @S9S_MB_2U_LIB.S9S_MB_2U(SCH_1):M_G_CPU0_SB_PAR
  74 M_G_CPU0_SA_PAR  PAR_A @S9S_MB_2U_LIB.S9S_MB_2U(SCH_1):M_G_CPU0_SA_PAR
  87 M_G_CPU0_SB_RSP<1> LBS||RSP_B_N @S9S_MB_2U_LIB.S9S_MB_2U(SCH_1):M_G_CPU0_SB_RSP(1)
  86 M_G_CPU0_SA_RSP<1> LBD||RSP_A_N @S9S_MB_2U_LIB.S9S_MB_2U(SCH_1):M_G_CPU0_SA_RSP(1)
   5 I3C_SPD_DDREFGH_CPU0_LVC1_SDA   HSDA @S9S_MB_2U_LIB.S9S_MB_2U(SCH_1):I3C_SPD_DDREFGH_CPU0_LVC1_SDA
   4 I3C_SPD_DDREFGH_CPU0_LVC1_SCL_5   HSCL @S9S_MB_2U_LIB.S9S_MB_2U(SCH_1):I3C_SPD_DDREFGH_CPU0_LVC1_SCL_R6
 148 PD_CHG_CPU0_DIMM2_SAA    HSA @S9S_MB_2U_LIB.S9S_MB_2U(SCH_1):PD_CHG_CPU0_DIMM2_SAA
 100 M_G_CPU0_SB_DQ<0>  DQ0_B @S9S_MB_2U_LIB.S9S_MB_2U(SCH_1):M_G_CPU0_SB_DQ(0)
 102 M_G_CPU0_SB_DQ<1>  DQ1_B @S9S_MB_2U_LIB.S9S_MB_2U(SCH_1):M_G_CPU0_SB_DQ(1)
 245 M_G_CPU0_SB_DQ<2>  DQ2_B @S9S_MB_2U_LIB.S9S_MB_2U(SCH_1):M_G_CPU0_SB_DQ(2)
 247 M_G_CPU0_SB_DQ<3>  DQ3_B @S9S_MB_2U_LIB.S9S_MB_2U(SCH_1):M_G_CPU0_SB_DQ(3)
 107 M_G_CPU0_SB_DQ<4>  DQ4_B @S9S_MB_2U_LIB.S9S_MB_2U(SCH_1):M_G_CPU0_SB_DQ(4)
 109 M_G_CPU0_SB_DQ<5>  DQ5_B @S9S_MB_2U_LIB.S9S_MB_2U(SCH_1):M_G_CPU0_SB_DQ(5)
 252 M_G_CPU0_SB_DQ<6>  DQ6_B @S9S_MB_2U_LIB.S9S_MB_2U(SCH_1):M_G_CPU0_SB_DQ(6)
 254 M_G_CPU0_SB_DQ<7>  DQ7_B @S9S_MB_2U_LIB.S9S_MB_2U(SCH_1):M_G_CPU0_SB_DQ(7)
 111 M_G_CPU0_SB_DQ<8>  DQ8_B @S9S_MB_2U_LIB.S9S_MB_2U(SCH_1):M_G_CPU0_SB_DQ(8)
 113 M_G_CPU0_SB_DQ<9>  DQ9_B @S9S_MB_2U_LIB.S9S_MB_2U(SCH_1):M_G_CPU0_SB_DQ(9)
 256 M_G_CPU0_SB_DQ<10> DQ10_B @S9S_MB_2U_LIB.S9S_MB_2U(SCH_1):M_G_CPU0_SB_DQ(10)
 258 M_G_CPU0_SB_DQ<11> DQ11_B @S9S_MB_2U_LIB.S9S_MB_2U(SCH_1):M_G_CPU0_SB_DQ(11)
 118 M_G_CPU0_SB_DQ<12> DQ12_B @S9S_MB_2U_LIB.S9S_MB_2U(SCH_1):M_G_CPU0_SB_DQ(12)
 120 M_G_CPU0_SB_DQ<13> DQ13_B @S9S_MB_2U_LIB.S9S_MB_2U(SCH_1):M_G_CPU0_SB_DQ(13)
 263 M_G_CPU0_SB_DQ<14> DQ14_B @S9S_MB_2U_LIB.S9S_MB_2U(SCH_1):M_G_CPU0_SB_DQ(14)
 265 M_G_CPU0_SB_DQ<15> DQ15_B @S9S_MB_2U_LIB.S9S_MB_2U(SCH_1):M_G_CPU0_SB_DQ(15)
 122 M_G_CPU0_SB_DQ<16> DQ16_B @S9S_MB_2U_LIB.S9S_MB_2U(SCH_1):M_G_CPU0_SB_DQ(16)
 124 M_G_CPU0_SB_DQ<17> DQ17_B @S9S_MB_2U_LIB.S9S_MB_2U(SCH_1):M_G_CPU0_SB_DQ(17)
 267 M_G_CPU0_SB_DQ<18> DQ18_B @S9S_MB_2U_LIB.S9S_MB_2U(SCH_1):M_G_CPU0_SB_DQ(18)
 269 M_G_CPU0_SB_DQ<19> DQ19_B @S9S_MB_2U_LIB.S9S_MB_2U(SCH_1):M_G_CPU0_SB_DQ(19)
 129 M_G_CPU0_SB_DQ<20> DQ20_B @S9S_MB_2U_LIB.S9S_MB_2U(SCH_1):M_G_CPU0_SB_DQ(20)
 131 M_G_CPU0_SB_DQ<21> DQ21_B @S9S_MB_2U_LIB.S9S_MB_2U(SCH_1):M_G_CPU0_SB_DQ(21)
 274 M_G_CPU0_SB_DQ<22> DQ22_B @S9S_MB_2U_LIB.S9S_MB_2U(SCH_1):M_G_CPU0_SB_DQ(22)
 276 M_G_CPU0_SB_DQ<23> DQ23_B @S9S_MB_2U_LIB.S9S_MB_2U(SCH_1):M_G_CPU0_SB_DQ(23)
 133 M_G_CPU0_SB_DQ<24> DQ24_B @S9S_MB_2U_LIB.S9S_MB_2U(SCH_1):M_G_CPU0_SB_DQ(24)
 135 M_G_CPU0_SB_DQ<25> DQ25_B @S9S_MB_2U_LIB.S9S_MB_2U(SCH_1):M_G_CPU0_SB_DQ(25)
 278 M_G_CPU0_SB_DQ<26> DQ26_B @S9S_MB_2U_LIB.S9S_MB_2U(SCH_1):M_G_CPU0_SB_DQ(26)
 280 M_G_CPU0_SB_DQ<27> DQ27_B @S9S_MB_2U_LIB.S9S_MB_2U(SCH_1):M_G_CPU0_SB_DQ(27)
 140 M_G_CPU0_SB_DQ<28> DQ28_B @S9S_MB_2U_LIB.S9S_MB_2U(SCH_1):M_G_CPU0_SB_DQ(28)
 142 M_G_CPU0_SB_DQ<29> DQ29_B @S9S_MB_2U_LIB.S9S_MB_2U(SCH_1):M_G_CPU0_SB_DQ(29)
 285 M_G_CPU0_SB_DQ<30> DQ30_B @S9S_MB_2U_LIB.S9S_MB_2U(SCH_1):M_G_CPU0_SB_DQ(30)
 287 M_G_CPU0_SB_DQ<31> DQ31_B @S9S_MB_2U_LIB.S9S_MB_2U(SCH_1):M_G_CPU0_SB_DQ(31)
   7 M_G_CPU0_SA_DQ<0>  DQ0_A @S9S_MB_2U_LIB.S9S_MB_2U(SCH_1):M_G_CPU0_SA_DQ(0)
   9 M_G_CPU0_SA_DQ<1>  DQ1_A @S9S_MB_2U_LIB.S9S_MB_2U(SCH_1):M_G_CPU0_SA_DQ(1)
 152 M_G_CPU0_SA_DQ<2>  DQ2_A @S9S_MB_2U_LIB.S9S_MB_2U(SCH_1):M_G_CPU0_SA_DQ(2)
 154 M_G_CPU0_SA_DQ<3>  DQ3_A @S9S_MB_2U_LIB.S9S_MB_2U(SCH_1):M_G_CPU0_SA_DQ(3)
  14 M_G_CPU0_SA_DQ<4>  DQ4_A @S9S_MB_2U_LIB.S9S_MB_2U(SCH_1):M_G_CPU0_SA_DQ(4)
  16 M_G_CPU0_SA_DQ<5>  DQ5_A @S9S_MB_2U_LIB.S9S_MB_2U(SCH_1):M_G_CPU0_SA_DQ(5)
 159 M_G_CPU0_SA_DQ<6>  DQ6_A @S9S_MB_2U_LIB.S9S_MB_2U(SCH_1):M_G_CPU0_SA_DQ(6)
 161 M_G_CPU0_SA_DQ<7>  DQ7_A @S9S_MB_2U_LIB.S9S_MB_2U(SCH_1):M_G_CPU0_SA_DQ(7)
  18 M_G_CPU0_SA_DQ<8>  DQ8_A @S9S_MB_2U_LIB.S9S_MB_2U(SCH_1):M_G_CPU0_SA_DQ(8)
  20 M_G_CPU0_SA_DQ<9>  DQ9_A @S9S_MB_2U_LIB.S9S_MB_2U(SCH_1):M_G_CPU0_SA_DQ(9)
 163 M_G_CPU0_SA_DQ<10> DQ10_A @S9S_MB_2U_LIB.S9S_MB_2U(SCH_1):M_G_CPU0_SA_DQ(10)
 165 M_G_CPU0_SA_DQ<11> DQ11_A @S9S_MB_2U_LIB.S9S_MB_2U(SCH_1):M_G_CPU0_SA_DQ(11)
  25 M_G_CPU0_SA_DQ<12> DQ12_A @S9S_MB_2U_LIB.S9S_MB_2U(SCH_1):M_G_CPU0_SA_DQ(12)
  27 M_G_CPU0_SA_DQ<13> DQ13_A @S9S_MB_2U_LIB.S9S_MB_2U(SCH_1):M_G_CPU0_SA_DQ(13)
 170 M_G_CPU0_SA_DQ<14> DQ14_A @S9S_MB_2U_LIB.S9S_MB_2U(SCH_1):M_G_CPU0_SA_DQ(14)
 172 M_G_CPU0_SA_DQ<15> DQ15_A @S9S_MB_2U_LIB.S9S_MB_2U(SCH_1):M_G_CPU0_SA_DQ(15)
  29 M_G_CPU0_SA_DQ<16> DQ16_A @S9S_MB_2U_LIB.S9S_MB_2U(SCH_1):M_G_CPU0_SA_DQ(16)
  31 M_G_CPU0_SA_DQ<17> DQ17_A @S9S_MB_2U_LIB.S9S_MB_2U(SCH_1):M_G_CPU0_SA_DQ(17)
 174 M_G_CPU0_SA_DQ<18> DQ18_A @S9S_MB_2U_LIB.S9S_MB_2U(SCH_1):M_G_CPU0_SA_DQ(18)
 176 M_G_CPU0_SA_DQ<19> DQ19_A @S9S_MB_2U_LIB.S9S_MB_2U(SCH_1):M_G_CPU0_SA_DQ(19)
  36 M_G_CPU0_SA_DQ<20> DQ20_A @S9S_MB_2U_LIB.S9S_MB_2U(SCH_1):M_G_CPU0_SA_DQ(20)
  38 M_G_CPU0_SA_DQ<21> DQ21_A @S9S_MB_2U_LIB.S9S_MB_2U(SCH_1):M_G_CPU0_SA_DQ(21)
 181 M_G_CPU0_SA_DQ<22> DQ22_A @S9S_MB_2U_LIB.S9S_MB_2U(SCH_1):M_G_CPU0_SA_DQ(22)
 183 M_G_CPU0_SA_DQ<23> DQ23_A @S9S_MB_2U_LIB.S9S_MB_2U(SCH_1):M_G_CPU0_SA_DQ(23)
  40 M_G_CPU0_SA_DQ<24> DQ24_A @S9S_MB_2U_LIB.S9S_MB_2U(SCH_1):M_G_CPU0_SA_DQ(24)
  42 M_G_CPU0_SA_DQ<25> DQ25_A @S9S_MB_2U_LIB.S9S_MB_2U(SCH_1):M_G_CPU0_SA_DQ(25)
 185 M_G_CPU0_SA_DQ<26> DQ26_A @S9S_MB_2U_LIB.S9S_MB_2U(SCH_1):M_G_CPU0_SA_DQ(26)
 187 M_G_CPU0_SA_DQ<27> DQ27_A @S9S_MB_2U_LIB.S9S_MB_2U(SCH_1):M_G_CPU0_SA_DQ(27)
  47 M_G_CPU0_SA_DQ<28> DQ28_A @S9S_MB_2U_LIB.S9S_MB_2U(SCH_1):M_G_CPU0_SA_DQ(28)
  49 M_G_CPU0_SA_DQ<29> DQ29_A @S9S_MB_2U_LIB.S9S_MB_2U(SCH_1):M_G_CPU0_SA_DQ(29)
 192 M_G_CPU0_SA_DQ<30> DQ30_A @S9S_MB_2U_LIB.S9S_MB_2U(SCH_1):M_G_CPU0_SA_DQ(30)
 229 M_G_CPU0_SB_CS_N<3> CS1_B_N @S9S_MB_2U_LIB.S9S_MB_2U(SCH_1):M_G_CPU0_SB_CS_N(3)
 209 M_G_CPU0_SA_CS_N<3> CS1_A_N @S9S_MB_2U_LIB.S9S_MB_2U(SCH_1):M_G_CPU0_SA_CS_N(3)
  84 M_G_CPU0_SB_CS_N<2> CS0_B_N @S9S_MB_2U_LIB.S9S_MB_2U(SCH_1):M_G_CPU0_SB_CS_N(2)
  64 M_G_CPU0_SA_CS_N<2> CS0_A_N @S9S_MB_2U_LIB.S9S_MB_2U(SCH_1):M_G_CPU0_SA_CS_N(2)
 217 M_G_CPU0_CLK_DP<1>   CK_T @S9S_MB_2U_LIB.S9S_MB_2U(SCH_1):M_G_CPU0_CLK_DP(1)
 218 M_G_CPU0_CLK_DN<1>   CK_C @S9S_MB_2U_LIB.S9S_MB_2U(SCH_1):M_G_CPU0_CLK_DN(1)
  96 M_G_CPU0_SB_CB<0>  CB0_B @S9S_MB_2U_LIB.S9S_MB_2U(SCH_1):M_G_CPU0_SB_CB(0)
  98 M_G_CPU0_SB_CB<1>  CB1_B @S9S_MB_2U_LIB.S9S_MB_2U(SCH_1):M_G_CPU0_SB_CB(1)
 241 M_G_CPU0_SB_CB<2>  CB2_B @S9S_MB_2U_LIB.S9S_MB_2U(SCH_1):M_G_CPU0_SB_CB(2)
 243 M_G_CPU0_SB_CB<3>  CB3_B @S9S_MB_2U_LIB.S9S_MB_2U(SCH_1):M_G_CPU0_SB_CB(3)
  89 M_G_CPU0_SB_CB<4>  CB4_B @S9S_MB_2U_LIB.S9S_MB_2U(SCH_1):M_G_CPU0_SB_CB(4)
  91 M_G_CPU0_SB_CB<5>  CB5_B @S9S_MB_2U_LIB.S9S_MB_2U(SCH_1):M_G_CPU0_SB_CB(5)
 234 M_G_CPU0_SB_CB<6>  CB6_B @S9S_MB_2U_LIB.S9S_MB_2U(SCH_1):M_G_CPU0_SB_CB(6)
  51 M_G_CPU0_SA_CB<0>  CB0_A @S9S_MB_2U_LIB.S9S_MB_2U(SCH_1):M_G_CPU0_SA_CB(0)
 196 M_G_CPU0_SA_CB<2>  CB2_A @S9S_MB_2U_LIB.S9S_MB_2U(SCH_1):M_G_CPU0_SA_CB(2)
 198 M_G_CPU0_SA_CB<3>  CB3_A @S9S_MB_2U_LIB.S9S_MB_2U(SCH_1):M_G_CPU0_SA_CB(3)
  60 M_G_CPU0_SA_CB<5>  CB5_A @S9S_MB_2U_LIB.S9S_MB_2U(SCH_1):M_G_CPU0_SA_CB(5)
 203 M_G_CPU0_SA_CB<6>  CB6_A @S9S_MB_2U_LIB.S9S_MB_2U(SCH_1):M_G_CPU0_SA_CB(6)
  82 M_G_CPU0_SB_CA<6>  CA6_B @S9S_MB_2U_LIB.S9S_MB_2U(SCH_1):M_G_CPU0_SB_CA(6)
  72 M_G_CPU0_SA_CA<6>  CA6_A @S9S_MB_2U_LIB.S9S_MB_2U(SCH_1):M_G_CPU0_SA_CA(6)
 225 M_G_CPU0_SB_CA<5>  CA5_B @S9S_MB_2U_LIB.S9S_MB_2U(SCH_1):M_G_CPU0_SB_CA(5)
 215 M_G_CPU0_SA_CA<5>  CA5_A @S9S_MB_2U_LIB.S9S_MB_2U(SCH_1):M_G_CPU0_SA_CA(5)
  80 M_G_CPU0_SB_CA<4>  CA4_B @S9S_MB_2U_LIB.S9S_MB_2U(SCH_1):M_G_CPU0_SB_CA(4)
  70 M_G_CPU0_SA_CA<4>  CA4_A @S9S_MB_2U_LIB.S9S_MB_2U(SCH_1):M_G_CPU0_SA_CA(4)
 223 M_G_CPU0_SB_CA<3>  CA3_B @S9S_MB_2U_LIB.S9S_MB_2U(SCH_1):M_G_CPU0_SB_CA(3)
 213 M_G_CPU0_SA_CA<3>  CA3_A @S9S_MB_2U_LIB.S9S_MB_2U(SCH_1):M_G_CPU0_SA_CA(3)
  78 M_G_CPU0_SB_CA<2>  CA2_B @S9S_MB_2U_LIB.S9S_MB_2U(SCH_1):M_G_CPU0_SB_CA(2)
  68 M_G_CPU0_SA_CA<2>  CA2_A @S9S_MB_2U_LIB.S9S_MB_2U(SCH_1):M_G_CPU0_SA_CA(2)
 221 M_G_CPU0_SB_CA<1>  CA1_B @S9S_MB_2U_LIB.S9S_MB_2U(SCH_1):M_G_CPU0_SB_CA(1)
 211 M_G_CPU0_SA_CA<1>  CA1_A @S9S_MB_2U_LIB.S9S_MB_2U(SCH_1):M_G_CPU0_SA_CA(1)
  76 M_G_CPU0_SB_CA<0>  CA0_B @S9S_MB_2U_LIB.S9S_MB_2U(SCH_1):M_G_CPU0_SB_CA(0)
  66 M_G_CPU0_SA_CA<0>  CA0_A @S9S_MB_2U_LIB.S9S_MB_2U(SCH_1):M_G_CPU0_SA_CA(0)
  62 M_G_CPU0_ALERT_N ALERT_N @S9S_MB_2U_LIB.S9S_MB_2U(SCH_1):M_G_CPU0_ALERT_N
 236 M_G_CPU0_SB_CB<7>  CB7_B @S9S_MB_2U_LIB.S9S_MB_2U(SCH_1):M_G_CPU0_SB_CB(7)
  53 M_G_CPU0_SA_CB<1>  CB1_A @S9S_MB_2U_LIB.S9S_MB_2U(SCH_1):M_G_CPU0_SA_CB(1)
  58 M_G_CPU0_SA_CB<4>  CB4_A @S9S_MB_2U_LIB.S9S_MB_2U(SCH_1):M_G_CPU0_SA_CB(4)
 205 M_G_CPU0_SA_CB<7>  CB7_A @S9S_MB_2U_LIB.S9S_MB_2U(SCH_1):M_G_CPU0_SA_CB(7)
 194 M_G_CPU0_SA_DQ<31> DQ31_A @S9S_MB_2U_LIB.S9S_MB_2U(SCH_1):M_G_CPU0_SA_DQ(31)

Q_CAP_C0402-2.2UF,6.3V,20%,X6SA  I121  C41
   1 P3V3_AUX      A @S9S_MB_2U_LIB.S9S_MB_2U(SCH_1):P3V3_AUX
   2    GND      B @S9S_MB_2U_LIB.S9S_MB_2U(SCH_1):GND

Q_CAP_C0805-10UF,16V,10%,X6S,CA  I125  C42
   1 P12V_S3_AUX_CPU0_NVDIMM      A @S9S_MB_2U_LIB.S9S_MB_2U(SCH_1):P12V_S3_AUX_CPU0_NVDIMM
   2    GND      B @S9S_MB_2U_LIB.S9S_MB_2U(SCH_1):GND

Q_CAP_C0805-10UF,16V,10%,X6S,CA  I128  C43
   1 P12V_S3_AUX_CPU0_NVDIMM      A @S9S_MB_2U_LIB.S9S_MB_2U(SCH_1):P12V_S3_AUX_CPU0_NVDIMM
   2    GND      B @S9S_MB_2U_LIB.S9S_MB_2U(SCH_1):GND

SCONN288_ADR50017P087CC-SCONN2A  I176  J14
   6    GND   VSS0 @S9S_MB_2U_LIB.S9S_MB_2U(SCH_1):GND
   8    GND   VSS1 @S9S_MB_2U_LIB.S9S_MB_2U(SCH_1):GND
  10    GND   VSS2 @S9S_MB_2U_LIB.S9S_MB_2U(SCH_1):GND
  13    GND   VSS3 @S9S_MB_2U_LIB.S9S_MB_2U(SCH_1):GND
  15    GND   VSS4 @S9S_MB_2U_LIB.S9S_MB_2U(SCH_1):GND
  17    GND   VSS5 @S9S_MB_2U_LIB.S9S_MB_2U(SCH_1):GND
  19    GND   VSS6 @S9S_MB_2U_LIB.S9S_MB_2U(SCH_1):GND
  21    GND   VSS7 @S9S_MB_2U_LIB.S9S_MB_2U(SCH_1):GND
  24    GND   VSS8 @S9S_MB_2U_LIB.S9S_MB_2U(SCH_1):GND
  26    GND   VSS9 @S9S_MB_2U_LIB.S9S_MB_2U(SCH_1):GND
  28    GND  VSS10 @S9S_MB_2U_LIB.S9S_MB_2U(SCH_1):GND
  30    GND  VSS11 @S9S_MB_2U_LIB.S9S_MB_2U(SCH_1):GND
  32    GND  VSS12 @S9S_MB_2U_LIB.S9S_MB_2U(SCH_1):GND
  35    GND  VSS13 @S9S_MB_2U_LIB.S9S_MB_2U(SCH_1):GND
  37    GND  VSS14 @S9S_MB_2U_LIB.S9S_MB_2U(SCH_1):GND
  39    GND  VSS15 @S9S_MB_2U_LIB.S9S_MB_2U(SCH_1):GND
  41    GND  VSS16 @S9S_MB_2U_LIB.S9S_MB_2U(SCH_1):GND
  43    GND  VSS17 @S9S_MB_2U_LIB.S9S_MB_2U(SCH_1):GND
  46    GND  VSS18 @S9S_MB_2U_LIB.S9S_MB_2U(SCH_1):GND
  48    GND  VSS19 @S9S_MB_2U_LIB.S9S_MB_2U(SCH_1):GND
  50    GND  VSS20 @S9S_MB_2U_LIB.S9S_MB_2U(SCH_1):GND
  52    GND  VSS21 @S9S_MB_2U_LIB.S9S_MB_2U(SCH_1):GND
  54    GND  VSS22 @S9S_MB_2U_LIB.S9S_MB_2U(SCH_1):GND
  57    GND  VSS23 @S9S_MB_2U_LIB.S9S_MB_2U(SCH_1):GND
  59    GND  VSS24 @S9S_MB_2U_LIB.S9S_MB_2U(SCH_1):GND
  61    GND  VSS25 @S9S_MB_2U_LIB.S9S_MB_2U(SCH_1):GND
  63    GND  VSS26 @S9S_MB_2U_LIB.S9S_MB_2U(SCH_1):GND
  65    GND  VSS27 @S9S_MB_2U_LIB.S9S_MB_2U(SCH_1):GND
  67    GND  VSS28 @S9S_MB_2U_LIB.S9S_MB_2U(SCH_1):GND
  69    GND  VSS29 @S9S_MB_2U_LIB.S9S_MB_2U(SCH_1):GND
  71    GND  VSS30 @S9S_MB_2U_LIB.S9S_MB_2U(SCH_1):GND
  73    GND  VSS31 @S9S_MB_2U_LIB.S9S_MB_2U(SCH_1):GND
  75    GND  VSS32 @S9S_MB_2U_LIB.S9S_MB_2U(SCH_1):GND
  77    GND  VSS33 @S9S_MB_2U_LIB.S9S_MB_2U(SCH_1):GND
  79    GND  VSS34 @S9S_MB_2U_LIB.S9S_MB_2U(SCH_1):GND
  81    GND  VSS35 @S9S_MB_2U_LIB.S9S_MB_2U(SCH_1):GND
  83    GND  VSS36 @S9S_MB_2U_LIB.S9S_MB_2U(SCH_1):GND
  85    GND  VSS37 @S9S_MB_2U_LIB.S9S_MB_2U(SCH_1):GND
  88    GND  VSS38 @S9S_MB_2U_LIB.S9S_MB_2U(SCH_1):GND
  90    GND  VSS39 @S9S_MB_2U_LIB.S9S_MB_2U(SCH_1):GND
  92    GND  VSS40 @S9S_MB_2U_LIB.S9S_MB_2U(SCH_1):GND
  95    GND  VSS41 @S9S_MB_2U_LIB.S9S_MB_2U(SCH_1):GND
  97    GND  VSS42 @S9S_MB_2U_LIB.S9S_MB_2U(SCH_1):GND
  99    GND  VSS43 @S9S_MB_2U_LIB.S9S_MB_2U(SCH_1):GND
 101    GND  VSS44 @S9S_MB_2U_LIB.S9S_MB_2U(SCH_1):GND
 103    GND  VSS45 @S9S_MB_2U_LIB.S9S_MB_2U(SCH_1):GND
 106    GND  VSS46 @S9S_MB_2U_LIB.S9S_MB_2U(SCH_1):GND
 108    GND  VSS47 @S9S_MB_2U_LIB.S9S_MB_2U(SCH_1):GND
 110    GND  VSS48 @S9S_MB_2U_LIB.S9S_MB_2U(SCH_1):GND
 112    GND  VSS49 @S9S_MB_2U_LIB.S9S_MB_2U(SCH_1):GND
 114    GND  VSS50 @S9S_MB_2U_LIB.S9S_MB_2U(SCH_1):GND
 117    GND  VSS51 @S9S_MB_2U_LIB.S9S_MB_2U(SCH_1):GND
 119    GND  VSS52 @S9S_MB_2U_LIB.S9S_MB_2U(SCH_1):GND
 121    GND  VSS53 @S9S_MB_2U_LIB.S9S_MB_2U(SCH_1):GND
 123    GND  VSS54 @S9S_MB_2U_LIB.S9S_MB_2U(SCH_1):GND
 125    GND  VSS55 @S9S_MB_2U_LIB.S9S_MB_2U(SCH_1):GND
 128    GND  VSS56 @S9S_MB_2U_LIB.S9S_MB_2U(SCH_1):GND
 130    GND  VSS57 @S9S_MB_2U_LIB.S9S_MB_2U(SCH_1):GND
 134    GND  VSS59 @S9S_MB_2U_LIB.S9S_MB_2U(SCH_1):GND
 143    GND  VSS63 @S9S_MB_2U_LIB.S9S_MB_2U(SCH_1):GND
 151    GND  VSS64 @S9S_MB_2U_LIB.S9S_MB_2U(SCH_1):GND
 153    GND  VSS65 @S9S_MB_2U_LIB.S9S_MB_2U(SCH_1):GND
 155    GND  VSS66 @S9S_MB_2U_LIB.S9S_MB_2U(SCH_1):GND
 158    GND  VSS67 @S9S_MB_2U_LIB.S9S_MB_2U(SCH_1):GND
 160    GND  VSS68 @S9S_MB_2U_LIB.S9S_MB_2U(SCH_1):GND
 162    GND  VSS69 @S9S_MB_2U_LIB.S9S_MB_2U(SCH_1):GND
 164    GND  VSS70 @S9S_MB_2U_LIB.S9S_MB_2U(SCH_1):GND
 166    GND  VSS71 @S9S_MB_2U_LIB.S9S_MB_2U(SCH_1):GND
 169    GND  VSS72 @S9S_MB_2U_LIB.S9S_MB_2U(SCH_1):GND
 171    GND  VSS73 @S9S_MB_2U_LIB.S9S_MB_2U(SCH_1):GND
 173    GND  VSS74 @S9S_MB_2U_LIB.S9S_MB_2U(SCH_1):GND
 175    GND  VSS75 @S9S_MB_2U_LIB.S9S_MB_2U(SCH_1):GND
 177    GND  VSS76 @S9S_MB_2U_LIB.S9S_MB_2U(SCH_1):GND
 180    GND  VSS77 @S9S_MB_2U_LIB.S9S_MB_2U(SCH_1):GND
 182    GND  VSS78 @S9S_MB_2U_LIB.S9S_MB_2U(SCH_1):GND
 184    GND  VSS79 @S9S_MB_2U_LIB.S9S_MB_2U(SCH_1):GND
 186    GND  VSS80 @S9S_MB_2U_LIB.S9S_MB_2U(SCH_1):GND
 188    GND  VSS81 @S9S_MB_2U_LIB.S9S_MB_2U(SCH_1):GND
 191    GND  VSS82 @S9S_MB_2U_LIB.S9S_MB_2U(SCH_1):GND
 193    GND  VSS83 @S9S_MB_2U_LIB.S9S_MB_2U(SCH_1):GND
 195    GND  VSS84 @S9S_MB_2U_LIB.S9S_MB_2U(SCH_1):GND
 197    GND  VSS85 @S9S_MB_2U_LIB.S9S_MB_2U(SCH_1):GND
 199    GND  VSS86 @S9S_MB_2U_LIB.S9S_MB_2U(SCH_1):GND
 202    GND  VSS87 @S9S_MB_2U_LIB.S9S_MB_2U(SCH_1):GND
 204    GND  VSS88 @S9S_MB_2U_LIB.S9S_MB_2U(SCH_1):GND
 206    GND  VSS89 @S9S_MB_2U_LIB.S9S_MB_2U(SCH_1):GND
 208    GND  VSS90 @S9S_MB_2U_LIB.S9S_MB_2U(SCH_1):GND
 210    GND  VSS91 @S9S_MB_2U_LIB.S9S_MB_2U(SCH_1):GND
 212    GND  VSS92 @S9S_MB_2U_LIB.S9S_MB_2U(SCH_1):GND
 214    GND  VSS93 @S9S_MB_2U_LIB.S9S_MB_2U(SCH_1):GND
 216    GND  VSS94 @S9S_MB_2U_LIB.S9S_MB_2U(SCH_1):GND
 219    GND  VSS95 @S9S_MB_2U_LIB.S9S_MB_2U(SCH_1):GND
 222    GND  VSS96 @S9S_MB_2U_LIB.S9S_MB_2U(SCH_1):GND
 224    GND  VSS97 @S9S_MB_2U_LIB.S9S_MB_2U(SCH_1):GND
 226    GND  VSS98 @S9S_MB_2U_LIB.S9S_MB_2U(SCH_1):GND
 228    GND  VSS99 @S9S_MB_2U_LIB.S9S_MB_2U(SCH_1):GND
 233    GND VSS101 @S9S_MB_2U_LIB.S9S_MB_2U(SCH_1):GND
 237    GND VSS103 @S9S_MB_2U_LIB.S9S_MB_2U(SCH_1):GND
 242    GND VSS105 @S9S_MB_2U_LIB.S9S_MB_2U(SCH_1):GND
 244    GND VSS106 @S9S_MB_2U_LIB.S9S_MB_2U(SCH_1):GND
 246    GND VSS107 @S9S_MB_2U_LIB.S9S_MB_2U(SCH_1):GND
 248    GND VSS108 @S9S_MB_2U_LIB.S9S_MB_2U(SCH_1):GND
 251    GND VSS109 @S9S_MB_2U_LIB.S9S_MB_2U(SCH_1):GND
 253    GND VSS110 @S9S_MB_2U_LIB.S9S_MB_2U(SCH_1):GND
 255    GND VSS111 @S9S_MB_2U_LIB.S9S_MB_2U(SCH_1):GND
 257    GND VSS112 @S9S_MB_2U_LIB.S9S_MB_2U(SCH_1):GND
 259    GND VSS113 @S9S_MB_2U_LIB.S9S_MB_2U(SCH_1):GND
 262    GND VSS114 @S9S_MB_2U_LIB.S9S_MB_2U(SCH_1):GND
 264    GND VSS115 @S9S_MB_2U_LIB.S9S_MB_2U(SCH_1):GND
 266    GND VSS116 @S9S_MB_2U_LIB.S9S_MB_2U(SCH_1):GND
 268    GND VSS117 @S9S_MB_2U_LIB.S9S_MB_2U(SCH_1):GND
 270    GND VSS118 @S9S_MB_2U_LIB.S9S_MB_2U(SCH_1):GND
 273    GND VSS119 @S9S_MB_2U_LIB.S9S_MB_2U(SCH_1):GND
 275    GND VSS120 @S9S_MB_2U_LIB.S9S_MB_2U(SCH_1):GND
 277    GND VSS121 @S9S_MB_2U_LIB.S9S_MB_2U(SCH_1):GND
 279    GND VSS122 @S9S_MB_2U_LIB.S9S_MB_2U(SCH_1):GND
 281    GND VSS123 @S9S_MB_2U_LIB.S9S_MB_2U(SCH_1):GND
 284    GND VSS124 @S9S_MB_2U_LIB.S9S_MB_2U(SCH_1):GND
 286    GND VSS125 @S9S_MB_2U_LIB.S9S_MB_2U(SCH_1):GND
 288    GND VSS126 @S9S_MB_2U_LIB.S9S_MB_2U(SCH_1):GND
   1 P12V_S3_AUX_CPU0_NVDIMM VIN_BULK0 @S9S_MB_2U_LIB.S9S_MB_2U(SCH_1):P12V_S3_AUX_CPU0_NVDIMM
 145 P12V_S3_AUX_CPU0_NVDIMM VIN_BULK1 @S9S_MB_2U_LIB.S9S_MB_2U(SCH_1):P12V_S3_AUX_CPU0_NVDIMM
 146 P12V_S3_AUX_CPU0_NVDIMM VIN_BULK2 @S9S_MB_2U_LIB.S9S_MB_2U(SCH_1):P12V_S3_AUX_CPU0_NVDIMM
 230    GND VSS100 @S9S_MB_2U_LIB.S9S_MB_2U(SCH_1):GND
 235    GND VSS102 @S9S_MB_2U_LIB.S9S_MB_2U(SCH_1):GND
 240    GND VSS104 @S9S_MB_2U_LIB.S9S_MB_2U(SCH_1):GND
 132    GND  VSS58 @S9S_MB_2U_LIB.S9S_MB_2U(SCH_1):GND
 136    GND  VSS60 @S9S_MB_2U_LIB.S9S_MB_2U(SCH_1):GND
 139    GND  VSS61 @S9S_MB_2U_LIB.S9S_MB_2U(SCH_1):GND
 141    GND  VSS62 @S9S_MB_2U_LIB.S9S_MB_2U(SCH_1):GND
  G1    GND     G1 @S9S_MB_2U_LIB.S9S_MB_2U(SCH_1):GND
  G2    GND     G2 @S9S_MB_2U_LIB.S9S_MB_2U(SCH_1):GND
  G3    GND     G3 @S9S_MB_2U_LIB.S9S_MB_2U(SCH_1):GND

SCONN288_ADR50017P087CC-SCONN2A  I178  J14
  93 M_G_CPU0_SB_DQS_DP<9> DQS9_B_T||TDQS9_B_T||DBI4_B_N @S9S_MB_2U_LIB.S9S_MB_2U(SCH_1):M_G_CPU0_SB_DQS_DP(9)
  94 M_G_CPU0_SB_DQS_DN<9> DQS9_B_C||TDQS9_B_C @S9S_MB_2U_LIB.S9S_MB_2U(SCH_1):M_G_CPU0_SB_DQS_DN(9)
 201 M_G_CPU0_SA_DQS_DP<9> DQS9_A_T||TDQS9_A_T @S9S_MB_2U_LIB.S9S_MB_2U(SCH_1):M_G_CPU0_SA_DQS_DP(9)
 200 M_G_CPU0_SA_DQS_DN<9> DQS9_A_C||TDQS9_A_C @S9S_MB_2U_LIB.S9S_MB_2U(SCH_1):M_G_CPU0_SA_DQS_DN(9)
 190 M_G_CPU0_SA_DQS_DP<8> DQS8_A_T||TDQS8_A_T @S9S_MB_2U_LIB.S9S_MB_2U(SCH_1):M_G_CPU0_SA_DQS_DP(8)
 189 M_G_CPU0_SA_DQS_DN<8> DQS8_A_C||TDQS8_A_C @S9S_MB_2U_LIB.S9S_MB_2U(SCH_1):M_G_CPU0_SA_DQS_DN(8)
 271 M_G_CPU0_SB_DQS_DN<7> DQS7_B_C||TDQS7_B_C @S9S_MB_2U_LIB.S9S_MB_2U(SCH_1):M_G_CPU0_SB_DQS_DN(7)
 179 M_G_CPU0_SA_DQS_DP<7> DQS7_A_T||TDQS7_A_T @S9S_MB_2U_LIB.S9S_MB_2U(SCH_1):M_G_CPU0_SA_DQS_DP(7)
 261 M_G_CPU0_SB_DQS_DP<6> DQS6_B_T||TDQS6_B_T @S9S_MB_2U_LIB.S9S_MB_2U(SCH_1):M_G_CPU0_SB_DQS_DP(6)
 260 M_G_CPU0_SB_DQS_DN<6> DQS6_B_C||TDQS6_B_C @S9S_MB_2U_LIB.S9S_MB_2U(SCH_1):M_G_CPU0_SB_DQS_DN(6)
 167 M_G_CPU0_SA_DQS_DN<6> DQS6_A_C||TDQS6_A_C||DQS6_A_T||TDQS6_A_T @S9S_MB_2U_LIB.S9S_MB_2U(SCH_1):M_G_CPU0_SA_DQS_DN(6)
 250 M_G_CPU0_SB_DQS_DP<5> DQS5_B_T||TDQS5_B_T @S9S_MB_2U_LIB.S9S_MB_2U(SCH_1):M_G_CPU0_SB_DQS_DP(5)
 249 M_G_CPU0_SB_DQS_DN<5> DQS5_B_C||TDQS5_B_C @S9S_MB_2U_LIB.S9S_MB_2U(SCH_1):M_G_CPU0_SB_DQS_DN(5)
 157 M_G_CPU0_SA_DQS_DP<5> DQS5_A_T||TDQS5_A_T @S9S_MB_2U_LIB.S9S_MB_2U(SCH_1):M_G_CPU0_SA_DQS_DP(5)
 156 M_G_CPU0_SA_DQS_DN<5> DQS5_A_C||TDQS5_A_C||DQS5_A_T||TDQS5_A_T @S9S_MB_2U_LIB.S9S_MB_2U(SCH_1):M_G_CPU0_SA_DQS_DN(5)
 239 M_G_CPU0_SB_DQS_DP<4> DQS4_B_T @S9S_MB_2U_LIB.S9S_MB_2U(SCH_1):M_G_CPU0_SB_DQS_DP(4)
 238 M_G_CPU0_SB_DQS_DN<4> DQS4_B_C @S9S_MB_2U_LIB.S9S_MB_2U(SCH_1):M_G_CPU0_SB_DQS_DN(4)
  55 M_G_CPU0_SA_DQS_DP<4> DQS4_A_T @S9S_MB_2U_LIB.S9S_MB_2U(SCH_1):M_G_CPU0_SA_DQS_DP(4)
  56 M_G_CPU0_SA_DQS_DN<4> DQS4_A_C @S9S_MB_2U_LIB.S9S_MB_2U(SCH_1):M_G_CPU0_SA_DQS_DN(4)
 137 M_G_CPU0_SB_DQS_DP<3> DQS3_B_T @S9S_MB_2U_LIB.S9S_MB_2U(SCH_1):M_G_CPU0_SB_DQS_DP(3)
 138 M_G_CPU0_SB_DQS_DN<3> DQS3_B_C @S9S_MB_2U_LIB.S9S_MB_2U(SCH_1):M_G_CPU0_SB_DQS_DN(3)
  44 M_G_CPU0_SA_DQS_DP<3> DQS3_A_T @S9S_MB_2U_LIB.S9S_MB_2U(SCH_1):M_G_CPU0_SA_DQS_DP(3)
  45 M_G_CPU0_SA_DQS_DN<3> DQS3_A_C @S9S_MB_2U_LIB.S9S_MB_2U(SCH_1):M_G_CPU0_SA_DQS_DN(3)
 126 M_G_CPU0_SB_DQS_DP<2> DQS2_B_T @S9S_MB_2U_LIB.S9S_MB_2U(SCH_1):M_G_CPU0_SB_DQS_DP(2)
 127 M_G_CPU0_SB_DQS_DN<2> DQS2_B_C @S9S_MB_2U_LIB.S9S_MB_2U(SCH_1):M_G_CPU0_SB_DQS_DN(2)
  33 M_G_CPU0_SA_DQS_DP<2> DQS2_A_T @S9S_MB_2U_LIB.S9S_MB_2U(SCH_1):M_G_CPU0_SA_DQS_DP(2)
  34 M_G_CPU0_SA_DQS_DN<2> DQS2_A_C @S9S_MB_2U_LIB.S9S_MB_2U(SCH_1):M_G_CPU0_SA_DQS_DN(2)
 115 M_G_CPU0_SB_DQS_DP<1> DQS1_B_T @S9S_MB_2U_LIB.S9S_MB_2U(SCH_1):M_G_CPU0_SB_DQS_DP(1)
 116 M_G_CPU0_SB_DQS_DN<1> DQS1_B_C @S9S_MB_2U_LIB.S9S_MB_2U(SCH_1):M_G_CPU0_SB_DQS_DN(1)
  22 M_G_CPU0_SA_DQS_DP<1> DQS1_A_T @S9S_MB_2U_LIB.S9S_MB_2U(SCH_1):M_G_CPU0_SA_DQS_DP(1)
  23 M_G_CPU0_SA_DQS_DN<1> DQS1_A_C @S9S_MB_2U_LIB.S9S_MB_2U(SCH_1):M_G_CPU0_SA_DQS_DN(1)
 104 M_G_CPU0_SB_DQS_DP<0> DQS0_B_T @S9S_MB_2U_LIB.S9S_MB_2U(SCH_1):M_G_CPU0_SB_DQS_DP(0)
 105 M_G_CPU0_SB_DQS_DN<0> DQS0_B_C @S9S_MB_2U_LIB.S9S_MB_2U(SCH_1):M_G_CPU0_SB_DQS_DN(0)
  11 M_G_CPU0_SA_DQS_DP<0> DQS0_A_T @S9S_MB_2U_LIB.S9S_MB_2U(SCH_1):M_G_CPU0_SA_DQS_DP(0)
  12 M_G_CPU0_SA_DQS_DN<0> DQS0_A_C @S9S_MB_2U_LIB.S9S_MB_2U(SCH_1):M_G_CPU0_SA_DQS_DN(0)
 272 M_G_CPU0_SB_DQS_DP<7> DQS7_B_T||TDQS7_B_T @S9S_MB_2U_LIB.S9S_MB_2U(SCH_1):M_G_CPU0_SB_DQS_DP(7)
 282 M_G_CPU0_SB_DQS_DN<8> DQS8_B_C||TDQS8_B_C @S9S_MB_2U_LIB.S9S_MB_2U(SCH_1):M_G_CPU0_SB_DQS_DN(8)
 283 M_G_CPU0_SB_DQS_DP<8> DQS8_B_T||TDQS8_B_T @S9S_MB_2U_LIB.S9S_MB_2U(SCH_1):M_G_CPU0_SB_DQS_DP(8)
 168 M_G_CPU0_SA_DQS_DP<6> DQS6_A_T||TDQS6_A_T @S9S_MB_2U_LIB.S9S_MB_2U(SCH_1):M_G_CPU0_SA_DQS_DP(6)
 178 M_G_CPU0_SA_DQS_DN<7> DQS7_A_C||TDQS7_A_C @S9S_MB_2U_LIB.S9S_MB_2U(SCH_1):M_G_CPU0_SA_DQS_DN(7)

Q_RES_0402LF-49.9,1%,1/16W,CHIA  I179  R3888
   1 I3C_SPD_DDREFGH_CPU0_LVC1_SCL_5      A @S9S_MB_2U_LIB.S9S_MB_2U(SCH_1):I3C_SPD_DDREFGH_CPU0_LVC1_SCL_R6
   2 I3C_SPD_DDREFGH_CPU0_LVC1_SCL      B @S9S_MB_2U_LIB.S9S_MB_2U(SCH_1):I3C_SPD_DDREFGH_CPU0_LVC1_SCL


DRAWING: @S9S_MB_2U_LIB.S9S_MB_2U(SCH_1):PAGE96 

Q_RES_0402LF-127K,1%,1/16W,CHIA  I47  R40
   1 PD_CHH_CPU0_DIMM1_SAA      A @S9S_MB_2U_LIB.S9S_MB_2U(SCH_1):PD_CHH_CPU0_DIMM1_SAA
   2    GND      B @S9S_MB_2U_LIB.S9S_MB_2U(SCH_1):GND

SCONN288_ADR50017P130CC-SCONN2A  I48  J15
   3 P3V3_AUX VIN_MGMT @S9S_MB_2U_LIB.S9S_MB_2U(SCH_1):P3V3_AUX
   2 TP_CHH_CPU0_DIMM1_FRU_0   RFU0 @S9S_MB_2U_LIB.S9S_MB_2U(SCH_1):TP_CHH_CPU0_DIMM1_FRU_0
 144 TP_CHH_CPU0_DIMM1_FRU_1   RFU1 @S9S_MB_2U_LIB.S9S_MB_2U(SCH_1):TP_CHH_CPU0_DIMM1_FRU_1
 149 TP_CHH_CPU0_DIMM1_FRU_2   RFU2 @S9S_MB_2U_LIB.S9S_MB_2U(SCH_1):TP_CHH_CPU0_DIMM1_FRU_2
 150 TP_CHH_CPU0_DIMM1_FRU_3   RFU3 @S9S_MB_2U_LIB.S9S_MB_2U(SCH_1):TP_CHH_CPU0_DIMM1_FRU_3
 220 TP_CHH_CPU0_DIMM1_FRU_4   RFU4 @S9S_MB_2U_LIB.S9S_MB_2U(SCH_1):TP_CHH_CPU0_DIMM1_FRU_4
 231 TP_CHH_CPU0_DIMM1_FRU_5   RFU5 @S9S_MB_2U_LIB.S9S_MB_2U(SCH_1):TP_CHH_CPU0_DIMM1_FRU_5
 232 TP_CHH_CPU0_DIMM1_FRU_6   RFU6 @S9S_MB_2U_LIB.S9S_MB_2U(SCH_1):TP_CHH_CPU0_DIMM1_FRU_6
 207 RST_M_GH_CPU0_FPGA_N RESET_N @S9S_MB_2U_LIB.S9S_MB_2U(SCH_1):RST_M_GH_CPU0_FPGA_N
 147 PWRGD_CHH_CPU0_DIMM1 PWR_GOOD||FAIL_N @S9S_MB_2U_LIB.S9S_MB_2U(SCH_1):PWRGD_CHH_CPU0_DIMM1
 227 M_H_CPU0_SB_PAR  PAR_B @S9S_MB_2U_LIB.S9S_MB_2U(SCH_1):M_H_CPU0_SB_PAR
  74 M_H_CPU0_SA_PAR  PAR_A @S9S_MB_2U_LIB.S9S_MB_2U(SCH_1):M_H_CPU0_SA_PAR
  87 M_H_CPU0_SB_RSP<0> LBS||RSP_B_N @S9S_MB_2U_LIB.S9S_MB_2U(SCH_1):M_H_CPU0_SB_RSP(0)
  86 M_H_CPU0_SA_RSP<0> LBD||RSP_A_N @S9S_MB_2U_LIB.S9S_MB_2U(SCH_1):M_H_CPU0_SA_RSP(0)
   5 I3C_SPD_DDREFGH_CPU0_LVC1_SDA   HSDA @S9S_MB_2U_LIB.S9S_MB_2U(SCH_1):I3C_SPD_DDREFGH_CPU0_LVC1_SDA
   4 I3C_SPD_DDREFGH_CPU0_LVC1_SCL_6   HSCL @S9S_MB_2U_LIB.S9S_MB_2U(SCH_1):I3C_SPD_DDREFGH_CPU0_LVC1_SCL_R7
 148 PD_CHH_CPU0_DIMM1_SAA    HSA @S9S_MB_2U_LIB.S9S_MB_2U(SCH_1):PD_CHH_CPU0_DIMM1_SAA
 100 M_H_CPU0_SB_DQ<0>  DQ0_B @S9S_MB_2U_LIB.S9S_MB_2U(SCH_1):M_H_CPU0_SB_DQ(0)
 102 M_H_CPU0_SB_DQ<1>  DQ1_B @S9S_MB_2U_LIB.S9S_MB_2U(SCH_1):M_H_CPU0_SB_DQ(1)
 245 M_H_CPU0_SB_DQ<2>  DQ2_B @S9S_MB_2U_LIB.S9S_MB_2U(SCH_1):M_H_CPU0_SB_DQ(2)
 247 M_H_CPU0_SB_DQ<3>  DQ3_B @S9S_MB_2U_LIB.S9S_MB_2U(SCH_1):M_H_CPU0_SB_DQ(3)
 107 M_H_CPU0_SB_DQ<4>  DQ4_B @S9S_MB_2U_LIB.S9S_MB_2U(SCH_1):M_H_CPU0_SB_DQ(4)
 109 M_H_CPU0_SB_DQ<5>  DQ5_B @S9S_MB_2U_LIB.S9S_MB_2U(SCH_1):M_H_CPU0_SB_DQ(5)
 252 M_H_CPU0_SB_DQ<6>  DQ6_B @S9S_MB_2U_LIB.S9S_MB_2U(SCH_1):M_H_CPU0_SB_DQ(6)
 254 M_H_CPU0_SB_DQ<7>  DQ7_B @S9S_MB_2U_LIB.S9S_MB_2U(SCH_1):M_H_CPU0_SB_DQ(7)
 111 M_H_CPU0_SB_DQ<8>  DQ8_B @S9S_MB_2U_LIB.S9S_MB_2U(SCH_1):M_H_CPU0_SB_DQ(8)
 113 M_H_CPU0_SB_DQ<9>  DQ9_B @S9S_MB_2U_LIB.S9S_MB_2U(SCH_1):M_H_CPU0_SB_DQ(9)
 256 M_H_CPU0_SB_DQ<10> DQ10_B @S9S_MB_2U_LIB.S9S_MB_2U(SCH_1):M_H_CPU0_SB_DQ(10)
 258 M_H_CPU0_SB_DQ<11> DQ11_B @S9S_MB_2U_LIB.S9S_MB_2U(SCH_1):M_H_CPU0_SB_DQ(11)
 118 M_H_CPU0_SB_DQ<12> DQ12_B @S9S_MB_2U_LIB.S9S_MB_2U(SCH_1):M_H_CPU0_SB_DQ(12)
 120 M_H_CPU0_SB_DQ<13> DQ13_B @S9S_MB_2U_LIB.S9S_MB_2U(SCH_1):M_H_CPU0_SB_DQ(13)
 263 M_H_CPU0_SB_DQ<14> DQ14_B @S9S_MB_2U_LIB.S9S_MB_2U(SCH_1):M_H_CPU0_SB_DQ(14)
 265 M_H_CPU0_SB_DQ<15> DQ15_B @S9S_MB_2U_LIB.S9S_MB_2U(SCH_1):M_H_CPU0_SB_DQ(15)
 122 M_H_CPU0_SB_DQ<16> DQ16_B @S9S_MB_2U_LIB.S9S_MB_2U(SCH_1):M_H_CPU0_SB_DQ(16)
 124 M_H_CPU0_SB_DQ<17> DQ17_B @S9S_MB_2U_LIB.S9S_MB_2U(SCH_1):M_H_CPU0_SB_DQ(17)
 267 M_H_CPU0_SB_DQ<18> DQ18_B @S9S_MB_2U_LIB.S9S_MB_2U(SCH_1):M_H_CPU0_SB_DQ(18)
 269 M_H_CPU0_SB_DQ<19> DQ19_B @S9S_MB_2U_LIB.S9S_MB_2U(SCH_1):M_H_CPU0_SB_DQ(19)
 129 M_H_CPU0_SB_DQ<20> DQ20_B @S9S_MB_2U_LIB.S9S_MB_2U(SCH_1):M_H_CPU0_SB_DQ(20)
 131 M_H_CPU0_SB_DQ<21> DQ21_B @S9S_MB_2U_LIB.S9S_MB_2U(SCH_1):M_H_CPU0_SB_DQ(21)
 274 M_H_CPU0_SB_DQ<22> DQ22_B @S9S_MB_2U_LIB.S9S_MB_2U(SCH_1):M_H_CPU0_SB_DQ(22)
 276 M_H_CPU0_SB_DQ<23> DQ23_B @S9S_MB_2U_LIB.S9S_MB_2U(SCH_1):M_H_CPU0_SB_DQ(23)
 133 M_H_CPU0_SB_DQ<24> DQ24_B @S9S_MB_2U_LIB.S9S_MB_2U(SCH_1):M_H_CPU0_SB_DQ(24)
 135 M_H_CPU0_SB_DQ<25> DQ25_B @S9S_MB_2U_LIB.S9S_MB_2U(SCH_1):M_H_CPU0_SB_DQ(25)
 278 M_H_CPU0_SB_DQ<26> DQ26_B @S9S_MB_2U_LIB.S9S_MB_2U(SCH_1):M_H_CPU0_SB_DQ(26)
 280 M_H_CPU0_SB_DQ<27> DQ27_B @S9S_MB_2U_LIB.S9S_MB_2U(SCH_1):M_H_CPU0_SB_DQ(27)
 140 M_H_CPU0_SB_DQ<28> DQ28_B @S9S_MB_2U_LIB.S9S_MB_2U(SCH_1):M_H_CPU0_SB_DQ(28)
 142 M_H_CPU0_SB_DQ<29> DQ29_B @S9S_MB_2U_LIB.S9S_MB_2U(SCH_1):M_H_CPU0_SB_DQ(29)
 285 M_H_CPU0_SB_DQ<30> DQ30_B @S9S_MB_2U_LIB.S9S_MB_2U(SCH_1):M_H_CPU0_SB_DQ(30)
 287 M_H_CPU0_SB_DQ<31> DQ31_B @S9S_MB_2U_LIB.S9S_MB_2U(SCH_1):M_H_CPU0_SB_DQ(31)
   7 M_H_CPU0_SA_DQ<0>  DQ0_A @S9S_MB_2U_LIB.S9S_MB_2U(SCH_1):M_H_CPU0_SA_DQ(0)
   9 M_H_CPU0_SA_DQ<1>  DQ1_A @S9S_MB_2U_LIB.S9S_MB_2U(SCH_1):M_H_CPU0_SA_DQ(1)
 152 M_H_CPU0_SA_DQ<2>  DQ2_A @S9S_MB_2U_LIB.S9S_MB_2U(SCH_1):M_H_CPU0_SA_DQ(2)
 154 M_H_CPU0_SA_DQ<3>  DQ3_A @S9S_MB_2U_LIB.S9S_MB_2U(SCH_1):M_H_CPU0_SA_DQ(3)
  14 M_H_CPU0_SA_DQ<4>  DQ4_A @S9S_MB_2U_LIB.S9S_MB_2U(SCH_1):M_H_CPU0_SA_DQ(4)
  16 M_H_CPU0_SA_DQ<5>  DQ5_A @S9S_MB_2U_LIB.S9S_MB_2U(SCH_1):M_H_CPU0_SA_DQ(5)
 159 M_H_CPU0_SA_DQ<6>  DQ6_A @S9S_MB_2U_LIB.S9S_MB_2U(SCH_1):M_H_CPU0_SA_DQ(6)
 161 M_H_CPU0_SA_DQ<7>  DQ7_A @S9S_MB_2U_LIB.S9S_MB_2U(SCH_1):M_H_CPU0_SA_DQ(7)
  18 M_H_CPU0_SA_DQ<8>  DQ8_A @S9S_MB_2U_LIB.S9S_MB_2U(SCH_1):M_H_CPU0_SA_DQ(8)
  20 M_H_CPU0_SA_DQ<9>  DQ9_A @S9S_MB_2U_LIB.S9S_MB_2U(SCH_1):M_H_CPU0_SA_DQ(9)
 163 M_H_CPU0_SA_DQ<10> DQ10_A @S9S_MB_2U_LIB.S9S_MB_2U(SCH_1):M_H_CPU0_SA_DQ(10)
 165 M_H_CPU0_SA_DQ<11> DQ11_A @S9S_MB_2U_LIB.S9S_MB_2U(SCH_1):M_H_CPU0_SA_DQ(11)
  25 M_H_CPU0_SA_DQ<12> DQ12_A @S9S_MB_2U_LIB.S9S_MB_2U(SCH_1):M_H_CPU0_SA_DQ(12)
  27 M_H_CPU0_SA_DQ<13> DQ13_A @S9S_MB_2U_LIB.S9S_MB_2U(SCH_1):M_H_CPU0_SA_DQ(13)
 170 M_H_CPU0_SA_DQ<14> DQ14_A @S9S_MB_2U_LIB.S9S_MB_2U(SCH_1):M_H_CPU0_SA_DQ(14)
 172 M_H_CPU0_SA_DQ<15> DQ15_A @S9S_MB_2U_LIB.S9S_MB_2U(SCH_1):M_H_CPU0_SA_DQ(15)
  29 M_H_CPU0_SA_DQ<16> DQ16_A @S9S_MB_2U_LIB.S9S_MB_2U(SCH_1):M_H_CPU0_SA_DQ(16)
  31 M_H_CPU0_SA_DQ<17> DQ17_A @S9S_MB_2U_LIB.S9S_MB_2U(SCH_1):M_H_CPU0_SA_DQ(17)
 174 M_H_CPU0_SA_DQ<18> DQ18_A @S9S_MB_2U_LIB.S9S_MB_2U(SCH_1):M_H_CPU0_SA_DQ(18)
 176 M_H_CPU0_SA_DQ<19> DQ19_A @S9S_MB_2U_LIB.S9S_MB_2U(SCH_1):M_H_CPU0_SA_DQ(19)
  36 M_H_CPU0_SA_DQ<20> DQ20_A @S9S_MB_2U_LIB.S9S_MB_2U(SCH_1):M_H_CPU0_SA_DQ(20)
  38 M_H_CPU0_SA_DQ<21> DQ21_A @S9S_MB_2U_LIB.S9S_MB_2U(SCH_1):M_H_CPU0_SA_DQ(21)
 181 M_H_CPU0_SA_DQ<22> DQ22_A @S9S_MB_2U_LIB.S9S_MB_2U(SCH_1):M_H_CPU0_SA_DQ(22)
 183 M_H_CPU0_SA_DQ<23> DQ23_A @S9S_MB_2U_LIB.S9S_MB_2U(SCH_1):M_H_CPU0_SA_DQ(23)
  40 M_H_CPU0_SA_DQ<24> DQ24_A @S9S_MB_2U_LIB.S9S_MB_2U(SCH_1):M_H_CPU0_SA_DQ(24)
  42 M_H_CPU0_SA_DQ<25> DQ25_A @S9S_MB_2U_LIB.S9S_MB_2U(SCH_1):M_H_CPU0_SA_DQ(25)
 185 M_H_CPU0_SA_DQ<26> DQ26_A @S9S_MB_2U_LIB.S9S_MB_2U(SCH_1):M_H_CPU0_SA_DQ(26)
 187 M_H_CPU0_SA_DQ<27> DQ27_A @S9S_MB_2U_LIB.S9S_MB_2U(SCH_1):M_H_CPU0_SA_DQ(27)
  47 M_H_CPU0_SA_DQ<28> DQ28_A @S9S_MB_2U_LIB.S9S_MB_2U(SCH_1):M_H_CPU0_SA_DQ(28)
  49 M_H_CPU0_SA_DQ<29> DQ29_A @S9S_MB_2U_LIB.S9S_MB_2U(SCH_1):M_H_CPU0_SA_DQ(29)
 192 M_H_CPU0_SA_DQ<30> DQ30_A @S9S_MB_2U_LIB.S9S_MB_2U(SCH_1):M_H_CPU0_SA_DQ(30)
 229 M_H_CPU0_SB_CS_N<1> CS1_B_N @S9S_MB_2U_LIB.S9S_MB_2U(SCH_1):M_H_CPU0_SB_CS_N(1)
 209 M_H_CPU0_SA_CS_N<1> CS1_A_N @S9S_MB_2U_LIB.S9S_MB_2U(SCH_1):M_H_CPU0_SA_CS_N(1)
  84 M_H_CPU0_SB_CS_N<0> CS0_B_N @S9S_MB_2U_LIB.S9S_MB_2U(SCH_1):M_H_CPU0_SB_CS_N(0)
  64 M_H_CPU0_SA_CS_N<0> CS0_A_N @S9S_MB_2U_LIB.S9S_MB_2U(SCH_1):M_H_CPU0_SA_CS_N(0)
 217 M_H_CPU0_CLK_DP<0>   CK_T @S9S_MB_2U_LIB.S9S_MB_2U(SCH_1):M_H_CPU0_CLK_DP(0)
 218 M_H_CPU0_CLK_DN<0>   CK_C @S9S_MB_2U_LIB.S9S_MB_2U(SCH_1):M_H_CPU0_CLK_DN(0)
  96 M_H_CPU0_SB_CB<0>  CB0_B @S9S_MB_2U_LIB.S9S_MB_2U(SCH_1):M_H_CPU0_SB_CB(0)
  98 M_H_CPU0_SB_CB<1>  CB1_B @S9S_MB_2U_LIB.S9S_MB_2U(SCH_1):M_H_CPU0_SB_CB(1)
 241 M_H_CPU0_SB_CB<2>  CB2_B @S9S_MB_2U_LIB.S9S_MB_2U(SCH_1):M_H_CPU0_SB_CB(2)
 243 M_H_CPU0_SB_CB<3>  CB3_B @S9S_MB_2U_LIB.S9S_MB_2U(SCH_1):M_H_CPU0_SB_CB(3)
  89 M_H_CPU0_SB_CB<4>  CB4_B @S9S_MB_2U_LIB.S9S_MB_2U(SCH_1):M_H_CPU0_SB_CB(4)
  91 M_H_CPU0_SB_CB<5>  CB5_B @S9S_MB_2U_LIB.S9S_MB_2U(SCH_1):M_H_CPU0_SB_CB(5)
 234 M_H_CPU0_SB_CB<6>  CB6_B @S9S_MB_2U_LIB.S9S_MB_2U(SCH_1):M_H_CPU0_SB_CB(6)
  51 M_H_CPU0_SA_CB<0>  CB0_A @S9S_MB_2U_LIB.S9S_MB_2U(SCH_1):M_H_CPU0_SA_CB(0)
 196 M_H_CPU0_SA_CB<2>  CB2_A @S9S_MB_2U_LIB.S9S_MB_2U(SCH_1):M_H_CPU0_SA_CB(2)
 198 M_H_CPU0_SA_CB<3>  CB3_A @S9S_MB_2U_LIB.S9S_MB_2U(SCH_1):M_H_CPU0_SA_CB(3)
  60 M_H_CPU0_SA_CB<5>  CB5_A @S9S_MB_2U_LIB.S9S_MB_2U(SCH_1):M_H_CPU0_SA_CB(5)
 203 M_H_CPU0_SA_CB<6>  CB6_A @S9S_MB_2U_LIB.S9S_MB_2U(SCH_1):M_H_CPU0_SA_CB(6)
  82 M_H_CPU0_SB_CA<6>  CA6_B @S9S_MB_2U_LIB.S9S_MB_2U(SCH_1):M_H_CPU0_SB_CA(6)
  72 M_H_CPU0_SA_CA<6>  CA6_A @S9S_MB_2U_LIB.S9S_MB_2U(SCH_1):M_H_CPU0_SA_CA(6)
 225 M_H_CPU0_SB_CA<5>  CA5_B @S9S_MB_2U_LIB.S9S_MB_2U(SCH_1):M_H_CPU0_SB_CA(5)
 215 M_H_CPU0_SA_CA<5>  CA5_A @S9S_MB_2U_LIB.S9S_MB_2U(SCH_1):M_H_CPU0_SA_CA(5)
  80 M_H_CPU0_SB_CA<4>  CA4_B @S9S_MB_2U_LIB.S9S_MB_2U(SCH_1):M_H_CPU0_SB_CA(4)
  70 M_H_CPU0_SA_CA<4>  CA4_A @S9S_MB_2U_LIB.S9S_MB_2U(SCH_1):M_H_CPU0_SA_CA(4)
 223 M_H_CPU0_SB_CA<3>  CA3_B @S9S_MB_2U_LIB.S9S_MB_2U(SCH_1):M_H_CPU0_SB_CA(3)
 213 M_H_CPU0_SA_CA<3>  CA3_A @S9S_MB_2U_LIB.S9S_MB_2U(SCH_1):M_H_CPU0_SA_CA(3)
  78 M_H_CPU0_SB_CA<2>  CA2_B @S9S_MB_2U_LIB.S9S_MB_2U(SCH_1):M_H_CPU0_SB_CA(2)
  68 M_H_CPU0_SA_CA<2>  CA2_A @S9S_MB_2U_LIB.S9S_MB_2U(SCH_1):M_H_CPU0_SA_CA(2)
 221 M_H_CPU0_SB_CA<1>  CA1_B @S9S_MB_2U_LIB.S9S_MB_2U(SCH_1):M_H_CPU0_SB_CA(1)
 211 M_H_CPU0_SA_CA<1>  CA1_A @S9S_MB_2U_LIB.S9S_MB_2U(SCH_1):M_H_CPU0_SA_CA(1)
  76 M_H_CPU0_SB_CA<0>  CA0_B @S9S_MB_2U_LIB.S9S_MB_2U(SCH_1):M_H_CPU0_SB_CA(0)
  66 M_H_CPU0_SA_CA<0>  CA0_A @S9S_MB_2U_LIB.S9S_MB_2U(SCH_1):M_H_CPU0_SA_CA(0)
  62 M_H_CPU0_ALERT_N ALERT_N @S9S_MB_2U_LIB.S9S_MB_2U(SCH_1):M_H_CPU0_ALERT_N
 236 M_H_CPU0_SB_CB<7>  CB7_B @S9S_MB_2U_LIB.S9S_MB_2U(SCH_1):M_H_CPU0_SB_CB(7)
  53 M_H_CPU0_SA_CB<1>  CB1_A @S9S_MB_2U_LIB.S9S_MB_2U(SCH_1):M_H_CPU0_SA_CB(1)
  58 M_H_CPU0_SA_CB<4>  CB4_A @S9S_MB_2U_LIB.S9S_MB_2U(SCH_1):M_H_CPU0_SA_CB(4)
 205 M_H_CPU0_SA_CB<7>  CB7_A @S9S_MB_2U_LIB.S9S_MB_2U(SCH_1):M_H_CPU0_SA_CB(7)
 194 M_H_CPU0_SA_DQ<31> DQ31_A @S9S_MB_2U_LIB.S9S_MB_2U(SCH_1):M_H_CPU0_SA_DQ(31)

Q_CAP_C0402-2.2UF,6.3V,20%,X6SA  I121  C44
   1 P3V3_AUX      A @S9S_MB_2U_LIB.S9S_MB_2U(SCH_1):P3V3_AUX
   2    GND      B @S9S_MB_2U_LIB.S9S_MB_2U(SCH_1):GND

Q_CAP_C0805-10UF,16V,10%,X6S,CA  I125  C45
   1 P12V_S3_AUX_CPU0_NVDIMM      A @S9S_MB_2U_LIB.S9S_MB_2U(SCH_1):P12V_S3_AUX_CPU0_NVDIMM
   2    GND      B @S9S_MB_2U_LIB.S9S_MB_2U(SCH_1):GND

Q_CAP_C0805-10UF,16V,10%,X6S,CA  I127  C46
   1 P12V_S3_AUX_CPU0_NVDIMM      A @S9S_MB_2U_LIB.S9S_MB_2U(SCH_1):P12V_S3_AUX_CPU0_NVDIMM
   2    GND      B @S9S_MB_2U_LIB.S9S_MB_2U(SCH_1):GND

SCONN288_ADR50017P130CC-SCONN2A  I176  J15
   6    GND   VSS0 @S9S_MB_2U_LIB.S9S_MB_2U(SCH_1):GND
   8    GND   VSS1 @S9S_MB_2U_LIB.S9S_MB_2U(SCH_1):GND
  10    GND   VSS2 @S9S_MB_2U_LIB.S9S_MB_2U(SCH_1):GND
  13    GND   VSS3 @S9S_MB_2U_LIB.S9S_MB_2U(SCH_1):GND
  15    GND   VSS4 @S9S_MB_2U_LIB.S9S_MB_2U(SCH_1):GND
  17    GND   VSS5 @S9S_MB_2U_LIB.S9S_MB_2U(SCH_1):GND
  19    GND   VSS6 @S9S_MB_2U_LIB.S9S_MB_2U(SCH_1):GND
  21    GND   VSS7 @S9S_MB_2U_LIB.S9S_MB_2U(SCH_1):GND
  24    GND   VSS8 @S9S_MB_2U_LIB.S9S_MB_2U(SCH_1):GND
  26    GND   VSS9 @S9S_MB_2U_LIB.S9S_MB_2U(SCH_1):GND
  28    GND  VSS10 @S9S_MB_2U_LIB.S9S_MB_2U(SCH_1):GND
  30    GND  VSS11 @S9S_MB_2U_LIB.S9S_MB_2U(SCH_1):GND
  32    GND  VSS12 @S9S_MB_2U_LIB.S9S_MB_2U(SCH_1):GND
  35    GND  VSS13 @S9S_MB_2U_LIB.S9S_MB_2U(SCH_1):GND
  37    GND  VSS14 @S9S_MB_2U_LIB.S9S_MB_2U(SCH_1):GND
  39    GND  VSS15 @S9S_MB_2U_LIB.S9S_MB_2U(SCH_1):GND
  41    GND  VSS16 @S9S_MB_2U_LIB.S9S_MB_2U(SCH_1):GND
  43    GND  VSS17 @S9S_MB_2U_LIB.S9S_MB_2U(SCH_1):GND
  46    GND  VSS18 @S9S_MB_2U_LIB.S9S_MB_2U(SCH_1):GND
  48    GND  VSS19 @S9S_MB_2U_LIB.S9S_MB_2U(SCH_1):GND
  50    GND  VSS20 @S9S_MB_2U_LIB.S9S_MB_2U(SCH_1):GND
  52    GND  VSS21 @S9S_MB_2U_LIB.S9S_MB_2U(SCH_1):GND
  54    GND  VSS22 @S9S_MB_2U_LIB.S9S_MB_2U(SCH_1):GND
  57    GND  VSS23 @S9S_MB_2U_LIB.S9S_MB_2U(SCH_1):GND
  59    GND  VSS24 @S9S_MB_2U_LIB.S9S_MB_2U(SCH_1):GND
  61    GND  VSS25 @S9S_MB_2U_LIB.S9S_MB_2U(SCH_1):GND
  63    GND  VSS26 @S9S_MB_2U_LIB.S9S_MB_2U(SCH_1):GND
  65    GND  VSS27 @S9S_MB_2U_LIB.S9S_MB_2U(SCH_1):GND
  67    GND  VSS28 @S9S_MB_2U_LIB.S9S_MB_2U(SCH_1):GND
  69    GND  VSS29 @S9S_MB_2U_LIB.S9S_MB_2U(SCH_1):GND
  71    GND  VSS30 @S9S_MB_2U_LIB.S9S_MB_2U(SCH_1):GND
  73    GND  VSS31 @S9S_MB_2U_LIB.S9S_MB_2U(SCH_1):GND
  75    GND  VSS32 @S9S_MB_2U_LIB.S9S_MB_2U(SCH_1):GND
  77    GND  VSS33 @S9S_MB_2U_LIB.S9S_MB_2U(SCH_1):GND
  79    GND  VSS34 @S9S_MB_2U_LIB.S9S_MB_2U(SCH_1):GND
  81    GND  VSS35 @S9S_MB_2U_LIB.S9S_MB_2U(SCH_1):GND
  83    GND  VSS36 @S9S_MB_2U_LIB.S9S_MB_2U(SCH_1):GND
  85    GND  VSS37 @S9S_MB_2U_LIB.S9S_MB_2U(SCH_1):GND
  88    GND  VSS38 @S9S_MB_2U_LIB.S9S_MB_2U(SCH_1):GND
  90    GND  VSS39 @S9S_MB_2U_LIB.S9S_MB_2U(SCH_1):GND
  92    GND  VSS40 @S9S_MB_2U_LIB.S9S_MB_2U(SCH_1):GND
  95    GND  VSS41 @S9S_MB_2U_LIB.S9S_MB_2U(SCH_1):GND
  97    GND  VSS42 @S9S_MB_2U_LIB.S9S_MB_2U(SCH_1):GND
  99    GND  VSS43 @S9S_MB_2U_LIB.S9S_MB_2U(SCH_1):GND
 101    GND  VSS44 @S9S_MB_2U_LIB.S9S_MB_2U(SCH_1):GND
 103    GND  VSS45 @S9S_MB_2U_LIB.S9S_MB_2U(SCH_1):GND
 106    GND  VSS46 @S9S_MB_2U_LIB.S9S_MB_2U(SCH_1):GND
 108    GND  VSS47 @S9S_MB_2U_LIB.S9S_MB_2U(SCH_1):GND
 110    GND  VSS48 @S9S_MB_2U_LIB.S9S_MB_2U(SCH_1):GND
 112    GND  VSS49 @S9S_MB_2U_LIB.S9S_MB_2U(SCH_1):GND
 114    GND  VSS50 @S9S_MB_2U_LIB.S9S_MB_2U(SCH_1):GND
 117    GND  VSS51 @S9S_MB_2U_LIB.S9S_MB_2U(SCH_1):GND
 119    GND  VSS52 @S9S_MB_2U_LIB.S9S_MB_2U(SCH_1):GND
 121    GND  VSS53 @S9S_MB_2U_LIB.S9S_MB_2U(SCH_1):GND
 123    GND  VSS54 @S9S_MB_2U_LIB.S9S_MB_2U(SCH_1):GND
 125    GND  VSS55 @S9S_MB_2U_LIB.S9S_MB_2U(SCH_1):GND
 128    GND  VSS56 @S9S_MB_2U_LIB.S9S_MB_2U(SCH_1):GND
 130    GND  VSS57 @S9S_MB_2U_LIB.S9S_MB_2U(SCH_1):GND
 134    GND  VSS59 @S9S_MB_2U_LIB.S9S_MB_2U(SCH_1):GND
 143    GND  VSS63 @S9S_MB_2U_LIB.S9S_MB_2U(SCH_1):GND
 151    GND  VSS64 @S9S_MB_2U_LIB.S9S_MB_2U(SCH_1):GND
 153    GND  VSS65 @S9S_MB_2U_LIB.S9S_MB_2U(SCH_1):GND
 155    GND  VSS66 @S9S_MB_2U_LIB.S9S_MB_2U(SCH_1):GND
 158    GND  VSS67 @S9S_MB_2U_LIB.S9S_MB_2U(SCH_1):GND
 160    GND  VSS68 @S9S_MB_2U_LIB.S9S_MB_2U(SCH_1):GND
 162    GND  VSS69 @S9S_MB_2U_LIB.S9S_MB_2U(SCH_1):GND
 164    GND  VSS70 @S9S_MB_2U_LIB.S9S_MB_2U(SCH_1):GND
 166    GND  VSS71 @S9S_MB_2U_LIB.S9S_MB_2U(SCH_1):GND
 169    GND  VSS72 @S9S_MB_2U_LIB.S9S_MB_2U(SCH_1):GND
 171    GND  VSS73 @S9S_MB_2U_LIB.S9S_MB_2U(SCH_1):GND
 173    GND  VSS74 @S9S_MB_2U_LIB.S9S_MB_2U(SCH_1):GND
 175    GND  VSS75 @S9S_MB_2U_LIB.S9S_MB_2U(SCH_1):GND
 177    GND  VSS76 @S9S_MB_2U_LIB.S9S_MB_2U(SCH_1):GND
 180    GND  VSS77 @S9S_MB_2U_LIB.S9S_MB_2U(SCH_1):GND
 182    GND  VSS78 @S9S_MB_2U_LIB.S9S_MB_2U(SCH_1):GND
 184    GND  VSS79 @S9S_MB_2U_LIB.S9S_MB_2U(SCH_1):GND
 186    GND  VSS80 @S9S_MB_2U_LIB.S9S_MB_2U(SCH_1):GND
 188    GND  VSS81 @S9S_MB_2U_LIB.S9S_MB_2U(SCH_1):GND
 191    GND  VSS82 @S9S_MB_2U_LIB.S9S_MB_2U(SCH_1):GND
 193    GND  VSS83 @S9S_MB_2U_LIB.S9S_MB_2U(SCH_1):GND
 195    GND  VSS84 @S9S_MB_2U_LIB.S9S_MB_2U(SCH_1):GND
 197    GND  VSS85 @S9S_MB_2U_LIB.S9S_MB_2U(SCH_1):GND
 199    GND  VSS86 @S9S_MB_2U_LIB.S9S_MB_2U(SCH_1):GND
 202    GND  VSS87 @S9S_MB_2U_LIB.S9S_MB_2U(SCH_1):GND
 204    GND  VSS88 @S9S_MB_2U_LIB.S9S_MB_2U(SCH_1):GND
 206    GND  VSS89 @S9S_MB_2U_LIB.S9S_MB_2U(SCH_1):GND
 208    GND  VSS90 @S9S_MB_2U_LIB.S9S_MB_2U(SCH_1):GND
 210    GND  VSS91 @S9S_MB_2U_LIB.S9S_MB_2U(SCH_1):GND
 212    GND  VSS92 @S9S_MB_2U_LIB.S9S_MB_2U(SCH_1):GND
 214    GND  VSS93 @S9S_MB_2U_LIB.S9S_MB_2U(SCH_1):GND
 216    GND  VSS94 @S9S_MB_2U_LIB.S9S_MB_2U(SCH_1):GND
 219    GND  VSS95 @S9S_MB_2U_LIB.S9S_MB_2U(SCH_1):GND
 222    GND  VSS96 @S9S_MB_2U_LIB.S9S_MB_2U(SCH_1):GND
 224    GND  VSS97 @S9S_MB_2U_LIB.S9S_MB_2U(SCH_1):GND
 226    GND  VSS98 @S9S_MB_2U_LIB.S9S_MB_2U(SCH_1):GND
 228    GND  VSS99 @S9S_MB_2U_LIB.S9S_MB_2U(SCH_1):GND
 233    GND VSS101 @S9S_MB_2U_LIB.S9S_MB_2U(SCH_1):GND
 237    GND VSS103 @S9S_MB_2U_LIB.S9S_MB_2U(SCH_1):GND
 242    GND VSS105 @S9S_MB_2U_LIB.S9S_MB_2U(SCH_1):GND
 244    GND VSS106 @S9S_MB_2U_LIB.S9S_MB_2U(SCH_1):GND
 246    GND VSS107 @S9S_MB_2U_LIB.S9S_MB_2U(SCH_1):GND
 248    GND VSS108 @S9S_MB_2U_LIB.S9S_MB_2U(SCH_1):GND
 251    GND VSS109 @S9S_MB_2U_LIB.S9S_MB_2U(SCH_1):GND
 253    GND VSS110 @S9S_MB_2U_LIB.S9S_MB_2U(SCH_1):GND
 255    GND VSS111 @S9S_MB_2U_LIB.S9S_MB_2U(SCH_1):GND
 257    GND VSS112 @S9S_MB_2U_LIB.S9S_MB_2U(SCH_1):GND
 259    GND VSS113 @S9S_MB_2U_LIB.S9S_MB_2U(SCH_1):GND
 262    GND VSS114 @S9S_MB_2U_LIB.S9S_MB_2U(SCH_1):GND
 264    GND VSS115 @S9S_MB_2U_LIB.S9S_MB_2U(SCH_1):GND
 266    GND VSS116 @S9S_MB_2U_LIB.S9S_MB_2U(SCH_1):GND
 268    GND VSS117 @S9S_MB_2U_LIB.S9S_MB_2U(SCH_1):GND
 270    GND VSS118 @S9S_MB_2U_LIB.S9S_MB_2U(SCH_1):GND
 273    GND VSS119 @S9S_MB_2U_LIB.S9S_MB_2U(SCH_1):GND
 275    GND VSS120 @S9S_MB_2U_LIB.S9S_MB_2U(SCH_1):GND
 277    GND VSS121 @S9S_MB_2U_LIB.S9S_MB_2U(SCH_1):GND
 279    GND VSS122 @S9S_MB_2U_LIB.S9S_MB_2U(SCH_1):GND
 281    GND VSS123 @S9S_MB_2U_LIB.S9S_MB_2U(SCH_1):GND
 284    GND VSS124 @S9S_MB_2U_LIB.S9S_MB_2U(SCH_1):GND
 286    GND VSS125 @S9S_MB_2U_LIB.S9S_MB_2U(SCH_1):GND
 288    GND VSS126 @S9S_MB_2U_LIB.S9S_MB_2U(SCH_1):GND
   1 P12V_S3_AUX_CPU0_NVDIMM VIN_BULK0 @S9S_MB_2U_LIB.S9S_MB_2U(SCH_1):P12V_S3_AUX_CPU0_NVDIMM
 145 P12V_S3_AUX_CPU0_NVDIMM VIN_BULK1 @S9S_MB_2U_LIB.S9S_MB_2U(SCH_1):P12V_S3_AUX_CPU0_NVDIMM
 146 P12V_S3_AUX_CPU0_NVDIMM VIN_BULK2 @S9S_MB_2U_LIB.S9S_MB_2U(SCH_1):P12V_S3_AUX_CPU0_NVDIMM
 230    GND VSS100 @S9S_MB_2U_LIB.S9S_MB_2U(SCH_1):GND
 235    GND VSS102 @S9S_MB_2U_LIB.S9S_MB_2U(SCH_1):GND
 240    GND VSS104 @S9S_MB_2U_LIB.S9S_MB_2U(SCH_1):GND
 132    GND  VSS58 @S9S_MB_2U_LIB.S9S_MB_2U(SCH_1):GND
 136    GND  VSS60 @S9S_MB_2U_LIB.S9S_MB_2U(SCH_1):GND
 139    GND  VSS61 @S9S_MB_2U_LIB.S9S_MB_2U(SCH_1):GND
 141    GND  VSS62 @S9S_MB_2U_LIB.S9S_MB_2U(SCH_1):GND
  G1    GND     G1 @S9S_MB_2U_LIB.S9S_MB_2U(SCH_1):GND
  G2    GND     G2 @S9S_MB_2U_LIB.S9S_MB_2U(SCH_1):GND
  G3    GND     G3 @S9S_MB_2U_LIB.S9S_MB_2U(SCH_1):GND

SCONN288_ADR50017P130CC-SCONN2A  I178  J15
  93 M_H_CPU0_SB_DQS_DP<9> DQS9_B_T||TDQS9_B_T||DBI4_B_N @S9S_MB_2U_LIB.S9S_MB_2U(SCH_1):M_H_CPU0_SB_DQS_DP(9)
  94 M_H_CPU0_SB_DQS_DN<9> DQS9_B_C||TDQS9_B_C @S9S_MB_2U_LIB.S9S_MB_2U(SCH_1):M_H_CPU0_SB_DQS_DN(9)
 201 M_H_CPU0_SA_DQS_DP<9> DQS9_A_T||TDQS9_A_T @S9S_MB_2U_LIB.S9S_MB_2U(SCH_1):M_H_CPU0_SA_DQS_DP(9)
 200 M_H_CPU0_SA_DQS_DN<9> DQS9_A_C||TDQS9_A_C @S9S_MB_2U_LIB.S9S_MB_2U(SCH_1):M_H_CPU0_SA_DQS_DN(9)
 190 M_H_CPU0_SA_DQS_DP<8> DQS8_A_T||TDQS8_A_T @S9S_MB_2U_LIB.S9S_MB_2U(SCH_1):M_H_CPU0_SA_DQS_DP(8)
 189 M_H_CPU0_SA_DQS_DN<8> DQS8_A_C||TDQS8_A_C @S9S_MB_2U_LIB.S9S_MB_2U(SCH_1):M_H_CPU0_SA_DQS_DN(8)
 271 M_H_CPU0_SB_DQS_DN<7> DQS7_B_C||TDQS7_B_C @S9S_MB_2U_LIB.S9S_MB_2U(SCH_1):M_H_CPU0_SB_DQS_DN(7)
 179 M_H_CPU0_SA_DQS_DP<7> DQS7_A_T||TDQS7_A_T @S9S_MB_2U_LIB.S9S_MB_2U(SCH_1):M_H_CPU0_SA_DQS_DP(7)
 261 M_H_CPU0_SB_DQS_DP<6> DQS6_B_T||TDQS6_B_T @S9S_MB_2U_LIB.S9S_MB_2U(SCH_1):M_H_CPU0_SB_DQS_DP(6)
 260 M_H_CPU0_SB_DQS_DN<6> DQS6_B_C||TDQS6_B_C @S9S_MB_2U_LIB.S9S_MB_2U(SCH_1):M_H_CPU0_SB_DQS_DN(6)
 167 M_H_CPU0_SA_DQS_DN<6> DQS6_A_C||TDQS6_A_C||DQS6_A_T||TDQS6_A_T @S9S_MB_2U_LIB.S9S_MB_2U(SCH_1):M_H_CPU0_SA_DQS_DN(6)
 250 M_H_CPU0_SB_DQS_DP<5> DQS5_B_T||TDQS5_B_T @S9S_MB_2U_LIB.S9S_MB_2U(SCH_1):M_H_CPU0_SB_DQS_DP(5)
 249 M_H_CPU0_SB_DQS_DN<5> DQS5_B_C||TDQS5_B_C @S9S_MB_2U_LIB.S9S_MB_2U(SCH_1):M_H_CPU0_SB_DQS_DN(5)
 157 M_H_CPU0_SA_DQS_DP<5> DQS5_A_T||TDQS5_A_T @S9S_MB_2U_LIB.S9S_MB_2U(SCH_1):M_H_CPU0_SA_DQS_DP(5)
 156 M_H_CPU0_SA_DQS_DN<5> DQS5_A_C||TDQS5_A_C||DQS5_A_T||TDQS5_A_T @S9S_MB_2U_LIB.S9S_MB_2U(SCH_1):M_H_CPU0_SA_DQS_DN(5)
 239 M_H_CPU0_SB_DQS_DP<4> DQS4_B_T @S9S_MB_2U_LIB.S9S_MB_2U(SCH_1):M_H_CPU0_SB_DQS_DP(4)
 238 M_H_CPU0_SB_DQS_DN<4> DQS4_B_C @S9S_MB_2U_LIB.S9S_MB_2U(SCH_1):M_H_CPU0_SB_DQS_DN(4)
  55 M_H_CPU0_SA_DQS_DP<4> DQS4_A_T @S9S_MB_2U_LIB.S9S_MB_2U(SCH_1):M_H_CPU0_SA_DQS_DP(4)
  56 M_H_CPU0_SA_DQS_DN<4> DQS4_A_C @S9S_MB_2U_LIB.S9S_MB_2U(SCH_1):M_H_CPU0_SA_DQS_DN(4)
 137 M_H_CPU0_SB_DQS_DP<3> DQS3_B_T @S9S_MB_2U_LIB.S9S_MB_2U(SCH_1):M_H_CPU0_SB_DQS_DP(3)
 138 M_H_CPU0_SB_DQS_DN<3> DQS3_B_C @S9S_MB_2U_LIB.S9S_MB_2U(SCH_1):M_H_CPU0_SB_DQS_DN(3)
  44 M_H_CPU0_SA_DQS_DP<3> DQS3_A_T @S9S_MB_2U_LIB.S9S_MB_2U(SCH_1):M_H_CPU0_SA_DQS_DP(3)
  45 M_H_CPU0_SA_DQS_DN<3> DQS3_A_C @S9S_MB_2U_LIB.S9S_MB_2U(SCH_1):M_H_CPU0_SA_DQS_DN(3)
 126 M_H_CPU0_SB_DQS_DP<2> DQS2_B_T @S9S_MB_2U_LIB.S9S_MB_2U(SCH_1):M_H_CPU0_SB_DQS_DP(2)
 127 M_H_CPU0_SB_DQS_DN<2> DQS2_B_C @S9S_MB_2U_LIB.S9S_MB_2U(SCH_1):M_H_CPU0_SB_DQS_DN(2)
  33 M_H_CPU0_SA_DQS_DP<2> DQS2_A_T @S9S_MB_2U_LIB.S9S_MB_2U(SCH_1):M_H_CPU0_SA_DQS_DP(2)
  34 M_H_CPU0_SA_DQS_DN<2> DQS2_A_C @S9S_MB_2U_LIB.S9S_MB_2U(SCH_1):M_H_CPU0_SA_DQS_DN(2)
 115 M_H_CPU0_SB_DQS_DP<1> DQS1_B_T @S9S_MB_2U_LIB.S9S_MB_2U(SCH_1):M_H_CPU0_SB_DQS_DP(1)
 116 M_H_CPU0_SB_DQS_DN<1> DQS1_B_C @S9S_MB_2U_LIB.S9S_MB_2U(SCH_1):M_H_CPU0_SB_DQS_DN(1)
  22 M_H_CPU0_SA_DQS_DP<1> DQS1_A_T @S9S_MB_2U_LIB.S9S_MB_2U(SCH_1):M_H_CPU0_SA_DQS_DP(1)
  23 M_H_CPU0_SA_DQS_DN<1> DQS1_A_C @S9S_MB_2U_LIB.S9S_MB_2U(SCH_1):M_H_CPU0_SA_DQS_DN(1)
 104 M_H_CPU0_SB_DQS_DP<0> DQS0_B_T @S9S_MB_2U_LIB.S9S_MB_2U(SCH_1):M_H_CPU0_SB_DQS_DP(0)
 105 M_H_CPU0_SB_DQS_DN<0> DQS0_B_C @S9S_MB_2U_LIB.S9S_MB_2U(SCH_1):M_H_CPU0_SB_DQS_DN(0)
  11 M_H_CPU0_SA_DQS_DP<0> DQS0_A_T @S9S_MB_2U_LIB.S9S_MB_2U(SCH_1):M_H_CPU0_SA_DQS_DP(0)
  12 M_H_CPU0_SA_DQS_DN<0> DQS0_A_C @S9S_MB_2U_LIB.S9S_MB_2U(SCH_1):M_H_CPU0_SA_DQS_DN(0)
 272 M_H_CPU0_SB_DQS_DP<7> DQS7_B_T||TDQS7_B_T @S9S_MB_2U_LIB.S9S_MB_2U(SCH_1):M_H_CPU0_SB_DQS_DP(7)
 282 M_H_CPU0_SB_DQS_DN<8> DQS8_B_C||TDQS8_B_C @S9S_MB_2U_LIB.S9S_MB_2U(SCH_1):M_H_CPU0_SB_DQS_DN(8)
 283 M_H_CPU0_SB_DQS_DP<8> DQS8_B_T||TDQS8_B_T @S9S_MB_2U_LIB.S9S_MB_2U(SCH_1):M_H_CPU0_SB_DQS_DP(8)
 168 M_H_CPU0_SA_DQS_DP<6> DQS6_A_T||TDQS6_A_T @S9S_MB_2U_LIB.S9S_MB_2U(SCH_1):M_H_CPU0_SA_DQS_DP(6)
 178 M_H_CPU0_SA_DQS_DN<7> DQS7_A_C||TDQS7_A_C @S9S_MB_2U_LIB.S9S_MB_2U(SCH_1):M_H_CPU0_SA_DQS_DN(7)

Q_RES_0402LF-49.9,1%,1/16W,CHIA  I179  R3889
   1 I3C_SPD_DDREFGH_CPU0_LVC1_SCL_6      A @S9S_MB_2U_LIB.S9S_MB_2U(SCH_1):I3C_SPD_DDREFGH_CPU0_LVC1_SCL_R7
   2 I3C_SPD_DDREFGH_CPU0_LVC1_SCL      B @S9S_MB_2U_LIB.S9S_MB_2U(SCH_1):I3C_SPD_DDREFGH_CPU0_LVC1_SCL


DRAWING: @S9S_MB_2U_LIB.S9S_MB_2U(SCH_1):PAGE97 

Q_RES_0402LF-196K,1%,1/16W,CHIA  I5  R41
   1 PD_CHH_CPU0_DIMM2_SAA      A @S9S_MB_2U_LIB.S9S_MB_2U(SCH_1):PD_CHH_CPU0_DIMM2_SAA
   2    GND      B @S9S_MB_2U_LIB.S9S_MB_2U(SCH_1):GND

SCONN288_ADR50017P087CC-SCONN2A  I6  J16
   3 P3V3_AUX VIN_MGMT @S9S_MB_2U_LIB.S9S_MB_2U(SCH_1):P3V3_AUX
   2 TP_CHH_CPU0_DIMM2_FRU_0   RFU0 @S9S_MB_2U_LIB.S9S_MB_2U(SCH_1):TP_CHH_CPU0_DIMM2_FRU_0
 144 TP_CHH_CPU0_DIMM2_FRU_1   RFU1 @S9S_MB_2U_LIB.S9S_MB_2U(SCH_1):TP_CHH_CPU0_DIMM2_FRU_1
 149 TP_CHH_CPU0_DIMM2_FRU_2   RFU2 @S9S_MB_2U_LIB.S9S_MB_2U(SCH_1):TP_CHH_CPU0_DIMM2_FRU_2
 150 TP_CHH_CPU0_DIMM2_FRU_3   RFU3 @S9S_MB_2U_LIB.S9S_MB_2U(SCH_1):TP_CHH_CPU0_DIMM2_FRU_3
 220 TP_CHH_CPU0_DIMM2_FRU_4   RFU4 @S9S_MB_2U_LIB.S9S_MB_2U(SCH_1):TP_CHH_CPU0_DIMM2_FRU_4
 231 TP_CHH_CPU0_DIMM2_FRU_5   RFU5 @S9S_MB_2U_LIB.S9S_MB_2U(SCH_1):TP_CHH_CPU0_DIMM2_FRU_5
 232 TP_CHH_CPU0_DIMM2_FRU_6   RFU6 @S9S_MB_2U_LIB.S9S_MB_2U(SCH_1):TP_CHH_CPU0_DIMM2_FRU_6
 207 RST_M_GH_CPU0_FPGA_N RESET_N @S9S_MB_2U_LIB.S9S_MB_2U(SCH_1):RST_M_GH_CPU0_FPGA_N
 147 PWRGD_CHH_CPU0_DIMM2 PWR_GOOD||FAIL_N @S9S_MB_2U_LIB.S9S_MB_2U(SCH_1):PWRGD_CHH_CPU0_DIMM2
 227 M_H_CPU0_SB_PAR  PAR_B @S9S_MB_2U_LIB.S9S_MB_2U(SCH_1):M_H_CPU0_SB_PAR
  74 M_H_CPU0_SA_PAR  PAR_A @S9S_MB_2U_LIB.S9S_MB_2U(SCH_1):M_H_CPU0_SA_PAR
  87 M_H_CPU0_SB_RSP<1> LBS||RSP_B_N @S9S_MB_2U_LIB.S9S_MB_2U(SCH_1):M_H_CPU0_SB_RSP(1)
  86 M_H_CPU0_SA_RSP<1> LBD||RSP_A_N @S9S_MB_2U_LIB.S9S_MB_2U(SCH_1):M_H_CPU0_SA_RSP(1)
   5 I3C_SPD_DDREFGH_CPU0_LVC1_SDA   HSDA @S9S_MB_2U_LIB.S9S_MB_2U(SCH_1):I3C_SPD_DDREFGH_CPU0_LVC1_SDA
   4 I3C_SPD_DDREFGH_CPU0_LVC1_SCL_7   HSCL @S9S_MB_2U_LIB.S9S_MB_2U(SCH_1):I3C_SPD_DDREFGH_CPU0_LVC1_SCL_R8
 148 PD_CHH_CPU0_DIMM2_SAA    HSA @S9S_MB_2U_LIB.S9S_MB_2U(SCH_1):PD_CHH_CPU0_DIMM2_SAA
 100 M_H_CPU0_SB_DQ<0>  DQ0_B @S9S_MB_2U_LIB.S9S_MB_2U(SCH_1):M_H_CPU0_SB_DQ(0)
 102 M_H_CPU0_SB_DQ<1>  DQ1_B @S9S_MB_2U_LIB.S9S_MB_2U(SCH_1):M_H_CPU0_SB_DQ(1)
 245 M_H_CPU0_SB_DQ<2>  DQ2_B @S9S_MB_2U_LIB.S9S_MB_2U(SCH_1):M_H_CPU0_SB_DQ(2)
 247 M_H_CPU0_SB_DQ<3>  DQ3_B @S9S_MB_2U_LIB.S9S_MB_2U(SCH_1):M_H_CPU0_SB_DQ(3)
 107 M_H_CPU0_SB_DQ<4>  DQ4_B @S9S_MB_2U_LIB.S9S_MB_2U(SCH_1):M_H_CPU0_SB_DQ(4)
 109 M_H_CPU0_SB_DQ<5>  DQ5_B @S9S_MB_2U_LIB.S9S_MB_2U(SCH_1):M_H_CPU0_SB_DQ(5)
 252 M_H_CPU0_SB_DQ<6>  DQ6_B @S9S_MB_2U_LIB.S9S_MB_2U(SCH_1):M_H_CPU0_SB_DQ(6)
 254 M_H_CPU0_SB_DQ<7>  DQ7_B @S9S_MB_2U_LIB.S9S_MB_2U(SCH_1):M_H_CPU0_SB_DQ(7)
 111 M_H_CPU0_SB_DQ<8>  DQ8_B @S9S_MB_2U_LIB.S9S_MB_2U(SCH_1):M_H_CPU0_SB_DQ(8)
 113 M_H_CPU0_SB_DQ<9>  DQ9_B @S9S_MB_2U_LIB.S9S_MB_2U(SCH_1):M_H_CPU0_SB_DQ(9)
 256 M_H_CPU0_SB_DQ<10> DQ10_B @S9S_MB_2U_LIB.S9S_MB_2U(SCH_1):M_H_CPU0_SB_DQ(10)
 258 M_H_CPU0_SB_DQ<11> DQ11_B @S9S_MB_2U_LIB.S9S_MB_2U(SCH_1):M_H_CPU0_SB_DQ(11)
 118 M_H_CPU0_SB_DQ<12> DQ12_B @S9S_MB_2U_LIB.S9S_MB_2U(SCH_1):M_H_CPU0_SB_DQ(12)
 120 M_H_CPU0_SB_DQ<13> DQ13_B @S9S_MB_2U_LIB.S9S_MB_2U(SCH_1):M_H_CPU0_SB_DQ(13)
 263 M_H_CPU0_SB_DQ<14> DQ14_B @S9S_MB_2U_LIB.S9S_MB_2U(SCH_1):M_H_CPU0_SB_DQ(14)
 265 M_H_CPU0_SB_DQ<15> DQ15_B @S9S_MB_2U_LIB.S9S_MB_2U(SCH_1):M_H_CPU0_SB_DQ(15)
 122 M_H_CPU0_SB_DQ<16> DQ16_B @S9S_MB_2U_LIB.S9S_MB_2U(SCH_1):M_H_CPU0_SB_DQ(16)
 124 M_H_CPU0_SB_DQ<17> DQ17_B @S9S_MB_2U_LIB.S9S_MB_2U(SCH_1):M_H_CPU0_SB_DQ(17)
 267 M_H_CPU0_SB_DQ<18> DQ18_B @S9S_MB_2U_LIB.S9S_MB_2U(SCH_1):M_H_CPU0_SB_DQ(18)
 269 M_H_CPU0_SB_DQ<19> DQ19_B @S9S_MB_2U_LIB.S9S_MB_2U(SCH_1):M_H_CPU0_SB_DQ(19)
 129 M_H_CPU0_SB_DQ<20> DQ20_B @S9S_MB_2U_LIB.S9S_MB_2U(SCH_1):M_H_CPU0_SB_DQ(20)
 131 M_H_CPU0_SB_DQ<21> DQ21_B @S9S_MB_2U_LIB.S9S_MB_2U(SCH_1):M_H_CPU0_SB_DQ(21)
 274 M_H_CPU0_SB_DQ<22> DQ22_B @S9S_MB_2U_LIB.S9S_MB_2U(SCH_1):M_H_CPU0_SB_DQ(22)
 276 M_H_CPU0_SB_DQ<23> DQ23_B @S9S_MB_2U_LIB.S9S_MB_2U(SCH_1):M_H_CPU0_SB_DQ(23)
 133 M_H_CPU0_SB_DQ<24> DQ24_B @S9S_MB_2U_LIB.S9S_MB_2U(SCH_1):M_H_CPU0_SB_DQ(24)
 135 M_H_CPU0_SB_DQ<25> DQ25_B @S9S_MB_2U_LIB.S9S_MB_2U(SCH_1):M_H_CPU0_SB_DQ(25)
 278 M_H_CPU0_SB_DQ<26> DQ26_B @S9S_MB_2U_LIB.S9S_MB_2U(SCH_1):M_H_CPU0_SB_DQ(26)
 280 M_H_CPU0_SB_DQ<27> DQ27_B @S9S_MB_2U_LIB.S9S_MB_2U(SCH_1):M_H_CPU0_SB_DQ(27)
 140 M_H_CPU0_SB_DQ<28> DQ28_B @S9S_MB_2U_LIB.S9S_MB_2U(SCH_1):M_H_CPU0_SB_DQ(28)
 142 M_H_CPU0_SB_DQ<29> DQ29_B @S9S_MB_2U_LIB.S9S_MB_2U(SCH_1):M_H_CPU0_SB_DQ(29)
 285 M_H_CPU0_SB_DQ<30> DQ30_B @S9S_MB_2U_LIB.S9S_MB_2U(SCH_1):M_H_CPU0_SB_DQ(30)
 287 M_H_CPU0_SB_DQ<31> DQ31_B @S9S_MB_2U_LIB.S9S_MB_2U(SCH_1):M_H_CPU0_SB_DQ(31)
   7 M_H_CPU0_SA_DQ<0>  DQ0_A @S9S_MB_2U_LIB.S9S_MB_2U(SCH_1):M_H_CPU0_SA_DQ(0)
   9 M_H_CPU0_SA_DQ<1>  DQ1_A @S9S_MB_2U_LIB.S9S_MB_2U(SCH_1):M_H_CPU0_SA_DQ(1)
 152 M_H_CPU0_SA_DQ<2>  DQ2_A @S9S_MB_2U_LIB.S9S_MB_2U(SCH_1):M_H_CPU0_SA_DQ(2)
 154 M_H_CPU0_SA_DQ<3>  DQ3_A @S9S_MB_2U_LIB.S9S_MB_2U(SCH_1):M_H_CPU0_SA_DQ(3)
  14 M_H_CPU0_SA_DQ<4>  DQ4_A @S9S_MB_2U_LIB.S9S_MB_2U(SCH_1):M_H_CPU0_SA_DQ(4)
  16 M_H_CPU0_SA_DQ<5>  DQ5_A @S9S_MB_2U_LIB.S9S_MB_2U(SCH_1):M_H_CPU0_SA_DQ(5)
 159 M_H_CPU0_SA_DQ<6>  DQ6_A @S9S_MB_2U_LIB.S9S_MB_2U(SCH_1):M_H_CPU0_SA_DQ(6)
 161 M_H_CPU0_SA_DQ<7>  DQ7_A @S9S_MB_2U_LIB.S9S_MB_2U(SCH_1):M_H_CPU0_SA_DQ(7)
  18 M_H_CPU0_SA_DQ<8>  DQ8_A @S9S_MB_2U_LIB.S9S_MB_2U(SCH_1):M_H_CPU0_SA_DQ(8)
  20 M_H_CPU0_SA_DQ<9>  DQ9_A @S9S_MB_2U_LIB.S9S_MB_2U(SCH_1):M_H_CPU0_SA_DQ(9)
 163 M_H_CPU0_SA_DQ<10> DQ10_A @S9S_MB_2U_LIB.S9S_MB_2U(SCH_1):M_H_CPU0_SA_DQ(10)
 165 M_H_CPU0_SA_DQ<11> DQ11_A @S9S_MB_2U_LIB.S9S_MB_2U(SCH_1):M_H_CPU0_SA_DQ(11)
  25 M_H_CPU0_SA_DQ<12> DQ12_A @S9S_MB_2U_LIB.S9S_MB_2U(SCH_1):M_H_CPU0_SA_DQ(12)
  27 M_H_CPU0_SA_DQ<13> DQ13_A @S9S_MB_2U_LIB.S9S_MB_2U(SCH_1):M_H_CPU0_SA_DQ(13)
 170 M_H_CPU0_SA_DQ<14> DQ14_A @S9S_MB_2U_LIB.S9S_MB_2U(SCH_1):M_H_CPU0_SA_DQ(14)
 172 M_H_CPU0_SA_DQ<15> DQ15_A @S9S_MB_2U_LIB.S9S_MB_2U(SCH_1):M_H_CPU0_SA_DQ(15)
  29 M_H_CPU0_SA_DQ<16> DQ16_A @S9S_MB_2U_LIB.S9S_MB_2U(SCH_1):M_H_CPU0_SA_DQ(16)
  31 M_H_CPU0_SA_DQ<17> DQ17_A @S9S_MB_2U_LIB.S9S_MB_2U(SCH_1):M_H_CPU0_SA_DQ(17)
 174 M_H_CPU0_SA_DQ<18> DQ18_A @S9S_MB_2U_LIB.S9S_MB_2U(SCH_1):M_H_CPU0_SA_DQ(18)
 176 M_H_CPU0_SA_DQ<19> DQ19_A @S9S_MB_2U_LIB.S9S_MB_2U(SCH_1):M_H_CPU0_SA_DQ(19)
  36 M_H_CPU0_SA_DQ<20> DQ20_A @S9S_MB_2U_LIB.S9S_MB_2U(SCH_1):M_H_CPU0_SA_DQ(20)
  38 M_H_CPU0_SA_DQ<21> DQ21_A @S9S_MB_2U_LIB.S9S_MB_2U(SCH_1):M_H_CPU0_SA_DQ(21)
 181 M_H_CPU0_SA_DQ<22> DQ22_A @S9S_MB_2U_LIB.S9S_MB_2U(SCH_1):M_H_CPU0_SA_DQ(22)
 183 M_H_CPU0_SA_DQ<23> DQ23_A @S9S_MB_2U_LIB.S9S_MB_2U(SCH_1):M_H_CPU0_SA_DQ(23)
  40 M_H_CPU0_SA_DQ<24> DQ24_A @S9S_MB_2U_LIB.S9S_MB_2U(SCH_1):M_H_CPU0_SA_DQ(24)
  42 M_H_CPU0_SA_DQ<25> DQ25_A @S9S_MB_2U_LIB.S9S_MB_2U(SCH_1):M_H_CPU0_SA_DQ(25)
 185 M_H_CPU0_SA_DQ<26> DQ26_A @S9S_MB_2U_LIB.S9S_MB_2U(SCH_1):M_H_CPU0_SA_DQ(26)
 187 M_H_CPU0_SA_DQ<27> DQ27_A @S9S_MB_2U_LIB.S9S_MB_2U(SCH_1):M_H_CPU0_SA_DQ(27)
  47 M_H_CPU0_SA_DQ<28> DQ28_A @S9S_MB_2U_LIB.S9S_MB_2U(SCH_1):M_H_CPU0_SA_DQ(28)
  49 M_H_CPU0_SA_DQ<29> DQ29_A @S9S_MB_2U_LIB.S9S_MB_2U(SCH_1):M_H_CPU0_SA_DQ(29)
 192 M_H_CPU0_SA_DQ<30> DQ30_A @S9S_MB_2U_LIB.S9S_MB_2U(SCH_1):M_H_CPU0_SA_DQ(30)
 229 M_H_CPU0_SB_CS_N<3> CS1_B_N @S9S_MB_2U_LIB.S9S_MB_2U(SCH_1):M_H_CPU0_SB_CS_N(3)
 209 M_H_CPU0_SA_CS_N<3> CS1_A_N @S9S_MB_2U_LIB.S9S_MB_2U(SCH_1):M_H_CPU0_SA_CS_N(3)
  84 M_H_CPU0_SB_CS_N<2> CS0_B_N @S9S_MB_2U_LIB.S9S_MB_2U(SCH_1):M_H_CPU0_SB_CS_N(2)
  64 M_H_CPU0_SA_CS_N<2> CS0_A_N @S9S_MB_2U_LIB.S9S_MB_2U(SCH_1):M_H_CPU0_SA_CS_N(2)
 217 M_H_CPU0_CLK_DP<1>   CK_T @S9S_MB_2U_LIB.S9S_MB_2U(SCH_1):M_H_CPU0_CLK_DP(1)
 218 M_H_CPU0_CLK_DN<1>   CK_C @S9S_MB_2U_LIB.S9S_MB_2U(SCH_1):M_H_CPU0_CLK_DN(1)
  96 M_H_CPU0_SB_CB<0>  CB0_B @S9S_MB_2U_LIB.S9S_MB_2U(SCH_1):M_H_CPU0_SB_CB(0)
  98 M_H_CPU0_SB_CB<1>  CB1_B @S9S_MB_2U_LIB.S9S_MB_2U(SCH_1):M_H_CPU0_SB_CB(1)
 241 M_H_CPU0_SB_CB<2>  CB2_B @S9S_MB_2U_LIB.S9S_MB_2U(SCH_1):M_H_CPU0_SB_CB(2)
 243 M_H_CPU0_SB_CB<3>  CB3_B @S9S_MB_2U_LIB.S9S_MB_2U(SCH_1):M_H_CPU0_SB_CB(3)
  89 M_H_CPU0_SB_CB<4>  CB4_B @S9S_MB_2U_LIB.S9S_MB_2U(SCH_1):M_H_CPU0_SB_CB(4)
  91 M_H_CPU0_SB_CB<5>  CB5_B @S9S_MB_2U_LIB.S9S_MB_2U(SCH_1):M_H_CPU0_SB_CB(5)
 234 M_H_CPU0_SB_CB<6>  CB6_B @S9S_MB_2U_LIB.S9S_MB_2U(SCH_1):M_H_CPU0_SB_CB(6)
  51 M_H_CPU0_SA_CB<0>  CB0_A @S9S_MB_2U_LIB.S9S_MB_2U(SCH_1):M_H_CPU0_SA_CB(0)
 196 M_H_CPU0_SA_CB<2>  CB2_A @S9S_MB_2U_LIB.S9S_MB_2U(SCH_1):M_H_CPU0_SA_CB(2)
 198 M_H_CPU0_SA_CB<3>  CB3_A @S9S_MB_2U_LIB.S9S_MB_2U(SCH_1):M_H_CPU0_SA_CB(3)
  60 M_H_CPU0_SA_CB<5>  CB5_A @S9S_MB_2U_LIB.S9S_MB_2U(SCH_1):M_H_CPU0_SA_CB(5)
 203 M_H_CPU0_SA_CB<6>  CB6_A @S9S_MB_2U_LIB.S9S_MB_2U(SCH_1):M_H_CPU0_SA_CB(6)
  82 M_H_CPU0_SB_CA<6>  CA6_B @S9S_MB_2U_LIB.S9S_MB_2U(SCH_1):M_H_CPU0_SB_CA(6)
  72 M_H_CPU0_SA_CA<6>  CA6_A @S9S_MB_2U_LIB.S9S_MB_2U(SCH_1):M_H_CPU0_SA_CA(6)
 225 M_H_CPU0_SB_CA<5>  CA5_B @S9S_MB_2U_LIB.S9S_MB_2U(SCH_1):M_H_CPU0_SB_CA(5)
 215 M_H_CPU0_SA_CA<5>  CA5_A @S9S_MB_2U_LIB.S9S_MB_2U(SCH_1):M_H_CPU0_SA_CA(5)
  80 M_H_CPU0_SB_CA<4>  CA4_B @S9S_MB_2U_LIB.S9S_MB_2U(SCH_1):M_H_CPU0_SB_CA(4)
  70 M_H_CPU0_SA_CA<4>  CA4_A @S9S_MB_2U_LIB.S9S_MB_2U(SCH_1):M_H_CPU0_SA_CA(4)
 223 M_H_CPU0_SB_CA<3>  CA3_B @S9S_MB_2U_LIB.S9S_MB_2U(SCH_1):M_H_CPU0_SB_CA(3)
 213 M_H_CPU0_SA_CA<3>  CA3_A @S9S_MB_2U_LIB.S9S_MB_2U(SCH_1):M_H_CPU0_SA_CA(3)
  78 M_H_CPU0_SB_CA<2>  CA2_B @S9S_MB_2U_LIB.S9S_MB_2U(SCH_1):M_H_CPU0_SB_CA(2)
  68 M_H_CPU0_SA_CA<2>  CA2_A @S9S_MB_2U_LIB.S9S_MB_2U(SCH_1):M_H_CPU0_SA_CA(2)
 221 M_H_CPU0_SB_CA<1>  CA1_B @S9S_MB_2U_LIB.S9S_MB_2U(SCH_1):M_H_CPU0_SB_CA(1)
 211 M_H_CPU0_SA_CA<1>  CA1_A @S9S_MB_2U_LIB.S9S_MB_2U(SCH_1):M_H_CPU0_SA_CA(1)
  76 M_H_CPU0_SB_CA<0>  CA0_B @S9S_MB_2U_LIB.S9S_MB_2U(SCH_1):M_H_CPU0_SB_CA(0)
  66 M_H_CPU0_SA_CA<0>  CA0_A @S9S_MB_2U_LIB.S9S_MB_2U(SCH_1):M_H_CPU0_SA_CA(0)
  62 M_H_CPU0_ALERT_N ALERT_N @S9S_MB_2U_LIB.S9S_MB_2U(SCH_1):M_H_CPU0_ALERT_N
 236 M_H_CPU0_SB_CB<7>  CB7_B @S9S_MB_2U_LIB.S9S_MB_2U(SCH_1):M_H_CPU0_SB_CB(7)
  53 M_H_CPU0_SA_CB<1>  CB1_A @S9S_MB_2U_LIB.S9S_MB_2U(SCH_1):M_H_CPU0_SA_CB(1)
  58 M_H_CPU0_SA_CB<4>  CB4_A @S9S_MB_2U_LIB.S9S_MB_2U(SCH_1):M_H_CPU0_SA_CB(4)
 205 M_H_CPU0_SA_CB<7>  CB7_A @S9S_MB_2U_LIB.S9S_MB_2U(SCH_1):M_H_CPU0_SA_CB(7)
 194 M_H_CPU0_SA_DQ<31> DQ31_A @S9S_MB_2U_LIB.S9S_MB_2U(SCH_1):M_H_CPU0_SA_DQ(31)

Q_CAP_C0402-2.2UF,6.3V,20%,X6SA  I56  C47
   1 P3V3_AUX      A @S9S_MB_2U_LIB.S9S_MB_2U(SCH_1):P3V3_AUX
   2    GND      B @S9S_MB_2U_LIB.S9S_MB_2U(SCH_1):GND

Q_CAP_C0805-10UF,16V,10%,X6S,CA  I59  C48
   1 P12V_S3_AUX_CPU0_NVDIMM      A @S9S_MB_2U_LIB.S9S_MB_2U(SCH_1):P12V_S3_AUX_CPU0_NVDIMM
   2    GND      B @S9S_MB_2U_LIB.S9S_MB_2U(SCH_1):GND

Q_CAP_C0805-10UF,16V,10%,X6S,CA  I62  C49
   1 P12V_S3_AUX_CPU0_NVDIMM      A @S9S_MB_2U_LIB.S9S_MB_2U(SCH_1):P12V_S3_AUX_CPU0_NVDIMM
   2    GND      B @S9S_MB_2U_LIB.S9S_MB_2U(SCH_1):GND

SCONN288_ADR50017P087CC-SCONN2A  I64  J16
   6    GND   VSS0 @S9S_MB_2U_LIB.S9S_MB_2U(SCH_1):GND
   8    GND   VSS1 @S9S_MB_2U_LIB.S9S_MB_2U(SCH_1):GND
  10    GND   VSS2 @S9S_MB_2U_LIB.S9S_MB_2U(SCH_1):GND
  13    GND   VSS3 @S9S_MB_2U_LIB.S9S_MB_2U(SCH_1):GND
  15    GND   VSS4 @S9S_MB_2U_LIB.S9S_MB_2U(SCH_1):GND
  17    GND   VSS5 @S9S_MB_2U_LIB.S9S_MB_2U(SCH_1):GND
  19    GND   VSS6 @S9S_MB_2U_LIB.S9S_MB_2U(SCH_1):GND
  21    GND   VSS7 @S9S_MB_2U_LIB.S9S_MB_2U(SCH_1):GND
  24    GND   VSS8 @S9S_MB_2U_LIB.S9S_MB_2U(SCH_1):GND
  26    GND   VSS9 @S9S_MB_2U_LIB.S9S_MB_2U(SCH_1):GND
  28    GND  VSS10 @S9S_MB_2U_LIB.S9S_MB_2U(SCH_1):GND
  30    GND  VSS11 @S9S_MB_2U_LIB.S9S_MB_2U(SCH_1):GND
  32    GND  VSS12 @S9S_MB_2U_LIB.S9S_MB_2U(SCH_1):GND
  35    GND  VSS13 @S9S_MB_2U_LIB.S9S_MB_2U(SCH_1):GND
  37    GND  VSS14 @S9S_MB_2U_LIB.S9S_MB_2U(SCH_1):GND
  39    GND  VSS15 @S9S_MB_2U_LIB.S9S_MB_2U(SCH_1):GND
  41    GND  VSS16 @S9S_MB_2U_LIB.S9S_MB_2U(SCH_1):GND
  43    GND  VSS17 @S9S_MB_2U_LIB.S9S_MB_2U(SCH_1):GND
  46    GND  VSS18 @S9S_MB_2U_LIB.S9S_MB_2U(SCH_1):GND
  48    GND  VSS19 @S9S_MB_2U_LIB.S9S_MB_2U(SCH_1):GND
  50    GND  VSS20 @S9S_MB_2U_LIB.S9S_MB_2U(SCH_1):GND
  52    GND  VSS21 @S9S_MB_2U_LIB.S9S_MB_2U(SCH_1):GND
  54    GND  VSS22 @S9S_MB_2U_LIB.S9S_MB_2U(SCH_1):GND
  57    GND  VSS23 @S9S_MB_2U_LIB.S9S_MB_2U(SCH_1):GND
  59    GND  VSS24 @S9S_MB_2U_LIB.S9S_MB_2U(SCH_1):GND
  61    GND  VSS25 @S9S_MB_2U_LIB.S9S_MB_2U(SCH_1):GND
  63    GND  VSS26 @S9S_MB_2U_LIB.S9S_MB_2U(SCH_1):GND
  65    GND  VSS27 @S9S_MB_2U_LIB.S9S_MB_2U(SCH_1):GND
  67    GND  VSS28 @S9S_MB_2U_LIB.S9S_MB_2U(SCH_1):GND
  69    GND  VSS29 @S9S_MB_2U_LIB.S9S_MB_2U(SCH_1):GND
  71    GND  VSS30 @S9S_MB_2U_LIB.S9S_MB_2U(SCH_1):GND
  73    GND  VSS31 @S9S_MB_2U_LIB.S9S_MB_2U(SCH_1):GND
  75    GND  VSS32 @S9S_MB_2U_LIB.S9S_MB_2U(SCH_1):GND
  77    GND  VSS33 @S9S_MB_2U_LIB.S9S_MB_2U(SCH_1):GND
  79    GND  VSS34 @S9S_MB_2U_LIB.S9S_MB_2U(SCH_1):GND
  81    GND  VSS35 @S9S_MB_2U_LIB.S9S_MB_2U(SCH_1):GND
  83    GND  VSS36 @S9S_MB_2U_LIB.S9S_MB_2U(SCH_1):GND
  85    GND  VSS37 @S9S_MB_2U_LIB.S9S_MB_2U(SCH_1):GND
  88    GND  VSS38 @S9S_MB_2U_LIB.S9S_MB_2U(SCH_1):GND
  90    GND  VSS39 @S9S_MB_2U_LIB.S9S_MB_2U(SCH_1):GND
  92    GND  VSS40 @S9S_MB_2U_LIB.S9S_MB_2U(SCH_1):GND
  95    GND  VSS41 @S9S_MB_2U_LIB.S9S_MB_2U(SCH_1):GND
  97    GND  VSS42 @S9S_MB_2U_LIB.S9S_MB_2U(SCH_1):GND
  99    GND  VSS43 @S9S_MB_2U_LIB.S9S_MB_2U(SCH_1):GND
 101    GND  VSS44 @S9S_MB_2U_LIB.S9S_MB_2U(SCH_1):GND
 103    GND  VSS45 @S9S_MB_2U_LIB.S9S_MB_2U(SCH_1):GND
 106    GND  VSS46 @S9S_MB_2U_LIB.S9S_MB_2U(SCH_1):GND
 108    GND  VSS47 @S9S_MB_2U_LIB.S9S_MB_2U(SCH_1):GND
 110    GND  VSS48 @S9S_MB_2U_LIB.S9S_MB_2U(SCH_1):GND
 112    GND  VSS49 @S9S_MB_2U_LIB.S9S_MB_2U(SCH_1):GND
 114    GND  VSS50 @S9S_MB_2U_LIB.S9S_MB_2U(SCH_1):GND
 117    GND  VSS51 @S9S_MB_2U_LIB.S9S_MB_2U(SCH_1):GND
 119    GND  VSS52 @S9S_MB_2U_LIB.S9S_MB_2U(SCH_1):GND
 121    GND  VSS53 @S9S_MB_2U_LIB.S9S_MB_2U(SCH_1):GND
 123    GND  VSS54 @S9S_MB_2U_LIB.S9S_MB_2U(SCH_1):GND
 125    GND  VSS55 @S9S_MB_2U_LIB.S9S_MB_2U(SCH_1):GND
 128    GND  VSS56 @S9S_MB_2U_LIB.S9S_MB_2U(SCH_1):GND
 130    GND  VSS57 @S9S_MB_2U_LIB.S9S_MB_2U(SCH_1):GND
 134    GND  VSS59 @S9S_MB_2U_LIB.S9S_MB_2U(SCH_1):GND
 143    GND  VSS63 @S9S_MB_2U_LIB.S9S_MB_2U(SCH_1):GND
 151    GND  VSS64 @S9S_MB_2U_LIB.S9S_MB_2U(SCH_1):GND
 153    GND  VSS65 @S9S_MB_2U_LIB.S9S_MB_2U(SCH_1):GND
 155    GND  VSS66 @S9S_MB_2U_LIB.S9S_MB_2U(SCH_1):GND
 158    GND  VSS67 @S9S_MB_2U_LIB.S9S_MB_2U(SCH_1):GND
 160    GND  VSS68 @S9S_MB_2U_LIB.S9S_MB_2U(SCH_1):GND
 162    GND  VSS69 @S9S_MB_2U_LIB.S9S_MB_2U(SCH_1):GND
 164    GND  VSS70 @S9S_MB_2U_LIB.S9S_MB_2U(SCH_1):GND
 166    GND  VSS71 @S9S_MB_2U_LIB.S9S_MB_2U(SCH_1):GND
 169    GND  VSS72 @S9S_MB_2U_LIB.S9S_MB_2U(SCH_1):GND
 171    GND  VSS73 @S9S_MB_2U_LIB.S9S_MB_2U(SCH_1):GND
 173    GND  VSS74 @S9S_MB_2U_LIB.S9S_MB_2U(SCH_1):GND
 175    GND  VSS75 @S9S_MB_2U_LIB.S9S_MB_2U(SCH_1):GND
 177    GND  VSS76 @S9S_MB_2U_LIB.S9S_MB_2U(SCH_1):GND
 180    GND  VSS77 @S9S_MB_2U_LIB.S9S_MB_2U(SCH_1):GND
 182    GND  VSS78 @S9S_MB_2U_LIB.S9S_MB_2U(SCH_1):GND
 184    GND  VSS79 @S9S_MB_2U_LIB.S9S_MB_2U(SCH_1):GND
 186    GND  VSS80 @S9S_MB_2U_LIB.S9S_MB_2U(SCH_1):GND
 188    GND  VSS81 @S9S_MB_2U_LIB.S9S_MB_2U(SCH_1):GND
 191    GND  VSS82 @S9S_MB_2U_LIB.S9S_MB_2U(SCH_1):GND
 193    GND  VSS83 @S9S_MB_2U_LIB.S9S_MB_2U(SCH_1):GND
 195    GND  VSS84 @S9S_MB_2U_LIB.S9S_MB_2U(SCH_1):GND
 197    GND  VSS85 @S9S_MB_2U_LIB.S9S_MB_2U(SCH_1):GND
 199    GND  VSS86 @S9S_MB_2U_LIB.S9S_MB_2U(SCH_1):GND
 202    GND  VSS87 @S9S_MB_2U_LIB.S9S_MB_2U(SCH_1):GND
 204    GND  VSS88 @S9S_MB_2U_LIB.S9S_MB_2U(SCH_1):GND
 206    GND  VSS89 @S9S_MB_2U_LIB.S9S_MB_2U(SCH_1):GND
 208    GND  VSS90 @S9S_MB_2U_LIB.S9S_MB_2U(SCH_1):GND
 210    GND  VSS91 @S9S_MB_2U_LIB.S9S_MB_2U(SCH_1):GND
 212    GND  VSS92 @S9S_MB_2U_LIB.S9S_MB_2U(SCH_1):GND
 214    GND  VSS93 @S9S_MB_2U_LIB.S9S_MB_2U(SCH_1):GND
 216    GND  VSS94 @S9S_MB_2U_LIB.S9S_MB_2U(SCH_1):GND
 219    GND  VSS95 @S9S_MB_2U_LIB.S9S_MB_2U(SCH_1):GND
 222    GND  VSS96 @S9S_MB_2U_LIB.S9S_MB_2U(SCH_1):GND
 224    GND  VSS97 @S9S_MB_2U_LIB.S9S_MB_2U(SCH_1):GND
 226    GND  VSS98 @S9S_MB_2U_LIB.S9S_MB_2U(SCH_1):GND
 228    GND  VSS99 @S9S_MB_2U_LIB.S9S_MB_2U(SCH_1):GND
 233    GND VSS101 @S9S_MB_2U_LIB.S9S_MB_2U(SCH_1):GND
 237    GND VSS103 @S9S_MB_2U_LIB.S9S_MB_2U(SCH_1):GND
 242    GND VSS105 @S9S_MB_2U_LIB.S9S_MB_2U(SCH_1):GND
 244    GND VSS106 @S9S_MB_2U_LIB.S9S_MB_2U(SCH_1):GND
 246    GND VSS107 @S9S_MB_2U_LIB.S9S_MB_2U(SCH_1):GND
 248    GND VSS108 @S9S_MB_2U_LIB.S9S_MB_2U(SCH_1):GND
 251    GND VSS109 @S9S_MB_2U_LIB.S9S_MB_2U(SCH_1):GND
 253    GND VSS110 @S9S_MB_2U_LIB.S9S_MB_2U(SCH_1):GND
 255    GND VSS111 @S9S_MB_2U_LIB.S9S_MB_2U(SCH_1):GND
 257    GND VSS112 @S9S_MB_2U_LIB.S9S_MB_2U(SCH_1):GND
 259    GND VSS113 @S9S_MB_2U_LIB.S9S_MB_2U(SCH_1):GND
 262    GND VSS114 @S9S_MB_2U_LIB.S9S_MB_2U(SCH_1):GND
 264    GND VSS115 @S9S_MB_2U_LIB.S9S_MB_2U(SCH_1):GND
 266    GND VSS116 @S9S_MB_2U_LIB.S9S_MB_2U(SCH_1):GND
 268    GND VSS117 @S9S_MB_2U_LIB.S9S_MB_2U(SCH_1):GND
 270    GND VSS118 @S9S_MB_2U_LIB.S9S_MB_2U(SCH_1):GND
 273    GND VSS119 @S9S_MB_2U_LIB.S9S_MB_2U(SCH_1):GND
 275    GND VSS120 @S9S_MB_2U_LIB.S9S_MB_2U(SCH_1):GND
 277    GND VSS121 @S9S_MB_2U_LIB.S9S_MB_2U(SCH_1):GND
 279    GND VSS122 @S9S_MB_2U_LIB.S9S_MB_2U(SCH_1):GND
 281    GND VSS123 @S9S_MB_2U_LIB.S9S_MB_2U(SCH_1):GND
 284    GND VSS124 @S9S_MB_2U_LIB.S9S_MB_2U(SCH_1):GND
 286    GND VSS125 @S9S_MB_2U_LIB.S9S_MB_2U(SCH_1):GND
 288    GND VSS126 @S9S_MB_2U_LIB.S9S_MB_2U(SCH_1):GND
   1 P12V_S3_AUX_CPU0_NVDIMM VIN_BULK0 @S9S_MB_2U_LIB.S9S_MB_2U(SCH_1):P12V_S3_AUX_CPU0_NVDIMM
 145 P12V_S3_AUX_CPU0_NVDIMM VIN_BULK1 @S9S_MB_2U_LIB.S9S_MB_2U(SCH_1):P12V_S3_AUX_CPU0_NVDIMM
 146 P12V_S3_AUX_CPU0_NVDIMM VIN_BULK2 @S9S_MB_2U_LIB.S9S_MB_2U(SCH_1):P12V_S3_AUX_CPU0_NVDIMM
 230    GND VSS100 @S9S_MB_2U_LIB.S9S_MB_2U(SCH_1):GND
 235    GND VSS102 @S9S_MB_2U_LIB.S9S_MB_2U(SCH_1):GND
 240    GND VSS104 @S9S_MB_2U_LIB.S9S_MB_2U(SCH_1):GND
 132    GND  VSS58 @S9S_MB_2U_LIB.S9S_MB_2U(SCH_1):GND
 136    GND  VSS60 @S9S_MB_2U_LIB.S9S_MB_2U(SCH_1):GND
 139    GND  VSS61 @S9S_MB_2U_LIB.S9S_MB_2U(SCH_1):GND
 141    GND  VSS62 @S9S_MB_2U_LIB.S9S_MB_2U(SCH_1):GND
  G1    GND     G1 @S9S_MB_2U_LIB.S9S_MB_2U(SCH_1):GND
  G2    GND     G2 @S9S_MB_2U_LIB.S9S_MB_2U(SCH_1):GND
  G3    GND     G3 @S9S_MB_2U_LIB.S9S_MB_2U(SCH_1):GND

SCONN288_ADR50017P087CC-SCONN2A  I178  J16
  93 M_H_CPU0_SB_DQS_DP<9> DQS9_B_T||TDQS9_B_T||DBI4_B_N @S9S_MB_2U_LIB.S9S_MB_2U(SCH_1):M_H_CPU0_SB_DQS_DP(9)
  94 M_H_CPU0_SB_DQS_DN<9> DQS9_B_C||TDQS9_B_C @S9S_MB_2U_LIB.S9S_MB_2U(SCH_1):M_H_CPU0_SB_DQS_DN(9)
 201 M_H_CPU0_SA_DQS_DP<9> DQS9_A_T||TDQS9_A_T @S9S_MB_2U_LIB.S9S_MB_2U(SCH_1):M_H_CPU0_SA_DQS_DP(9)
 200 M_H_CPU0_SA_DQS_DN<9> DQS9_A_C||TDQS9_A_C @S9S_MB_2U_LIB.S9S_MB_2U(SCH_1):M_H_CPU0_SA_DQS_DN(9)
 190 M_H_CPU0_SA_DQS_DP<8> DQS8_A_T||TDQS8_A_T @S9S_MB_2U_LIB.S9S_MB_2U(SCH_1):M_H_CPU0_SA_DQS_DP(8)
 189 M_H_CPU0_SA_DQS_DN<8> DQS8_A_C||TDQS8_A_C @S9S_MB_2U_LIB.S9S_MB_2U(SCH_1):M_H_CPU0_SA_DQS_DN(8)
 271 M_H_CPU0_SB_DQS_DN<7> DQS7_B_C||TDQS7_B_C @S9S_MB_2U_LIB.S9S_MB_2U(SCH_1):M_H_CPU0_SB_DQS_DN(7)
 179 M_H_CPU0_SA_DQS_DP<7> DQS7_A_T||TDQS7_A_T @S9S_MB_2U_LIB.S9S_MB_2U(SCH_1):M_H_CPU0_SA_DQS_DP(7)
 261 M_H_CPU0_SB_DQS_DP<6> DQS6_B_T||TDQS6_B_T @S9S_MB_2U_LIB.S9S_MB_2U(SCH_1):M_H_CPU0_SB_DQS_DP(6)
 260 M_H_CPU0_SB_DQS_DN<6> DQS6_B_C||TDQS6_B_C @S9S_MB_2U_LIB.S9S_MB_2U(SCH_1):M_H_CPU0_SB_DQS_DN(6)
 167 M_H_CPU0_SA_DQS_DN<6> DQS6_A_C||TDQS6_A_C||DQS6_A_T||TDQS6_A_T @S9S_MB_2U_LIB.S9S_MB_2U(SCH_1):M_H_CPU0_SA_DQS_DN(6)
 250 M_H_CPU0_SB_DQS_DP<5> DQS5_B_T||TDQS5_B_T @S9S_MB_2U_LIB.S9S_MB_2U(SCH_1):M_H_CPU0_SB_DQS_DP(5)
 249 M_H_CPU0_SB_DQS_DN<5> DQS5_B_C||TDQS5_B_C @S9S_MB_2U_LIB.S9S_MB_2U(SCH_1):M_H_CPU0_SB_DQS_DN(5)
 157 M_H_CPU0_SA_DQS_DP<5> DQS5_A_T||TDQS5_A_T @S9S_MB_2U_LIB.S9S_MB_2U(SCH_1):M_H_CPU0_SA_DQS_DP(5)
 156 M_H_CPU0_SA_DQS_DN<5> DQS5_A_C||TDQS5_A_C||DQS5_A_T||TDQS5_A_T @S9S_MB_2U_LIB.S9S_MB_2U(SCH_1):M_H_CPU0_SA_DQS_DN(5)
 239 M_H_CPU0_SB_DQS_DP<4> DQS4_B_T @S9S_MB_2U_LIB.S9S_MB_2U(SCH_1):M_H_CPU0_SB_DQS_DP(4)
 238 M_H_CPU0_SB_DQS_DN<4> DQS4_B_C @S9S_MB_2U_LIB.S9S_MB_2U(SCH_1):M_H_CPU0_SB_DQS_DN(4)
  55 M_H_CPU0_SA_DQS_DP<4> DQS4_A_T @S9S_MB_2U_LIB.S9S_MB_2U(SCH_1):M_H_CPU0_SA_DQS_DP(4)
  56 M_H_CPU0_SA_DQS_DN<4> DQS4_A_C @S9S_MB_2U_LIB.S9S_MB_2U(SCH_1):M_H_CPU0_SA_DQS_DN(4)
 137 M_H_CPU0_SB_DQS_DP<3> DQS3_B_T @S9S_MB_2U_LIB.S9S_MB_2U(SCH_1):M_H_CPU0_SB_DQS_DP(3)
 138 M_H_CPU0_SB_DQS_DN<3> DQS3_B_C @S9S_MB_2U_LIB.S9S_MB_2U(SCH_1):M_H_CPU0_SB_DQS_DN(3)
  44 M_H_CPU0_SA_DQS_DP<3> DQS3_A_T @S9S_MB_2U_LIB.S9S_MB_2U(SCH_1):M_H_CPU0_SA_DQS_DP(3)
  45 M_H_CPU0_SA_DQS_DN<3> DQS3_A_C @S9S_MB_2U_LIB.S9S_MB_2U(SCH_1):M_H_CPU0_SA_DQS_DN(3)
 126 M_H_CPU0_SB_DQS_DP<2> DQS2_B_T @S9S_MB_2U_LIB.S9S_MB_2U(SCH_1):M_H_CPU0_SB_DQS_DP(2)
 127 M_H_CPU0_SB_DQS_DN<2> DQS2_B_C @S9S_MB_2U_LIB.S9S_MB_2U(SCH_1):M_H_CPU0_SB_DQS_DN(2)
  33 M_H_CPU0_SA_DQS_DP<2> DQS2_A_T @S9S_MB_2U_LIB.S9S_MB_2U(SCH_1):M_H_CPU0_SA_DQS_DP(2)
  34 M_H_CPU0_SA_DQS_DN<2> DQS2_A_C @S9S_MB_2U_LIB.S9S_MB_2U(SCH_1):M_H_CPU0_SA_DQS_DN(2)
 115 M_H_CPU0_SB_DQS_DP<1> DQS1_B_T @S9S_MB_2U_LIB.S9S_MB_2U(SCH_1):M_H_CPU0_SB_DQS_DP(1)
 116 M_H_CPU0_SB_DQS_DN<1> DQS1_B_C @S9S_MB_2U_LIB.S9S_MB_2U(SCH_1):M_H_CPU0_SB_DQS_DN(1)
  22 M_H_CPU0_SA_DQS_DP<1> DQS1_A_T @S9S_MB_2U_LIB.S9S_MB_2U(SCH_1):M_H_CPU0_SA_DQS_DP(1)
  23 M_H_CPU0_SA_DQS_DN<1> DQS1_A_C @S9S_MB_2U_LIB.S9S_MB_2U(SCH_1):M_H_CPU0_SA_DQS_DN(1)
 104 M_H_CPU0_SB_DQS_DP<0> DQS0_B_T @S9S_MB_2U_LIB.S9S_MB_2U(SCH_1):M_H_CPU0_SB_DQS_DP(0)
 105 M_H_CPU0_SB_DQS_DN<0> DQS0_B_C @S9S_MB_2U_LIB.S9S_MB_2U(SCH_1):M_H_CPU0_SB_DQS_DN(0)
  11 M_H_CPU0_SA_DQS_DP<0> DQS0_A_T @S9S_MB_2U_LIB.S9S_MB_2U(SCH_1):M_H_CPU0_SA_DQS_DP(0)
  12 M_H_CPU0_SA_DQS_DN<0> DQS0_A_C @S9S_MB_2U_LIB.S9S_MB_2U(SCH_1):M_H_CPU0_SA_DQS_DN(0)
 272 M_H_CPU0_SB_DQS_DP<7> DQS7_B_T||TDQS7_B_T @S9S_MB_2U_LIB.S9S_MB_2U(SCH_1):M_H_CPU0_SB_DQS_DP(7)
 282 M_H_CPU0_SB_DQS_DN<8> DQS8_B_C||TDQS8_B_C @S9S_MB_2U_LIB.S9S_MB_2U(SCH_1):M_H_CPU0_SB_DQS_DN(8)
 283 M_H_CPU0_SB_DQS_DP<8> DQS8_B_T||TDQS8_B_T @S9S_MB_2U_LIB.S9S_MB_2U(SCH_1):M_H_CPU0_SB_DQS_DP(8)
 168 M_H_CPU0_SA_DQS_DP<6> DQS6_A_T||TDQS6_A_T @S9S_MB_2U_LIB.S9S_MB_2U(SCH_1):M_H_CPU0_SA_DQS_DP(6)
 178 M_H_CPU0_SA_DQS_DN<7> DQS7_A_C||TDQS7_A_C @S9S_MB_2U_LIB.S9S_MB_2U(SCH_1):M_H_CPU0_SA_DQS_DN(7)

Q_RES_0402LF-49.9,1%,1/16W,CHIA  I179  R3890
   1 I3C_SPD_DDREFGH_CPU0_LVC1_SCL_7      A @S9S_MB_2U_LIB.S9S_MB_2U(SCH_1):I3C_SPD_DDREFGH_CPU0_LVC1_SCL_R8
   2 I3C_SPD_DDREFGH_CPU0_LVC1_SCL      B @S9S_MB_2U_LIB.S9S_MB_2U(SCH_1):I3C_SPD_DDREFGH_CPU0_LVC1_SCL


DRAWING: @S9S_MB_2U_LIB.S9S_MB_2U(SCH_1):PAGE98 

Q_RES_0402LF-10K,1%,1/16W,CHIPA  I11  R42
   1 PD_CHA_CPU1_DIMM1_SAA      A @S9S_MB_2U_LIB.S9S_MB_2U(SCH_1):PD_CHA_CPU1_DIMM1_SAA
   2    GND      B @S9S_MB_2U_LIB.S9S_MB_2U(SCH_1):GND

SCONN288_ADR50017P130CC-SCONN2A  I12  J17
   3 P3V3_AUX VIN_MGMT @S9S_MB_2U_LIB.S9S_MB_2U(SCH_1):P3V3_AUX
   2 TP_CHA_CPU1_DIMM1_FRU_0   RFU0 @S9S_MB_2U_LIB.S9S_MB_2U(SCH_1):TP_CHA_CPU1_DIMM1_FRU_0
 144 TP_CHA_CPU1_DIMM1_FRU_1   RFU1 @S9S_MB_2U_LIB.S9S_MB_2U(SCH_1):TP_CHA_CPU1_DIMM1_FRU_1
 149 TP_CHA_CPU1_DIMM1_FRU_2   RFU2 @S9S_MB_2U_LIB.S9S_MB_2U(SCH_1):TP_CHA_CPU1_DIMM1_FRU_2
 150 TP_CHA_CPU1_DIMM1_FRU_3   RFU3 @S9S_MB_2U_LIB.S9S_MB_2U(SCH_1):TP_CHA_CPU1_DIMM1_FRU_3
 220 TP_CHA_CPU1_DIMM1_FRU_4   RFU4 @S9S_MB_2U_LIB.S9S_MB_2U(SCH_1):TP_CHA_CPU1_DIMM1_FRU_4
 231 TP_CHA_CPU1_DIMM1_FRU_5   RFU5 @S9S_MB_2U_LIB.S9S_MB_2U(SCH_1):TP_CHA_CPU1_DIMM1_FRU_5
 232 TP_CHA_CPU1_DIMM1_FRU_6   RFU6 @S9S_MB_2U_LIB.S9S_MB_2U(SCH_1):TP_CHA_CPU1_DIMM1_FRU_6
 207 RST_M_AB_CPU1_FPGA_N RESET_N @S9S_MB_2U_LIB.S9S_MB_2U(SCH_1):RST_M_AB_CPU1_FPGA_N
 147 PWRGD_CHA_CPU1_DIMM1 PWR_GOOD||FAIL_N @S9S_MB_2U_LIB.S9S_MB_2U(SCH_1):PWRGD_CHA_CPU1_DIMM1
 227 M_A_CPU1_SB_PAR  PAR_B @S9S_MB_2U_LIB.S9S_MB_2U(SCH_1):M_A_CPU1_SB_PAR
  74 M_A_CPU1_SA_PAR  PAR_A @S9S_MB_2U_LIB.S9S_MB_2U(SCH_1):M_A_CPU1_SA_PAR
  87 M_A_CPU1_SB_RSP<0> LBS||RSP_B_N @S9S_MB_2U_LIB.S9S_MB_2U(SCH_1):M_A_CPU1_SB_RSP(0)
  86 M_A_CPU1_SA_RSP<0> LBD||RSP_A_N @S9S_MB_2U_LIB.S9S_MB_2U(SCH_1):M_A_CPU1_SA_RSP(0)
   5 I3C_SPD_DDRABCD_CPU1_LVC1_SDA   HSDA @S9S_MB_2U_LIB.S9S_MB_2U(SCH_1):I3C_SPD_DDRABCD_CPU1_LVC1_SDA
   4 I3C_SPD_DDRABCD_CPU1_LVC1_SCL_R   HSCL @S9S_MB_2U_LIB.S9S_MB_2U(SCH_1):I3C_SPD_DDRABCD_CPU1_LVC1_SCL_R1
 148 PD_CHA_CPU1_DIMM1_SAA    HSA @S9S_MB_2U_LIB.S9S_MB_2U(SCH_1):PD_CHA_CPU1_DIMM1_SAA
 100 M_A_CPU1_SB_DQ<0>  DQ0_B @S9S_MB_2U_LIB.S9S_MB_2U(SCH_1):M_A_CPU1_SB_DQ(0)
 102 M_A_CPU1_SB_DQ<1>  DQ1_B @S9S_MB_2U_LIB.S9S_MB_2U(SCH_1):M_A_CPU1_SB_DQ(1)
 245 M_A_CPU1_SB_DQ<2>  DQ2_B @S9S_MB_2U_LIB.S9S_MB_2U(SCH_1):M_A_CPU1_SB_DQ(2)
 247 M_A_CPU1_SB_DQ<3>  DQ3_B @S9S_MB_2U_LIB.S9S_MB_2U(SCH_1):M_A_CPU1_SB_DQ(3)
 107 M_A_CPU1_SB_DQ<4>  DQ4_B @S9S_MB_2U_LIB.S9S_MB_2U(SCH_1):M_A_CPU1_SB_DQ(4)
 109 M_A_CPU1_SB_DQ<5>  DQ5_B @S9S_MB_2U_LIB.S9S_MB_2U(SCH_1):M_A_CPU1_SB_DQ(5)
 252 M_A_CPU1_SB_DQ<6>  DQ6_B @S9S_MB_2U_LIB.S9S_MB_2U(SCH_1):M_A_CPU1_SB_DQ(6)
 254 M_A_CPU1_SB_DQ<7>  DQ7_B @S9S_MB_2U_LIB.S9S_MB_2U(SCH_1):M_A_CPU1_SB_DQ(7)
 111 M_A_CPU1_SB_DQ<8>  DQ8_B @S9S_MB_2U_LIB.S9S_MB_2U(SCH_1):M_A_CPU1_SB_DQ(8)
 113 M_A_CPU1_SB_DQ<9>  DQ9_B @S9S_MB_2U_LIB.S9S_MB_2U(SCH_1):M_A_CPU1_SB_DQ(9)
 256 M_A_CPU1_SB_DQ<10> DQ10_B @S9S_MB_2U_LIB.S9S_MB_2U(SCH_1):M_A_CPU1_SB_DQ(10)
 258 M_A_CPU1_SB_DQ<11> DQ11_B @S9S_MB_2U_LIB.S9S_MB_2U(SCH_1):M_A_CPU1_SB_DQ(11)
 118 M_A_CPU1_SB_DQ<12> DQ12_B @S9S_MB_2U_LIB.S9S_MB_2U(SCH_1):M_A_CPU1_SB_DQ(12)
 120 M_A_CPU1_SB_DQ<13> DQ13_B @S9S_MB_2U_LIB.S9S_MB_2U(SCH_1):M_A_CPU1_SB_DQ(13)
 263 M_A_CPU1_SB_DQ<14> DQ14_B @S9S_MB_2U_LIB.S9S_MB_2U(SCH_1):M_A_CPU1_SB_DQ(14)
 265 M_A_CPU1_SB_DQ<15> DQ15_B @S9S_MB_2U_LIB.S9S_MB_2U(SCH_1):M_A_CPU1_SB_DQ(15)
 122 M_A_CPU1_SB_DQ<16> DQ16_B @S9S_MB_2U_LIB.S9S_MB_2U(SCH_1):M_A_CPU1_SB_DQ(16)
 124 M_A_CPU1_SB_DQ<17> DQ17_B @S9S_MB_2U_LIB.S9S_MB_2U(SCH_1):M_A_CPU1_SB_DQ(17)
 267 M_A_CPU1_SB_DQ<18> DQ18_B @S9S_MB_2U_LIB.S9S_MB_2U(SCH_1):M_A_CPU1_SB_DQ(18)
 269 M_A_CPU1_SB_DQ<19> DQ19_B @S9S_MB_2U_LIB.S9S_MB_2U(SCH_1):M_A_CPU1_SB_DQ(19)
 129 M_A_CPU1_SB_DQ<20> DQ20_B @S9S_MB_2U_LIB.S9S_MB_2U(SCH_1):M_A_CPU1_SB_DQ(20)
 131 M_A_CPU1_SB_DQ<21> DQ21_B @S9S_MB_2U_LIB.S9S_MB_2U(SCH_1):M_A_CPU1_SB_DQ(21)
 274 M_A_CPU1_SB_DQ<22> DQ22_B @S9S_MB_2U_LIB.S9S_MB_2U(SCH_1):M_A_CPU1_SB_DQ(22)
 276 M_A_CPU1_SB_DQ<23> DQ23_B @S9S_MB_2U_LIB.S9S_MB_2U(SCH_1):M_A_CPU1_SB_DQ(23)
 133 M_A_CPU1_SB_DQ<24> DQ24_B @S9S_MB_2U_LIB.S9S_MB_2U(SCH_1):M_A_CPU1_SB_DQ(24)
 135 M_A_CPU1_SB_DQ<25> DQ25_B @S9S_MB_2U_LIB.S9S_MB_2U(SCH_1):M_A_CPU1_SB_DQ(25)
 278 M_A_CPU1_SB_DQ<26> DQ26_B @S9S_MB_2U_LIB.S9S_MB_2U(SCH_1):M_A_CPU1_SB_DQ(26)
 280 M_A_CPU1_SB_DQ<27> DQ27_B @S9S_MB_2U_LIB.S9S_MB_2U(SCH_1):M_A_CPU1_SB_DQ(27)
 140 M_A_CPU1_SB_DQ<28> DQ28_B @S9S_MB_2U_LIB.S9S_MB_2U(SCH_1):M_A_CPU1_SB_DQ(28)
 142 M_A_CPU1_SB_DQ<29> DQ29_B @S9S_MB_2U_LIB.S9S_MB_2U(SCH_1):M_A_CPU1_SB_DQ(29)
 285 M_A_CPU1_SB_DQ<30> DQ30_B @S9S_MB_2U_LIB.S9S_MB_2U(SCH_1):M_A_CPU1_SB_DQ(30)
 287 M_A_CPU1_SB_DQ<31> DQ31_B @S9S_MB_2U_LIB.S9S_MB_2U(SCH_1):M_A_CPU1_SB_DQ(31)
   7 M_A_CPU1_SA_DQ<0>  DQ0_A @S9S_MB_2U_LIB.S9S_MB_2U(SCH_1):M_A_CPU1_SA_DQ(0)
   9 M_A_CPU1_SA_DQ<1>  DQ1_A @S9S_MB_2U_LIB.S9S_MB_2U(SCH_1):M_A_CPU1_SA_DQ(1)
 152 M_A_CPU1_SA_DQ<2>  DQ2_A @S9S_MB_2U_LIB.S9S_MB_2U(SCH_1):M_A_CPU1_SA_DQ(2)
 154 M_A_CPU1_SA_DQ<3>  DQ3_A @S9S_MB_2U_LIB.S9S_MB_2U(SCH_1):M_A_CPU1_SA_DQ(3)
  14 M_A_CPU1_SA_DQ<4>  DQ4_A @S9S_MB_2U_LIB.S9S_MB_2U(SCH_1):M_A_CPU1_SA_DQ(4)
  16 M_A_CPU1_SA_DQ<5>  DQ5_A @S9S_MB_2U_LIB.S9S_MB_2U(SCH_1):M_A_CPU1_SA_DQ(5)
 159 M_A_CPU1_SA_DQ<6>  DQ6_A @S9S_MB_2U_LIB.S9S_MB_2U(SCH_1):M_A_CPU1_SA_DQ(6)
 161 M_A_CPU1_SA_DQ<7>  DQ7_A @S9S_MB_2U_LIB.S9S_MB_2U(SCH_1):M_A_CPU1_SA_DQ(7)
  18 M_A_CPU1_SA_DQ<8>  DQ8_A @S9S_MB_2U_LIB.S9S_MB_2U(SCH_1):M_A_CPU1_SA_DQ(8)
  20 M_A_CPU1_SA_DQ<9>  DQ9_A @S9S_MB_2U_LIB.S9S_MB_2U(SCH_1):M_A_CPU1_SA_DQ(9)
 163 M_A_CPU1_SA_DQ<10> DQ10_A @S9S_MB_2U_LIB.S9S_MB_2U(SCH_1):M_A_CPU1_SA_DQ(10)
 165 M_A_CPU1_SA_DQ<11> DQ11_A @S9S_MB_2U_LIB.S9S_MB_2U(SCH_1):M_A_CPU1_SA_DQ(11)
  25 M_A_CPU1_SA_DQ<12> DQ12_A @S9S_MB_2U_LIB.S9S_MB_2U(SCH_1):M_A_CPU1_SA_DQ(12)
  27 M_A_CPU1_SA_DQ<13> DQ13_A @S9S_MB_2U_LIB.S9S_MB_2U(SCH_1):M_A_CPU1_SA_DQ(13)
 170 M_A_CPU1_SA_DQ<14> DQ14_A @S9S_MB_2U_LIB.S9S_MB_2U(SCH_1):M_A_CPU1_SA_DQ(14)
 172 M_A_CPU1_SA_DQ<15> DQ15_A @S9S_MB_2U_LIB.S9S_MB_2U(SCH_1):M_A_CPU1_SA_DQ(15)
  29 M_A_CPU1_SA_DQ<16> DQ16_A @S9S_MB_2U_LIB.S9S_MB_2U(SCH_1):M_A_CPU1_SA_DQ(16)
  31 M_A_CPU1_SA_DQ<17> DQ17_A @S9S_MB_2U_LIB.S9S_MB_2U(SCH_1):M_A_CPU1_SA_DQ(17)
 174 M_A_CPU1_SA_DQ<18> DQ18_A @S9S_MB_2U_LIB.S9S_MB_2U(SCH_1):M_A_CPU1_SA_DQ(18)
 176 M_A_CPU1_SA_DQ<19> DQ19_A @S9S_MB_2U_LIB.S9S_MB_2U(SCH_1):M_A_CPU1_SA_DQ(19)
  36 M_A_CPU1_SA_DQ<20> DQ20_A @S9S_MB_2U_LIB.S9S_MB_2U(SCH_1):M_A_CPU1_SA_DQ(20)
  38 M_A_CPU1_SA_DQ<21> DQ21_A @S9S_MB_2U_LIB.S9S_MB_2U(SCH_1):M_A_CPU1_SA_DQ(21)
 181 M_A_CPU1_SA_DQ<22> DQ22_A @S9S_MB_2U_LIB.S9S_MB_2U(SCH_1):M_A_CPU1_SA_DQ(22)
 183 M_A_CPU1_SA_DQ<23> DQ23_A @S9S_MB_2U_LIB.S9S_MB_2U(SCH_1):M_A_CPU1_SA_DQ(23)
  40 M_A_CPU1_SA_DQ<24> DQ24_A @S9S_MB_2U_LIB.S9S_MB_2U(SCH_1):M_A_CPU1_SA_DQ(24)
  42 M_A_CPU1_SA_DQ<25> DQ25_A @S9S_MB_2U_LIB.S9S_MB_2U(SCH_1):M_A_CPU1_SA_DQ(25)
 185 M_A_CPU1_SA_DQ<26> DQ26_A @S9S_MB_2U_LIB.S9S_MB_2U(SCH_1):M_A_CPU1_SA_DQ(26)
 187 M_A_CPU1_SA_DQ<27> DQ27_A @S9S_MB_2U_LIB.S9S_MB_2U(SCH_1):M_A_CPU1_SA_DQ(27)
  47 M_A_CPU1_SA_DQ<28> DQ28_A @S9S_MB_2U_LIB.S9S_MB_2U(SCH_1):M_A_CPU1_SA_DQ(28)
  49 M_A_CPU1_SA_DQ<29> DQ29_A @S9S_MB_2U_LIB.S9S_MB_2U(SCH_1):M_A_CPU1_SA_DQ(29)
 192 M_A_CPU1_SA_DQ<30> DQ30_A @S9S_MB_2U_LIB.S9S_MB_2U(SCH_1):M_A_CPU1_SA_DQ(30)
 229 M_A_CPU1_SB_CS_N<1> CS1_B_N @S9S_MB_2U_LIB.S9S_MB_2U(SCH_1):M_A_CPU1_SB_CS_N(1)
 209 M_A_CPU1_SA_CS_N<1> CS1_A_N @S9S_MB_2U_LIB.S9S_MB_2U(SCH_1):M_A_CPU1_SA_CS_N(1)
  84 M_A_CPU1_SB_CS_N<0> CS0_B_N @S9S_MB_2U_LIB.S9S_MB_2U(SCH_1):M_A_CPU1_SB_CS_N(0)
  64 M_A_CPU1_SA_CS_N<0> CS0_A_N @S9S_MB_2U_LIB.S9S_MB_2U(SCH_1):M_A_CPU1_SA_CS_N(0)
 217 M_A_CPU1_CLK_DP<0>   CK_T @S9S_MB_2U_LIB.S9S_MB_2U(SCH_1):M_A_CPU1_CLK_DP(0)
 218 M_A_CPU1_CLK_DN<0>   CK_C @S9S_MB_2U_LIB.S9S_MB_2U(SCH_1):M_A_CPU1_CLK_DN(0)
  96 M_A_CPU1_SB_CB<0>  CB0_B @S9S_MB_2U_LIB.S9S_MB_2U(SCH_1):M_A_CPU1_SB_CB(0)
  98 M_A_CPU1_SB_CB<1>  CB1_B @S9S_MB_2U_LIB.S9S_MB_2U(SCH_1):M_A_CPU1_SB_CB(1)
 241 M_A_CPU1_SB_CB<2>  CB2_B @S9S_MB_2U_LIB.S9S_MB_2U(SCH_1):M_A_CPU1_SB_CB(2)
 243 M_A_CPU1_SB_CB<3>  CB3_B @S9S_MB_2U_LIB.S9S_MB_2U(SCH_1):M_A_CPU1_SB_CB(3)
  89 M_A_CPU1_SB_CB<4>  CB4_B @S9S_MB_2U_LIB.S9S_MB_2U(SCH_1):M_A_CPU1_SB_CB(4)
  91 M_A_CPU1_SB_CB<5>  CB5_B @S9S_MB_2U_LIB.S9S_MB_2U(SCH_1):M_A_CPU1_SB_CB(5)
 234 M_A_CPU1_SB_CB<6>  CB6_B @S9S_MB_2U_LIB.S9S_MB_2U(SCH_1):M_A_CPU1_SB_CB(6)
  51 M_A_CPU1_SA_CB<0>  CB0_A @S9S_MB_2U_LIB.S9S_MB_2U(SCH_1):M_A_CPU1_SA_CB(0)
 196 M_A_CPU1_SA_CB<2>  CB2_A @S9S_MB_2U_LIB.S9S_MB_2U(SCH_1):M_A_CPU1_SA_CB(2)
 198 M_A_CPU1_SA_CB<3>  CB3_A @S9S_MB_2U_LIB.S9S_MB_2U(SCH_1):M_A_CPU1_SA_CB(3)
  60 M_A_CPU1_SA_CB<5>  CB5_A @S9S_MB_2U_LIB.S9S_MB_2U(SCH_1):M_A_CPU1_SA_CB(5)
 203 M_A_CPU1_SA_CB<6>  CB6_A @S9S_MB_2U_LIB.S9S_MB_2U(SCH_1):M_A_CPU1_SA_CB(6)
  82 M_A_CPU1_SB_CA<6>  CA6_B @S9S_MB_2U_LIB.S9S_MB_2U(SCH_1):M_A_CPU1_SB_CA(6)
  72 M_A_CPU1_SA_CA<6>  CA6_A @S9S_MB_2U_LIB.S9S_MB_2U(SCH_1):M_A_CPU1_SA_CA(6)
 225 M_A_CPU1_SB_CA<5>  CA5_B @S9S_MB_2U_LIB.S9S_MB_2U(SCH_1):M_A_CPU1_SB_CA(5)
 215 M_A_CPU1_SA_CA<5>  CA5_A @S9S_MB_2U_LIB.S9S_MB_2U(SCH_1):M_A_CPU1_SA_CA(5)
  80 M_A_CPU1_SB_CA<4>  CA4_B @S9S_MB_2U_LIB.S9S_MB_2U(SCH_1):M_A_CPU1_SB_CA(4)
  70 M_A_CPU1_SA_CA<4>  CA4_A @S9S_MB_2U_LIB.S9S_MB_2U(SCH_1):M_A_CPU1_SA_CA(4)
 223 M_A_CPU1_SB_CA<3>  CA3_B @S9S_MB_2U_LIB.S9S_MB_2U(SCH_1):M_A_CPU1_SB_CA(3)
 213 M_A_CPU1_SA_CA<3>  CA3_A @S9S_MB_2U_LIB.S9S_MB_2U(SCH_1):M_A_CPU1_SA_CA(3)
  78 M_A_CPU1_SB_CA<2>  CA2_B @S9S_MB_2U_LIB.S9S_MB_2U(SCH_1):M_A_CPU1_SB_CA(2)
  68 M_A_CPU1_SA_CA<2>  CA2_A @S9S_MB_2U_LIB.S9S_MB_2U(SCH_1):M_A_CPU1_SA_CA(2)
 221 M_A_CPU1_SB_CA<1>  CA1_B @S9S_MB_2U_LIB.S9S_MB_2U(SCH_1):M_A_CPU1_SB_CA(1)
 211 M_A_CPU1_SA_CA<1>  CA1_A @S9S_MB_2U_LIB.S9S_MB_2U(SCH_1):M_A_CPU1_SA_CA(1)
  76 M_A_CPU1_SB_CA<0>  CA0_B @S9S_MB_2U_LIB.S9S_MB_2U(SCH_1):M_A_CPU1_SB_CA(0)
  66 M_A_CPU1_SA_CA<0>  CA0_A @S9S_MB_2U_LIB.S9S_MB_2U(SCH_1):M_A_CPU1_SA_CA(0)
  62 M_A_CPU1_ALERT_N ALERT_N @S9S_MB_2U_LIB.S9S_MB_2U(SCH_1):M_A_CPU1_ALERT_N
 236 M_A_CPU1_SB_CB<7>  CB7_B @S9S_MB_2U_LIB.S9S_MB_2U(SCH_1):M_A_CPU1_SB_CB(7)
  53 M_A_CPU1_SA_CB<1>  CB1_A @S9S_MB_2U_LIB.S9S_MB_2U(SCH_1):M_A_CPU1_SA_CB(1)
  58 M_A_CPU1_SA_CB<4>  CB4_A @S9S_MB_2U_LIB.S9S_MB_2U(SCH_1):M_A_CPU1_SA_CB(4)
 205 M_A_CPU1_SA_CB<7>  CB7_A @S9S_MB_2U_LIB.S9S_MB_2U(SCH_1):M_A_CPU1_SA_CB(7)
 194 M_A_CPU1_SA_DQ<31> DQ31_A @S9S_MB_2U_LIB.S9S_MB_2U(SCH_1):M_A_CPU1_SA_DQ(31)

Q_CAP_C0402-2.2UF,6.3V,20%,X6SA  I122  C50
   1 P3V3_AUX      A @S9S_MB_2U_LIB.S9S_MB_2U(SCH_1):P3V3_AUX
   2    GND      B @S9S_MB_2U_LIB.S9S_MB_2U(SCH_1):GND

Q_CAP_C0805-10UF,16V,10%,X6S,CA  I123  C51
   1 P12V_S3_AUX_CPU1_NVDIMM      A @S9S_MB_2U_LIB.S9S_MB_2U(SCH_1):P12V_S3_AUX_CPU1_NVDIMM
   2    GND      B @S9S_MB_2U_LIB.S9S_MB_2U(SCH_1):GND

Q_CAP_C0805-10UF,16V,10%,X6S,CA  I145  C52
   1 P12V_S3_AUX_CPU1_NVDIMM      A @S9S_MB_2U_LIB.S9S_MB_2U(SCH_1):P12V_S3_AUX_CPU1_NVDIMM
   2    GND      B @S9S_MB_2U_LIB.S9S_MB_2U(SCH_1):GND

SCONN288_ADR50017P130CC-SCONN2A  I147  J17
   6    GND   VSS0 @S9S_MB_2U_LIB.S9S_MB_2U(SCH_1):GND
   8    GND   VSS1 @S9S_MB_2U_LIB.S9S_MB_2U(SCH_1):GND
  10    GND   VSS2 @S9S_MB_2U_LIB.S9S_MB_2U(SCH_1):GND
  13    GND   VSS3 @S9S_MB_2U_LIB.S9S_MB_2U(SCH_1):GND
  15    GND   VSS4 @S9S_MB_2U_LIB.S9S_MB_2U(SCH_1):GND
  17    GND   VSS5 @S9S_MB_2U_LIB.S9S_MB_2U(SCH_1):GND
  19    GND   VSS6 @S9S_MB_2U_LIB.S9S_MB_2U(SCH_1):GND
  21    GND   VSS7 @S9S_MB_2U_LIB.S9S_MB_2U(SCH_1):GND
  24    GND   VSS8 @S9S_MB_2U_LIB.S9S_MB_2U(SCH_1):GND
  26    GND   VSS9 @S9S_MB_2U_LIB.S9S_MB_2U(SCH_1):GND
  28    GND  VSS10 @S9S_MB_2U_LIB.S9S_MB_2U(SCH_1):GND
  30    GND  VSS11 @S9S_MB_2U_LIB.S9S_MB_2U(SCH_1):GND
  32    GND  VSS12 @S9S_MB_2U_LIB.S9S_MB_2U(SCH_1):GND
  35    GND  VSS13 @S9S_MB_2U_LIB.S9S_MB_2U(SCH_1):GND
  37    GND  VSS14 @S9S_MB_2U_LIB.S9S_MB_2U(SCH_1):GND
  39    GND  VSS15 @S9S_MB_2U_LIB.S9S_MB_2U(SCH_1):GND
  41    GND  VSS16 @S9S_MB_2U_LIB.S9S_MB_2U(SCH_1):GND
  43    GND  VSS17 @S9S_MB_2U_LIB.S9S_MB_2U(SCH_1):GND
  46    GND  VSS18 @S9S_MB_2U_LIB.S9S_MB_2U(SCH_1):GND
  48    GND  VSS19 @S9S_MB_2U_LIB.S9S_MB_2U(SCH_1):GND
  50    GND  VSS20 @S9S_MB_2U_LIB.S9S_MB_2U(SCH_1):GND
  52    GND  VSS21 @S9S_MB_2U_LIB.S9S_MB_2U(SCH_1):GND
  54    GND  VSS22 @S9S_MB_2U_LIB.S9S_MB_2U(SCH_1):GND
  57    GND  VSS23 @S9S_MB_2U_LIB.S9S_MB_2U(SCH_1):GND
  59    GND  VSS24 @S9S_MB_2U_LIB.S9S_MB_2U(SCH_1):GND
  61    GND  VSS25 @S9S_MB_2U_LIB.S9S_MB_2U(SCH_1):GND
  63    GND  VSS26 @S9S_MB_2U_LIB.S9S_MB_2U(SCH_1):GND
  65    GND  VSS27 @S9S_MB_2U_LIB.S9S_MB_2U(SCH_1):GND
  67    GND  VSS28 @S9S_MB_2U_LIB.S9S_MB_2U(SCH_1):GND
  69    GND  VSS29 @S9S_MB_2U_LIB.S9S_MB_2U(SCH_1):GND
  71    GND  VSS30 @S9S_MB_2U_LIB.S9S_MB_2U(SCH_1):GND
  73    GND  VSS31 @S9S_MB_2U_LIB.S9S_MB_2U(SCH_1):GND
  75    GND  VSS32 @S9S_MB_2U_LIB.S9S_MB_2U(SCH_1):GND
  77    GND  VSS33 @S9S_MB_2U_LIB.S9S_MB_2U(SCH_1):GND
  79    GND  VSS34 @S9S_MB_2U_LIB.S9S_MB_2U(SCH_1):GND
  81    GND  VSS35 @S9S_MB_2U_LIB.S9S_MB_2U(SCH_1):GND
  83    GND  VSS36 @S9S_MB_2U_LIB.S9S_MB_2U(SCH_1):GND
  85    GND  VSS37 @S9S_MB_2U_LIB.S9S_MB_2U(SCH_1):GND
  88    GND  VSS38 @S9S_MB_2U_LIB.S9S_MB_2U(SCH_1):GND
  90    GND  VSS39 @S9S_MB_2U_LIB.S9S_MB_2U(SCH_1):GND
  92    GND  VSS40 @S9S_MB_2U_LIB.S9S_MB_2U(SCH_1):GND
  95    GND  VSS41 @S9S_MB_2U_LIB.S9S_MB_2U(SCH_1):GND
  97    GND  VSS42 @S9S_MB_2U_LIB.S9S_MB_2U(SCH_1):GND
  99    GND  VSS43 @S9S_MB_2U_LIB.S9S_MB_2U(SCH_1):GND
 101    GND  VSS44 @S9S_MB_2U_LIB.S9S_MB_2U(SCH_1):GND
 103    GND  VSS45 @S9S_MB_2U_LIB.S9S_MB_2U(SCH_1):GND
 106    GND  VSS46 @S9S_MB_2U_LIB.S9S_MB_2U(SCH_1):GND
 108    GND  VSS47 @S9S_MB_2U_LIB.S9S_MB_2U(SCH_1):GND
 110    GND  VSS48 @S9S_MB_2U_LIB.S9S_MB_2U(SCH_1):GND
 112    GND  VSS49 @S9S_MB_2U_LIB.S9S_MB_2U(SCH_1):GND
 114    GND  VSS50 @S9S_MB_2U_LIB.S9S_MB_2U(SCH_1):GND
 117    GND  VSS51 @S9S_MB_2U_LIB.S9S_MB_2U(SCH_1):GND
 119    GND  VSS52 @S9S_MB_2U_LIB.S9S_MB_2U(SCH_1):GND
 121    GND  VSS53 @S9S_MB_2U_LIB.S9S_MB_2U(SCH_1):GND
 123    GND  VSS54 @S9S_MB_2U_LIB.S9S_MB_2U(SCH_1):GND
 125    GND  VSS55 @S9S_MB_2U_LIB.S9S_MB_2U(SCH_1):GND
 128    GND  VSS56 @S9S_MB_2U_LIB.S9S_MB_2U(SCH_1):GND
 130    GND  VSS57 @S9S_MB_2U_LIB.S9S_MB_2U(SCH_1):GND
 134    GND  VSS59 @S9S_MB_2U_LIB.S9S_MB_2U(SCH_1):GND
 143    GND  VSS63 @S9S_MB_2U_LIB.S9S_MB_2U(SCH_1):GND
 151    GND  VSS64 @S9S_MB_2U_LIB.S9S_MB_2U(SCH_1):GND
 153    GND  VSS65 @S9S_MB_2U_LIB.S9S_MB_2U(SCH_1):GND
 155    GND  VSS66 @S9S_MB_2U_LIB.S9S_MB_2U(SCH_1):GND
 158    GND  VSS67 @S9S_MB_2U_LIB.S9S_MB_2U(SCH_1):GND
 160    GND  VSS68 @S9S_MB_2U_LIB.S9S_MB_2U(SCH_1):GND
 162    GND  VSS69 @S9S_MB_2U_LIB.S9S_MB_2U(SCH_1):GND
 164    GND  VSS70 @S9S_MB_2U_LIB.S9S_MB_2U(SCH_1):GND
 166    GND  VSS71 @S9S_MB_2U_LIB.S9S_MB_2U(SCH_1):GND
 169    GND  VSS72 @S9S_MB_2U_LIB.S9S_MB_2U(SCH_1):GND
 171    GND  VSS73 @S9S_MB_2U_LIB.S9S_MB_2U(SCH_1):GND
 173    GND  VSS74 @S9S_MB_2U_LIB.S9S_MB_2U(SCH_1):GND
 175    GND  VSS75 @S9S_MB_2U_LIB.S9S_MB_2U(SCH_1):GND
 177    GND  VSS76 @S9S_MB_2U_LIB.S9S_MB_2U(SCH_1):GND
 180    GND  VSS77 @S9S_MB_2U_LIB.S9S_MB_2U(SCH_1):GND
 182    GND  VSS78 @S9S_MB_2U_LIB.S9S_MB_2U(SCH_1):GND
 184    GND  VSS79 @S9S_MB_2U_LIB.S9S_MB_2U(SCH_1):GND
 186    GND  VSS80 @S9S_MB_2U_LIB.S9S_MB_2U(SCH_1):GND
 188    GND  VSS81 @S9S_MB_2U_LIB.S9S_MB_2U(SCH_1):GND
 191    GND  VSS82 @S9S_MB_2U_LIB.S9S_MB_2U(SCH_1):GND
 193    GND  VSS83 @S9S_MB_2U_LIB.S9S_MB_2U(SCH_1):GND
 195    GND  VSS84 @S9S_MB_2U_LIB.S9S_MB_2U(SCH_1):GND
 197    GND  VSS85 @S9S_MB_2U_LIB.S9S_MB_2U(SCH_1):GND
 199    GND  VSS86 @S9S_MB_2U_LIB.S9S_MB_2U(SCH_1):GND
 202    GND  VSS87 @S9S_MB_2U_LIB.S9S_MB_2U(SCH_1):GND
 204    GND  VSS88 @S9S_MB_2U_LIB.S9S_MB_2U(SCH_1):GND
 206    GND  VSS89 @S9S_MB_2U_LIB.S9S_MB_2U(SCH_1):GND
 208    GND  VSS90 @S9S_MB_2U_LIB.S9S_MB_2U(SCH_1):GND
 210    GND  VSS91 @S9S_MB_2U_LIB.S9S_MB_2U(SCH_1):GND
 212    GND  VSS92 @S9S_MB_2U_LIB.S9S_MB_2U(SCH_1):GND
 214    GND  VSS93 @S9S_MB_2U_LIB.S9S_MB_2U(SCH_1):GND
 216    GND  VSS94 @S9S_MB_2U_LIB.S9S_MB_2U(SCH_1):GND
 219    GND  VSS95 @S9S_MB_2U_LIB.S9S_MB_2U(SCH_1):GND
 222    GND  VSS96 @S9S_MB_2U_LIB.S9S_MB_2U(SCH_1):GND
 224    GND  VSS97 @S9S_MB_2U_LIB.S9S_MB_2U(SCH_1):GND
 226    GND  VSS98 @S9S_MB_2U_LIB.S9S_MB_2U(SCH_1):GND
 228    GND  VSS99 @S9S_MB_2U_LIB.S9S_MB_2U(SCH_1):GND
 233    GND VSS101 @S9S_MB_2U_LIB.S9S_MB_2U(SCH_1):GND
 237    GND VSS103 @S9S_MB_2U_LIB.S9S_MB_2U(SCH_1):GND
 242    GND VSS105 @S9S_MB_2U_LIB.S9S_MB_2U(SCH_1):GND
 244    GND VSS106 @S9S_MB_2U_LIB.S9S_MB_2U(SCH_1):GND
 246    GND VSS107 @S9S_MB_2U_LIB.S9S_MB_2U(SCH_1):GND
 248    GND VSS108 @S9S_MB_2U_LIB.S9S_MB_2U(SCH_1):GND
 251    GND VSS109 @S9S_MB_2U_LIB.S9S_MB_2U(SCH_1):GND
 253    GND VSS110 @S9S_MB_2U_LIB.S9S_MB_2U(SCH_1):GND
 255    GND VSS111 @S9S_MB_2U_LIB.S9S_MB_2U(SCH_1):GND
 257    GND VSS112 @S9S_MB_2U_LIB.S9S_MB_2U(SCH_1):GND
 259    GND VSS113 @S9S_MB_2U_LIB.S9S_MB_2U(SCH_1):GND
 262    GND VSS114 @S9S_MB_2U_LIB.S9S_MB_2U(SCH_1):GND
 264    GND VSS115 @S9S_MB_2U_LIB.S9S_MB_2U(SCH_1):GND
 266    GND VSS116 @S9S_MB_2U_LIB.S9S_MB_2U(SCH_1):GND
 268    GND VSS117 @S9S_MB_2U_LIB.S9S_MB_2U(SCH_1):GND
 270    GND VSS118 @S9S_MB_2U_LIB.S9S_MB_2U(SCH_1):GND
 273    GND VSS119 @S9S_MB_2U_LIB.S9S_MB_2U(SCH_1):GND
 275    GND VSS120 @S9S_MB_2U_LIB.S9S_MB_2U(SCH_1):GND
 277    GND VSS121 @S9S_MB_2U_LIB.S9S_MB_2U(SCH_1):GND
 279    GND VSS122 @S9S_MB_2U_LIB.S9S_MB_2U(SCH_1):GND
 281    GND VSS123 @S9S_MB_2U_LIB.S9S_MB_2U(SCH_1):GND
 284    GND VSS124 @S9S_MB_2U_LIB.S9S_MB_2U(SCH_1):GND
 286    GND VSS125 @S9S_MB_2U_LIB.S9S_MB_2U(SCH_1):GND
 288    GND VSS126 @S9S_MB_2U_LIB.S9S_MB_2U(SCH_1):GND
   1 P12V_S3_AUX_CPU1_NVDIMM VIN_BULK0 @S9S_MB_2U_LIB.S9S_MB_2U(SCH_1):P12V_S3_AUX_CPU1_NVDIMM
 145 P12V_S3_AUX_CPU1_NVDIMM VIN_BULK1 @S9S_MB_2U_LIB.S9S_MB_2U(SCH_1):P12V_S3_AUX_CPU1_NVDIMM
 146 P12V_S3_AUX_CPU1_NVDIMM VIN_BULK2 @S9S_MB_2U_LIB.S9S_MB_2U(SCH_1):P12V_S3_AUX_CPU1_NVDIMM
 230    GND VSS100 @S9S_MB_2U_LIB.S9S_MB_2U(SCH_1):GND
 235    GND VSS102 @S9S_MB_2U_LIB.S9S_MB_2U(SCH_1):GND
 240    GND VSS104 @S9S_MB_2U_LIB.S9S_MB_2U(SCH_1):GND
 132    GND  VSS58 @S9S_MB_2U_LIB.S9S_MB_2U(SCH_1):GND
 136    GND  VSS60 @S9S_MB_2U_LIB.S9S_MB_2U(SCH_1):GND
 139    GND  VSS61 @S9S_MB_2U_LIB.S9S_MB_2U(SCH_1):GND
 141    GND  VSS62 @S9S_MB_2U_LIB.S9S_MB_2U(SCH_1):GND
  G1    GND     G1 @S9S_MB_2U_LIB.S9S_MB_2U(SCH_1):GND
  G2    GND     G2 @S9S_MB_2U_LIB.S9S_MB_2U(SCH_1):GND
  G3    GND     G3 @S9S_MB_2U_LIB.S9S_MB_2U(SCH_1):GND

SCONN288_ADR50017P130CC-SCONN2A  I178  J17
  93 M_A_CPU1_SB_DQS_DP<9> DQS9_B_T||TDQS9_B_T||DBI4_B_N @S9S_MB_2U_LIB.S9S_MB_2U(SCH_1):M_A_CPU1_SB_DQS_DP(9)
  94 M_A_CPU1_SB_DQS_DN<9> DQS9_B_C||TDQS9_B_C @S9S_MB_2U_LIB.S9S_MB_2U(SCH_1):M_A_CPU1_SB_DQS_DN(9)
 201 M_A_CPU1_SA_DQS_DP<9> DQS9_A_T||TDQS9_A_T @S9S_MB_2U_LIB.S9S_MB_2U(SCH_1):M_A_CPU1_SA_DQS_DP(9)
 200 M_A_CPU1_SA_DQS_DN<9> DQS9_A_C||TDQS9_A_C @S9S_MB_2U_LIB.S9S_MB_2U(SCH_1):M_A_CPU1_SA_DQS_DN(9)
 190 M_A_CPU1_SA_DQS_DP<8> DQS8_A_T||TDQS8_A_T @S9S_MB_2U_LIB.S9S_MB_2U(SCH_1):M_A_CPU1_SA_DQS_DP(8)
 189 M_A_CPU1_SA_DQS_DN<8> DQS8_A_C||TDQS8_A_C @S9S_MB_2U_LIB.S9S_MB_2U(SCH_1):M_A_CPU1_SA_DQS_DN(8)
 271 M_A_CPU1_SB_DQS_DN<7> DQS7_B_C||TDQS7_B_C @S9S_MB_2U_LIB.S9S_MB_2U(SCH_1):M_A_CPU1_SB_DQS_DN(7)
 179 M_A_CPU1_SA_DQS_DP<7> DQS7_A_T||TDQS7_A_T @S9S_MB_2U_LIB.S9S_MB_2U(SCH_1):M_A_CPU1_SA_DQS_DP(7)
 261 M_A_CPU1_SB_DQS_DP<6> DQS6_B_T||TDQS6_B_T @S9S_MB_2U_LIB.S9S_MB_2U(SCH_1):M_A_CPU1_SB_DQS_DP(6)
 260 M_A_CPU1_SB_DQS_DN<6> DQS6_B_C||TDQS6_B_C @S9S_MB_2U_LIB.S9S_MB_2U(SCH_1):M_A_CPU1_SB_DQS_DN(6)
 167 M_A_CPU1_SA_DQS_DN<6> DQS6_A_C||TDQS6_A_C||DQS6_A_T||TDQS6_A_T @S9S_MB_2U_LIB.S9S_MB_2U(SCH_1):M_A_CPU1_SA_DQS_DN(6)
 250 M_A_CPU1_SB_DQS_DP<5> DQS5_B_T||TDQS5_B_T @S9S_MB_2U_LIB.S9S_MB_2U(SCH_1):M_A_CPU1_SB_DQS_DP(5)
 249 M_A_CPU1_SB_DQS_DN<5> DQS5_B_C||TDQS5_B_C @S9S_MB_2U_LIB.S9S_MB_2U(SCH_1):M_A_CPU1_SB_DQS_DN(5)
 157 M_A_CPU1_SA_DQS_DP<5> DQS5_A_T||TDQS5_A_T @S9S_MB_2U_LIB.S9S_MB_2U(SCH_1):M_A_CPU1_SA_DQS_DP(5)
 156 M_A_CPU1_SA_DQS_DN<5> DQS5_A_C||TDQS5_A_C||DQS5_A_T||TDQS5_A_T @S9S_MB_2U_LIB.S9S_MB_2U(SCH_1):M_A_CPU1_SA_DQS_DN(5)
 239 M_A_CPU1_SB_DQS_DP<4> DQS4_B_T @S9S_MB_2U_LIB.S9S_MB_2U(SCH_1):M_A_CPU1_SB_DQS_DP(4)
 238 M_A_CPU1_SB_DQS_DN<4> DQS4_B_C @S9S_MB_2U_LIB.S9S_MB_2U(SCH_1):M_A_CPU1_SB_DQS_DN(4)
  55 M_A_CPU1_SA_DQS_DP<4> DQS4_A_T @S9S_MB_2U_LIB.S9S_MB_2U(SCH_1):M_A_CPU1_SA_DQS_DP(4)
  56 M_A_CPU1_SA_DQS_DN<4> DQS4_A_C @S9S_MB_2U_LIB.S9S_MB_2U(SCH_1):M_A_CPU1_SA_DQS_DN(4)
 137 M_A_CPU1_SB_DQS_DP<3> DQS3_B_T @S9S_MB_2U_LIB.S9S_MB_2U(SCH_1):M_A_CPU1_SB_DQS_DP(3)
 138 M_A_CPU1_SB_DQS_DN<3> DQS3_B_C @S9S_MB_2U_LIB.S9S_MB_2U(SCH_1):M_A_CPU1_SB_DQS_DN(3)
  44 M_A_CPU1_SA_DQS_DP<3> DQS3_A_T @S9S_MB_2U_LIB.S9S_MB_2U(SCH_1):M_A_CPU1_SA_DQS_DP(3)
  45 M_A_CPU1_SA_DQS_DN<3> DQS3_A_C @S9S_MB_2U_LIB.S9S_MB_2U(SCH_1):M_A_CPU1_SA_DQS_DN(3)
 126 M_A_CPU1_SB_DQS_DP<2> DQS2_B_T @S9S_MB_2U_LIB.S9S_MB_2U(SCH_1):M_A_CPU1_SB_DQS_DP(2)
 127 M_A_CPU1_SB_DQS_DN<2> DQS2_B_C @S9S_MB_2U_LIB.S9S_MB_2U(SCH_1):M_A_CPU1_SB_DQS_DN(2)
  33 M_A_CPU1_SA_DQS_DP<2> DQS2_A_T @S9S_MB_2U_LIB.S9S_MB_2U(SCH_1):M_A_CPU1_SA_DQS_DP(2)
  34 M_A_CPU1_SA_DQS_DN<2> DQS2_A_C @S9S_MB_2U_LIB.S9S_MB_2U(SCH_1):M_A_CPU1_SA_DQS_DN(2)
 115 M_A_CPU1_SB_DQS_DP<1> DQS1_B_T @S9S_MB_2U_LIB.S9S_MB_2U(SCH_1):M_A_CPU1_SB_DQS_DP(1)
 116 M_A_CPU1_SB_DQS_DN<1> DQS1_B_C @S9S_MB_2U_LIB.S9S_MB_2U(SCH_1):M_A_CPU1_SB_DQS_DN(1)
  22 M_A_CPU1_SA_DQS_DP<1> DQS1_A_T @S9S_MB_2U_LIB.S9S_MB_2U(SCH_1):M_A_CPU1_SA_DQS_DP(1)
  23 M_A_CPU1_SA_DQS_DN<1> DQS1_A_C @S9S_MB_2U_LIB.S9S_MB_2U(SCH_1):M_A_CPU1_SA_DQS_DN(1)
 104 M_A_CPU1_SB_DQS_DP<0> DQS0_B_T @S9S_MB_2U_LIB.S9S_MB_2U(SCH_1):M_A_CPU1_SB_DQS_DP(0)
 105 M_A_CPU1_SB_DQS_DN<0> DQS0_B_C @S9S_MB_2U_LIB.S9S_MB_2U(SCH_1):M_A_CPU1_SB_DQS_DN(0)
  11 M_A_CPU1_SA_DQS_DP<0> DQS0_A_T @S9S_MB_2U_LIB.S9S_MB_2U(SCH_1):M_A_CPU1_SA_DQS_DP(0)
  12 M_A_CPU1_SA_DQS_DN<0> DQS0_A_C @S9S_MB_2U_LIB.S9S_MB_2U(SCH_1):M_A_CPU1_SA_DQS_DN(0)
 272 M_A_CPU1_SB_DQS_DP<7> DQS7_B_T||TDQS7_B_T @S9S_MB_2U_LIB.S9S_MB_2U(SCH_1):M_A_CPU1_SB_DQS_DP(7)
 282 M_A_CPU1_SB_DQS_DN<8> DQS8_B_C||TDQS8_B_C @S9S_MB_2U_LIB.S9S_MB_2U(SCH_1):M_A_CPU1_SB_DQS_DN(8)
 283 M_A_CPU1_SB_DQS_DP<8> DQS8_B_T||TDQS8_B_T @S9S_MB_2U_LIB.S9S_MB_2U(SCH_1):M_A_CPU1_SB_DQS_DP(8)
 168 M_A_CPU1_SA_DQS_DP<6> DQS6_A_T||TDQS6_A_T @S9S_MB_2U_LIB.S9S_MB_2U(SCH_1):M_A_CPU1_SA_DQS_DP(6)
 178 M_A_CPU1_SA_DQS_DN<7> DQS7_A_C||TDQS7_A_C @S9S_MB_2U_LIB.S9S_MB_2U(SCH_1):M_A_CPU1_SA_DQS_DN(7)

Q_RES_0402LF-49.9,1%,1/16W,CHIA  I179  R3891
   1 I3C_SPD_DDRABCD_CPU1_LVC1_SCL_R      A @S9S_MB_2U_LIB.S9S_MB_2U(SCH_1):I3C_SPD_DDRABCD_CPU1_LVC1_SCL_R1
   2 I3C_SPD_DDRABCD_CPU1_LVC1_SCL      B @S9S_MB_2U_LIB.S9S_MB_2U(SCH_1):I3C_SPD_DDRABCD_CPU1_LVC1_SCL


DRAWING: @S9S_MB_2U_LIB.S9S_MB_2U(SCH_1):PAGE99 

Q_RES_0402LF-15.4K,1%,1/16W,CHA  I2  R43
   1 PD_CHA_CPU1_DIMM2_SAA      A @S9S_MB_2U_LIB.S9S_MB_2U(SCH_1):PD_CHA_CPU1_DIMM2_SAA
   2    GND      B @S9S_MB_2U_LIB.S9S_MB_2U(SCH_1):GND

SCONN288_ADR50017P087CC-SCONN2A  I24  J18
   3 P3V3_AUX VIN_MGMT @S9S_MB_2U_LIB.S9S_MB_2U(SCH_1):P3V3_AUX
   2 TP_CHA_CPU1_DIMM2_FRU_0   RFU0 @S9S_MB_2U_LIB.S9S_MB_2U(SCH_1):TP_CHA_CPU1_DIMM2_FRU_0
 144 TP_CHA_CPU1_DIMM2_FRU_1   RFU1 @S9S_MB_2U_LIB.S9S_MB_2U(SCH_1):TP_CHA_CPU1_DIMM2_FRU_1
 149 TP_CHA_CPU1_DIMM2_FRU_2   RFU2 @S9S_MB_2U_LIB.S9S_MB_2U(SCH_1):TP_CHA_CPU1_DIMM2_FRU_2
 150 TP_CHA_CPU1_DIMM2_FRU_3   RFU3 @S9S_MB_2U_LIB.S9S_MB_2U(SCH_1):TP_CHA_CPU1_DIMM2_FRU_3
 220 TP_CHA_CPU1_DIMM2_FRU_4   RFU4 @S9S_MB_2U_LIB.S9S_MB_2U(SCH_1):TP_CHA_CPU1_DIMM2_FRU_4
 231 TP_CHA_CPU1_DIMM2_FRU_5   RFU5 @S9S_MB_2U_LIB.S9S_MB_2U(SCH_1):TP_CHA_CPU1_DIMM2_FRU_5
 232 TP_CHA_CPU1_DIMM2_FRU_6   RFU6 @S9S_MB_2U_LIB.S9S_MB_2U(SCH_1):TP_CHA_CPU1_DIMM2_FRU_6
 207 RST_M_AB_CPU1_FPGA_N RESET_N @S9S_MB_2U_LIB.S9S_MB_2U(SCH_1):RST_M_AB_CPU1_FPGA_N
 147 PWRGD_CHA_CPU1_DIMM2 PWR_GOOD||FAIL_N @S9S_MB_2U_LIB.S9S_MB_2U(SCH_1):PWRGD_CHA_CPU1_DIMM2
 227 M_A_CPU1_SB_PAR  PAR_B @S9S_MB_2U_LIB.S9S_MB_2U(SCH_1):M_A_CPU1_SB_PAR
  74 M_A_CPU1_SA_PAR  PAR_A @S9S_MB_2U_LIB.S9S_MB_2U(SCH_1):M_A_CPU1_SA_PAR
  87 M_A_CPU1_SB_RSP<1> LBS||RSP_B_N @S9S_MB_2U_LIB.S9S_MB_2U(SCH_1):M_A_CPU1_SB_RSP(1)
  86 M_A_CPU1_SA_RSP<1> LBD||RSP_A_N @S9S_MB_2U_LIB.S9S_MB_2U(SCH_1):M_A_CPU1_SA_RSP(1)
   5 I3C_SPD_DDRABCD_CPU1_LVC1_SDA   HSDA @S9S_MB_2U_LIB.S9S_MB_2U(SCH_1):I3C_SPD_DDRABCD_CPU1_LVC1_SDA
   4 I3C_SPD_DDRABCD_CPU1_LVC1_SCL_1   HSCL @S9S_MB_2U_LIB.S9S_MB_2U(SCH_1):I3C_SPD_DDRABCD_CPU1_LVC1_SCL_R2
 148 PD_CHA_CPU1_DIMM2_SAA    HSA @S9S_MB_2U_LIB.S9S_MB_2U(SCH_1):PD_CHA_CPU1_DIMM2_SAA
 100 M_A_CPU1_SB_DQ<0>  DQ0_B @S9S_MB_2U_LIB.S9S_MB_2U(SCH_1):M_A_CPU1_SB_DQ(0)
 102 M_A_CPU1_SB_DQ<1>  DQ1_B @S9S_MB_2U_LIB.S9S_MB_2U(SCH_1):M_A_CPU1_SB_DQ(1)
 245 M_A_CPU1_SB_DQ<2>  DQ2_B @S9S_MB_2U_LIB.S9S_MB_2U(SCH_1):M_A_CPU1_SB_DQ(2)
 247 M_A_CPU1_SB_DQ<3>  DQ3_B @S9S_MB_2U_LIB.S9S_MB_2U(SCH_1):M_A_CPU1_SB_DQ(3)
 107 M_A_CPU1_SB_DQ<4>  DQ4_B @S9S_MB_2U_LIB.S9S_MB_2U(SCH_1):M_A_CPU1_SB_DQ(4)
 109 M_A_CPU1_SB_DQ<5>  DQ5_B @S9S_MB_2U_LIB.S9S_MB_2U(SCH_1):M_A_CPU1_SB_DQ(5)
 252 M_A_CPU1_SB_DQ<6>  DQ6_B @S9S_MB_2U_LIB.S9S_MB_2U(SCH_1):M_A_CPU1_SB_DQ(6)
 254 M_A_CPU1_SB_DQ<7>  DQ7_B @S9S_MB_2U_LIB.S9S_MB_2U(SCH_1):M_A_CPU1_SB_DQ(7)
 111 M_A_CPU1_SB_DQ<8>  DQ8_B @S9S_MB_2U_LIB.S9S_MB_2U(SCH_1):M_A_CPU1_SB_DQ(8)
 113 M_A_CPU1_SB_DQ<9>  DQ9_B @S9S_MB_2U_LIB.S9S_MB_2U(SCH_1):M_A_CPU1_SB_DQ(9)
 256 M_A_CPU1_SB_DQ<10> DQ10_B @S9S_MB_2U_LIB.S9S_MB_2U(SCH_1):M_A_CPU1_SB_DQ(10)
 258 M_A_CPU1_SB_DQ<11> DQ11_B @S9S_MB_2U_LIB.S9S_MB_2U(SCH_1):M_A_CPU1_SB_DQ(11)
 118 M_A_CPU1_SB_DQ<12> DQ12_B @S9S_MB_2U_LIB.S9S_MB_2U(SCH_1):M_A_CPU1_SB_DQ(12)
 120 M_A_CPU1_SB_DQ<13> DQ13_B @S9S_MB_2U_LIB.S9S_MB_2U(SCH_1):M_A_CPU1_SB_DQ(13)
 263 M_A_CPU1_SB_DQ<14> DQ14_B @S9S_MB_2U_LIB.S9S_MB_2U(SCH_1):M_A_CPU1_SB_DQ(14)
 265 M_A_CPU1_SB_DQ<15> DQ15_B @S9S_MB_2U_LIB.S9S_MB_2U(SCH_1):M_A_CPU1_SB_DQ(15)
 122 M_A_CPU1_SB_DQ<16> DQ16_B @S9S_MB_2U_LIB.S9S_MB_2U(SCH_1):M_A_CPU1_SB_DQ(16)
 124 M_A_CPU1_SB_DQ<17> DQ17_B @S9S_MB_2U_LIB.S9S_MB_2U(SCH_1):M_A_CPU1_SB_DQ(17)
 267 M_A_CPU1_SB_DQ<18> DQ18_B @S9S_MB_2U_LIB.S9S_MB_2U(SCH_1):M_A_CPU1_SB_DQ(18)
 269 M_A_CPU1_SB_DQ<19> DQ19_B @S9S_MB_2U_LIB.S9S_MB_2U(SCH_1):M_A_CPU1_SB_DQ(19)
 129 M_A_CPU1_SB_DQ<20> DQ20_B @S9S_MB_2U_LIB.S9S_MB_2U(SCH_1):M_A_CPU1_SB_DQ(20)
 131 M_A_CPU1_SB_DQ<21> DQ21_B @S9S_MB_2U_LIB.S9S_MB_2U(SCH_1):M_A_CPU1_SB_DQ(21)
 274 M_A_CPU1_SB_DQ<22> DQ22_B @S9S_MB_2U_LIB.S9S_MB_2U(SCH_1):M_A_CPU1_SB_DQ(22)
 276 M_A_CPU1_SB_DQ<23> DQ23_B @S9S_MB_2U_LIB.S9S_MB_2U(SCH_1):M_A_CPU1_SB_DQ(23)
 133 M_A_CPU1_SB_DQ<24> DQ24_B @S9S_MB_2U_LIB.S9S_MB_2U(SCH_1):M_A_CPU1_SB_DQ(24)
 135 M_A_CPU1_SB_DQ<25> DQ25_B @S9S_MB_2U_LIB.S9S_MB_2U(SCH_1):M_A_CPU1_SB_DQ(25)
 278 M_A_CPU1_SB_DQ<26> DQ26_B @S9S_MB_2U_LIB.S9S_MB_2U(SCH_1):M_A_CPU1_SB_DQ(26)
 280 M_A_CPU1_SB_DQ<27> DQ27_B @S9S_MB_2U_LIB.S9S_MB_2U(SCH_1):M_A_CPU1_SB_DQ(27)
 140 M_A_CPU1_SB_DQ<28> DQ28_B @S9S_MB_2U_LIB.S9S_MB_2U(SCH_1):M_A_CPU1_SB_DQ(28)
 142 M_A_CPU1_SB_DQ<29> DQ29_B @S9S_MB_2U_LIB.S9S_MB_2U(SCH_1):M_A_CPU1_SB_DQ(29)
 285 M_A_CPU1_SB_DQ<30> DQ30_B @S9S_MB_2U_LIB.S9S_MB_2U(SCH_1):M_A_CPU1_SB_DQ(30)
 287 M_A_CPU1_SB_DQ<31> DQ31_B @S9S_MB_2U_LIB.S9S_MB_2U(SCH_1):M_A_CPU1_SB_DQ(31)
   7 M_A_CPU1_SA_DQ<0>  DQ0_A @S9S_MB_2U_LIB.S9S_MB_2U(SCH_1):M_A_CPU1_SA_DQ(0)
   9 M_A_CPU1_SA_DQ<1>  DQ1_A @S9S_MB_2U_LIB.S9S_MB_2U(SCH_1):M_A_CPU1_SA_DQ(1)
 152 M_A_CPU1_SA_DQ<2>  DQ2_A @S9S_MB_2U_LIB.S9S_MB_2U(SCH_1):M_A_CPU1_SA_DQ(2)
 154 M_A_CPU1_SA_DQ<3>  DQ3_A @S9S_MB_2U_LIB.S9S_MB_2U(SCH_1):M_A_CPU1_SA_DQ(3)
  14 M_A_CPU1_SA_DQ<4>  DQ4_A @S9S_MB_2U_LIB.S9S_MB_2U(SCH_1):M_A_CPU1_SA_DQ(4)
  16 M_A_CPU1_SA_DQ<5>  DQ5_A @S9S_MB_2U_LIB.S9S_MB_2U(SCH_1):M_A_CPU1_SA_DQ(5)
 159 M_A_CPU1_SA_DQ<6>  DQ6_A @S9S_MB_2U_LIB.S9S_MB_2U(SCH_1):M_A_CPU1_SA_DQ(6)
 161 M_A_CPU1_SA_DQ<7>  DQ7_A @S9S_MB_2U_LIB.S9S_MB_2U(SCH_1):M_A_CPU1_SA_DQ(7)
  18 M_A_CPU1_SA_DQ<8>  DQ8_A @S9S_MB_2U_LIB.S9S_MB_2U(SCH_1):M_A_CPU1_SA_DQ(8)
  20 M_A_CPU1_SA_DQ<9>  DQ9_A @S9S_MB_2U_LIB.S9S_MB_2U(SCH_1):M_A_CPU1_SA_DQ(9)
 163 M_A_CPU1_SA_DQ<10> DQ10_A @S9S_MB_2U_LIB.S9S_MB_2U(SCH_1):M_A_CPU1_SA_DQ(10)
 165 M_A_CPU1_SA_DQ<11> DQ11_A @S9S_MB_2U_LIB.S9S_MB_2U(SCH_1):M_A_CPU1_SA_DQ(11)
  25 M_A_CPU1_SA_DQ<12> DQ12_A @S9S_MB_2U_LIB.S9S_MB_2U(SCH_1):M_A_CPU1_SA_DQ(12)
  27 M_A_CPU1_SA_DQ<13> DQ13_A @S9S_MB_2U_LIB.S9S_MB_2U(SCH_1):M_A_CPU1_SA_DQ(13)
 170 M_A_CPU1_SA_DQ<14> DQ14_A @S9S_MB_2U_LIB.S9S_MB_2U(SCH_1):M_A_CPU1_SA_DQ(14)
 172 M_A_CPU1_SA_DQ<15> DQ15_A @S9S_MB_2U_LIB.S9S_MB_2U(SCH_1):M_A_CPU1_SA_DQ(15)
  29 M_A_CPU1_SA_DQ<16> DQ16_A @S9S_MB_2U_LIB.S9S_MB_2U(SCH_1):M_A_CPU1_SA_DQ(16)
  31 M_A_CPU1_SA_DQ<17> DQ17_A @S9S_MB_2U_LIB.S9S_MB_2U(SCH_1):M_A_CPU1_SA_DQ(17)
 174 M_A_CPU1_SA_DQ<18> DQ18_A @S9S_MB_2U_LIB.S9S_MB_2U(SCH_1):M_A_CPU1_SA_DQ(18)
 176 M_A_CPU1_SA_DQ<19> DQ19_A @S9S_MB_2U_LIB.S9S_MB_2U(SCH_1):M_A_CPU1_SA_DQ(19)
  36 M_A_CPU1_SA_DQ<20> DQ20_A @S9S_MB_2U_LIB.S9S_MB_2U(SCH_1):M_A_CPU1_SA_DQ(20)
  38 M_A_CPU1_SA_DQ<21> DQ21_A @S9S_MB_2U_LIB.S9S_MB_2U(SCH_1):M_A_CPU1_SA_DQ(21)
 181 M_A_CPU1_SA_DQ<22> DQ22_A @S9S_MB_2U_LIB.S9S_MB_2U(SCH_1):M_A_CPU1_SA_DQ(22)
 183 M_A_CPU1_SA_DQ<23> DQ23_A @S9S_MB_2U_LIB.S9S_MB_2U(SCH_1):M_A_CPU1_SA_DQ(23)
  40 M_A_CPU1_SA_DQ<24> DQ24_A @S9S_MB_2U_LIB.S9S_MB_2U(SCH_1):M_A_CPU1_SA_DQ(24)
  42 M_A_CPU1_SA_DQ<25> DQ25_A @S9S_MB_2U_LIB.S9S_MB_2U(SCH_1):M_A_CPU1_SA_DQ(25)
 185 M_A_CPU1_SA_DQ<26> DQ26_A @S9S_MB_2U_LIB.S9S_MB_2U(SCH_1):M_A_CPU1_SA_DQ(26)
 187 M_A_CPU1_SA_DQ<27> DQ27_A @S9S_MB_2U_LIB.S9S_MB_2U(SCH_1):M_A_CPU1_SA_DQ(27)
  47 M_A_CPU1_SA_DQ<28> DQ28_A @S9S_MB_2U_LIB.S9S_MB_2U(SCH_1):M_A_CPU1_SA_DQ(28)
  49 M_A_CPU1_SA_DQ<29> DQ29_A @S9S_MB_2U_LIB.S9S_MB_2U(SCH_1):M_A_CPU1_SA_DQ(29)
 192 M_A_CPU1_SA_DQ<30> DQ30_A @S9S_MB_2U_LIB.S9S_MB_2U(SCH_1):M_A_CPU1_SA_DQ(30)
 229 M_A_CPU1_SB_CS_N<3> CS1_B_N @S9S_MB_2U_LIB.S9S_MB_2U(SCH_1):M_A_CPU1_SB_CS_N(3)
 209 M_A_CPU1_SA_CS_N<3> CS1_A_N @S9S_MB_2U_LIB.S9S_MB_2U(SCH_1):M_A_CPU1_SA_CS_N(3)
  84 M_A_CPU1_SB_CS_N<2> CS0_B_N @S9S_MB_2U_LIB.S9S_MB_2U(SCH_1):M_A_CPU1_SB_CS_N(2)
  64 M_A_CPU1_SA_CS_N<2> CS0_A_N @S9S_MB_2U_LIB.S9S_MB_2U(SCH_1):M_A_CPU1_SA_CS_N(2)
 217 M_A_CPU1_CLK_DP<1>   CK_T @S9S_MB_2U_LIB.S9S_MB_2U(SCH_1):M_A_CPU1_CLK_DP(1)
 218 M_A_CPU1_CLK_DN<1>   CK_C @S9S_MB_2U_LIB.S9S_MB_2U(SCH_1):M_A_CPU1_CLK_DN(1)
  96 M_A_CPU1_SB_CB<0>  CB0_B @S9S_MB_2U_LIB.S9S_MB_2U(SCH_1):M_A_CPU1_SB_CB(0)
  98 M_A_CPU1_SB_CB<1>  CB1_B @S9S_MB_2U_LIB.S9S_MB_2U(SCH_1):M_A_CPU1_SB_CB(1)
 241 M_A_CPU1_SB_CB<2>  CB2_B @S9S_MB_2U_LIB.S9S_MB_2U(SCH_1):M_A_CPU1_SB_CB(2)
 243 M_A_CPU1_SB_CB<3>  CB3_B @S9S_MB_2U_LIB.S9S_MB_2U(SCH_1):M_A_CPU1_SB_CB(3)
  89 M_A_CPU1_SB_CB<4>  CB4_B @S9S_MB_2U_LIB.S9S_MB_2U(SCH_1):M_A_CPU1_SB_CB(4)
  91 M_A_CPU1_SB_CB<5>  CB5_B @S9S_MB_2U_LIB.S9S_MB_2U(SCH_1):M_A_CPU1_SB_CB(5)
 234 M_A_CPU1_SB_CB<6>  CB6_B @S9S_MB_2U_LIB.S9S_MB_2U(SCH_1):M_A_CPU1_SB_CB(6)
  51 M_A_CPU1_SA_CB<0>  CB0_A @S9S_MB_2U_LIB.S9S_MB_2U(SCH_1):M_A_CPU1_SA_CB(0)
 196 M_A_CPU1_SA_CB<2>  CB2_A @S9S_MB_2U_LIB.S9S_MB_2U(SCH_1):M_A_CPU1_SA_CB(2)
 198 M_A_CPU1_SA_CB<3>  CB3_A @S9S_MB_2U_LIB.S9S_MB_2U(SCH_1):M_A_CPU1_SA_CB(3)
  60 M_A_CPU1_SA_CB<5>  CB5_A @S9S_MB_2U_LIB.S9S_MB_2U(SCH_1):M_A_CPU1_SA_CB(5)
 203 M_A_CPU1_SA_CB<6>  CB6_A @S9S_MB_2U_LIB.S9S_MB_2U(SCH_1):M_A_CPU1_SA_CB(6)
  82 M_A_CPU1_SB_CA<6>  CA6_B @S9S_MB_2U_LIB.S9S_MB_2U(SCH_1):M_A_CPU1_SB_CA(6)
  72 M_A_CPU1_SA_CA<6>  CA6_A @S9S_MB_2U_LIB.S9S_MB_2U(SCH_1):M_A_CPU1_SA_CA(6)
 225 M_A_CPU1_SB_CA<5>  CA5_B @S9S_MB_2U_LIB.S9S_MB_2U(SCH_1):M_A_CPU1_SB_CA(5)
 215 M_A_CPU1_SA_CA<5>  CA5_A @S9S_MB_2U_LIB.S9S_MB_2U(SCH_1):M_A_CPU1_SA_CA(5)
  80 M_A_CPU1_SB_CA<4>  CA4_B @S9S_MB_2U_LIB.S9S_MB_2U(SCH_1):M_A_CPU1_SB_CA(4)
  70 M_A_CPU1_SA_CA<4>  CA4_A @S9S_MB_2U_LIB.S9S_MB_2U(SCH_1):M_A_CPU1_SA_CA(4)
 223 M_A_CPU1_SB_CA<3>  CA3_B @S9S_MB_2U_LIB.S9S_MB_2U(SCH_1):M_A_CPU1_SB_CA(3)
 213 M_A_CPU1_SA_CA<3>  CA3_A @S9S_MB_2U_LIB.S9S_MB_2U(SCH_1):M_A_CPU1_SA_CA(3)
  78 M_A_CPU1_SB_CA<2>  CA2_B @S9S_MB_2U_LIB.S9S_MB_2U(SCH_1):M_A_CPU1_SB_CA(2)
  68 M_A_CPU1_SA_CA<2>  CA2_A @S9S_MB_2U_LIB.S9S_MB_2U(SCH_1):M_A_CPU1_SA_CA(2)
 221 M_A_CPU1_SB_CA<1>  CA1_B @S9S_MB_2U_LIB.S9S_MB_2U(SCH_1):M_A_CPU1_SB_CA(1)
 211 M_A_CPU1_SA_CA<1>  CA1_A @S9S_MB_2U_LIB.S9S_MB_2U(SCH_1):M_A_CPU1_SA_CA(1)
  76 M_A_CPU1_SB_CA<0>  CA0_B @S9S_MB_2U_LIB.S9S_MB_2U(SCH_1):M_A_CPU1_SB_CA(0)
  66 M_A_CPU1_SA_CA<0>  CA0_A @S9S_MB_2U_LIB.S9S_MB_2U(SCH_1):M_A_CPU1_SA_CA(0)
  62 M_A_CPU1_ALERT_N ALERT_N @S9S_MB_2U_LIB.S9S_MB_2U(SCH_1):M_A_CPU1_ALERT_N
 236 M_A_CPU1_SB_CB<7>  CB7_B @S9S_MB_2U_LIB.S9S_MB_2U(SCH_1):M_A_CPU1_SB_CB(7)
  53 M_A_CPU1_SA_CB<1>  CB1_A @S9S_MB_2U_LIB.S9S_MB_2U(SCH_1):M_A_CPU1_SA_CB(1)
  58 M_A_CPU1_SA_CB<4>  CB4_A @S9S_MB_2U_LIB.S9S_MB_2U(SCH_1):M_A_CPU1_SA_CB(4)
 205 M_A_CPU1_SA_CB<7>  CB7_A @S9S_MB_2U_LIB.S9S_MB_2U(SCH_1):M_A_CPU1_SA_CB(7)
 194 M_A_CPU1_SA_DQ<31> DQ31_A @S9S_MB_2U_LIB.S9S_MB_2U(SCH_1):M_A_CPU1_SA_DQ(31)

Q_CAP_C0402-2.2UF,6.3V,20%,X6SA  I122  C53
   1 P3V3_AUX      A @S9S_MB_2U_LIB.S9S_MB_2U(SCH_1):P3V3_AUX
   2    GND      B @S9S_MB_2U_LIB.S9S_MB_2U(SCH_1):GND

Q_CAP_C0805-10UF,16V,10%,X6S,CA  I126  C54
   1 P12V_S3_AUX_CPU1_NVDIMM      A @S9S_MB_2U_LIB.S9S_MB_2U(SCH_1):P12V_S3_AUX_CPU1_NVDIMM
   2    GND      B @S9S_MB_2U_LIB.S9S_MB_2U(SCH_1):GND

Q_CAP_C0805-10UF,16V,10%,X6S,CA  I128  C55
   1 P12V_S3_AUX_CPU1_NVDIMM      A @S9S_MB_2U_LIB.S9S_MB_2U(SCH_1):P12V_S3_AUX_CPU1_NVDIMM
   2    GND      B @S9S_MB_2U_LIB.S9S_MB_2U(SCH_1):GND

SCONN288_ADR50017P087CC-SCONN2A  I175  J18
   6    GND   VSS0 @S9S_MB_2U_LIB.S9S_MB_2U(SCH_1):GND
   8    GND   VSS1 @S9S_MB_2U_LIB.S9S_MB_2U(SCH_1):GND
  10    GND   VSS2 @S9S_MB_2U_LIB.S9S_MB_2U(SCH_1):GND
  13    GND   VSS3 @S9S_MB_2U_LIB.S9S_MB_2U(SCH_1):GND
  15    GND   VSS4 @S9S_MB_2U_LIB.S9S_MB_2U(SCH_1):GND
  17    GND   VSS5 @S9S_MB_2U_LIB.S9S_MB_2U(SCH_1):GND
  19    GND   VSS6 @S9S_MB_2U_LIB.S9S_MB_2U(SCH_1):GND
  21    GND   VSS7 @S9S_MB_2U_LIB.S9S_MB_2U(SCH_1):GND
  24    GND   VSS8 @S9S_MB_2U_LIB.S9S_MB_2U(SCH_1):GND
  26    GND   VSS9 @S9S_MB_2U_LIB.S9S_MB_2U(SCH_1):GND
  28    GND  VSS10 @S9S_MB_2U_LIB.S9S_MB_2U(SCH_1):GND
  30    GND  VSS11 @S9S_MB_2U_LIB.S9S_MB_2U(SCH_1):GND
  32    GND  VSS12 @S9S_MB_2U_LIB.S9S_MB_2U(SCH_1):GND
  35    GND  VSS13 @S9S_MB_2U_LIB.S9S_MB_2U(SCH_1):GND
  37    GND  VSS14 @S9S_MB_2U_LIB.S9S_MB_2U(SCH_1):GND
  39    GND  VSS15 @S9S_MB_2U_LIB.S9S_MB_2U(SCH_1):GND
  41    GND  VSS16 @S9S_MB_2U_LIB.S9S_MB_2U(SCH_1):GND
  43    GND  VSS17 @S9S_MB_2U_LIB.S9S_MB_2U(SCH_1):GND
  46    GND  VSS18 @S9S_MB_2U_LIB.S9S_MB_2U(SCH_1):GND
  48    GND  VSS19 @S9S_MB_2U_LIB.S9S_MB_2U(SCH_1):GND
  50    GND  VSS20 @S9S_MB_2U_LIB.S9S_MB_2U(SCH_1):GND
  52    GND  VSS21 @S9S_MB_2U_LIB.S9S_MB_2U(SCH_1):GND
  54    GND  VSS22 @S9S_MB_2U_LIB.S9S_MB_2U(SCH_1):GND
  57    GND  VSS23 @S9S_MB_2U_LIB.S9S_MB_2U(SCH_1):GND
  59    GND  VSS24 @S9S_MB_2U_LIB.S9S_MB_2U(SCH_1):GND
  61    GND  VSS25 @S9S_MB_2U_LIB.S9S_MB_2U(SCH_1):GND
  63    GND  VSS26 @S9S_MB_2U_LIB.S9S_MB_2U(SCH_1):GND
  65    GND  VSS27 @S9S_MB_2U_LIB.S9S_MB_2U(SCH_1):GND
  67    GND  VSS28 @S9S_MB_2U_LIB.S9S_MB_2U(SCH_1):GND
  69    GND  VSS29 @S9S_MB_2U_LIB.S9S_MB_2U(SCH_1):GND
  71    GND  VSS30 @S9S_MB_2U_LIB.S9S_MB_2U(SCH_1):GND
  73    GND  VSS31 @S9S_MB_2U_LIB.S9S_MB_2U(SCH_1):GND
  75    GND  VSS32 @S9S_MB_2U_LIB.S9S_MB_2U(SCH_1):GND
  77    GND  VSS33 @S9S_MB_2U_LIB.S9S_MB_2U(SCH_1):GND
  79    GND  VSS34 @S9S_MB_2U_LIB.S9S_MB_2U(SCH_1):GND
  81    GND  VSS35 @S9S_MB_2U_LIB.S9S_MB_2U(SCH_1):GND
  83    GND  VSS36 @S9S_MB_2U_LIB.S9S_MB_2U(SCH_1):GND
  85    GND  VSS37 @S9S_MB_2U_LIB.S9S_MB_2U(SCH_1):GND
  88    GND  VSS38 @S9S_MB_2U_LIB.S9S_MB_2U(SCH_1):GND
  90    GND  VSS39 @S9S_MB_2U_LIB.S9S_MB_2U(SCH_1):GND
  92    GND  VSS40 @S9S_MB_2U_LIB.S9S_MB_2U(SCH_1):GND
  95    GND  VSS41 @S9S_MB_2U_LIB.S9S_MB_2U(SCH_1):GND
  97    GND  VSS42 @S9S_MB_2U_LIB.S9S_MB_2U(SCH_1):GND
  99    GND  VSS43 @S9S_MB_2U_LIB.S9S_MB_2U(SCH_1):GND
 101    GND  VSS44 @S9S_MB_2U_LIB.S9S_MB_2U(SCH_1):GND
 103    GND  VSS45 @S9S_MB_2U_LIB.S9S_MB_2U(SCH_1):GND
 106    GND  VSS46 @S9S_MB_2U_LIB.S9S_MB_2U(SCH_1):GND
 108    GND  VSS47 @S9S_MB_2U_LIB.S9S_MB_2U(SCH_1):GND
 110    GND  VSS48 @S9S_MB_2U_LIB.S9S_MB_2U(SCH_1):GND
 112    GND  VSS49 @S9S_MB_2U_LIB.S9S_MB_2U(SCH_1):GND
 114    GND  VSS50 @S9S_MB_2U_LIB.S9S_MB_2U(SCH_1):GND
 117    GND  VSS51 @S9S_MB_2U_LIB.S9S_MB_2U(SCH_1):GND
 119    GND  VSS52 @S9S_MB_2U_LIB.S9S_MB_2U(SCH_1):GND
 121    GND  VSS53 @S9S_MB_2U_LIB.S9S_MB_2U(SCH_1):GND
 123    GND  VSS54 @S9S_MB_2U_LIB.S9S_MB_2U(SCH_1):GND
 125    GND  VSS55 @S9S_MB_2U_LIB.S9S_MB_2U(SCH_1):GND
 128    GND  VSS56 @S9S_MB_2U_LIB.S9S_MB_2U(SCH_1):GND
 130    GND  VSS57 @S9S_MB_2U_LIB.S9S_MB_2U(SCH_1):GND
 134    GND  VSS59 @S9S_MB_2U_LIB.S9S_MB_2U(SCH_1):GND
 143    GND  VSS63 @S9S_MB_2U_LIB.S9S_MB_2U(SCH_1):GND
 151    GND  VSS64 @S9S_MB_2U_LIB.S9S_MB_2U(SCH_1):GND
 153    GND  VSS65 @S9S_MB_2U_LIB.S9S_MB_2U(SCH_1):GND
 155    GND  VSS66 @S9S_MB_2U_LIB.S9S_MB_2U(SCH_1):GND
 158    GND  VSS67 @S9S_MB_2U_LIB.S9S_MB_2U(SCH_1):GND
 160    GND  VSS68 @S9S_MB_2U_LIB.S9S_MB_2U(SCH_1):GND
 162    GND  VSS69 @S9S_MB_2U_LIB.S9S_MB_2U(SCH_1):GND
 164    GND  VSS70 @S9S_MB_2U_LIB.S9S_MB_2U(SCH_1):GND
 166    GND  VSS71 @S9S_MB_2U_LIB.S9S_MB_2U(SCH_1):GND
 169    GND  VSS72 @S9S_MB_2U_LIB.S9S_MB_2U(SCH_1):GND
 171    GND  VSS73 @S9S_MB_2U_LIB.S9S_MB_2U(SCH_1):GND
 173    GND  VSS74 @S9S_MB_2U_LIB.S9S_MB_2U(SCH_1):GND
 175    GND  VSS75 @S9S_MB_2U_LIB.S9S_MB_2U(SCH_1):GND
 177    GND  VSS76 @S9S_MB_2U_LIB.S9S_MB_2U(SCH_1):GND
 180    GND  VSS77 @S9S_MB_2U_LIB.S9S_MB_2U(SCH_1):GND
 182    GND  VSS78 @S9S_MB_2U_LIB.S9S_MB_2U(SCH_1):GND
 184    GND  VSS79 @S9S_MB_2U_LIB.S9S_MB_2U(SCH_1):GND
 186    GND  VSS80 @S9S_MB_2U_LIB.S9S_MB_2U(SCH_1):GND
 188    GND  VSS81 @S9S_MB_2U_LIB.S9S_MB_2U(SCH_1):GND
 191    GND  VSS82 @S9S_MB_2U_LIB.S9S_MB_2U(SCH_1):GND
 193    GND  VSS83 @S9S_MB_2U_LIB.S9S_MB_2U(SCH_1):GND
 195    GND  VSS84 @S9S_MB_2U_LIB.S9S_MB_2U(SCH_1):GND
 197    GND  VSS85 @S9S_MB_2U_LIB.S9S_MB_2U(SCH_1):GND
 199    GND  VSS86 @S9S_MB_2U_LIB.S9S_MB_2U(SCH_1):GND
 202    GND  VSS87 @S9S_MB_2U_LIB.S9S_MB_2U(SCH_1):GND
 204    GND  VSS88 @S9S_MB_2U_LIB.S9S_MB_2U(SCH_1):GND
 206    GND  VSS89 @S9S_MB_2U_LIB.S9S_MB_2U(SCH_1):GND
 208    GND  VSS90 @S9S_MB_2U_LIB.S9S_MB_2U(SCH_1):GND
 210    GND  VSS91 @S9S_MB_2U_LIB.S9S_MB_2U(SCH_1):GND
 212    GND  VSS92 @S9S_MB_2U_LIB.S9S_MB_2U(SCH_1):GND
 214    GND  VSS93 @S9S_MB_2U_LIB.S9S_MB_2U(SCH_1):GND
 216    GND  VSS94 @S9S_MB_2U_LIB.S9S_MB_2U(SCH_1):GND
 219    GND  VSS95 @S9S_MB_2U_LIB.S9S_MB_2U(SCH_1):GND
 222    GND  VSS96 @S9S_MB_2U_LIB.S9S_MB_2U(SCH_1):GND
 224    GND  VSS97 @S9S_MB_2U_LIB.S9S_MB_2U(SCH_1):GND
 226    GND  VSS98 @S9S_MB_2U_LIB.S9S_MB_2U(SCH_1):GND
 228    GND  VSS99 @S9S_MB_2U_LIB.S9S_MB_2U(SCH_1):GND
 233    GND VSS101 @S9S_MB_2U_LIB.S9S_MB_2U(SCH_1):GND
 237    GND VSS103 @S9S_MB_2U_LIB.S9S_MB_2U(SCH_1):GND
 242    GND VSS105 @S9S_MB_2U_LIB.S9S_MB_2U(SCH_1):GND
 244    GND VSS106 @S9S_MB_2U_LIB.S9S_MB_2U(SCH_1):GND
 246    GND VSS107 @S9S_MB_2U_LIB.S9S_MB_2U(SCH_1):GND
 248    GND VSS108 @S9S_MB_2U_LIB.S9S_MB_2U(SCH_1):GND
 251    GND VSS109 @S9S_MB_2U_LIB.S9S_MB_2U(SCH_1):GND
 253    GND VSS110 @S9S_MB_2U_LIB.S9S_MB_2U(SCH_1):GND
 255    GND VSS111 @S9S_MB_2U_LIB.S9S_MB_2U(SCH_1):GND
 257    GND VSS112 @S9S_MB_2U_LIB.S9S_MB_2U(SCH_1):GND
 259    GND VSS113 @S9S_MB_2U_LIB.S9S_MB_2U(SCH_1):GND
 262    GND VSS114 @S9S_MB_2U_LIB.S9S_MB_2U(SCH_1):GND
 264    GND VSS115 @S9S_MB_2U_LIB.S9S_MB_2U(SCH_1):GND
 266    GND VSS116 @S9S_MB_2U_LIB.S9S_MB_2U(SCH_1):GND
 268    GND VSS117 @S9S_MB_2U_LIB.S9S_MB_2U(SCH_1):GND
 270    GND VSS118 @S9S_MB_2U_LIB.S9S_MB_2U(SCH_1):GND
 273    GND VSS119 @S9S_MB_2U_LIB.S9S_MB_2U(SCH_1):GND
 275    GND VSS120 @S9S_MB_2U_LIB.S9S_MB_2U(SCH_1):GND
 277    GND VSS121 @S9S_MB_2U_LIB.S9S_MB_2U(SCH_1):GND
 279    GND VSS122 @S9S_MB_2U_LIB.S9S_MB_2U(SCH_1):GND
 281    GND VSS123 @S9S_MB_2U_LIB.S9S_MB_2U(SCH_1):GND
 284    GND VSS124 @S9S_MB_2U_LIB.S9S_MB_2U(SCH_1):GND
 286    GND VSS125 @S9S_MB_2U_LIB.S9S_MB_2U(SCH_1):GND
 288    GND VSS126 @S9S_MB_2U_LIB.S9S_MB_2U(SCH_1):GND
   1 P12V_S3_AUX_CPU1_NVDIMM VIN_BULK0 @S9S_MB_2U_LIB.S9S_MB_2U(SCH_1):P12V_S3_AUX_CPU1_NVDIMM
 145 P12V_S3_AUX_CPU1_NVDIMM VIN_BULK1 @S9S_MB_2U_LIB.S9S_MB_2U(SCH_1):P12V_S3_AUX_CPU1_NVDIMM
 146 P12V_S3_AUX_CPU1_NVDIMM VIN_BULK2 @S9S_MB_2U_LIB.S9S_MB_2U(SCH_1):P12V_S3_AUX_CPU1_NVDIMM
 230    GND VSS100 @S9S_MB_2U_LIB.S9S_MB_2U(SCH_1):GND
 235    GND VSS102 @S9S_MB_2U_LIB.S9S_MB_2U(SCH_1):GND
 240    GND VSS104 @S9S_MB_2U_LIB.S9S_MB_2U(SCH_1):GND
 132    GND  VSS58 @S9S_MB_2U_LIB.S9S_MB_2U(SCH_1):GND
 136    GND  VSS60 @S9S_MB_2U_LIB.S9S_MB_2U(SCH_1):GND
 139    GND  VSS61 @S9S_MB_2U_LIB.S9S_MB_2U(SCH_1):GND
 141    GND  VSS62 @S9S_MB_2U_LIB.S9S_MB_2U(SCH_1):GND
  G1    GND     G1 @S9S_MB_2U_LIB.S9S_MB_2U(SCH_1):GND
  G2    GND     G2 @S9S_MB_2U_LIB.S9S_MB_2U(SCH_1):GND
  G3    GND     G3 @S9S_MB_2U_LIB.S9S_MB_2U(SCH_1):GND

SCONN288_ADR50017P087CC-SCONN2A  I178  J18
  93 M_A_CPU1_SB_DQS_DP<9> DQS9_B_T||TDQS9_B_T||DBI4_B_N @S9S_MB_2U_LIB.S9S_MB_2U(SCH_1):M_A_CPU1_SB_DQS_DP(9)
  94 M_A_CPU1_SB_DQS_DN<9> DQS9_B_C||TDQS9_B_C @S9S_MB_2U_LIB.S9S_MB_2U(SCH_1):M_A_CPU1_SB_DQS_DN(9)
 201 M_A_CPU1_SA_DQS_DP<9> DQS9_A_T||TDQS9_A_T @S9S_MB_2U_LIB.S9S_MB_2U(SCH_1):M_A_CPU1_SA_DQS_DP(9)
 200 M_A_CPU1_SA_DQS_DN<9> DQS9_A_C||TDQS9_A_C @S9S_MB_2U_LIB.S9S_MB_2U(SCH_1):M_A_CPU1_SA_DQS_DN(9)
 190 M_A_CPU1_SA_DQS_DP<8> DQS8_A_T||TDQS8_A_T @S9S_MB_2U_LIB.S9S_MB_2U(SCH_1):M_A_CPU1_SA_DQS_DP(8)
 189 M_A_CPU1_SA_DQS_DN<8> DQS8_A_C||TDQS8_A_C @S9S_MB_2U_LIB.S9S_MB_2U(SCH_1):M_A_CPU1_SA_DQS_DN(8)
 271 M_A_CPU1_SB_DQS_DN<7> DQS7_B_C||TDQS7_B_C @S9S_MB_2U_LIB.S9S_MB_2U(SCH_1):M_A_CPU1_SB_DQS_DN(7)
 179 M_A_CPU1_SA_DQS_DP<7> DQS7_A_T||TDQS7_A_T @S9S_MB_2U_LIB.S9S_MB_2U(SCH_1):M_A_CPU1_SA_DQS_DP(7)
 261 M_A_CPU1_SB_DQS_DP<6> DQS6_B_T||TDQS6_B_T @S9S_MB_2U_LIB.S9S_MB_2U(SCH_1):M_A_CPU1_SB_DQS_DP(6)
 260 M_A_CPU1_SB_DQS_DN<6> DQS6_B_C||TDQS6_B_C @S9S_MB_2U_LIB.S9S_MB_2U(SCH_1):M_A_CPU1_SB_DQS_DN(6)
 167 M_A_CPU1_SA_DQS_DN<6> DQS6_A_C||TDQS6_A_C||DQS6_A_T||TDQS6_A_T @S9S_MB_2U_LIB.S9S_MB_2U(SCH_1):M_A_CPU1_SA_DQS_DN(6)
 250 M_A_CPU1_SB_DQS_DP<5> DQS5_B_T||TDQS5_B_T @S9S_MB_2U_LIB.S9S_MB_2U(SCH_1):M_A_CPU1_SB_DQS_DP(5)
 249 M_A_CPU1_SB_DQS_DN<5> DQS5_B_C||TDQS5_B_C @S9S_MB_2U_LIB.S9S_MB_2U(SCH_1):M_A_CPU1_SB_DQS_DN(5)
 157 M_A_CPU1_SA_DQS_DP<5> DQS5_A_T||TDQS5_A_T @S9S_MB_2U_LIB.S9S_MB_2U(SCH_1):M_A_CPU1_SA_DQS_DP(5)
 156 M_A_CPU1_SA_DQS_DN<5> DQS5_A_C||TDQS5_A_C||DQS5_A_T||TDQS5_A_T @S9S_MB_2U_LIB.S9S_MB_2U(SCH_1):M_A_CPU1_SA_DQS_DN(5)
 239 M_A_CPU1_SB_DQS_DP<4> DQS4_B_T @S9S_MB_2U_LIB.S9S_MB_2U(SCH_1):M_A_CPU1_SB_DQS_DP(4)
 238 M_A_CPU1_SB_DQS_DN<4> DQS4_B_C @S9S_MB_2U_LIB.S9S_MB_2U(SCH_1):M_A_CPU1_SB_DQS_DN(4)
  55 M_A_CPU1_SA_DQS_DP<4> DQS4_A_T @S9S_MB_2U_LIB.S9S_MB_2U(SCH_1):M_A_CPU1_SA_DQS_DP(4)
  56 M_A_CPU1_SA_DQS_DN<4> DQS4_A_C @S9S_MB_2U_LIB.S9S_MB_2U(SCH_1):M_A_CPU1_SA_DQS_DN(4)
 137 M_A_CPU1_SB_DQS_DP<3> DQS3_B_T @S9S_MB_2U_LIB.S9S_MB_2U(SCH_1):M_A_CPU1_SB_DQS_DP(3)
 138 M_A_CPU1_SB_DQS_DN<3> DQS3_B_C @S9S_MB_2U_LIB.S9S_MB_2U(SCH_1):M_A_CPU1_SB_DQS_DN(3)
  44 M_A_CPU1_SA_DQS_DP<3> DQS3_A_T @S9S_MB_2U_LIB.S9S_MB_2U(SCH_1):M_A_CPU1_SA_DQS_DP(3)
  45 M_A_CPU1_SA_DQS_DN<3> DQS3_A_C @S9S_MB_2U_LIB.S9S_MB_2U(SCH_1):M_A_CPU1_SA_DQS_DN(3)
 126 M_A_CPU1_SB_DQS_DP<2> DQS2_B_T @S9S_MB_2U_LIB.S9S_MB_2U(SCH_1):M_A_CPU1_SB_DQS_DP(2)
 127 M_A_CPU1_SB_DQS_DN<2> DQS2_B_C @S9S_MB_2U_LIB.S9S_MB_2U(SCH_1):M_A_CPU1_SB_DQS_DN(2)
  33 M_A_CPU1_SA_DQS_DP<2> DQS2_A_T @S9S_MB_2U_LIB.S9S_MB_2U(SCH_1):M_A_CPU1_SA_DQS_DP(2)
  34 M_A_CPU1_SA_DQS_DN<2> DQS2_A_C @S9S_MB_2U_LIB.S9S_MB_2U(SCH_1):M_A_CPU1_SA_DQS_DN(2)
 115 M_A_CPU1_SB_DQS_DP<1> DQS1_B_T @S9S_MB_2U_LIB.S9S_MB_2U(SCH_1):M_A_CPU1_SB_DQS_DP(1)
 116 M_A_CPU1_SB_DQS_DN<1> DQS1_B_C @S9S_MB_2U_LIB.S9S_MB_2U(SCH_1):M_A_CPU1_SB_DQS_DN(1)
  22 M_A_CPU1_SA_DQS_DP<1> DQS1_A_T @S9S_MB_2U_LIB.S9S_MB_2U(SCH_1):M_A_CPU1_SA_DQS_DP(1)
  23 M_A_CPU1_SA_DQS_DN<1> DQS1_A_C @S9S_MB_2U_LIB.S9S_MB_2U(SCH_1):M_A_CPU1_SA_DQS_DN(1)
 104 M_A_CPU1_SB_DQS_DP<0> DQS0_B_T @S9S_MB_2U_LIB.S9S_MB_2U(SCH_1):M_A_CPU1_SB_DQS_DP(0)
 105 M_A_CPU1_SB_DQS_DN<0> DQS0_B_C @S9S_MB_2U_LIB.S9S_MB_2U(SCH_1):M_A_CPU1_SB_DQS_DN(0)
  11 M_A_CPU1_SA_DQS_DP<0> DQS0_A_T @S9S_MB_2U_LIB.S9S_MB_2U(SCH_1):M_A_CPU1_SA_DQS_DP(0)
  12 M_A_CPU1_SA_DQS_DN<0> DQS0_A_C @S9S_MB_2U_LIB.S9S_MB_2U(SCH_1):M_A_CPU1_SA_DQS_DN(0)
 272 M_A_CPU1_SB_DQS_DP<7> DQS7_B_T||TDQS7_B_T @S9S_MB_2U_LIB.S9S_MB_2U(SCH_1):M_A_CPU1_SB_DQS_DP(7)
 282 M_A_CPU1_SB_DQS_DN<8> DQS8_B_C||TDQS8_B_C @S9S_MB_2U_LIB.S9S_MB_2U(SCH_1):M_A_CPU1_SB_DQS_DN(8)
 283 M_A_CPU1_SB_DQS_DP<8> DQS8_B_T||TDQS8_B_T @S9S_MB_2U_LIB.S9S_MB_2U(SCH_1):M_A_CPU1_SB_DQS_DP(8)
 168 M_A_CPU1_SA_DQS_DP<6> DQS6_A_T||TDQS6_A_T @S9S_MB_2U_LIB.S9S_MB_2U(SCH_1):M_A_CPU1_SA_DQS_DP(6)
 178 M_A_CPU1_SA_DQS_DN<7> DQS7_A_C||TDQS7_A_C @S9S_MB_2U_LIB.S9S_MB_2U(SCH_1):M_A_CPU1_SA_DQS_DN(7)

Q_RES_0402LF-49.9,1%,1/16W,CHIA  I180  R3892
   1 I3C_SPD_DDRABCD_CPU1_LVC1_SCL_1      A @S9S_MB_2U_LIB.S9S_MB_2U(SCH_1):I3C_SPD_DDRABCD_CPU1_LVC1_SCL_R2
   2 I3C_SPD_DDRABCD_CPU1_LVC1_SCL      B @S9S_MB_2U_LIB.S9S_MB_2U(SCH_1):I3C_SPD_DDRABCD_CPU1_LVC1_SCL


DRAWING: @S9S_MB_2U_LIB.S9S_MB_2U(SCH_1):PAGE100 

Q_RES_0402LF-23.2K,1%,1/16W,CHA  I3  R44
   1 PD_CHB_CPU1_DIMM1_SAA      A @S9S_MB_2U_LIB.S9S_MB_2U(SCH_1):PD_CHB_CPU1_DIMM1_SAA
   2    GND      B @S9S_MB_2U_LIB.S9S_MB_2U(SCH_1):GND

SCONN288_ADR50017P130CC-SCONN2A  I25  J19
   3 P3V3_AUX VIN_MGMT @S9S_MB_2U_LIB.S9S_MB_2U(SCH_1):P3V3_AUX
   2 TP_CHB_CPU1_DIMM1_FRU_0   RFU0 @S9S_MB_2U_LIB.S9S_MB_2U(SCH_1):TP_CHB_CPU1_DIMM1_FRU_0
 144 TP_CHB_CPU1_DIMM1_FRU_1   RFU1 @S9S_MB_2U_LIB.S9S_MB_2U(SCH_1):TP_CHB_CPU1_DIMM1_FRU_1
 149 TP_CHB_CPU1_DIMM1_FRU_2   RFU2 @S9S_MB_2U_LIB.S9S_MB_2U(SCH_1):TP_CHB_CPU1_DIMM1_FRU_2
 150 TP_CHB_CPU1_DIMM1_FRU_3   RFU3 @S9S_MB_2U_LIB.S9S_MB_2U(SCH_1):TP_CHB_CPU1_DIMM1_FRU_3
 220 TP_CHB_CPU1_DIMM1_FRU_4   RFU4 @S9S_MB_2U_LIB.S9S_MB_2U(SCH_1):TP_CHB_CPU1_DIMM1_FRU_4
 231 TP_CHB_CPU1_DIMM1_FRU_5   RFU5 @S9S_MB_2U_LIB.S9S_MB_2U(SCH_1):TP_CHB_CPU1_DIMM1_FRU_5
 232 TP_CHB_CPU1_DIMM1_FRU_6   RFU6 @S9S_MB_2U_LIB.S9S_MB_2U(SCH_1):TP_CHB_CPU1_DIMM1_FRU_6
 207 RST_M_AB_CPU1_FPGA_N RESET_N @S9S_MB_2U_LIB.S9S_MB_2U(SCH_1):RST_M_AB_CPU1_FPGA_N
 147 PWRGD_CHB_CPU1_DIMM1 PWR_GOOD||FAIL_N @S9S_MB_2U_LIB.S9S_MB_2U(SCH_1):PWRGD_CHB_CPU1_DIMM1
 227 M_B_CPU1_SB_PAR  PAR_B @S9S_MB_2U_LIB.S9S_MB_2U(SCH_1):M_B_CPU1_SB_PAR
  74 M_B_CPU1_SA_PAR  PAR_A @S9S_MB_2U_LIB.S9S_MB_2U(SCH_1):M_B_CPU1_SA_PAR
  87 M_B_CPU1_SB_RSP<0> LBS||RSP_B_N @S9S_MB_2U_LIB.S9S_MB_2U(SCH_1):M_B_CPU1_SB_RSP(0)
  86 M_B_CPU1_SA_RSP<0> LBD||RSP_A_N @S9S_MB_2U_LIB.S9S_MB_2U(SCH_1):M_B_CPU1_SA_RSP(0)
   5 I3C_SPD_DDRABCD_CPU1_LVC1_SDA   HSDA @S9S_MB_2U_LIB.S9S_MB_2U(SCH_1):I3C_SPD_DDRABCD_CPU1_LVC1_SDA
   4 I3C_SPD_DDRABCD_CPU1_LVC1_SCL_2   HSCL @S9S_MB_2U_LIB.S9S_MB_2U(SCH_1):I3C_SPD_DDRABCD_CPU1_LVC1_SCL_R3
 148 PD_CHB_CPU1_DIMM1_SAA    HSA @S9S_MB_2U_LIB.S9S_MB_2U(SCH_1):PD_CHB_CPU1_DIMM1_SAA
 100 M_B_CPU1_SB_DQ<0>  DQ0_B @S9S_MB_2U_LIB.S9S_MB_2U(SCH_1):M_B_CPU1_SB_DQ(0)
 102 M_B_CPU1_SB_DQ<1>  DQ1_B @S9S_MB_2U_LIB.S9S_MB_2U(SCH_1):M_B_CPU1_SB_DQ(1)
 245 M_B_CPU1_SB_DQ<2>  DQ2_B @S9S_MB_2U_LIB.S9S_MB_2U(SCH_1):M_B_CPU1_SB_DQ(2)
 247 M_B_CPU1_SB_DQ<3>  DQ3_B @S9S_MB_2U_LIB.S9S_MB_2U(SCH_1):M_B_CPU1_SB_DQ(3)
 107 M_B_CPU1_SB_DQ<4>  DQ4_B @S9S_MB_2U_LIB.S9S_MB_2U(SCH_1):M_B_CPU1_SB_DQ(4)
 109 M_B_CPU1_SB_DQ<5>  DQ5_B @S9S_MB_2U_LIB.S9S_MB_2U(SCH_1):M_B_CPU1_SB_DQ(5)
 252 M_B_CPU1_SB_DQ<6>  DQ6_B @S9S_MB_2U_LIB.S9S_MB_2U(SCH_1):M_B_CPU1_SB_DQ(6)
 254 M_B_CPU1_SB_DQ<7>  DQ7_B @S9S_MB_2U_LIB.S9S_MB_2U(SCH_1):M_B_CPU1_SB_DQ(7)
 111 M_B_CPU1_SB_DQ<8>  DQ8_B @S9S_MB_2U_LIB.S9S_MB_2U(SCH_1):M_B_CPU1_SB_DQ(8)
 113 M_B_CPU1_SB_DQ<9>  DQ9_B @S9S_MB_2U_LIB.S9S_MB_2U(SCH_1):M_B_CPU1_SB_DQ(9)
 256 M_B_CPU1_SB_DQ<10> DQ10_B @S9S_MB_2U_LIB.S9S_MB_2U(SCH_1):M_B_CPU1_SB_DQ(10)
 258 M_B_CPU1_SB_DQ<11> DQ11_B @S9S_MB_2U_LIB.S9S_MB_2U(SCH_1):M_B_CPU1_SB_DQ(11)
 118 M_B_CPU1_SB_DQ<12> DQ12_B @S9S_MB_2U_LIB.S9S_MB_2U(SCH_1):M_B_CPU1_SB_DQ(12)
 120 M_B_CPU1_SB_DQ<13> DQ13_B @S9S_MB_2U_LIB.S9S_MB_2U(SCH_1):M_B_CPU1_SB_DQ(13)
 263 M_B_CPU1_SB_DQ<14> DQ14_B @S9S_MB_2U_LIB.S9S_MB_2U(SCH_1):M_B_CPU1_SB_DQ(14)
 265 M_B_CPU1_SB_DQ<15> DQ15_B @S9S_MB_2U_LIB.S9S_MB_2U(SCH_1):M_B_CPU1_SB_DQ(15)
 122 M_B_CPU1_SB_DQ<16> DQ16_B @S9S_MB_2U_LIB.S9S_MB_2U(SCH_1):M_B_CPU1_SB_DQ(16)
 124 M_B_CPU1_SB_DQ<17> DQ17_B @S9S_MB_2U_LIB.S9S_MB_2U(SCH_1):M_B_CPU1_SB_DQ(17)
 267 M_B_CPU1_SB_DQ<18> DQ18_B @S9S_MB_2U_LIB.S9S_MB_2U(SCH_1):M_B_CPU1_SB_DQ(18)
 269 M_B_CPU1_SB_DQ<19> DQ19_B @S9S_MB_2U_LIB.S9S_MB_2U(SCH_1):M_B_CPU1_SB_DQ(19)
 129 M_B_CPU1_SB_DQ<20> DQ20_B @S9S_MB_2U_LIB.S9S_MB_2U(SCH_1):M_B_CPU1_SB_DQ(20)
 131 M_B_CPU1_SB_DQ<21> DQ21_B @S9S_MB_2U_LIB.S9S_MB_2U(SCH_1):M_B_CPU1_SB_DQ(21)
 274 M_B_CPU1_SB_DQ<22> DQ22_B @S9S_MB_2U_LIB.S9S_MB_2U(SCH_1):M_B_CPU1_SB_DQ(22)
 276 M_B_CPU1_SB_DQ<23> DQ23_B @S9S_MB_2U_LIB.S9S_MB_2U(SCH_1):M_B_CPU1_SB_DQ(23)
 133 M_B_CPU1_SB_DQ<24> DQ24_B @S9S_MB_2U_LIB.S9S_MB_2U(SCH_1):M_B_CPU1_SB_DQ(24)
 135 M_B_CPU1_SB_DQ<25> DQ25_B @S9S_MB_2U_LIB.S9S_MB_2U(SCH_1):M_B_CPU1_SB_DQ(25)
 278 M_B_CPU1_SB_DQ<26> DQ26_B @S9S_MB_2U_LIB.S9S_MB_2U(SCH_1):M_B_CPU1_SB_DQ(26)
 280 M_B_CPU1_SB_DQ<27> DQ27_B @S9S_MB_2U_LIB.S9S_MB_2U(SCH_1):M_B_CPU1_SB_DQ(27)
 140 M_B_CPU1_SB_DQ<28> DQ28_B @S9S_MB_2U_LIB.S9S_MB_2U(SCH_1):M_B_CPU1_SB_DQ(28)
 142 M_B_CPU1_SB_DQ<29> DQ29_B @S9S_MB_2U_LIB.S9S_MB_2U(SCH_1):M_B_CPU1_SB_DQ(29)
 285 M_B_CPU1_SB_DQ<30> DQ30_B @S9S_MB_2U_LIB.S9S_MB_2U(SCH_1):M_B_CPU1_SB_DQ(30)
 287 M_B_CPU1_SB_DQ<31> DQ31_B @S9S_MB_2U_LIB.S9S_MB_2U(SCH_1):M_B_CPU1_SB_DQ(31)
   7 M_B_CPU1_SA_DQ<0>  DQ0_A @S9S_MB_2U_LIB.S9S_MB_2U(SCH_1):M_B_CPU1_SA_DQ(0)
   9 M_B_CPU1_SA_DQ<1>  DQ1_A @S9S_MB_2U_LIB.S9S_MB_2U(SCH_1):M_B_CPU1_SA_DQ(1)
 152 M_B_CPU1_SA_DQ<2>  DQ2_A @S9S_MB_2U_LIB.S9S_MB_2U(SCH_1):M_B_CPU1_SA_DQ(2)
 154 M_B_CPU1_SA_DQ<3>  DQ3_A @S9S_MB_2U_LIB.S9S_MB_2U(SCH_1):M_B_CPU1_SA_DQ(3)
  14 M_B_CPU1_SA_DQ<4>  DQ4_A @S9S_MB_2U_LIB.S9S_MB_2U(SCH_1):M_B_CPU1_SA_DQ(4)
  16 M_B_CPU1_SA_DQ<5>  DQ5_A @S9S_MB_2U_LIB.S9S_MB_2U(SCH_1):M_B_CPU1_SA_DQ(5)
 159 M_B_CPU1_SA_DQ<6>  DQ6_A @S9S_MB_2U_LIB.S9S_MB_2U(SCH_1):M_B_CPU1_SA_DQ(6)
 161 M_B_CPU1_SA_DQ<7>  DQ7_A @S9S_MB_2U_LIB.S9S_MB_2U(SCH_1):M_B_CPU1_SA_DQ(7)
  18 M_B_CPU1_SA_DQ<8>  DQ8_A @S9S_MB_2U_LIB.S9S_MB_2U(SCH_1):M_B_CPU1_SA_DQ(8)
  20 M_B_CPU1_SA_DQ<9>  DQ9_A @S9S_MB_2U_LIB.S9S_MB_2U(SCH_1):M_B_CPU1_SA_DQ(9)
 163 M_B_CPU1_SA_DQ<10> DQ10_A @S9S_MB_2U_LIB.S9S_MB_2U(SCH_1):M_B_CPU1_SA_DQ(10)
 165 M_B_CPU1_SA_DQ<11> DQ11_A @S9S_MB_2U_LIB.S9S_MB_2U(SCH_1):M_B_CPU1_SA_DQ(11)
  25 M_B_CPU1_SA_DQ<12> DQ12_A @S9S_MB_2U_LIB.S9S_MB_2U(SCH_1):M_B_CPU1_SA_DQ(12)
  27 M_B_CPU1_SA_DQ<13> DQ13_A @S9S_MB_2U_LIB.S9S_MB_2U(SCH_1):M_B_CPU1_SA_DQ(13)
 170 M_B_CPU1_SA_DQ<14> DQ14_A @S9S_MB_2U_LIB.S9S_MB_2U(SCH_1):M_B_CPU1_SA_DQ(14)
 172 M_B_CPU1_SA_DQ<15> DQ15_A @S9S_MB_2U_LIB.S9S_MB_2U(SCH_1):M_B_CPU1_SA_DQ(15)
  29 M_B_CPU1_SA_DQ<16> DQ16_A @S9S_MB_2U_LIB.S9S_MB_2U(SCH_1):M_B_CPU1_SA_DQ(16)
  31 M_B_CPU1_SA_DQ<17> DQ17_A @S9S_MB_2U_LIB.S9S_MB_2U(SCH_1):M_B_CPU1_SA_DQ(17)
 174 M_B_CPU1_SA_DQ<18> DQ18_A @S9S_MB_2U_LIB.S9S_MB_2U(SCH_1):M_B_CPU1_SA_DQ(18)
 176 M_B_CPU1_SA_DQ<19> DQ19_A @S9S_MB_2U_LIB.S9S_MB_2U(SCH_1):M_B_CPU1_SA_DQ(19)
  36 M_B_CPU1_SA_DQ<20> DQ20_A @S9S_MB_2U_LIB.S9S_MB_2U(SCH_1):M_B_CPU1_SA_DQ(20)
  38 M_B_CPU1_SA_DQ<21> DQ21_A @S9S_MB_2U_LIB.S9S_MB_2U(SCH_1):M_B_CPU1_SA_DQ(21)
 181 M_B_CPU1_SA_DQ<22> DQ22_A @S9S_MB_2U_LIB.S9S_MB_2U(SCH_1):M_B_CPU1_SA_DQ(22)
 183 M_B_CPU1_SA_DQ<23> DQ23_A @S9S_MB_2U_LIB.S9S_MB_2U(SCH_1):M_B_CPU1_SA_DQ(23)
  40 M_B_CPU1_SA_DQ<24> DQ24_A @S9S_MB_2U_LIB.S9S_MB_2U(SCH_1):M_B_CPU1_SA_DQ(24)
  42 M_B_CPU1_SA_DQ<25> DQ25_A @S9S_MB_2U_LIB.S9S_MB_2U(SCH_1):M_B_CPU1_SA_DQ(25)
 185 M_B_CPU1_SA_DQ<26> DQ26_A @S9S_MB_2U_LIB.S9S_MB_2U(SCH_1):M_B_CPU1_SA_DQ(26)
 187 M_B_CPU1_SA_DQ<27> DQ27_A @S9S_MB_2U_LIB.S9S_MB_2U(SCH_1):M_B_CPU1_SA_DQ(27)
  47 M_B_CPU1_SA_DQ<28> DQ28_A @S9S_MB_2U_LIB.S9S_MB_2U(SCH_1):M_B_CPU1_SA_DQ(28)
  49 M_B_CPU1_SA_DQ<29> DQ29_A @S9S_MB_2U_LIB.S9S_MB_2U(SCH_1):M_B_CPU1_SA_DQ(29)
 192 M_B_CPU1_SA_DQ<30> DQ30_A @S9S_MB_2U_LIB.S9S_MB_2U(SCH_1):M_B_CPU1_SA_DQ(30)
 229 M_B_CPU1_SB_CS_N<1> CS1_B_N @S9S_MB_2U_LIB.S9S_MB_2U(SCH_1):M_B_CPU1_SB_CS_N(1)
 209 M_B_CPU1_SA_CS_N<1> CS1_A_N @S9S_MB_2U_LIB.S9S_MB_2U(SCH_1):M_B_CPU1_SA_CS_N(1)
  84 M_B_CPU1_SB_CS_N<0> CS0_B_N @S9S_MB_2U_LIB.S9S_MB_2U(SCH_1):M_B_CPU1_SB_CS_N(0)
  64 M_B_CPU1_SA_CS_N<0> CS0_A_N @S9S_MB_2U_LIB.S9S_MB_2U(SCH_1):M_B_CPU1_SA_CS_N(0)
 217 M_B_CPU1_CLK_DP<0>   CK_T @S9S_MB_2U_LIB.S9S_MB_2U(SCH_1):M_B_CPU1_CLK_DP(0)
 218 M_B_CPU1_CLK_DN<0>   CK_C @S9S_MB_2U_LIB.S9S_MB_2U(SCH_1):M_B_CPU1_CLK_DN(0)
  96 M_B_CPU1_SB_CB<0>  CB0_B @S9S_MB_2U_LIB.S9S_MB_2U(SCH_1):M_B_CPU1_SB_CB(0)
  98 M_B_CPU1_SB_CB<1>  CB1_B @S9S_MB_2U_LIB.S9S_MB_2U(SCH_1):M_B_CPU1_SB_CB(1)
 241 M_B_CPU1_SB_CB<2>  CB2_B @S9S_MB_2U_LIB.S9S_MB_2U(SCH_1):M_B_CPU1_SB_CB(2)
 243 M_B_CPU1_SB_CB<3>  CB3_B @S9S_MB_2U_LIB.S9S_MB_2U(SCH_1):M_B_CPU1_SB_CB(3)
  89 M_B_CPU1_SB_CB<4>  CB4_B @S9S_MB_2U_LIB.S9S_MB_2U(SCH_1):M_B_CPU1_SB_CB(4)
  91 M_B_CPU1_SB_CB<5>  CB5_B @S9S_MB_2U_LIB.S9S_MB_2U(SCH_1):M_B_CPU1_SB_CB(5)
 234 M_B_CPU1_SB_CB<6>  CB6_B @S9S_MB_2U_LIB.S9S_MB_2U(SCH_1):M_B_CPU1_SB_CB(6)
  51 M_B_CPU1_SA_CB<0>  CB0_A @S9S_MB_2U_LIB.S9S_MB_2U(SCH_1):M_B_CPU1_SA_CB(0)
 196 M_B_CPU1_SA_CB<2>  CB2_A @S9S_MB_2U_LIB.S9S_MB_2U(SCH_1):M_B_CPU1_SA_CB(2)
 198 M_B_CPU1_SA_CB<3>  CB3_A @S9S_MB_2U_LIB.S9S_MB_2U(SCH_1):M_B_CPU1_SA_CB(3)
  60 M_B_CPU1_SA_CB<5>  CB5_A @S9S_MB_2U_LIB.S9S_MB_2U(SCH_1):M_B_CPU1_SA_CB(5)
 203 M_B_CPU1_SA_CB<6>  CB6_A @S9S_MB_2U_LIB.S9S_MB_2U(SCH_1):M_B_CPU1_SA_CB(6)
  82 M_B_CPU1_SB_CA<6>  CA6_B @S9S_MB_2U_LIB.S9S_MB_2U(SCH_1):M_B_CPU1_SB_CA(6)
  72 M_B_CPU1_SA_CA<6>  CA6_A @S9S_MB_2U_LIB.S9S_MB_2U(SCH_1):M_B_CPU1_SA_CA(6)
 225 M_B_CPU1_SB_CA<5>  CA5_B @S9S_MB_2U_LIB.S9S_MB_2U(SCH_1):M_B_CPU1_SB_CA(5)
 215 M_B_CPU1_SA_CA<5>  CA5_A @S9S_MB_2U_LIB.S9S_MB_2U(SCH_1):M_B_CPU1_SA_CA(5)
  80 M_B_CPU1_SB_CA<4>  CA4_B @S9S_MB_2U_LIB.S9S_MB_2U(SCH_1):M_B_CPU1_SB_CA(4)
  70 M_B_CPU1_SA_CA<4>  CA4_A @S9S_MB_2U_LIB.S9S_MB_2U(SCH_1):M_B_CPU1_SA_CA(4)
 223 M_B_CPU1_SB_CA<3>  CA3_B @S9S_MB_2U_LIB.S9S_MB_2U(SCH_1):M_B_CPU1_SB_CA(3)
 213 M_B_CPU1_SA_CA<3>  CA3_A @S9S_MB_2U_LIB.S9S_MB_2U(SCH_1):M_B_CPU1_SA_CA(3)
  78 M_B_CPU1_SB_CA<2>  CA2_B @S9S_MB_2U_LIB.S9S_MB_2U(SCH_1):M_B_CPU1_SB_CA(2)
  68 M_B_CPU1_SA_CA<2>  CA2_A @S9S_MB_2U_LIB.S9S_MB_2U(SCH_1):M_B_CPU1_SA_CA(2)
 221 M_B_CPU1_SB_CA<1>  CA1_B @S9S_MB_2U_LIB.S9S_MB_2U(SCH_1):M_B_CPU1_SB_CA(1)
 211 M_B_CPU1_SA_CA<1>  CA1_A @S9S_MB_2U_LIB.S9S_MB_2U(SCH_1):M_B_CPU1_SA_CA(1)
  76 M_B_CPU1_SB_CA<0>  CA0_B @S9S_MB_2U_LIB.S9S_MB_2U(SCH_1):M_B_CPU1_SB_CA(0)
  66 M_B_CPU1_SA_CA<0>  CA0_A @S9S_MB_2U_LIB.S9S_MB_2U(SCH_1):M_B_CPU1_SA_CA(0)
  62 M_B_CPU1_ALERT_N ALERT_N @S9S_MB_2U_LIB.S9S_MB_2U(SCH_1):M_B_CPU1_ALERT_N
 236 M_B_CPU1_SB_CB<7>  CB7_B @S9S_MB_2U_LIB.S9S_MB_2U(SCH_1):M_B_CPU1_SB_CB(7)
  53 M_B_CPU1_SA_CB<1>  CB1_A @S9S_MB_2U_LIB.S9S_MB_2U(SCH_1):M_B_CPU1_SA_CB(1)
  58 M_B_CPU1_SA_CB<4>  CB4_A @S9S_MB_2U_LIB.S9S_MB_2U(SCH_1):M_B_CPU1_SA_CB(4)
 205 M_B_CPU1_SA_CB<7>  CB7_A @S9S_MB_2U_LIB.S9S_MB_2U(SCH_1):M_B_CPU1_SA_CB(7)
 194 M_B_CPU1_SA_DQ<31> DQ31_A @S9S_MB_2U_LIB.S9S_MB_2U(SCH_1):M_B_CPU1_SA_DQ(31)

Q_CAP_C0402-2.2UF,6.3V,20%,X6SA  I121  C56
   1 P3V3_AUX      A @S9S_MB_2U_LIB.S9S_MB_2U(SCH_1):P3V3_AUX
   2    GND      B @S9S_MB_2U_LIB.S9S_MB_2U(SCH_1):GND

Q_CAP_C0805-10UF,16V,10%,X6S,CA  I122  C57
   1 P12V_S3_AUX_CPU1_NVDIMM      A @S9S_MB_2U_LIB.S9S_MB_2U(SCH_1):P12V_S3_AUX_CPU1_NVDIMM
   2    GND      B @S9S_MB_2U_LIB.S9S_MB_2U(SCH_1):GND

Q_CAP_C0805-10UF,16V,10%,X6S,CA  I124  C58
   1 P12V_S3_AUX_CPU1_NVDIMM      A @S9S_MB_2U_LIB.S9S_MB_2U(SCH_1):P12V_S3_AUX_CPU1_NVDIMM
   2    GND      B @S9S_MB_2U_LIB.S9S_MB_2U(SCH_1):GND

SCONN288_ADR50017P130CC-SCONN2A  I175  J19
   6    GND   VSS0 @S9S_MB_2U_LIB.S9S_MB_2U(SCH_1):GND
   8    GND   VSS1 @S9S_MB_2U_LIB.S9S_MB_2U(SCH_1):GND
  10    GND   VSS2 @S9S_MB_2U_LIB.S9S_MB_2U(SCH_1):GND
  13    GND   VSS3 @S9S_MB_2U_LIB.S9S_MB_2U(SCH_1):GND
  15    GND   VSS4 @S9S_MB_2U_LIB.S9S_MB_2U(SCH_1):GND
  17    GND   VSS5 @S9S_MB_2U_LIB.S9S_MB_2U(SCH_1):GND
  19    GND   VSS6 @S9S_MB_2U_LIB.S9S_MB_2U(SCH_1):GND
  21    GND   VSS7 @S9S_MB_2U_LIB.S9S_MB_2U(SCH_1):GND
  24    GND   VSS8 @S9S_MB_2U_LIB.S9S_MB_2U(SCH_1):GND
  26    GND   VSS9 @S9S_MB_2U_LIB.S9S_MB_2U(SCH_1):GND
  28    GND  VSS10 @S9S_MB_2U_LIB.S9S_MB_2U(SCH_1):GND
  30    GND  VSS11 @S9S_MB_2U_LIB.S9S_MB_2U(SCH_1):GND
  32    GND  VSS12 @S9S_MB_2U_LIB.S9S_MB_2U(SCH_1):GND
  35    GND  VSS13 @S9S_MB_2U_LIB.S9S_MB_2U(SCH_1):GND
  37    GND  VSS14 @S9S_MB_2U_LIB.S9S_MB_2U(SCH_1):GND
  39    GND  VSS15 @S9S_MB_2U_LIB.S9S_MB_2U(SCH_1):GND
  41    GND  VSS16 @S9S_MB_2U_LIB.S9S_MB_2U(SCH_1):GND
  43    GND  VSS17 @S9S_MB_2U_LIB.S9S_MB_2U(SCH_1):GND
  46    GND  VSS18 @S9S_MB_2U_LIB.S9S_MB_2U(SCH_1):GND
  48    GND  VSS19 @S9S_MB_2U_LIB.S9S_MB_2U(SCH_1):GND
  50    GND  VSS20 @S9S_MB_2U_LIB.S9S_MB_2U(SCH_1):GND
  52    GND  VSS21 @S9S_MB_2U_LIB.S9S_MB_2U(SCH_1):GND
  54    GND  VSS22 @S9S_MB_2U_LIB.S9S_MB_2U(SCH_1):GND
  57    GND  VSS23 @S9S_MB_2U_LIB.S9S_MB_2U(SCH_1):GND
  59    GND  VSS24 @S9S_MB_2U_LIB.S9S_MB_2U(SCH_1):GND
  61    GND  VSS25 @S9S_MB_2U_LIB.S9S_MB_2U(SCH_1):GND
  63    GND  VSS26 @S9S_MB_2U_LIB.S9S_MB_2U(SCH_1):GND
  65    GND  VSS27 @S9S_MB_2U_LIB.S9S_MB_2U(SCH_1):GND
  67    GND  VSS28 @S9S_MB_2U_LIB.S9S_MB_2U(SCH_1):GND
  69    GND  VSS29 @S9S_MB_2U_LIB.S9S_MB_2U(SCH_1):GND
  71    GND  VSS30 @S9S_MB_2U_LIB.S9S_MB_2U(SCH_1):GND
  73    GND  VSS31 @S9S_MB_2U_LIB.S9S_MB_2U(SCH_1):GND
  75    GND  VSS32 @S9S_MB_2U_LIB.S9S_MB_2U(SCH_1):GND
  77    GND  VSS33 @S9S_MB_2U_LIB.S9S_MB_2U(SCH_1):GND
  79    GND  VSS34 @S9S_MB_2U_LIB.S9S_MB_2U(SCH_1):GND
  81    GND  VSS35 @S9S_MB_2U_LIB.S9S_MB_2U(SCH_1):GND
  83    GND  VSS36 @S9S_MB_2U_LIB.S9S_MB_2U(SCH_1):GND
  85    GND  VSS37 @S9S_MB_2U_LIB.S9S_MB_2U(SCH_1):GND
  88    GND  VSS38 @S9S_MB_2U_LIB.S9S_MB_2U(SCH_1):GND
  90    GND  VSS39 @S9S_MB_2U_LIB.S9S_MB_2U(SCH_1):GND
  92    GND  VSS40 @S9S_MB_2U_LIB.S9S_MB_2U(SCH_1):GND
  95    GND  VSS41 @S9S_MB_2U_LIB.S9S_MB_2U(SCH_1):GND
  97    GND  VSS42 @S9S_MB_2U_LIB.S9S_MB_2U(SCH_1):GND
  99    GND  VSS43 @S9S_MB_2U_LIB.S9S_MB_2U(SCH_1):GND
 101    GND  VSS44 @S9S_MB_2U_LIB.S9S_MB_2U(SCH_1):GND
 103    GND  VSS45 @S9S_MB_2U_LIB.S9S_MB_2U(SCH_1):GND
 106    GND  VSS46 @S9S_MB_2U_LIB.S9S_MB_2U(SCH_1):GND
 108    GND  VSS47 @S9S_MB_2U_LIB.S9S_MB_2U(SCH_1):GND
 110    GND  VSS48 @S9S_MB_2U_LIB.S9S_MB_2U(SCH_1):GND
 112    GND  VSS49 @S9S_MB_2U_LIB.S9S_MB_2U(SCH_1):GND
 114    GND  VSS50 @S9S_MB_2U_LIB.S9S_MB_2U(SCH_1):GND
 117    GND  VSS51 @S9S_MB_2U_LIB.S9S_MB_2U(SCH_1):GND
 119    GND  VSS52 @S9S_MB_2U_LIB.S9S_MB_2U(SCH_1):GND
 121    GND  VSS53 @S9S_MB_2U_LIB.S9S_MB_2U(SCH_1):GND
 123    GND  VSS54 @S9S_MB_2U_LIB.S9S_MB_2U(SCH_1):GND
 125    GND  VSS55 @S9S_MB_2U_LIB.S9S_MB_2U(SCH_1):GND
 128    GND  VSS56 @S9S_MB_2U_LIB.S9S_MB_2U(SCH_1):GND
 130    GND  VSS57 @S9S_MB_2U_LIB.S9S_MB_2U(SCH_1):GND
 134    GND  VSS59 @S9S_MB_2U_LIB.S9S_MB_2U(SCH_1):GND
 143    GND  VSS63 @S9S_MB_2U_LIB.S9S_MB_2U(SCH_1):GND
 151    GND  VSS64 @S9S_MB_2U_LIB.S9S_MB_2U(SCH_1):GND
 153    GND  VSS65 @S9S_MB_2U_LIB.S9S_MB_2U(SCH_1):GND
 155    GND  VSS66 @S9S_MB_2U_LIB.S9S_MB_2U(SCH_1):GND
 158    GND  VSS67 @S9S_MB_2U_LIB.S9S_MB_2U(SCH_1):GND
 160    GND  VSS68 @S9S_MB_2U_LIB.S9S_MB_2U(SCH_1):GND
 162    GND  VSS69 @S9S_MB_2U_LIB.S9S_MB_2U(SCH_1):GND
 164    GND  VSS70 @S9S_MB_2U_LIB.S9S_MB_2U(SCH_1):GND
 166    GND  VSS71 @S9S_MB_2U_LIB.S9S_MB_2U(SCH_1):GND
 169    GND  VSS72 @S9S_MB_2U_LIB.S9S_MB_2U(SCH_1):GND
 171    GND  VSS73 @S9S_MB_2U_LIB.S9S_MB_2U(SCH_1):GND
 173    GND  VSS74 @S9S_MB_2U_LIB.S9S_MB_2U(SCH_1):GND
 175    GND  VSS75 @S9S_MB_2U_LIB.S9S_MB_2U(SCH_1):GND
 177    GND  VSS76 @S9S_MB_2U_LIB.S9S_MB_2U(SCH_1):GND
 180    GND  VSS77 @S9S_MB_2U_LIB.S9S_MB_2U(SCH_1):GND
 182    GND  VSS78 @S9S_MB_2U_LIB.S9S_MB_2U(SCH_1):GND
 184    GND  VSS79 @S9S_MB_2U_LIB.S9S_MB_2U(SCH_1):GND
 186    GND  VSS80 @S9S_MB_2U_LIB.S9S_MB_2U(SCH_1):GND
 188    GND  VSS81 @S9S_MB_2U_LIB.S9S_MB_2U(SCH_1):GND
 191    GND  VSS82 @S9S_MB_2U_LIB.S9S_MB_2U(SCH_1):GND
 193    GND  VSS83 @S9S_MB_2U_LIB.S9S_MB_2U(SCH_1):GND
 195    GND  VSS84 @S9S_MB_2U_LIB.S9S_MB_2U(SCH_1):GND
 197    GND  VSS85 @S9S_MB_2U_LIB.S9S_MB_2U(SCH_1):GND
 199    GND  VSS86 @S9S_MB_2U_LIB.S9S_MB_2U(SCH_1):GND
 202    GND  VSS87 @S9S_MB_2U_LIB.S9S_MB_2U(SCH_1):GND
 204    GND  VSS88 @S9S_MB_2U_LIB.S9S_MB_2U(SCH_1):GND
 206    GND  VSS89 @S9S_MB_2U_LIB.S9S_MB_2U(SCH_1):GND
 208    GND  VSS90 @S9S_MB_2U_LIB.S9S_MB_2U(SCH_1):GND
 210    GND  VSS91 @S9S_MB_2U_LIB.S9S_MB_2U(SCH_1):GND
 212    GND  VSS92 @S9S_MB_2U_LIB.S9S_MB_2U(SCH_1):GND
 214    GND  VSS93 @S9S_MB_2U_LIB.S9S_MB_2U(SCH_1):GND
 216    GND  VSS94 @S9S_MB_2U_LIB.S9S_MB_2U(SCH_1):GND
 219    GND  VSS95 @S9S_MB_2U_LIB.S9S_MB_2U(SCH_1):GND
 222    GND  VSS96 @S9S_MB_2U_LIB.S9S_MB_2U(SCH_1):GND
 224    GND  VSS97 @S9S_MB_2U_LIB.S9S_MB_2U(SCH_1):GND
 226    GND  VSS98 @S9S_MB_2U_LIB.S9S_MB_2U(SCH_1):GND
 228    GND  VSS99 @S9S_MB_2U_LIB.S9S_MB_2U(SCH_1):GND
 233    GND VSS101 @S9S_MB_2U_LIB.S9S_MB_2U(SCH_1):GND
 237    GND VSS103 @S9S_MB_2U_LIB.S9S_MB_2U(SCH_1):GND
 242    GND VSS105 @S9S_MB_2U_LIB.S9S_MB_2U(SCH_1):GND
 244    GND VSS106 @S9S_MB_2U_LIB.S9S_MB_2U(SCH_1):GND
 246    GND VSS107 @S9S_MB_2U_LIB.S9S_MB_2U(SCH_1):GND
 248    GND VSS108 @S9S_MB_2U_LIB.S9S_MB_2U(SCH_1):GND
 251    GND VSS109 @S9S_MB_2U_LIB.S9S_MB_2U(SCH_1):GND
 253    GND VSS110 @S9S_MB_2U_LIB.S9S_MB_2U(SCH_1):GND
 255    GND VSS111 @S9S_MB_2U_LIB.S9S_MB_2U(SCH_1):GND
 257    GND VSS112 @S9S_MB_2U_LIB.S9S_MB_2U(SCH_1):GND
 259    GND VSS113 @S9S_MB_2U_LIB.S9S_MB_2U(SCH_1):GND
 262    GND VSS114 @S9S_MB_2U_LIB.S9S_MB_2U(SCH_1):GND
 264    GND VSS115 @S9S_MB_2U_LIB.S9S_MB_2U(SCH_1):GND
 266    GND VSS116 @S9S_MB_2U_LIB.S9S_MB_2U(SCH_1):GND
 268    GND VSS117 @S9S_MB_2U_LIB.S9S_MB_2U(SCH_1):GND
 270    GND VSS118 @S9S_MB_2U_LIB.S9S_MB_2U(SCH_1):GND
 273    GND VSS119 @S9S_MB_2U_LIB.S9S_MB_2U(SCH_1):GND
 275    GND VSS120 @S9S_MB_2U_LIB.S9S_MB_2U(SCH_1):GND
 277    GND VSS121 @S9S_MB_2U_LIB.S9S_MB_2U(SCH_1):GND
 279    GND VSS122 @S9S_MB_2U_LIB.S9S_MB_2U(SCH_1):GND
 281    GND VSS123 @S9S_MB_2U_LIB.S9S_MB_2U(SCH_1):GND
 284    GND VSS124 @S9S_MB_2U_LIB.S9S_MB_2U(SCH_1):GND
 286    GND VSS125 @S9S_MB_2U_LIB.S9S_MB_2U(SCH_1):GND
 288    GND VSS126 @S9S_MB_2U_LIB.S9S_MB_2U(SCH_1):GND
   1 P12V_S3_AUX_CPU1_NVDIMM VIN_BULK0 @S9S_MB_2U_LIB.S9S_MB_2U(SCH_1):P12V_S3_AUX_CPU1_NVDIMM
 145 P12V_S3_AUX_CPU1_NVDIMM VIN_BULK1 @S9S_MB_2U_LIB.S9S_MB_2U(SCH_1):P12V_S3_AUX_CPU1_NVDIMM
 146 P12V_S3_AUX_CPU1_NVDIMM VIN_BULK2 @S9S_MB_2U_LIB.S9S_MB_2U(SCH_1):P12V_S3_AUX_CPU1_NVDIMM
 230    GND VSS100 @S9S_MB_2U_LIB.S9S_MB_2U(SCH_1):GND
 235    GND VSS102 @S9S_MB_2U_LIB.S9S_MB_2U(SCH_1):GND
 240    GND VSS104 @S9S_MB_2U_LIB.S9S_MB_2U(SCH_1):GND
 132    GND  VSS58 @S9S_MB_2U_LIB.S9S_MB_2U(SCH_1):GND
 136    GND  VSS60 @S9S_MB_2U_LIB.S9S_MB_2U(SCH_1):GND
 139    GND  VSS61 @S9S_MB_2U_LIB.S9S_MB_2U(SCH_1):GND
 141    GND  VSS62 @S9S_MB_2U_LIB.S9S_MB_2U(SCH_1):GND
  G1    GND     G1 @S9S_MB_2U_LIB.S9S_MB_2U(SCH_1):GND
  G2    GND     G2 @S9S_MB_2U_LIB.S9S_MB_2U(SCH_1):GND
  G3    GND     G3 @S9S_MB_2U_LIB.S9S_MB_2U(SCH_1):GND

SCONN288_ADR50017P130CC-SCONN2A  I178  J19
  93 M_B_CPU1_SB_DQS_DP<9> DQS9_B_T||TDQS9_B_T||DBI4_B_N @S9S_MB_2U_LIB.S9S_MB_2U(SCH_1):M_B_CPU1_SB_DQS_DP(9)
  94 M_B_CPU1_SB_DQS_DN<9> DQS9_B_C||TDQS9_B_C @S9S_MB_2U_LIB.S9S_MB_2U(SCH_1):M_B_CPU1_SB_DQS_DN(9)
 201 M_B_CPU1_SA_DQS_DP<9> DQS9_A_T||TDQS9_A_T @S9S_MB_2U_LIB.S9S_MB_2U(SCH_1):M_B_CPU1_SA_DQS_DP(9)
 200 M_B_CPU1_SA_DQS_DN<9> DQS9_A_C||TDQS9_A_C @S9S_MB_2U_LIB.S9S_MB_2U(SCH_1):M_B_CPU1_SA_DQS_DN(9)
 190 M_B_CPU1_SA_DQS_DP<8> DQS8_A_T||TDQS8_A_T @S9S_MB_2U_LIB.S9S_MB_2U(SCH_1):M_B_CPU1_SA_DQS_DP(8)
 189 M_B_CPU1_SA_DQS_DN<8> DQS8_A_C||TDQS8_A_C @S9S_MB_2U_LIB.S9S_MB_2U(SCH_1):M_B_CPU1_SA_DQS_DN(8)
 271 M_B_CPU1_SB_DQS_DN<7> DQS7_B_C||TDQS7_B_C @S9S_MB_2U_LIB.S9S_MB_2U(SCH_1):M_B_CPU1_SB_DQS_DN(7)
 179 M_B_CPU1_SA_DQS_DP<7> DQS7_A_T||TDQS7_A_T @S9S_MB_2U_LIB.S9S_MB_2U(SCH_1):M_B_CPU1_SA_DQS_DP(7)
 261 M_B_CPU1_SB_DQS_DP<6> DQS6_B_T||TDQS6_B_T @S9S_MB_2U_LIB.S9S_MB_2U(SCH_1):M_B_CPU1_SB_DQS_DP(6)
 260 M_B_CPU1_SB_DQS_DN<6> DQS6_B_C||TDQS6_B_C @S9S_MB_2U_LIB.S9S_MB_2U(SCH_1):M_B_CPU1_SB_DQS_DN(6)
 167 M_B_CPU1_SA_DQS_DN<6> DQS6_A_C||TDQS6_A_C||DQS6_A_T||TDQS6_A_T @S9S_MB_2U_LIB.S9S_MB_2U(SCH_1):M_B_CPU1_SA_DQS_DN(6)
 250 M_B_CPU1_SB_DQS_DP<5> DQS5_B_T||TDQS5_B_T @S9S_MB_2U_LIB.S9S_MB_2U(SCH_1):M_B_CPU1_SB_DQS_DP(5)
 249 M_B_CPU1_SB_DQS_DN<5> DQS5_B_C||TDQS5_B_C @S9S_MB_2U_LIB.S9S_MB_2U(SCH_1):M_B_CPU1_SB_DQS_DN(5)
 157 M_B_CPU1_SA_DQS_DP<5> DQS5_A_T||TDQS5_A_T @S9S_MB_2U_LIB.S9S_MB_2U(SCH_1):M_B_CPU1_SA_DQS_DP(5)
 156 M_B_CPU1_SA_DQS_DN<5> DQS5_A_C||TDQS5_A_C||DQS5_A_T||TDQS5_A_T @S9S_MB_2U_LIB.S9S_MB_2U(SCH_1):M_B_CPU1_SA_DQS_DN(5)
 239 M_B_CPU1_SB_DQS_DP<4> DQS4_B_T @S9S_MB_2U_LIB.S9S_MB_2U(SCH_1):M_B_CPU1_SB_DQS_DP(4)
 238 M_B_CPU1_SB_DQS_DN<4> DQS4_B_C @S9S_MB_2U_LIB.S9S_MB_2U(SCH_1):M_B_CPU1_SB_DQS_DN(4)
  55 M_B_CPU1_SA_DQS_DP<4> DQS4_A_T @S9S_MB_2U_LIB.S9S_MB_2U(SCH_1):M_B_CPU1_SA_DQS_DP(4)
  56 M_B_CPU1_SA_DQS_DN<4> DQS4_A_C @S9S_MB_2U_LIB.S9S_MB_2U(SCH_1):M_B_CPU1_SA_DQS_DN(4)
 137 M_B_CPU1_SB_DQS_DP<3> DQS3_B_T @S9S_MB_2U_LIB.S9S_MB_2U(SCH_1):M_B_CPU1_SB_DQS_DP(3)
 138 M_B_CPU1_SB_DQS_DN<3> DQS3_B_C @S9S_MB_2U_LIB.S9S_MB_2U(SCH_1):M_B_CPU1_SB_DQS_DN(3)
  44 M_B_CPU1_SA_DQS_DP<3> DQS3_A_T @S9S_MB_2U_LIB.S9S_MB_2U(SCH_1):M_B_CPU1_SA_DQS_DP(3)
  45 M_B_CPU1_SA_DQS_DN<3> DQS3_A_C @S9S_MB_2U_LIB.S9S_MB_2U(SCH_1):M_B_CPU1_SA_DQS_DN(3)
 126 M_B_CPU1_SB_DQS_DP<2> DQS2_B_T @S9S_MB_2U_LIB.S9S_MB_2U(SCH_1):M_B_CPU1_SB_DQS_DP(2)
 127 M_B_CPU1_SB_DQS_DN<2> DQS2_B_C @S9S_MB_2U_LIB.S9S_MB_2U(SCH_1):M_B_CPU1_SB_DQS_DN(2)
  33 M_B_CPU1_SA_DQS_DP<2> DQS2_A_T @S9S_MB_2U_LIB.S9S_MB_2U(SCH_1):M_B_CPU1_SA_DQS_DP(2)
  34 M_B_CPU1_SA_DQS_DN<2> DQS2_A_C @S9S_MB_2U_LIB.S9S_MB_2U(SCH_1):M_B_CPU1_SA_DQS_DN(2)
 115 M_B_CPU1_SB_DQS_DP<1> DQS1_B_T @S9S_MB_2U_LIB.S9S_MB_2U(SCH_1):M_B_CPU1_SB_DQS_DP(1)
 116 M_B_CPU1_SB_DQS_DN<1> DQS1_B_C @S9S_MB_2U_LIB.S9S_MB_2U(SCH_1):M_B_CPU1_SB_DQS_DN(1)
  22 M_B_CPU1_SA_DQS_DP<1> DQS1_A_T @S9S_MB_2U_LIB.S9S_MB_2U(SCH_1):M_B_CPU1_SA_DQS_DP(1)
  23 M_B_CPU1_SA_DQS_DN<1> DQS1_A_C @S9S_MB_2U_LIB.S9S_MB_2U(SCH_1):M_B_CPU1_SA_DQS_DN(1)
 104 M_B_CPU1_SB_DQS_DP<0> DQS0_B_T @S9S_MB_2U_LIB.S9S_MB_2U(SCH_1):M_B_CPU1_SB_DQS_DP(0)
 105 M_B_CPU1_SB_DQS_DN<0> DQS0_B_C @S9S_MB_2U_LIB.S9S_MB_2U(SCH_1):M_B_CPU1_SB_DQS_DN(0)
  11 M_B_CPU1_SA_DQS_DP<0> DQS0_A_T @S9S_MB_2U_LIB.S9S_MB_2U(SCH_1):M_B_CPU1_SA_DQS_DP(0)
  12 M_B_CPU1_SA_DQS_DN<0> DQS0_A_C @S9S_MB_2U_LIB.S9S_MB_2U(SCH_1):M_B_CPU1_SA_DQS_DN(0)
 272 M_B_CPU1_SB_DQS_DP<7> DQS7_B_T||TDQS7_B_T @S9S_MB_2U_LIB.S9S_MB_2U(SCH_1):M_B_CPU1_SB_DQS_DP(7)
 282 M_B_CPU1_SB_DQS_DN<8> DQS8_B_C||TDQS8_B_C @S9S_MB_2U_LIB.S9S_MB_2U(SCH_1):M_B_CPU1_SB_DQS_DN(8)
 283 M_B_CPU1_SB_DQS_DP<8> DQS8_B_T||TDQS8_B_T @S9S_MB_2U_LIB.S9S_MB_2U(SCH_1):M_B_CPU1_SB_DQS_DP(8)
 168 M_B_CPU1_SA_DQS_DP<6> DQS6_A_T||TDQS6_A_T @S9S_MB_2U_LIB.S9S_MB_2U(SCH_1):M_B_CPU1_SA_DQS_DP(6)
 178 M_B_CPU1_SA_DQS_DN<7> DQS7_A_C||TDQS7_A_C @S9S_MB_2U_LIB.S9S_MB_2U(SCH_1):M_B_CPU1_SA_DQS_DN(7)

Q_RES_0402LF-49.9,1%,1/16W,CHIA  I180  R3893
   1 I3C_SPD_DDRABCD_CPU1_LVC1_SCL_2      A @S9S_MB_2U_LIB.S9S_MB_2U(SCH_1):I3C_SPD_DDRABCD_CPU1_LVC1_SCL_R3
   2 I3C_SPD_DDRABCD_CPU1_LVC1_SCL      B @S9S_MB_2U_LIB.S9S_MB_2U(SCH_1):I3C_SPD_DDRABCD_CPU1_LVC1_SCL


DRAWING: @S9S_MB_2U_LIB.S9S_MB_2U(SCH_1):PAGE101 

Q_RES_0402LF-35.7K,1%,1/16W,CHA  I46  R45
   1 PD_CHB_CPU1_DIMM2_SAA      A @S9S_MB_2U_LIB.S9S_MB_2U(SCH_1):PD_CHB_CPU1_DIMM2_SAA
   2    GND      B @S9S_MB_2U_LIB.S9S_MB_2U(SCH_1):GND

SCONN288_ADR50017P087CC-SCONN2A  I47  J20
   3 P3V3_AUX VIN_MGMT @S9S_MB_2U_LIB.S9S_MB_2U(SCH_1):P3V3_AUX
   2 TP_CHB_CPU1_DIMM2_FRU_0   RFU0 @S9S_MB_2U_LIB.S9S_MB_2U(SCH_1):TP_CHB_CPU1_DIMM2_FRU_0
 144 TP_CHB_CPU1_DIMM2_FRU_1   RFU1 @S9S_MB_2U_LIB.S9S_MB_2U(SCH_1):TP_CHB_CPU1_DIMM2_FRU_1
 149 TP_CHB_CPU1_DIMM2_FRU_2   RFU2 @S9S_MB_2U_LIB.S9S_MB_2U(SCH_1):TP_CHB_CPU1_DIMM2_FRU_2
 150 TP_CHB_CPU1_DIMM2_FRU_3   RFU3 @S9S_MB_2U_LIB.S9S_MB_2U(SCH_1):TP_CHB_CPU1_DIMM2_FRU_3
 220 TP_CHB_CPU1_DIMM2_FRU_4   RFU4 @S9S_MB_2U_LIB.S9S_MB_2U(SCH_1):TP_CHB_CPU1_DIMM2_FRU_4
 231 TP_CHB_CPU1_DIMM2_FRU_5   RFU5 @S9S_MB_2U_LIB.S9S_MB_2U(SCH_1):TP_CHB_CPU1_DIMM2_FRU_5
 232 TP_CHB_CPU1_DIMM2_FRU_6   RFU6 @S9S_MB_2U_LIB.S9S_MB_2U(SCH_1):TP_CHB_CPU1_DIMM2_FRU_6
 207 RST_M_AB_CPU1_FPGA_N RESET_N @S9S_MB_2U_LIB.S9S_MB_2U(SCH_1):RST_M_AB_CPU1_FPGA_N
 147 PWRGD_CHB_CPU1_DIMM2 PWR_GOOD||FAIL_N @S9S_MB_2U_LIB.S9S_MB_2U(SCH_1):PWRGD_CHB_CPU1_DIMM2
 227 M_B_CPU1_SB_PAR  PAR_B @S9S_MB_2U_LIB.S9S_MB_2U(SCH_1):M_B_CPU1_SB_PAR
  74 M_B_CPU1_SA_PAR  PAR_A @S9S_MB_2U_LIB.S9S_MB_2U(SCH_1):M_B_CPU1_SA_PAR
  87 M_B_CPU1_SB_RSP<1> LBS||RSP_B_N @S9S_MB_2U_LIB.S9S_MB_2U(SCH_1):M_B_CPU1_SB_RSP(1)
  86 M_B_CPU1_SA_RSP<1> LBD||RSP_A_N @S9S_MB_2U_LIB.S9S_MB_2U(SCH_1):M_B_CPU1_SA_RSP(1)
   5 I3C_SPD_DDRABCD_CPU1_LVC1_SDA   HSDA @S9S_MB_2U_LIB.S9S_MB_2U(SCH_1):I3C_SPD_DDRABCD_CPU1_LVC1_SDA
   4 I3C_SPD_DDRABCD_CPU1_LVC1_SCL_3   HSCL @S9S_MB_2U_LIB.S9S_MB_2U(SCH_1):I3C_SPD_DDRABCD_CPU1_LVC1_SCL_R4
 148 PD_CHB_CPU1_DIMM2_SAA    HSA @S9S_MB_2U_LIB.S9S_MB_2U(SCH_1):PD_CHB_CPU1_DIMM2_SAA
 100 M_B_CPU1_SB_DQ<0>  DQ0_B @S9S_MB_2U_LIB.S9S_MB_2U(SCH_1):M_B_CPU1_SB_DQ(0)
 102 M_B_CPU1_SB_DQ<1>  DQ1_B @S9S_MB_2U_LIB.S9S_MB_2U(SCH_1):M_B_CPU1_SB_DQ(1)
 245 M_B_CPU1_SB_DQ<2>  DQ2_B @S9S_MB_2U_LIB.S9S_MB_2U(SCH_1):M_B_CPU1_SB_DQ(2)
 247 M_B_CPU1_SB_DQ<3>  DQ3_B @S9S_MB_2U_LIB.S9S_MB_2U(SCH_1):M_B_CPU1_SB_DQ(3)
 107 M_B_CPU1_SB_DQ<4>  DQ4_B @S9S_MB_2U_LIB.S9S_MB_2U(SCH_1):M_B_CPU1_SB_DQ(4)
 109 M_B_CPU1_SB_DQ<5>  DQ5_B @S9S_MB_2U_LIB.S9S_MB_2U(SCH_1):M_B_CPU1_SB_DQ(5)
 252 M_B_CPU1_SB_DQ<6>  DQ6_B @S9S_MB_2U_LIB.S9S_MB_2U(SCH_1):M_B_CPU1_SB_DQ(6)
 254 M_B_CPU1_SB_DQ<7>  DQ7_B @S9S_MB_2U_LIB.S9S_MB_2U(SCH_1):M_B_CPU1_SB_DQ(7)
 111 M_B_CPU1_SB_DQ<8>  DQ8_B @S9S_MB_2U_LIB.S9S_MB_2U(SCH_1):M_B_CPU1_SB_DQ(8)
 113 M_B_CPU1_SB_DQ<9>  DQ9_B @S9S_MB_2U_LIB.S9S_MB_2U(SCH_1):M_B_CPU1_SB_DQ(9)
 256 M_B_CPU1_SB_DQ<10> DQ10_B @S9S_MB_2U_LIB.S9S_MB_2U(SCH_1):M_B_CPU1_SB_DQ(10)
 258 M_B_CPU1_SB_DQ<11> DQ11_B @S9S_MB_2U_LIB.S9S_MB_2U(SCH_1):M_B_CPU1_SB_DQ(11)
 118 M_B_CPU1_SB_DQ<12> DQ12_B @S9S_MB_2U_LIB.S9S_MB_2U(SCH_1):M_B_CPU1_SB_DQ(12)
 120 M_B_CPU1_SB_DQ<13> DQ13_B @S9S_MB_2U_LIB.S9S_MB_2U(SCH_1):M_B_CPU1_SB_DQ(13)
 263 M_B_CPU1_SB_DQ<14> DQ14_B @S9S_MB_2U_LIB.S9S_MB_2U(SCH_1):M_B_CPU1_SB_DQ(14)
 265 M_B_CPU1_SB_DQ<15> DQ15_B @S9S_MB_2U_LIB.S9S_MB_2U(SCH_1):M_B_CPU1_SB_DQ(15)
 122 M_B_CPU1_SB_DQ<16> DQ16_B @S9S_MB_2U_LIB.S9S_MB_2U(SCH_1):M_B_CPU1_SB_DQ(16)
 124 M_B_CPU1_SB_DQ<17> DQ17_B @S9S_MB_2U_LIB.S9S_MB_2U(SCH_1):M_B_CPU1_SB_DQ(17)
 267 M_B_CPU1_SB_DQ<18> DQ18_B @S9S_MB_2U_LIB.S9S_MB_2U(SCH_1):M_B_CPU1_SB_DQ(18)
 269 M_B_CPU1_SB_DQ<19> DQ19_B @S9S_MB_2U_LIB.S9S_MB_2U(SCH_1):M_B_CPU1_SB_DQ(19)
 129 M_B_CPU1_SB_DQ<20> DQ20_B @S9S_MB_2U_LIB.S9S_MB_2U(SCH_1):M_B_CPU1_SB_DQ(20)
 131 M_B_CPU1_SB_DQ<21> DQ21_B @S9S_MB_2U_LIB.S9S_MB_2U(SCH_1):M_B_CPU1_SB_DQ(21)
 274 M_B_CPU1_SB_DQ<22> DQ22_B @S9S_MB_2U_LIB.S9S_MB_2U(SCH_1):M_B_CPU1_SB_DQ(22)
 276 M_B_CPU1_SB_DQ<23> DQ23_B @S9S_MB_2U_LIB.S9S_MB_2U(SCH_1):M_B_CPU1_SB_DQ(23)
 133 M_B_CPU1_SB_DQ<24> DQ24_B @S9S_MB_2U_LIB.S9S_MB_2U(SCH_1):M_B_CPU1_SB_DQ(24)
 135 M_B_CPU1_SB_DQ<25> DQ25_B @S9S_MB_2U_LIB.S9S_MB_2U(SCH_1):M_B_CPU1_SB_DQ(25)
 278 M_B_CPU1_SB_DQ<26> DQ26_B @S9S_MB_2U_LIB.S9S_MB_2U(SCH_1):M_B_CPU1_SB_DQ(26)
 280 M_B_CPU1_SB_DQ<27> DQ27_B @S9S_MB_2U_LIB.S9S_MB_2U(SCH_1):M_B_CPU1_SB_DQ(27)
 140 M_B_CPU1_SB_DQ<28> DQ28_B @S9S_MB_2U_LIB.S9S_MB_2U(SCH_1):M_B_CPU1_SB_DQ(28)
 142 M_B_CPU1_SB_DQ<29> DQ29_B @S9S_MB_2U_LIB.S9S_MB_2U(SCH_1):M_B_CPU1_SB_DQ(29)
 285 M_B_CPU1_SB_DQ<30> DQ30_B @S9S_MB_2U_LIB.S9S_MB_2U(SCH_1):M_B_CPU1_SB_DQ(30)
 287 M_B_CPU1_SB_DQ<31> DQ31_B @S9S_MB_2U_LIB.S9S_MB_2U(SCH_1):M_B_CPU1_SB_DQ(31)
   7 M_B_CPU1_SA_DQ<0>  DQ0_A @S9S_MB_2U_LIB.S9S_MB_2U(SCH_1):M_B_CPU1_SA_DQ(0)
   9 M_B_CPU1_SA_DQ<1>  DQ1_A @S9S_MB_2U_LIB.S9S_MB_2U(SCH_1):M_B_CPU1_SA_DQ(1)
 152 M_B_CPU1_SA_DQ<2>  DQ2_A @S9S_MB_2U_LIB.S9S_MB_2U(SCH_1):M_B_CPU1_SA_DQ(2)
 154 M_B_CPU1_SA_DQ<3>  DQ3_A @S9S_MB_2U_LIB.S9S_MB_2U(SCH_1):M_B_CPU1_SA_DQ(3)
  14 M_B_CPU1_SA_DQ<4>  DQ4_A @S9S_MB_2U_LIB.S9S_MB_2U(SCH_1):M_B_CPU1_SA_DQ(4)
  16 M_B_CPU1_SA_DQ<5>  DQ5_A @S9S_MB_2U_LIB.S9S_MB_2U(SCH_1):M_B_CPU1_SA_DQ(5)
 159 M_B_CPU1_SA_DQ<6>  DQ6_A @S9S_MB_2U_LIB.S9S_MB_2U(SCH_1):M_B_CPU1_SA_DQ(6)
 161 M_B_CPU1_SA_DQ<7>  DQ7_A @S9S_MB_2U_LIB.S9S_MB_2U(SCH_1):M_B_CPU1_SA_DQ(7)
  18 M_B_CPU1_SA_DQ<8>  DQ8_A @S9S_MB_2U_LIB.S9S_MB_2U(SCH_1):M_B_CPU1_SA_DQ(8)
  20 M_B_CPU1_SA_DQ<9>  DQ9_A @S9S_MB_2U_LIB.S9S_MB_2U(SCH_1):M_B_CPU1_SA_DQ(9)
 163 M_B_CPU1_SA_DQ<10> DQ10_A @S9S_MB_2U_LIB.S9S_MB_2U(SCH_1):M_B_CPU1_SA_DQ(10)
 165 M_B_CPU1_SA_DQ<11> DQ11_A @S9S_MB_2U_LIB.S9S_MB_2U(SCH_1):M_B_CPU1_SA_DQ(11)
  25 M_B_CPU1_SA_DQ<12> DQ12_A @S9S_MB_2U_LIB.S9S_MB_2U(SCH_1):M_B_CPU1_SA_DQ(12)
  27 M_B_CPU1_SA_DQ<13> DQ13_A @S9S_MB_2U_LIB.S9S_MB_2U(SCH_1):M_B_CPU1_SA_DQ(13)
 170 M_B_CPU1_SA_DQ<14> DQ14_A @S9S_MB_2U_LIB.S9S_MB_2U(SCH_1):M_B_CPU1_SA_DQ(14)
 172 M_B_CPU1_SA_DQ<15> DQ15_A @S9S_MB_2U_LIB.S9S_MB_2U(SCH_1):M_B_CPU1_SA_DQ(15)
  29 M_B_CPU1_SA_DQ<16> DQ16_A @S9S_MB_2U_LIB.S9S_MB_2U(SCH_1):M_B_CPU1_SA_DQ(16)
  31 M_B_CPU1_SA_DQ<17> DQ17_A @S9S_MB_2U_LIB.S9S_MB_2U(SCH_1):M_B_CPU1_SA_DQ(17)
 174 M_B_CPU1_SA_DQ<18> DQ18_A @S9S_MB_2U_LIB.S9S_MB_2U(SCH_1):M_B_CPU1_SA_DQ(18)
 176 M_B_CPU1_SA_DQ<19> DQ19_A @S9S_MB_2U_LIB.S9S_MB_2U(SCH_1):M_B_CPU1_SA_DQ(19)
  36 M_B_CPU1_SA_DQ<20> DQ20_A @S9S_MB_2U_LIB.S9S_MB_2U(SCH_1):M_B_CPU1_SA_DQ(20)
  38 M_B_CPU1_SA_DQ<21> DQ21_A @S9S_MB_2U_LIB.S9S_MB_2U(SCH_1):M_B_CPU1_SA_DQ(21)
 181 M_B_CPU1_SA_DQ<22> DQ22_A @S9S_MB_2U_LIB.S9S_MB_2U(SCH_1):M_B_CPU1_SA_DQ(22)
 183 M_B_CPU1_SA_DQ<23> DQ23_A @S9S_MB_2U_LIB.S9S_MB_2U(SCH_1):M_B_CPU1_SA_DQ(23)
  40 M_B_CPU1_SA_DQ<24> DQ24_A @S9S_MB_2U_LIB.S9S_MB_2U(SCH_1):M_B_CPU1_SA_DQ(24)
  42 M_B_CPU1_SA_DQ<25> DQ25_A @S9S_MB_2U_LIB.S9S_MB_2U(SCH_1):M_B_CPU1_SA_DQ(25)
 185 M_B_CPU1_SA_DQ<26> DQ26_A @S9S_MB_2U_LIB.S9S_MB_2U(SCH_1):M_B_CPU1_SA_DQ(26)
 187 M_B_CPU1_SA_DQ<27> DQ27_A @S9S_MB_2U_LIB.S9S_MB_2U(SCH_1):M_B_CPU1_SA_DQ(27)
  47 M_B_CPU1_SA_DQ<28> DQ28_A @S9S_MB_2U_LIB.S9S_MB_2U(SCH_1):M_B_CPU1_SA_DQ(28)
  49 M_B_CPU1_SA_DQ<29> DQ29_A @S9S_MB_2U_LIB.S9S_MB_2U(SCH_1):M_B_CPU1_SA_DQ(29)
 192 M_B_CPU1_SA_DQ<30> DQ30_A @S9S_MB_2U_LIB.S9S_MB_2U(SCH_1):M_B_CPU1_SA_DQ(30)
 229 M_B_CPU1_SB_CS_N<3> CS1_B_N @S9S_MB_2U_LIB.S9S_MB_2U(SCH_1):M_B_CPU1_SB_CS_N(3)
 209 M_B_CPU1_SA_CS_N<3> CS1_A_N @S9S_MB_2U_LIB.S9S_MB_2U(SCH_1):M_B_CPU1_SA_CS_N(3)
  84 M_B_CPU1_SB_CS_N<2> CS0_B_N @S9S_MB_2U_LIB.S9S_MB_2U(SCH_1):M_B_CPU1_SB_CS_N(2)
  64 M_B_CPU1_SA_CS_N<2> CS0_A_N @S9S_MB_2U_LIB.S9S_MB_2U(SCH_1):M_B_CPU1_SA_CS_N(2)
 217 M_B_CPU1_CLK_DP<1>   CK_T @S9S_MB_2U_LIB.S9S_MB_2U(SCH_1):M_B_CPU1_CLK_DP(1)
 218 M_B_CPU1_CLK_DN<1>   CK_C @S9S_MB_2U_LIB.S9S_MB_2U(SCH_1):M_B_CPU1_CLK_DN(1)
  96 M_B_CPU1_SB_CB<0>  CB0_B @S9S_MB_2U_LIB.S9S_MB_2U(SCH_1):M_B_CPU1_SB_CB(0)
  98 M_B_CPU1_SB_CB<1>  CB1_B @S9S_MB_2U_LIB.S9S_MB_2U(SCH_1):M_B_CPU1_SB_CB(1)
 241 M_B_CPU1_SB_CB<2>  CB2_B @S9S_MB_2U_LIB.S9S_MB_2U(SCH_1):M_B_CPU1_SB_CB(2)
 243 M_B_CPU1_SB_CB<3>  CB3_B @S9S_MB_2U_LIB.S9S_MB_2U(SCH_1):M_B_CPU1_SB_CB(3)
  89 M_B_CPU1_SB_CB<4>  CB4_B @S9S_MB_2U_LIB.S9S_MB_2U(SCH_1):M_B_CPU1_SB_CB(4)
  91 M_B_CPU1_SB_CB<5>  CB5_B @S9S_MB_2U_LIB.S9S_MB_2U(SCH_1):M_B_CPU1_SB_CB(5)
 234 M_B_CPU1_SB_CB<6>  CB6_B @S9S_MB_2U_LIB.S9S_MB_2U(SCH_1):M_B_CPU1_SB_CB(6)
  51 M_B_CPU1_SA_CB<0>  CB0_A @S9S_MB_2U_LIB.S9S_MB_2U(SCH_1):M_B_CPU1_SA_CB(0)
 196 M_B_CPU1_SA_CB<2>  CB2_A @S9S_MB_2U_LIB.S9S_MB_2U(SCH_1):M_B_CPU1_SA_CB(2)
 198 M_B_CPU1_SA_CB<3>  CB3_A @S9S_MB_2U_LIB.S9S_MB_2U(SCH_1):M_B_CPU1_SA_CB(3)
  60 M_B_CPU1_SA_CB<5>  CB5_A @S9S_MB_2U_LIB.S9S_MB_2U(SCH_1):M_B_CPU1_SA_CB(5)
 203 M_B_CPU1_SA_CB<6>  CB6_A @S9S_MB_2U_LIB.S9S_MB_2U(SCH_1):M_B_CPU1_SA_CB(6)
  82 M_B_CPU1_SB_CA<6>  CA6_B @S9S_MB_2U_LIB.S9S_MB_2U(SCH_1):M_B_CPU1_SB_CA(6)
  72 M_B_CPU1_SA_CA<6>  CA6_A @S9S_MB_2U_LIB.S9S_MB_2U(SCH_1):M_B_CPU1_SA_CA(6)
 225 M_B_CPU1_SB_CA<5>  CA5_B @S9S_MB_2U_LIB.S9S_MB_2U(SCH_1):M_B_CPU1_SB_CA(5)
 215 M_B_CPU1_SA_CA<5>  CA5_A @S9S_MB_2U_LIB.S9S_MB_2U(SCH_1):M_B_CPU1_SA_CA(5)
  80 M_B_CPU1_SB_CA<4>  CA4_B @S9S_MB_2U_LIB.S9S_MB_2U(SCH_1):M_B_CPU1_SB_CA(4)
  70 M_B_CPU1_SA_CA<4>  CA4_A @S9S_MB_2U_LIB.S9S_MB_2U(SCH_1):M_B_CPU1_SA_CA(4)
 223 M_B_CPU1_SB_CA<3>  CA3_B @S9S_MB_2U_LIB.S9S_MB_2U(SCH_1):M_B_CPU1_SB_CA(3)
 213 M_B_CPU1_SA_CA<3>  CA3_A @S9S_MB_2U_LIB.S9S_MB_2U(SCH_1):M_B_CPU1_SA_CA(3)
  78 M_B_CPU1_SB_CA<2>  CA2_B @S9S_MB_2U_LIB.S9S_MB_2U(SCH_1):M_B_CPU1_SB_CA(2)
  68 M_B_CPU1_SA_CA<2>  CA2_A @S9S_MB_2U_LIB.S9S_MB_2U(SCH_1):M_B_CPU1_SA_CA(2)
 221 M_B_CPU1_SB_CA<1>  CA1_B @S9S_MB_2U_LIB.S9S_MB_2U(SCH_1):M_B_CPU1_SB_CA(1)
 211 M_B_CPU1_SA_CA<1>  CA1_A @S9S_MB_2U_LIB.S9S_MB_2U(SCH_1):M_B_CPU1_SA_CA(1)
  76 M_B_CPU1_SB_CA<0>  CA0_B @S9S_MB_2U_LIB.S9S_MB_2U(SCH_1):M_B_CPU1_SB_CA(0)
  66 M_B_CPU1_SA_CA<0>  CA0_A @S9S_MB_2U_LIB.S9S_MB_2U(SCH_1):M_B_CPU1_SA_CA(0)
  62 M_B_CPU1_ALERT_N ALERT_N @S9S_MB_2U_LIB.S9S_MB_2U(SCH_1):M_B_CPU1_ALERT_N
 236 M_B_CPU1_SB_CB<7>  CB7_B @S9S_MB_2U_LIB.S9S_MB_2U(SCH_1):M_B_CPU1_SB_CB(7)
  53 M_B_CPU1_SA_CB<1>  CB1_A @S9S_MB_2U_LIB.S9S_MB_2U(SCH_1):M_B_CPU1_SA_CB(1)
  58 M_B_CPU1_SA_CB<4>  CB4_A @S9S_MB_2U_LIB.S9S_MB_2U(SCH_1):M_B_CPU1_SA_CB(4)
 205 M_B_CPU1_SA_CB<7>  CB7_A @S9S_MB_2U_LIB.S9S_MB_2U(SCH_1):M_B_CPU1_SA_CB(7)
 194 M_B_CPU1_SA_DQ<31> DQ31_A @S9S_MB_2U_LIB.S9S_MB_2U(SCH_1):M_B_CPU1_SA_DQ(31)

Q_CAP_C0402-2.2UF,6.3V,20%,X6SA  I121  C59
   1 P3V3_AUX      A @S9S_MB_2U_LIB.S9S_MB_2U(SCH_1):P3V3_AUX
   2    GND      B @S9S_MB_2U_LIB.S9S_MB_2U(SCH_1):GND

Q_CAP_C0805-10UF,16V,10%,X6S,CA  I125  C60
   1 P12V_S3_AUX_CPU1_NVDIMM      A @S9S_MB_2U_LIB.S9S_MB_2U(SCH_1):P12V_S3_AUX_CPU1_NVDIMM
   2    GND      B @S9S_MB_2U_LIB.S9S_MB_2U(SCH_1):GND

Q_CAP_C0805-10UF,16V,10%,X6S,CA  I127  C61
   1 P12V_S3_AUX_CPU1_NVDIMM      A @S9S_MB_2U_LIB.S9S_MB_2U(SCH_1):P12V_S3_AUX_CPU1_NVDIMM
   2    GND      B @S9S_MB_2U_LIB.S9S_MB_2U(SCH_1):GND

SCONN288_ADR50017P087CC-SCONN2A  I176  J20
   6    GND   VSS0 @S9S_MB_2U_LIB.S9S_MB_2U(SCH_1):GND
   8    GND   VSS1 @S9S_MB_2U_LIB.S9S_MB_2U(SCH_1):GND
  10    GND   VSS2 @S9S_MB_2U_LIB.S9S_MB_2U(SCH_1):GND
  13    GND   VSS3 @S9S_MB_2U_LIB.S9S_MB_2U(SCH_1):GND
  15    GND   VSS4 @S9S_MB_2U_LIB.S9S_MB_2U(SCH_1):GND
  17    GND   VSS5 @S9S_MB_2U_LIB.S9S_MB_2U(SCH_1):GND
  19    GND   VSS6 @S9S_MB_2U_LIB.S9S_MB_2U(SCH_1):GND
  21    GND   VSS7 @S9S_MB_2U_LIB.S9S_MB_2U(SCH_1):GND
  24    GND   VSS8 @S9S_MB_2U_LIB.S9S_MB_2U(SCH_1):GND
  26    GND   VSS9 @S9S_MB_2U_LIB.S9S_MB_2U(SCH_1):GND
  28    GND  VSS10 @S9S_MB_2U_LIB.S9S_MB_2U(SCH_1):GND
  30    GND  VSS11 @S9S_MB_2U_LIB.S9S_MB_2U(SCH_1):GND
  32    GND  VSS12 @S9S_MB_2U_LIB.S9S_MB_2U(SCH_1):GND
  35    GND  VSS13 @S9S_MB_2U_LIB.S9S_MB_2U(SCH_1):GND
  37    GND  VSS14 @S9S_MB_2U_LIB.S9S_MB_2U(SCH_1):GND
  39    GND  VSS15 @S9S_MB_2U_LIB.S9S_MB_2U(SCH_1):GND
  41    GND  VSS16 @S9S_MB_2U_LIB.S9S_MB_2U(SCH_1):GND
  43    GND  VSS17 @S9S_MB_2U_LIB.S9S_MB_2U(SCH_1):GND
  46    GND  VSS18 @S9S_MB_2U_LIB.S9S_MB_2U(SCH_1):GND
  48    GND  VSS19 @S9S_MB_2U_LIB.S9S_MB_2U(SCH_1):GND
  50    GND  VSS20 @S9S_MB_2U_LIB.S9S_MB_2U(SCH_1):GND
  52    GND  VSS21 @S9S_MB_2U_LIB.S9S_MB_2U(SCH_1):GND
  54    GND  VSS22 @S9S_MB_2U_LIB.S9S_MB_2U(SCH_1):GND
  57    GND  VSS23 @S9S_MB_2U_LIB.S9S_MB_2U(SCH_1):GND
  59    GND  VSS24 @S9S_MB_2U_LIB.S9S_MB_2U(SCH_1):GND
  61    GND  VSS25 @S9S_MB_2U_LIB.S9S_MB_2U(SCH_1):GND
  63    GND  VSS26 @S9S_MB_2U_LIB.S9S_MB_2U(SCH_1):GND
  65    GND  VSS27 @S9S_MB_2U_LIB.S9S_MB_2U(SCH_1):GND
  67    GND  VSS28 @S9S_MB_2U_LIB.S9S_MB_2U(SCH_1):GND
  69    GND  VSS29 @S9S_MB_2U_LIB.S9S_MB_2U(SCH_1):GND
  71    GND  VSS30 @S9S_MB_2U_LIB.S9S_MB_2U(SCH_1):GND
  73    GND  VSS31 @S9S_MB_2U_LIB.S9S_MB_2U(SCH_1):GND
  75    GND  VSS32 @S9S_MB_2U_LIB.S9S_MB_2U(SCH_1):GND
  77    GND  VSS33 @S9S_MB_2U_LIB.S9S_MB_2U(SCH_1):GND
  79    GND  VSS34 @S9S_MB_2U_LIB.S9S_MB_2U(SCH_1):GND
  81    GND  VSS35 @S9S_MB_2U_LIB.S9S_MB_2U(SCH_1):GND
  83    GND  VSS36 @S9S_MB_2U_LIB.S9S_MB_2U(SCH_1):GND
  85    GND  VSS37 @S9S_MB_2U_LIB.S9S_MB_2U(SCH_1):GND
  88    GND  VSS38 @S9S_MB_2U_LIB.S9S_MB_2U(SCH_1):GND
  90    GND  VSS39 @S9S_MB_2U_LIB.S9S_MB_2U(SCH_1):GND
  92    GND  VSS40 @S9S_MB_2U_LIB.S9S_MB_2U(SCH_1):GND
  95    GND  VSS41 @S9S_MB_2U_LIB.S9S_MB_2U(SCH_1):GND
  97    GND  VSS42 @S9S_MB_2U_LIB.S9S_MB_2U(SCH_1):GND
  99    GND  VSS43 @S9S_MB_2U_LIB.S9S_MB_2U(SCH_1):GND
 101    GND  VSS44 @S9S_MB_2U_LIB.S9S_MB_2U(SCH_1):GND
 103    GND  VSS45 @S9S_MB_2U_LIB.S9S_MB_2U(SCH_1):GND
 106    GND  VSS46 @S9S_MB_2U_LIB.S9S_MB_2U(SCH_1):GND
 108    GND  VSS47 @S9S_MB_2U_LIB.S9S_MB_2U(SCH_1):GND
 110    GND  VSS48 @S9S_MB_2U_LIB.S9S_MB_2U(SCH_1):GND
 112    GND  VSS49 @S9S_MB_2U_LIB.S9S_MB_2U(SCH_1):GND
 114    GND  VSS50 @S9S_MB_2U_LIB.S9S_MB_2U(SCH_1):GND
 117    GND  VSS51 @S9S_MB_2U_LIB.S9S_MB_2U(SCH_1):GND
 119    GND  VSS52 @S9S_MB_2U_LIB.S9S_MB_2U(SCH_1):GND
 121    GND  VSS53 @S9S_MB_2U_LIB.S9S_MB_2U(SCH_1):GND
 123    GND  VSS54 @S9S_MB_2U_LIB.S9S_MB_2U(SCH_1):GND
 125    GND  VSS55 @S9S_MB_2U_LIB.S9S_MB_2U(SCH_1):GND
 128    GND  VSS56 @S9S_MB_2U_LIB.S9S_MB_2U(SCH_1):GND
 130    GND  VSS57 @S9S_MB_2U_LIB.S9S_MB_2U(SCH_1):GND
 134    GND  VSS59 @S9S_MB_2U_LIB.S9S_MB_2U(SCH_1):GND
 143    GND  VSS63 @S9S_MB_2U_LIB.S9S_MB_2U(SCH_1):GND
 151    GND  VSS64 @S9S_MB_2U_LIB.S9S_MB_2U(SCH_1):GND
 153    GND  VSS65 @S9S_MB_2U_LIB.S9S_MB_2U(SCH_1):GND
 155    GND  VSS66 @S9S_MB_2U_LIB.S9S_MB_2U(SCH_1):GND
 158    GND  VSS67 @S9S_MB_2U_LIB.S9S_MB_2U(SCH_1):GND
 160    GND  VSS68 @S9S_MB_2U_LIB.S9S_MB_2U(SCH_1):GND
 162    GND  VSS69 @S9S_MB_2U_LIB.S9S_MB_2U(SCH_1):GND
 164    GND  VSS70 @S9S_MB_2U_LIB.S9S_MB_2U(SCH_1):GND
 166    GND  VSS71 @S9S_MB_2U_LIB.S9S_MB_2U(SCH_1):GND
 169    GND  VSS72 @S9S_MB_2U_LIB.S9S_MB_2U(SCH_1):GND
 171    GND  VSS73 @S9S_MB_2U_LIB.S9S_MB_2U(SCH_1):GND
 173    GND  VSS74 @S9S_MB_2U_LIB.S9S_MB_2U(SCH_1):GND
 175    GND  VSS75 @S9S_MB_2U_LIB.S9S_MB_2U(SCH_1):GND
 177    GND  VSS76 @S9S_MB_2U_LIB.S9S_MB_2U(SCH_1):GND
 180    GND  VSS77 @S9S_MB_2U_LIB.S9S_MB_2U(SCH_1):GND
 182    GND  VSS78 @S9S_MB_2U_LIB.S9S_MB_2U(SCH_1):GND
 184    GND  VSS79 @S9S_MB_2U_LIB.S9S_MB_2U(SCH_1):GND
 186    GND  VSS80 @S9S_MB_2U_LIB.S9S_MB_2U(SCH_1):GND
 188    GND  VSS81 @S9S_MB_2U_LIB.S9S_MB_2U(SCH_1):GND
 191    GND  VSS82 @S9S_MB_2U_LIB.S9S_MB_2U(SCH_1):GND
 193    GND  VSS83 @S9S_MB_2U_LIB.S9S_MB_2U(SCH_1):GND
 195    GND  VSS84 @S9S_MB_2U_LIB.S9S_MB_2U(SCH_1):GND
 197    GND  VSS85 @S9S_MB_2U_LIB.S9S_MB_2U(SCH_1):GND
 199    GND  VSS86 @S9S_MB_2U_LIB.S9S_MB_2U(SCH_1):GND
 202    GND  VSS87 @S9S_MB_2U_LIB.S9S_MB_2U(SCH_1):GND
 204    GND  VSS88 @S9S_MB_2U_LIB.S9S_MB_2U(SCH_1):GND
 206    GND  VSS89 @S9S_MB_2U_LIB.S9S_MB_2U(SCH_1):GND
 208    GND  VSS90 @S9S_MB_2U_LIB.S9S_MB_2U(SCH_1):GND
 210    GND  VSS91 @S9S_MB_2U_LIB.S9S_MB_2U(SCH_1):GND
 212    GND  VSS92 @S9S_MB_2U_LIB.S9S_MB_2U(SCH_1):GND
 214    GND  VSS93 @S9S_MB_2U_LIB.S9S_MB_2U(SCH_1):GND
 216    GND  VSS94 @S9S_MB_2U_LIB.S9S_MB_2U(SCH_1):GND
 219    GND  VSS95 @S9S_MB_2U_LIB.S9S_MB_2U(SCH_1):GND
 222    GND  VSS96 @S9S_MB_2U_LIB.S9S_MB_2U(SCH_1):GND
 224    GND  VSS97 @S9S_MB_2U_LIB.S9S_MB_2U(SCH_1):GND
 226    GND  VSS98 @S9S_MB_2U_LIB.S9S_MB_2U(SCH_1):GND
 228    GND  VSS99 @S9S_MB_2U_LIB.S9S_MB_2U(SCH_1):GND
 233    GND VSS101 @S9S_MB_2U_LIB.S9S_MB_2U(SCH_1):GND
 237    GND VSS103 @S9S_MB_2U_LIB.S9S_MB_2U(SCH_1):GND
 242    GND VSS105 @S9S_MB_2U_LIB.S9S_MB_2U(SCH_1):GND
 244    GND VSS106 @S9S_MB_2U_LIB.S9S_MB_2U(SCH_1):GND
 246    GND VSS107 @S9S_MB_2U_LIB.S9S_MB_2U(SCH_1):GND
 248    GND VSS108 @S9S_MB_2U_LIB.S9S_MB_2U(SCH_1):GND
 251    GND VSS109 @S9S_MB_2U_LIB.S9S_MB_2U(SCH_1):GND
 253    GND VSS110 @S9S_MB_2U_LIB.S9S_MB_2U(SCH_1):GND
 255    GND VSS111 @S9S_MB_2U_LIB.S9S_MB_2U(SCH_1):GND
 257    GND VSS112 @S9S_MB_2U_LIB.S9S_MB_2U(SCH_1):GND
 259    GND VSS113 @S9S_MB_2U_LIB.S9S_MB_2U(SCH_1):GND
 262    GND VSS114 @S9S_MB_2U_LIB.S9S_MB_2U(SCH_1):GND
 264    GND VSS115 @S9S_MB_2U_LIB.S9S_MB_2U(SCH_1):GND
 266    GND VSS116 @S9S_MB_2U_LIB.S9S_MB_2U(SCH_1):GND
 268    GND VSS117 @S9S_MB_2U_LIB.S9S_MB_2U(SCH_1):GND
 270    GND VSS118 @S9S_MB_2U_LIB.S9S_MB_2U(SCH_1):GND
 273    GND VSS119 @S9S_MB_2U_LIB.S9S_MB_2U(SCH_1):GND
 275    GND VSS120 @S9S_MB_2U_LIB.S9S_MB_2U(SCH_1):GND
 277    GND VSS121 @S9S_MB_2U_LIB.S9S_MB_2U(SCH_1):GND
 279    GND VSS122 @S9S_MB_2U_LIB.S9S_MB_2U(SCH_1):GND
 281    GND VSS123 @S9S_MB_2U_LIB.S9S_MB_2U(SCH_1):GND
 284    GND VSS124 @S9S_MB_2U_LIB.S9S_MB_2U(SCH_1):GND
 286    GND VSS125 @S9S_MB_2U_LIB.S9S_MB_2U(SCH_1):GND
 288    GND VSS126 @S9S_MB_2U_LIB.S9S_MB_2U(SCH_1):GND
   1 P12V_S3_AUX_CPU1_NVDIMM VIN_BULK0 @S9S_MB_2U_LIB.S9S_MB_2U(SCH_1):P12V_S3_AUX_CPU1_NVDIMM
 145 P12V_S3_AUX_CPU1_NVDIMM VIN_BULK1 @S9S_MB_2U_LIB.S9S_MB_2U(SCH_1):P12V_S3_AUX_CPU1_NVDIMM
 146 P12V_S3_AUX_CPU1_NVDIMM VIN_BULK2 @S9S_MB_2U_LIB.S9S_MB_2U(SCH_1):P12V_S3_AUX_CPU1_NVDIMM
 230    GND VSS100 @S9S_MB_2U_LIB.S9S_MB_2U(SCH_1):GND
 235    GND VSS102 @S9S_MB_2U_LIB.S9S_MB_2U(SCH_1):GND
 240    GND VSS104 @S9S_MB_2U_LIB.S9S_MB_2U(SCH_1):GND
 132    GND  VSS58 @S9S_MB_2U_LIB.S9S_MB_2U(SCH_1):GND
 136    GND  VSS60 @S9S_MB_2U_LIB.S9S_MB_2U(SCH_1):GND
 139    GND  VSS61 @S9S_MB_2U_LIB.S9S_MB_2U(SCH_1):GND
 141    GND  VSS62 @S9S_MB_2U_LIB.S9S_MB_2U(SCH_1):GND
  G1    GND     G1 @S9S_MB_2U_LIB.S9S_MB_2U(SCH_1):GND
  G2    GND     G2 @S9S_MB_2U_LIB.S9S_MB_2U(SCH_1):GND
  G3    GND     G3 @S9S_MB_2U_LIB.S9S_MB_2U(SCH_1):GND

SCONN288_ADR50017P087CC-SCONN2A  I178  J20
  93 M_B_CPU1_SB_DQS_DP<9> DQS9_B_T||TDQS9_B_T||DBI4_B_N @S9S_MB_2U_LIB.S9S_MB_2U(SCH_1):M_B_CPU1_SB_DQS_DP(9)
  94 M_B_CPU1_SB_DQS_DN<9> DQS9_B_C||TDQS9_B_C @S9S_MB_2U_LIB.S9S_MB_2U(SCH_1):M_B_CPU1_SB_DQS_DN(9)
 201 M_B_CPU1_SA_DQS_DP<9> DQS9_A_T||TDQS9_A_T @S9S_MB_2U_LIB.S9S_MB_2U(SCH_1):M_B_CPU1_SA_DQS_DP(9)
 200 M_B_CPU1_SA_DQS_DN<9> DQS9_A_C||TDQS9_A_C @S9S_MB_2U_LIB.S9S_MB_2U(SCH_1):M_B_CPU1_SA_DQS_DN(9)
 190 M_B_CPU1_SA_DQS_DP<8> DQS8_A_T||TDQS8_A_T @S9S_MB_2U_LIB.S9S_MB_2U(SCH_1):M_B_CPU1_SA_DQS_DP(8)
 189 M_B_CPU1_SA_DQS_DN<8> DQS8_A_C||TDQS8_A_C @S9S_MB_2U_LIB.S9S_MB_2U(SCH_1):M_B_CPU1_SA_DQS_DN(8)
 271 M_B_CPU1_SB_DQS_DN<7> DQS7_B_C||TDQS7_B_C @S9S_MB_2U_LIB.S9S_MB_2U(SCH_1):M_B_CPU1_SB_DQS_DN(7)
 179 M_B_CPU1_SA_DQS_DP<7> DQS7_A_T||TDQS7_A_T @S9S_MB_2U_LIB.S9S_MB_2U(SCH_1):M_B_CPU1_SA_DQS_DP(7)
 261 M_B_CPU1_SB_DQS_DP<6> DQS6_B_T||TDQS6_B_T @S9S_MB_2U_LIB.S9S_MB_2U(SCH_1):M_B_CPU1_SB_DQS_DP(6)
 260 M_B_CPU1_SB_DQS_DN<6> DQS6_B_C||TDQS6_B_C @S9S_MB_2U_LIB.S9S_MB_2U(SCH_1):M_B_CPU1_SB_DQS_DN(6)
 167 M_B_CPU1_SA_DQS_DN<6> DQS6_A_C||TDQS6_A_C||DQS6_A_T||TDQS6_A_T @S9S_MB_2U_LIB.S9S_MB_2U(SCH_1):M_B_CPU1_SA_DQS_DN(6)
 250 M_B_CPU1_SB_DQS_DP<5> DQS5_B_T||TDQS5_B_T @S9S_MB_2U_LIB.S9S_MB_2U(SCH_1):M_B_CPU1_SB_DQS_DP(5)
 249 M_B_CPU1_SB_DQS_DN<5> DQS5_B_C||TDQS5_B_C @S9S_MB_2U_LIB.S9S_MB_2U(SCH_1):M_B_CPU1_SB_DQS_DN(5)
 157 M_B_CPU1_SA_DQS_DP<5> DQS5_A_T||TDQS5_A_T @S9S_MB_2U_LIB.S9S_MB_2U(SCH_1):M_B_CPU1_SA_DQS_DP(5)
 156 M_B_CPU1_SA_DQS_DN<5> DQS5_A_C||TDQS5_A_C||DQS5_A_T||TDQS5_A_T @S9S_MB_2U_LIB.S9S_MB_2U(SCH_1):M_B_CPU1_SA_DQS_DN(5)
 239 M_B_CPU1_SB_DQS_DP<4> DQS4_B_T @S9S_MB_2U_LIB.S9S_MB_2U(SCH_1):M_B_CPU1_SB_DQS_DP(4)
 238 M_B_CPU1_SB_DQS_DN<4> DQS4_B_C @S9S_MB_2U_LIB.S9S_MB_2U(SCH_1):M_B_CPU1_SB_DQS_DN(4)
  55 M_B_CPU1_SA_DQS_DP<4> DQS4_A_T @S9S_MB_2U_LIB.S9S_MB_2U(SCH_1):M_B_CPU1_SA_DQS_DP(4)
  56 M_B_CPU1_SA_DQS_DN<4> DQS4_A_C @S9S_MB_2U_LIB.S9S_MB_2U(SCH_1):M_B_CPU1_SA_DQS_DN(4)
 137 M_B_CPU1_SB_DQS_DP<3> DQS3_B_T @S9S_MB_2U_LIB.S9S_MB_2U(SCH_1):M_B_CPU1_SB_DQS_DP(3)
 138 M_B_CPU1_SB_DQS_DN<3> DQS3_B_C @S9S_MB_2U_LIB.S9S_MB_2U(SCH_1):M_B_CPU1_SB_DQS_DN(3)
  44 M_B_CPU1_SA_DQS_DP<3> DQS3_A_T @S9S_MB_2U_LIB.S9S_MB_2U(SCH_1):M_B_CPU1_SA_DQS_DP(3)
  45 M_B_CPU1_SA_DQS_DN<3> DQS3_A_C @S9S_MB_2U_LIB.S9S_MB_2U(SCH_1):M_B_CPU1_SA_DQS_DN(3)
 126 M_B_CPU1_SB_DQS_DP<2> DQS2_B_T @S9S_MB_2U_LIB.S9S_MB_2U(SCH_1):M_B_CPU1_SB_DQS_DP(2)
 127 M_B_CPU1_SB_DQS_DN<2> DQS2_B_C @S9S_MB_2U_LIB.S9S_MB_2U(SCH_1):M_B_CPU1_SB_DQS_DN(2)
  33 M_B_CPU1_SA_DQS_DP<2> DQS2_A_T @S9S_MB_2U_LIB.S9S_MB_2U(SCH_1):M_B_CPU1_SA_DQS_DP(2)
  34 M_B_CPU1_SA_DQS_DN<2> DQS2_A_C @S9S_MB_2U_LIB.S9S_MB_2U(SCH_1):M_B_CPU1_SA_DQS_DN(2)
 115 M_B_CPU1_SB_DQS_DP<1> DQS1_B_T @S9S_MB_2U_LIB.S9S_MB_2U(SCH_1):M_B_CPU1_SB_DQS_DP(1)
 116 M_B_CPU1_SB_DQS_DN<1> DQS1_B_C @S9S_MB_2U_LIB.S9S_MB_2U(SCH_1):M_B_CPU1_SB_DQS_DN(1)
  22 M_B_CPU1_SA_DQS_DP<1> DQS1_A_T @S9S_MB_2U_LIB.S9S_MB_2U(SCH_1):M_B_CPU1_SA_DQS_DP(1)
  23 M_B_CPU1_SA_DQS_DN<1> DQS1_A_C @S9S_MB_2U_LIB.S9S_MB_2U(SCH_1):M_B_CPU1_SA_DQS_DN(1)
 104 M_B_CPU1_SB_DQS_DP<0> DQS0_B_T @S9S_MB_2U_LIB.S9S_MB_2U(SCH_1):M_B_CPU1_SB_DQS_DP(0)
 105 M_B_CPU1_SB_DQS_DN<0> DQS0_B_C @S9S_MB_2U_LIB.S9S_MB_2U(SCH_1):M_B_CPU1_SB_DQS_DN(0)
  11 M_B_CPU1_SA_DQS_DP<0> DQS0_A_T @S9S_MB_2U_LIB.S9S_MB_2U(SCH_1):M_B_CPU1_SA_DQS_DP(0)
  12 M_B_CPU1_SA_DQS_DN<0> DQS0_A_C @S9S_MB_2U_LIB.S9S_MB_2U(SCH_1):M_B_CPU1_SA_DQS_DN(0)
 272 M_B_CPU1_SB_DQS_DP<7> DQS7_B_T||TDQS7_B_T @S9S_MB_2U_LIB.S9S_MB_2U(SCH_1):M_B_CPU1_SB_DQS_DP(7)
 282 M_B_CPU1_SB_DQS_DN<8> DQS8_B_C||TDQS8_B_C @S9S_MB_2U_LIB.S9S_MB_2U(SCH_1):M_B_CPU1_SB_DQS_DN(8)
 283 M_B_CPU1_SB_DQS_DP<8> DQS8_B_T||TDQS8_B_T @S9S_MB_2U_LIB.S9S_MB_2U(SCH_1):M_B_CPU1_SB_DQS_DP(8)
 168 M_B_CPU1_SA_DQS_DP<6> DQS6_A_T||TDQS6_A_T @S9S_MB_2U_LIB.S9S_MB_2U(SCH_1):M_B_CPU1_SA_DQS_DP(6)
 178 M_B_CPU1_SA_DQS_DN<7> DQS7_A_C||TDQS7_A_C @S9S_MB_2U_LIB.S9S_MB_2U(SCH_1):M_B_CPU1_SA_DQS_DN(7)

Q_RES_0402LF-49.9,1%,1/16W,CHIA  I180  R3894
   1 I3C_SPD_DDRABCD_CPU1_LVC1_SCL_3      A @S9S_MB_2U_LIB.S9S_MB_2U(SCH_1):I3C_SPD_DDRABCD_CPU1_LVC1_SCL_R4
   2 I3C_SPD_DDRABCD_CPU1_LVC1_SCL      B @S9S_MB_2U_LIB.S9S_MB_2U(SCH_1):I3C_SPD_DDRABCD_CPU1_LVC1_SCL


DRAWING: @S9S_MB_2U_LIB.S9S_MB_2U(SCH_1):PAGE102 

Q_RES_0402LF-54.9K,1%,1/16W,CHA  I2  R46
   1 PD_CHC_CPU1_DIMM1_SAA      A @S9S_MB_2U_LIB.S9S_MB_2U(SCH_1):PD_CHC_CPU1_DIMM1_SAA
   2    GND      B @S9S_MB_2U_LIB.S9S_MB_2U(SCH_1):GND

SCONN288_ADR50017P130CC-SCONN2A  I13  J21
   3 P3V3_AUX VIN_MGMT @S9S_MB_2U_LIB.S9S_MB_2U(SCH_1):P3V3_AUX
   2 TP_CHC_CPU1_DIMM1_FRU_0   RFU0 @S9S_MB_2U_LIB.S9S_MB_2U(SCH_1):TP_CHC_CPU1_DIMM1_FRU_0
 144 TP_CHC_CPU1_DIMM1_FRU_1   RFU1 @S9S_MB_2U_LIB.S9S_MB_2U(SCH_1):TP_CHC_CPU1_DIMM1_FRU_1
 149 TP_CHC_CPU1_DIMM1_FRU_2   RFU2 @S9S_MB_2U_LIB.S9S_MB_2U(SCH_1):TP_CHC_CPU1_DIMM1_FRU_2
 150 TP_CHC_CPU1_DIMM1_FRU_3   RFU3 @S9S_MB_2U_LIB.S9S_MB_2U(SCH_1):TP_CHC_CPU1_DIMM1_FRU_3
 220 TP_CHC_CPU1_DIMM1_FRU_4   RFU4 @S9S_MB_2U_LIB.S9S_MB_2U(SCH_1):TP_CHC_CPU1_DIMM1_FRU_4
 231 TP_CHC_CPU1_DIMM1_FRU_5   RFU5 @S9S_MB_2U_LIB.S9S_MB_2U(SCH_1):TP_CHC_CPU1_DIMM1_FRU_5
 232 TP_CHC_CPU1_DIMM1_FRU_6   RFU6 @S9S_MB_2U_LIB.S9S_MB_2U(SCH_1):TP_CHC_CPU1_DIMM1_FRU_6
 207 RST_M_CD_CPU1_FPGA_N RESET_N @S9S_MB_2U_LIB.S9S_MB_2U(SCH_1):RST_M_CD_CPU1_FPGA_N
 147 PWRGD_CHC_CPU1_DIMM1 PWR_GOOD||FAIL_N @S9S_MB_2U_LIB.S9S_MB_2U(SCH_1):PWRGD_CHC_CPU1_DIMM1
 227 M_C_CPU1_SB_PAR  PAR_B @S9S_MB_2U_LIB.S9S_MB_2U(SCH_1):M_C_CPU1_SB_PAR
  74 M_C_CPU1_SA_PAR  PAR_A @S9S_MB_2U_LIB.S9S_MB_2U(SCH_1):M_C_CPU1_SA_PAR
  87 M_C_CPU1_SB_RSP<0> LBS||RSP_B_N @S9S_MB_2U_LIB.S9S_MB_2U(SCH_1):M_C_CPU1_SB_RSP(0)
  86 M_C_CPU1_SA_RSP<0> LBD||RSP_A_N @S9S_MB_2U_LIB.S9S_MB_2U(SCH_1):M_C_CPU1_SA_RSP(0)
   5 I3C_SPD_DDRABCD_CPU1_LVC1_SDA   HSDA @S9S_MB_2U_LIB.S9S_MB_2U(SCH_1):I3C_SPD_DDRABCD_CPU1_LVC1_SDA
   4 I3C_SPD_DDRABCD_CPU1_LVC1_SCL_4   HSCL @S9S_MB_2U_LIB.S9S_MB_2U(SCH_1):I3C_SPD_DDRABCD_CPU1_LVC1_SCL_R5
 148 PD_CHC_CPU1_DIMM1_SAA    HSA @S9S_MB_2U_LIB.S9S_MB_2U(SCH_1):PD_CHC_CPU1_DIMM1_SAA
 100 M_C_CPU1_SB_DQ<0>  DQ0_B @S9S_MB_2U_LIB.S9S_MB_2U(SCH_1):M_C_CPU1_SB_DQ(0)
 102 M_C_CPU1_SB_DQ<1>  DQ1_B @S9S_MB_2U_LIB.S9S_MB_2U(SCH_1):M_C_CPU1_SB_DQ(1)
 245 M_C_CPU1_SB_DQ<2>  DQ2_B @S9S_MB_2U_LIB.S9S_MB_2U(SCH_1):M_C_CPU1_SB_DQ(2)
 247 M_C_CPU1_SB_DQ<3>  DQ3_B @S9S_MB_2U_LIB.S9S_MB_2U(SCH_1):M_C_CPU1_SB_DQ(3)
 107 M_C_CPU1_SB_DQ<4>  DQ4_B @S9S_MB_2U_LIB.S9S_MB_2U(SCH_1):M_C_CPU1_SB_DQ(4)
 109 M_C_CPU1_SB_DQ<5>  DQ5_B @S9S_MB_2U_LIB.S9S_MB_2U(SCH_1):M_C_CPU1_SB_DQ(5)
 252 M_C_CPU1_SB_DQ<6>  DQ6_B @S9S_MB_2U_LIB.S9S_MB_2U(SCH_1):M_C_CPU1_SB_DQ(6)
 254 M_C_CPU1_SB_DQ<7>  DQ7_B @S9S_MB_2U_LIB.S9S_MB_2U(SCH_1):M_C_CPU1_SB_DQ(7)
 111 M_C_CPU1_SB_DQ<8>  DQ8_B @S9S_MB_2U_LIB.S9S_MB_2U(SCH_1):M_C_CPU1_SB_DQ(8)
 113 M_C_CPU1_SB_DQ<9>  DQ9_B @S9S_MB_2U_LIB.S9S_MB_2U(SCH_1):M_C_CPU1_SB_DQ(9)
 256 M_C_CPU1_SB_DQ<10> DQ10_B @S9S_MB_2U_LIB.S9S_MB_2U(SCH_1):M_C_CPU1_SB_DQ(10)
 258 M_C_CPU1_SB_DQ<11> DQ11_B @S9S_MB_2U_LIB.S9S_MB_2U(SCH_1):M_C_CPU1_SB_DQ(11)
 118 M_C_CPU1_SB_DQ<12> DQ12_B @S9S_MB_2U_LIB.S9S_MB_2U(SCH_1):M_C_CPU1_SB_DQ(12)
 120 M_C_CPU1_SB_DQ<13> DQ13_B @S9S_MB_2U_LIB.S9S_MB_2U(SCH_1):M_C_CPU1_SB_DQ(13)
 263 M_C_CPU1_SB_DQ<14> DQ14_B @S9S_MB_2U_LIB.S9S_MB_2U(SCH_1):M_C_CPU1_SB_DQ(14)
 265 M_C_CPU1_SB_DQ<15> DQ15_B @S9S_MB_2U_LIB.S9S_MB_2U(SCH_1):M_C_CPU1_SB_DQ(15)
 122 M_C_CPU1_SB_DQ<16> DQ16_B @S9S_MB_2U_LIB.S9S_MB_2U(SCH_1):M_C_CPU1_SB_DQ(16)
 124 M_C_CPU1_SB_DQ<17> DQ17_B @S9S_MB_2U_LIB.S9S_MB_2U(SCH_1):M_C_CPU1_SB_DQ(17)
 267 M_C_CPU1_SB_DQ<18> DQ18_B @S9S_MB_2U_LIB.S9S_MB_2U(SCH_1):M_C_CPU1_SB_DQ(18)
 269 M_C_CPU1_SB_DQ<19> DQ19_B @S9S_MB_2U_LIB.S9S_MB_2U(SCH_1):M_C_CPU1_SB_DQ(19)
 129 M_C_CPU1_SB_DQ<20> DQ20_B @S9S_MB_2U_LIB.S9S_MB_2U(SCH_1):M_C_CPU1_SB_DQ(20)
 131 M_C_CPU1_SB_DQ<21> DQ21_B @S9S_MB_2U_LIB.S9S_MB_2U(SCH_1):M_C_CPU1_SB_DQ(21)
 274 M_C_CPU1_SB_DQ<22> DQ22_B @S9S_MB_2U_LIB.S9S_MB_2U(SCH_1):M_C_CPU1_SB_DQ(22)
 276 M_C_CPU1_SB_DQ<23> DQ23_B @S9S_MB_2U_LIB.S9S_MB_2U(SCH_1):M_C_CPU1_SB_DQ(23)
 133 M_C_CPU1_SB_DQ<24> DQ24_B @S9S_MB_2U_LIB.S9S_MB_2U(SCH_1):M_C_CPU1_SB_DQ(24)
 135 M_C_CPU1_SB_DQ<25> DQ25_B @S9S_MB_2U_LIB.S9S_MB_2U(SCH_1):M_C_CPU1_SB_DQ(25)
 278 M_C_CPU1_SB_DQ<26> DQ26_B @S9S_MB_2U_LIB.S9S_MB_2U(SCH_1):M_C_CPU1_SB_DQ(26)
 280 M_C_CPU1_SB_DQ<27> DQ27_B @S9S_MB_2U_LIB.S9S_MB_2U(SCH_1):M_C_CPU1_SB_DQ(27)
 140 M_C_CPU1_SB_DQ<28> DQ28_B @S9S_MB_2U_LIB.S9S_MB_2U(SCH_1):M_C_CPU1_SB_DQ(28)
 142 M_C_CPU1_SB_DQ<29> DQ29_B @S9S_MB_2U_LIB.S9S_MB_2U(SCH_1):M_C_CPU1_SB_DQ(29)
 285 M_C_CPU1_SB_DQ<30> DQ30_B @S9S_MB_2U_LIB.S9S_MB_2U(SCH_1):M_C_CPU1_SB_DQ(30)
 287 M_C_CPU1_SB_DQ<31> DQ31_B @S9S_MB_2U_LIB.S9S_MB_2U(SCH_1):M_C_CPU1_SB_DQ(31)
   7 M_C_CPU1_SA_DQ<0>  DQ0_A @S9S_MB_2U_LIB.S9S_MB_2U(SCH_1):M_C_CPU1_SA_DQ(0)
   9 M_C_CPU1_SA_DQ<1>  DQ1_A @S9S_MB_2U_LIB.S9S_MB_2U(SCH_1):M_C_CPU1_SA_DQ(1)
 152 M_C_CPU1_SA_DQ<2>  DQ2_A @S9S_MB_2U_LIB.S9S_MB_2U(SCH_1):M_C_CPU1_SA_DQ(2)
 154 M_C_CPU1_SA_DQ<3>  DQ3_A @S9S_MB_2U_LIB.S9S_MB_2U(SCH_1):M_C_CPU1_SA_DQ(3)
  14 M_C_CPU1_SA_DQ<4>  DQ4_A @S9S_MB_2U_LIB.S9S_MB_2U(SCH_1):M_C_CPU1_SA_DQ(4)
  16 M_C_CPU1_SA_DQ<5>  DQ5_A @S9S_MB_2U_LIB.S9S_MB_2U(SCH_1):M_C_CPU1_SA_DQ(5)
 159 M_C_CPU1_SA_DQ<6>  DQ6_A @S9S_MB_2U_LIB.S9S_MB_2U(SCH_1):M_C_CPU1_SA_DQ(6)
 161 M_C_CPU1_SA_DQ<7>  DQ7_A @S9S_MB_2U_LIB.S9S_MB_2U(SCH_1):M_C_CPU1_SA_DQ(7)
  18 M_C_CPU1_SA_DQ<8>  DQ8_A @S9S_MB_2U_LIB.S9S_MB_2U(SCH_1):M_C_CPU1_SA_DQ(8)
  20 M_C_CPU1_SA_DQ<9>  DQ9_A @S9S_MB_2U_LIB.S9S_MB_2U(SCH_1):M_C_CPU1_SA_DQ(9)
 163 M_C_CPU1_SA_DQ<10> DQ10_A @S9S_MB_2U_LIB.S9S_MB_2U(SCH_1):M_C_CPU1_SA_DQ(10)
 165 M_C_CPU1_SA_DQ<11> DQ11_A @S9S_MB_2U_LIB.S9S_MB_2U(SCH_1):M_C_CPU1_SA_DQ(11)
  25 M_C_CPU1_SA_DQ<12> DQ12_A @S9S_MB_2U_LIB.S9S_MB_2U(SCH_1):M_C_CPU1_SA_DQ(12)
  27 M_C_CPU1_SA_DQ<13> DQ13_A @S9S_MB_2U_LIB.S9S_MB_2U(SCH_1):M_C_CPU1_SA_DQ(13)
 170 M_C_CPU1_SA_DQ<14> DQ14_A @S9S_MB_2U_LIB.S9S_MB_2U(SCH_1):M_C_CPU1_SA_DQ(14)
 172 M_C_CPU1_SA_DQ<15> DQ15_A @S9S_MB_2U_LIB.S9S_MB_2U(SCH_1):M_C_CPU1_SA_DQ(15)
  29 M_C_CPU1_SA_DQ<16> DQ16_A @S9S_MB_2U_LIB.S9S_MB_2U(SCH_1):M_C_CPU1_SA_DQ(16)
  31 M_C_CPU1_SA_DQ<17> DQ17_A @S9S_MB_2U_LIB.S9S_MB_2U(SCH_1):M_C_CPU1_SA_DQ(17)
 174 M_C_CPU1_SA_DQ<18> DQ18_A @S9S_MB_2U_LIB.S9S_MB_2U(SCH_1):M_C_CPU1_SA_DQ(18)
 176 M_C_CPU1_SA_DQ<19> DQ19_A @S9S_MB_2U_LIB.S9S_MB_2U(SCH_1):M_C_CPU1_SA_DQ(19)
  36 M_C_CPU1_SA_DQ<20> DQ20_A @S9S_MB_2U_LIB.S9S_MB_2U(SCH_1):M_C_CPU1_SA_DQ(20)
  38 M_C_CPU1_SA_DQ<21> DQ21_A @S9S_MB_2U_LIB.S9S_MB_2U(SCH_1):M_C_CPU1_SA_DQ(21)
 181 M_C_CPU1_SA_DQ<22> DQ22_A @S9S_MB_2U_LIB.S9S_MB_2U(SCH_1):M_C_CPU1_SA_DQ(22)
 183 M_C_CPU1_SA_DQ<23> DQ23_A @S9S_MB_2U_LIB.S9S_MB_2U(SCH_1):M_C_CPU1_SA_DQ(23)
  40 M_C_CPU1_SA_DQ<24> DQ24_A @S9S_MB_2U_LIB.S9S_MB_2U(SCH_1):M_C_CPU1_SA_DQ(24)
  42 M_C_CPU1_SA_DQ<25> DQ25_A @S9S_MB_2U_LIB.S9S_MB_2U(SCH_1):M_C_CPU1_SA_DQ(25)
 185 M_C_CPU1_SA_DQ<26> DQ26_A @S9S_MB_2U_LIB.S9S_MB_2U(SCH_1):M_C_CPU1_SA_DQ(26)
 187 M_C_CPU1_SA_DQ<27> DQ27_A @S9S_MB_2U_LIB.S9S_MB_2U(SCH_1):M_C_CPU1_SA_DQ(27)
  47 M_C_CPU1_SA_DQ<28> DQ28_A @S9S_MB_2U_LIB.S9S_MB_2U(SCH_1):M_C_CPU1_SA_DQ(28)
  49 M_C_CPU1_SA_DQ<29> DQ29_A @S9S_MB_2U_LIB.S9S_MB_2U(SCH_1):M_C_CPU1_SA_DQ(29)
 192 M_C_CPU1_SA_DQ<30> DQ30_A @S9S_MB_2U_LIB.S9S_MB_2U(SCH_1):M_C_CPU1_SA_DQ(30)
 229 M_C_CPU1_SB_CS_N<1> CS1_B_N @S9S_MB_2U_LIB.S9S_MB_2U(SCH_1):M_C_CPU1_SB_CS_N(1)
 209 M_C_CPU1_SA_CS_N<1> CS1_A_N @S9S_MB_2U_LIB.S9S_MB_2U(SCH_1):M_C_CPU1_SA_CS_N(1)
  84 M_C_CPU1_SB_CS_N<0> CS0_B_N @S9S_MB_2U_LIB.S9S_MB_2U(SCH_1):M_C_CPU1_SB_CS_N(0)
  64 M_C_CPU1_SA_CS_N<0> CS0_A_N @S9S_MB_2U_LIB.S9S_MB_2U(SCH_1):M_C_CPU1_SA_CS_N(0)
 217 M_C_CPU1_CLK_DP<0>   CK_T @S9S_MB_2U_LIB.S9S_MB_2U(SCH_1):M_C_CPU1_CLK_DP(0)
 218 M_C_CPU1_CLK_DN<0>   CK_C @S9S_MB_2U_LIB.S9S_MB_2U(SCH_1):M_C_CPU1_CLK_DN(0)
  96 M_C_CPU1_SB_CB<0>  CB0_B @S9S_MB_2U_LIB.S9S_MB_2U(SCH_1):M_C_CPU1_SB_CB(0)
  98 M_C_CPU1_SB_CB<1>  CB1_B @S9S_MB_2U_LIB.S9S_MB_2U(SCH_1):M_C_CPU1_SB_CB(1)
 241 M_C_CPU1_SB_CB<2>  CB2_B @S9S_MB_2U_LIB.S9S_MB_2U(SCH_1):M_C_CPU1_SB_CB(2)
 243 M_C_CPU1_SB_CB<3>  CB3_B @S9S_MB_2U_LIB.S9S_MB_2U(SCH_1):M_C_CPU1_SB_CB(3)
  89 M_C_CPU1_SB_CB<4>  CB4_B @S9S_MB_2U_LIB.S9S_MB_2U(SCH_1):M_C_CPU1_SB_CB(4)
  91 M_C_CPU1_SB_CB<5>  CB5_B @S9S_MB_2U_LIB.S9S_MB_2U(SCH_1):M_C_CPU1_SB_CB(5)
 234 M_C_CPU1_SB_CB<6>  CB6_B @S9S_MB_2U_LIB.S9S_MB_2U(SCH_1):M_C_CPU1_SB_CB(6)
  51 M_C_CPU1_SA_CB<0>  CB0_A @S9S_MB_2U_LIB.S9S_MB_2U(SCH_1):M_C_CPU1_SA_CB(0)
 196 M_C_CPU1_SA_CB<2>  CB2_A @S9S_MB_2U_LIB.S9S_MB_2U(SCH_1):M_C_CPU1_SA_CB(2)
 198 M_C_CPU1_SA_CB<3>  CB3_A @S9S_MB_2U_LIB.S9S_MB_2U(SCH_1):M_C_CPU1_SA_CB(3)
  60 M_C_CPU1_SA_CB<5>  CB5_A @S9S_MB_2U_LIB.S9S_MB_2U(SCH_1):M_C_CPU1_SA_CB(5)
 203 M_C_CPU1_SA_CB<6>  CB6_A @S9S_MB_2U_LIB.S9S_MB_2U(SCH_1):M_C_CPU1_SA_CB(6)
  82 M_C_CPU1_SB_CA<6>  CA6_B @S9S_MB_2U_LIB.S9S_MB_2U(SCH_1):M_C_CPU1_SB_CA(6)
  72 M_C_CPU1_SA_CA<6>  CA6_A @S9S_MB_2U_LIB.S9S_MB_2U(SCH_1):M_C_CPU1_SA_CA(6)
 225 M_C_CPU1_SB_CA<5>  CA5_B @S9S_MB_2U_LIB.S9S_MB_2U(SCH_1):M_C_CPU1_SB_CA(5)
 215 M_C_CPU1_SA_CA<5>  CA5_A @S9S_MB_2U_LIB.S9S_MB_2U(SCH_1):M_C_CPU1_SA_CA(5)
  80 M_C_CPU1_SB_CA<4>  CA4_B @S9S_MB_2U_LIB.S9S_MB_2U(SCH_1):M_C_CPU1_SB_CA(4)
  70 M_C_CPU1_SA_CA<4>  CA4_A @S9S_MB_2U_LIB.S9S_MB_2U(SCH_1):M_C_CPU1_SA_CA(4)
 223 M_C_CPU1_SB_CA<3>  CA3_B @S9S_MB_2U_LIB.S9S_MB_2U(SCH_1):M_C_CPU1_SB_CA(3)
 213 M_C_CPU1_SA_CA<3>  CA3_A @S9S_MB_2U_LIB.S9S_MB_2U(SCH_1):M_C_CPU1_SA_CA(3)
  78 M_C_CPU1_SB_CA<2>  CA2_B @S9S_MB_2U_LIB.S9S_MB_2U(SCH_1):M_C_CPU1_SB_CA(2)
  68 M_C_CPU1_SA_CA<2>  CA2_A @S9S_MB_2U_LIB.S9S_MB_2U(SCH_1):M_C_CPU1_SA_CA(2)
 221 M_C_CPU1_SB_CA<1>  CA1_B @S9S_MB_2U_LIB.S9S_MB_2U(SCH_1):M_C_CPU1_SB_CA(1)
 211 M_C_CPU1_SA_CA<1>  CA1_A @S9S_MB_2U_LIB.S9S_MB_2U(SCH_1):M_C_CPU1_SA_CA(1)
  76 M_C_CPU1_SB_CA<0>  CA0_B @S9S_MB_2U_LIB.S9S_MB_2U(SCH_1):M_C_CPU1_SB_CA(0)
  66 M_C_CPU1_SA_CA<0>  CA0_A @S9S_MB_2U_LIB.S9S_MB_2U(SCH_1):M_C_CPU1_SA_CA(0)
  62 M_C_CPU1_ALERT_N ALERT_N @S9S_MB_2U_LIB.S9S_MB_2U(SCH_1):M_C_CPU1_ALERT_N
 236 M_C_CPU1_SB_CB<7>  CB7_B @S9S_MB_2U_LIB.S9S_MB_2U(SCH_1):M_C_CPU1_SB_CB(7)
  53 M_C_CPU1_SA_CB<1>  CB1_A @S9S_MB_2U_LIB.S9S_MB_2U(SCH_1):M_C_CPU1_SA_CB(1)
  58 M_C_CPU1_SA_CB<4>  CB4_A @S9S_MB_2U_LIB.S9S_MB_2U(SCH_1):M_C_CPU1_SA_CB(4)
 205 M_C_CPU1_SA_CB<7>  CB7_A @S9S_MB_2U_LIB.S9S_MB_2U(SCH_1):M_C_CPU1_SA_CB(7)
 194 M_C_CPU1_SA_DQ<31> DQ31_A @S9S_MB_2U_LIB.S9S_MB_2U(SCH_1):M_C_CPU1_SA_DQ(31)

Q_CAP_C0402-2.2UF,6.3V,20%,X6SA  I124  C62
   1 P3V3_AUX      A @S9S_MB_2U_LIB.S9S_MB_2U(SCH_1):P3V3_AUX
   2    GND      B @S9S_MB_2U_LIB.S9S_MB_2U(SCH_1):GND

Q_CAP_C0805-10UF,16V,10%,X6S,CA  I127  C63
   1 P12V_S3_AUX_CPU1_NVDIMM      A @S9S_MB_2U_LIB.S9S_MB_2U(SCH_1):P12V_S3_AUX_CPU1_NVDIMM
   2    GND      B @S9S_MB_2U_LIB.S9S_MB_2U(SCH_1):GND

Q_CAP_C0805-10UF,16V,10%,X6S,CA  I167  C64
   1 P12V_S3_AUX_CPU1_NVDIMM      A @S9S_MB_2U_LIB.S9S_MB_2U(SCH_1):P12V_S3_AUX_CPU1_NVDIMM
   2    GND      B @S9S_MB_2U_LIB.S9S_MB_2U(SCH_1):GND

SCONN288_ADR50017P130CC-SCONN2A  I169  J21
   6    GND   VSS0 @S9S_MB_2U_LIB.S9S_MB_2U(SCH_1):GND
   8    GND   VSS1 @S9S_MB_2U_LIB.S9S_MB_2U(SCH_1):GND
  10    GND   VSS2 @S9S_MB_2U_LIB.S9S_MB_2U(SCH_1):GND
  13    GND   VSS3 @S9S_MB_2U_LIB.S9S_MB_2U(SCH_1):GND
  15    GND   VSS4 @S9S_MB_2U_LIB.S9S_MB_2U(SCH_1):GND
  17    GND   VSS5 @S9S_MB_2U_LIB.S9S_MB_2U(SCH_1):GND
  19    GND   VSS6 @S9S_MB_2U_LIB.S9S_MB_2U(SCH_1):GND
  21    GND   VSS7 @S9S_MB_2U_LIB.S9S_MB_2U(SCH_1):GND
  24    GND   VSS8 @S9S_MB_2U_LIB.S9S_MB_2U(SCH_1):GND
  26    GND   VSS9 @S9S_MB_2U_LIB.S9S_MB_2U(SCH_1):GND
  28    GND  VSS10 @S9S_MB_2U_LIB.S9S_MB_2U(SCH_1):GND
  30    GND  VSS11 @S9S_MB_2U_LIB.S9S_MB_2U(SCH_1):GND
  32    GND  VSS12 @S9S_MB_2U_LIB.S9S_MB_2U(SCH_1):GND
  35    GND  VSS13 @S9S_MB_2U_LIB.S9S_MB_2U(SCH_1):GND
  37    GND  VSS14 @S9S_MB_2U_LIB.S9S_MB_2U(SCH_1):GND
  39    GND  VSS15 @S9S_MB_2U_LIB.S9S_MB_2U(SCH_1):GND
  41    GND  VSS16 @S9S_MB_2U_LIB.S9S_MB_2U(SCH_1):GND
  43    GND  VSS17 @S9S_MB_2U_LIB.S9S_MB_2U(SCH_1):GND
  46    GND  VSS18 @S9S_MB_2U_LIB.S9S_MB_2U(SCH_1):GND
  48    GND  VSS19 @S9S_MB_2U_LIB.S9S_MB_2U(SCH_1):GND
  50    GND  VSS20 @S9S_MB_2U_LIB.S9S_MB_2U(SCH_1):GND
  52    GND  VSS21 @S9S_MB_2U_LIB.S9S_MB_2U(SCH_1):GND
  54    GND  VSS22 @S9S_MB_2U_LIB.S9S_MB_2U(SCH_1):GND
  57    GND  VSS23 @S9S_MB_2U_LIB.S9S_MB_2U(SCH_1):GND
  59    GND  VSS24 @S9S_MB_2U_LIB.S9S_MB_2U(SCH_1):GND
  61    GND  VSS25 @S9S_MB_2U_LIB.S9S_MB_2U(SCH_1):GND
  63    GND  VSS26 @S9S_MB_2U_LIB.S9S_MB_2U(SCH_1):GND
  65    GND  VSS27 @S9S_MB_2U_LIB.S9S_MB_2U(SCH_1):GND
  67    GND  VSS28 @S9S_MB_2U_LIB.S9S_MB_2U(SCH_1):GND
  69    GND  VSS29 @S9S_MB_2U_LIB.S9S_MB_2U(SCH_1):GND
  71    GND  VSS30 @S9S_MB_2U_LIB.S9S_MB_2U(SCH_1):GND
  73    GND  VSS31 @S9S_MB_2U_LIB.S9S_MB_2U(SCH_1):GND
  75    GND  VSS32 @S9S_MB_2U_LIB.S9S_MB_2U(SCH_1):GND
  77    GND  VSS33 @S9S_MB_2U_LIB.S9S_MB_2U(SCH_1):GND
  79    GND  VSS34 @S9S_MB_2U_LIB.S9S_MB_2U(SCH_1):GND
  81    GND  VSS35 @S9S_MB_2U_LIB.S9S_MB_2U(SCH_1):GND
  83    GND  VSS36 @S9S_MB_2U_LIB.S9S_MB_2U(SCH_1):GND
  85    GND  VSS37 @S9S_MB_2U_LIB.S9S_MB_2U(SCH_1):GND
  88    GND  VSS38 @S9S_MB_2U_LIB.S9S_MB_2U(SCH_1):GND
  90    GND  VSS39 @S9S_MB_2U_LIB.S9S_MB_2U(SCH_1):GND
  92    GND  VSS40 @S9S_MB_2U_LIB.S9S_MB_2U(SCH_1):GND
  95    GND  VSS41 @S9S_MB_2U_LIB.S9S_MB_2U(SCH_1):GND
  97    GND  VSS42 @S9S_MB_2U_LIB.S9S_MB_2U(SCH_1):GND
  99    GND  VSS43 @S9S_MB_2U_LIB.S9S_MB_2U(SCH_1):GND
 101    GND  VSS44 @S9S_MB_2U_LIB.S9S_MB_2U(SCH_1):GND
 103    GND  VSS45 @S9S_MB_2U_LIB.S9S_MB_2U(SCH_1):GND
 106    GND  VSS46 @S9S_MB_2U_LIB.S9S_MB_2U(SCH_1):GND
 108    GND  VSS47 @S9S_MB_2U_LIB.S9S_MB_2U(SCH_1):GND
 110    GND  VSS48 @S9S_MB_2U_LIB.S9S_MB_2U(SCH_1):GND
 112    GND  VSS49 @S9S_MB_2U_LIB.S9S_MB_2U(SCH_1):GND
 114    GND  VSS50 @S9S_MB_2U_LIB.S9S_MB_2U(SCH_1):GND
 117    GND  VSS51 @S9S_MB_2U_LIB.S9S_MB_2U(SCH_1):GND
 119    GND  VSS52 @S9S_MB_2U_LIB.S9S_MB_2U(SCH_1):GND
 121    GND  VSS53 @S9S_MB_2U_LIB.S9S_MB_2U(SCH_1):GND
 123    GND  VSS54 @S9S_MB_2U_LIB.S9S_MB_2U(SCH_1):GND
 125    GND  VSS55 @S9S_MB_2U_LIB.S9S_MB_2U(SCH_1):GND
 128    GND  VSS56 @S9S_MB_2U_LIB.S9S_MB_2U(SCH_1):GND
 130    GND  VSS57 @S9S_MB_2U_LIB.S9S_MB_2U(SCH_1):GND
 134    GND  VSS59 @S9S_MB_2U_LIB.S9S_MB_2U(SCH_1):GND
 143    GND  VSS63 @S9S_MB_2U_LIB.S9S_MB_2U(SCH_1):GND
 151    GND  VSS64 @S9S_MB_2U_LIB.S9S_MB_2U(SCH_1):GND
 153    GND  VSS65 @S9S_MB_2U_LIB.S9S_MB_2U(SCH_1):GND
 155    GND  VSS66 @S9S_MB_2U_LIB.S9S_MB_2U(SCH_1):GND
 158    GND  VSS67 @S9S_MB_2U_LIB.S9S_MB_2U(SCH_1):GND
 160    GND  VSS68 @S9S_MB_2U_LIB.S9S_MB_2U(SCH_1):GND
 162    GND  VSS69 @S9S_MB_2U_LIB.S9S_MB_2U(SCH_1):GND
 164    GND  VSS70 @S9S_MB_2U_LIB.S9S_MB_2U(SCH_1):GND
 166    GND  VSS71 @S9S_MB_2U_LIB.S9S_MB_2U(SCH_1):GND
 169    GND  VSS72 @S9S_MB_2U_LIB.S9S_MB_2U(SCH_1):GND
 171    GND  VSS73 @S9S_MB_2U_LIB.S9S_MB_2U(SCH_1):GND
 173    GND  VSS74 @S9S_MB_2U_LIB.S9S_MB_2U(SCH_1):GND
 175    GND  VSS75 @S9S_MB_2U_LIB.S9S_MB_2U(SCH_1):GND
 177    GND  VSS76 @S9S_MB_2U_LIB.S9S_MB_2U(SCH_1):GND
 180    GND  VSS77 @S9S_MB_2U_LIB.S9S_MB_2U(SCH_1):GND
 182    GND  VSS78 @S9S_MB_2U_LIB.S9S_MB_2U(SCH_1):GND
 184    GND  VSS79 @S9S_MB_2U_LIB.S9S_MB_2U(SCH_1):GND
 186    GND  VSS80 @S9S_MB_2U_LIB.S9S_MB_2U(SCH_1):GND
 188    GND  VSS81 @S9S_MB_2U_LIB.S9S_MB_2U(SCH_1):GND
 191    GND  VSS82 @S9S_MB_2U_LIB.S9S_MB_2U(SCH_1):GND
 193    GND  VSS83 @S9S_MB_2U_LIB.S9S_MB_2U(SCH_1):GND
 195    GND  VSS84 @S9S_MB_2U_LIB.S9S_MB_2U(SCH_1):GND
 197    GND  VSS85 @S9S_MB_2U_LIB.S9S_MB_2U(SCH_1):GND
 199    GND  VSS86 @S9S_MB_2U_LIB.S9S_MB_2U(SCH_1):GND
 202    GND  VSS87 @S9S_MB_2U_LIB.S9S_MB_2U(SCH_1):GND
 204    GND  VSS88 @S9S_MB_2U_LIB.S9S_MB_2U(SCH_1):GND
 206    GND  VSS89 @S9S_MB_2U_LIB.S9S_MB_2U(SCH_1):GND
 208    GND  VSS90 @S9S_MB_2U_LIB.S9S_MB_2U(SCH_1):GND
 210    GND  VSS91 @S9S_MB_2U_LIB.S9S_MB_2U(SCH_1):GND
 212    GND  VSS92 @S9S_MB_2U_LIB.S9S_MB_2U(SCH_1):GND
 214    GND  VSS93 @S9S_MB_2U_LIB.S9S_MB_2U(SCH_1):GND
 216    GND  VSS94 @S9S_MB_2U_LIB.S9S_MB_2U(SCH_1):GND
 219    GND  VSS95 @S9S_MB_2U_LIB.S9S_MB_2U(SCH_1):GND
 222    GND  VSS96 @S9S_MB_2U_LIB.S9S_MB_2U(SCH_1):GND
 224    GND  VSS97 @S9S_MB_2U_LIB.S9S_MB_2U(SCH_1):GND
 226    GND  VSS98 @S9S_MB_2U_LIB.S9S_MB_2U(SCH_1):GND
 228    GND  VSS99 @S9S_MB_2U_LIB.S9S_MB_2U(SCH_1):GND
 233    GND VSS101 @S9S_MB_2U_LIB.S9S_MB_2U(SCH_1):GND
 237    GND VSS103 @S9S_MB_2U_LIB.S9S_MB_2U(SCH_1):GND
 242    GND VSS105 @S9S_MB_2U_LIB.S9S_MB_2U(SCH_1):GND
 244    GND VSS106 @S9S_MB_2U_LIB.S9S_MB_2U(SCH_1):GND
 246    GND VSS107 @S9S_MB_2U_LIB.S9S_MB_2U(SCH_1):GND
 248    GND VSS108 @S9S_MB_2U_LIB.S9S_MB_2U(SCH_1):GND
 251    GND VSS109 @S9S_MB_2U_LIB.S9S_MB_2U(SCH_1):GND
 253    GND VSS110 @S9S_MB_2U_LIB.S9S_MB_2U(SCH_1):GND
 255    GND VSS111 @S9S_MB_2U_LIB.S9S_MB_2U(SCH_1):GND
 257    GND VSS112 @S9S_MB_2U_LIB.S9S_MB_2U(SCH_1):GND
 259    GND VSS113 @S9S_MB_2U_LIB.S9S_MB_2U(SCH_1):GND
 262    GND VSS114 @S9S_MB_2U_LIB.S9S_MB_2U(SCH_1):GND
 264    GND VSS115 @S9S_MB_2U_LIB.S9S_MB_2U(SCH_1):GND
 266    GND VSS116 @S9S_MB_2U_LIB.S9S_MB_2U(SCH_1):GND
 268    GND VSS117 @S9S_MB_2U_LIB.S9S_MB_2U(SCH_1):GND
 270    GND VSS118 @S9S_MB_2U_LIB.S9S_MB_2U(SCH_1):GND
 273    GND VSS119 @S9S_MB_2U_LIB.S9S_MB_2U(SCH_1):GND
 275    GND VSS120 @S9S_MB_2U_LIB.S9S_MB_2U(SCH_1):GND
 277    GND VSS121 @S9S_MB_2U_LIB.S9S_MB_2U(SCH_1):GND
 279    GND VSS122 @S9S_MB_2U_LIB.S9S_MB_2U(SCH_1):GND
 281    GND VSS123 @S9S_MB_2U_LIB.S9S_MB_2U(SCH_1):GND
 284    GND VSS124 @S9S_MB_2U_LIB.S9S_MB_2U(SCH_1):GND
 286    GND VSS125 @S9S_MB_2U_LIB.S9S_MB_2U(SCH_1):GND
 288    GND VSS126 @S9S_MB_2U_LIB.S9S_MB_2U(SCH_1):GND
   1 P12V_S3_AUX_CPU1_NVDIMM VIN_BULK0 @S9S_MB_2U_LIB.S9S_MB_2U(SCH_1):P12V_S3_AUX_CPU1_NVDIMM
 145 P12V_S3_AUX_CPU1_NVDIMM VIN_BULK1 @S9S_MB_2U_LIB.S9S_MB_2U(SCH_1):P12V_S3_AUX_CPU1_NVDIMM
 146 P12V_S3_AUX_CPU1_NVDIMM VIN_BULK2 @S9S_MB_2U_LIB.S9S_MB_2U(SCH_1):P12V_S3_AUX_CPU1_NVDIMM
 230    GND VSS100 @S9S_MB_2U_LIB.S9S_MB_2U(SCH_1):GND
 235    GND VSS102 @S9S_MB_2U_LIB.S9S_MB_2U(SCH_1):GND
 240    GND VSS104 @S9S_MB_2U_LIB.S9S_MB_2U(SCH_1):GND
 132    GND  VSS58 @S9S_MB_2U_LIB.S9S_MB_2U(SCH_1):GND
 136    GND  VSS60 @S9S_MB_2U_LIB.S9S_MB_2U(SCH_1):GND
 139    GND  VSS61 @S9S_MB_2U_LIB.S9S_MB_2U(SCH_1):GND
 141    GND  VSS62 @S9S_MB_2U_LIB.S9S_MB_2U(SCH_1):GND
  G1    GND     G1 @S9S_MB_2U_LIB.S9S_MB_2U(SCH_1):GND
  G2    GND     G2 @S9S_MB_2U_LIB.S9S_MB_2U(SCH_1):GND
  G3    GND     G3 @S9S_MB_2U_LIB.S9S_MB_2U(SCH_1):GND

SCONN288_ADR50017P130CC-SCONN2A  I178  J21
  93 M_C_CPU1_SB_DQS_DP<9> DQS9_B_T||TDQS9_B_T||DBI4_B_N @S9S_MB_2U_LIB.S9S_MB_2U(SCH_1):M_C_CPU1_SB_DQS_DP(9)
  94 M_C_CPU1_SB_DQS_DN<9> DQS9_B_C||TDQS9_B_C @S9S_MB_2U_LIB.S9S_MB_2U(SCH_1):M_C_CPU1_SB_DQS_DN(9)
 201 M_C_CPU1_SA_DQS_DP<9> DQS9_A_T||TDQS9_A_T @S9S_MB_2U_LIB.S9S_MB_2U(SCH_1):M_C_CPU1_SA_DQS_DP(9)
 200 M_C_CPU1_SA_DQS_DN<9> DQS9_A_C||TDQS9_A_C @S9S_MB_2U_LIB.S9S_MB_2U(SCH_1):M_C_CPU1_SA_DQS_DN(9)
 190 M_C_CPU1_SA_DQS_DP<8> DQS8_A_T||TDQS8_A_T @S9S_MB_2U_LIB.S9S_MB_2U(SCH_1):M_C_CPU1_SA_DQS_DP(8)
 189 M_C_CPU1_SA_DQS_DN<8> DQS8_A_C||TDQS8_A_C @S9S_MB_2U_LIB.S9S_MB_2U(SCH_1):M_C_CPU1_SA_DQS_DN(8)
 271 M_C_CPU1_SB_DQS_DN<7> DQS7_B_C||TDQS7_B_C @S9S_MB_2U_LIB.S9S_MB_2U(SCH_1):M_C_CPU1_SB_DQS_DN(7)
 179 M_C_CPU1_SA_DQS_DP<7> DQS7_A_T||TDQS7_A_T @S9S_MB_2U_LIB.S9S_MB_2U(SCH_1):M_C_CPU1_SA_DQS_DP(7)
 261 M_C_CPU1_SB_DQS_DP<6> DQS6_B_T||TDQS6_B_T @S9S_MB_2U_LIB.S9S_MB_2U(SCH_1):M_C_CPU1_SB_DQS_DP(6)
 260 M_C_CPU1_SB_DQS_DN<6> DQS6_B_C||TDQS6_B_C @S9S_MB_2U_LIB.S9S_MB_2U(SCH_1):M_C_CPU1_SB_DQS_DN(6)
 167 M_C_CPU1_SA_DQS_DN<6> DQS6_A_C||TDQS6_A_C||DQS6_A_T||TDQS6_A_T @S9S_MB_2U_LIB.S9S_MB_2U(SCH_1):M_C_CPU1_SA_DQS_DN(6)
 250 M_C_CPU1_SB_DQS_DP<5> DQS5_B_T||TDQS5_B_T @S9S_MB_2U_LIB.S9S_MB_2U(SCH_1):M_C_CPU1_SB_DQS_DP(5)
 249 M_C_CPU1_SB_DQS_DN<5> DQS5_B_C||TDQS5_B_C @S9S_MB_2U_LIB.S9S_MB_2U(SCH_1):M_C_CPU1_SB_DQS_DN(5)
 157 M_C_CPU1_SA_DQS_DP<5> DQS5_A_T||TDQS5_A_T @S9S_MB_2U_LIB.S9S_MB_2U(SCH_1):M_C_CPU1_SA_DQS_DP(5)
 156 M_C_CPU1_SA_DQS_DN<5> DQS5_A_C||TDQS5_A_C||DQS5_A_T||TDQS5_A_T @S9S_MB_2U_LIB.S9S_MB_2U(SCH_1):M_C_CPU1_SA_DQS_DN(5)
 239 M_C_CPU1_SB_DQS_DP<4> DQS4_B_T @S9S_MB_2U_LIB.S9S_MB_2U(SCH_1):M_C_CPU1_SB_DQS_DP(4)
 238 M_C_CPU1_SB_DQS_DN<4> DQS4_B_C @S9S_MB_2U_LIB.S9S_MB_2U(SCH_1):M_C_CPU1_SB_DQS_DN(4)
  55 M_C_CPU1_SA_DQS_DP<4> DQS4_A_T @S9S_MB_2U_LIB.S9S_MB_2U(SCH_1):M_C_CPU1_SA_DQS_DP(4)
  56 M_C_CPU1_SA_DQS_DN<4> DQS4_A_C @S9S_MB_2U_LIB.S9S_MB_2U(SCH_1):M_C_CPU1_SA_DQS_DN(4)
 137 M_C_CPU1_SB_DQS_DP<3> DQS3_B_T @S9S_MB_2U_LIB.S9S_MB_2U(SCH_1):M_C_CPU1_SB_DQS_DP(3)
 138 M_C_CPU1_SB_DQS_DN<3> DQS3_B_C @S9S_MB_2U_LIB.S9S_MB_2U(SCH_1):M_C_CPU1_SB_DQS_DN(3)
  44 M_C_CPU1_SA_DQS_DP<3> DQS3_A_T @S9S_MB_2U_LIB.S9S_MB_2U(SCH_1):M_C_CPU1_SA_DQS_DP(3)
  45 M_C_CPU1_SA_DQS_DN<3> DQS3_A_C @S9S_MB_2U_LIB.S9S_MB_2U(SCH_1):M_C_CPU1_SA_DQS_DN(3)
 126 M_C_CPU1_SB_DQS_DP<2> DQS2_B_T @S9S_MB_2U_LIB.S9S_MB_2U(SCH_1):M_C_CPU1_SB_DQS_DP(2)
 127 M_C_CPU1_SB_DQS_DN<2> DQS2_B_C @S9S_MB_2U_LIB.S9S_MB_2U(SCH_1):M_C_CPU1_SB_DQS_DN(2)
  33 M_C_CPU1_SA_DQS_DP<2> DQS2_A_T @S9S_MB_2U_LIB.S9S_MB_2U(SCH_1):M_C_CPU1_SA_DQS_DP(2)
  34 M_C_CPU1_SA_DQS_DN<2> DQS2_A_C @S9S_MB_2U_LIB.S9S_MB_2U(SCH_1):M_C_CPU1_SA_DQS_DN(2)
 115 M_C_CPU1_SB_DQS_DP<1> DQS1_B_T @S9S_MB_2U_LIB.S9S_MB_2U(SCH_1):M_C_CPU1_SB_DQS_DP(1)
 116 M_C_CPU1_SB_DQS_DN<1> DQS1_B_C @S9S_MB_2U_LIB.S9S_MB_2U(SCH_1):M_C_CPU1_SB_DQS_DN(1)
  22 M_C_CPU1_SA_DQS_DP<1> DQS1_A_T @S9S_MB_2U_LIB.S9S_MB_2U(SCH_1):M_C_CPU1_SA_DQS_DP(1)
  23 M_C_CPU1_SA_DQS_DN<1> DQS1_A_C @S9S_MB_2U_LIB.S9S_MB_2U(SCH_1):M_C_CPU1_SA_DQS_DN(1)
 104 M_C_CPU1_SB_DQS_DP<0> DQS0_B_T @S9S_MB_2U_LIB.S9S_MB_2U(SCH_1):M_C_CPU1_SB_DQS_DP(0)
 105 M_C_CPU1_SB_DQS_DN<0> DQS0_B_C @S9S_MB_2U_LIB.S9S_MB_2U(SCH_1):M_C_CPU1_SB_DQS_DN(0)
  11 M_C_CPU1_SA_DQS_DP<0> DQS0_A_T @S9S_MB_2U_LIB.S9S_MB_2U(SCH_1):M_C_CPU1_SA_DQS_DP(0)
  12 M_C_CPU1_SA_DQS_DN<0> DQS0_A_C @S9S_MB_2U_LIB.S9S_MB_2U(SCH_1):M_C_CPU1_SA_DQS_DN(0)
 272 M_C_CPU1_SB_DQS_DP<7> DQS7_B_T||TDQS7_B_T @S9S_MB_2U_LIB.S9S_MB_2U(SCH_1):M_C_CPU1_SB_DQS_DP(7)
 282 M_C_CPU1_SB_DQS_DN<8> DQS8_B_C||TDQS8_B_C @S9S_MB_2U_LIB.S9S_MB_2U(SCH_1):M_C_CPU1_SB_DQS_DN(8)
 283 M_C_CPU1_SB_DQS_DP<8> DQS8_B_T||TDQS8_B_T @S9S_MB_2U_LIB.S9S_MB_2U(SCH_1):M_C_CPU1_SB_DQS_DP(8)
 168 M_C_CPU1_SA_DQS_DP<6> DQS6_A_T||TDQS6_A_T @S9S_MB_2U_LIB.S9S_MB_2U(SCH_1):M_C_CPU1_SA_DQS_DP(6)
 178 M_C_CPU1_SA_DQS_DN<7> DQS7_A_C||TDQS7_A_C @S9S_MB_2U_LIB.S9S_MB_2U(SCH_1):M_C_CPU1_SA_DQS_DN(7)

Q_RES_0402LF-49.9,1%,1/16W,CHIA  I180  R3895
   1 I3C_SPD_DDRABCD_CPU1_LVC1_SCL_4      A @S9S_MB_2U_LIB.S9S_MB_2U(SCH_1):I3C_SPD_DDRABCD_CPU1_LVC1_SCL_R5
   2 I3C_SPD_DDRABCD_CPU1_LVC1_SCL      B @S9S_MB_2U_LIB.S9S_MB_2U(SCH_1):I3C_SPD_DDRABCD_CPU1_LVC1_SCL


DRAWING: @S9S_MB_2U_LIB.S9S_MB_2U(SCH_1):PAGE103 

Q_RES_0402LF-84.5K,1%,1/16W,CHA  I2  R47
   1 PD_CHC_CPU1_DIMM2_SAA      A @S9S_MB_2U_LIB.S9S_MB_2U(SCH_1):PD_CHC_CPU1_DIMM2_SAA
   2    GND      B @S9S_MB_2U_LIB.S9S_MB_2U(SCH_1):GND

SCONN288_ADR50017P087CC-SCONN2A  I51  J22
   3 P3V3_AUX VIN_MGMT @S9S_MB_2U_LIB.S9S_MB_2U(SCH_1):P3V3_AUX
   2 TP_CHC_CPU1_DIMM2_FRU_0   RFU0 @S9S_MB_2U_LIB.S9S_MB_2U(SCH_1):TP_CHC_CPU1_DIMM2_FRU_0
 144 TP_CHC_CPU1_DIMM2_FRU_1   RFU1 @S9S_MB_2U_LIB.S9S_MB_2U(SCH_1):TP_CHC_CPU1_DIMM2_FRU_1
 149 TP_CHC_CPU1_DIMM2_FRU_2   RFU2 @S9S_MB_2U_LIB.S9S_MB_2U(SCH_1):TP_CHC_CPU1_DIMM2_FRU_2
 150 TP_CHC_CPU1_DIMM2_FRU_3   RFU3 @S9S_MB_2U_LIB.S9S_MB_2U(SCH_1):TP_CHC_CPU1_DIMM2_FRU_3
 220 TP_CHC_CPU1_DIMM2_FRU_4   RFU4 @S9S_MB_2U_LIB.S9S_MB_2U(SCH_1):TP_CHC_CPU1_DIMM2_FRU_4
 231 TP_CHC_CPU1_DIMM2_FRU_5   RFU5 @S9S_MB_2U_LIB.S9S_MB_2U(SCH_1):TP_CHC_CPU1_DIMM2_FRU_5
 232 TP_CHC_CPU1_DIMM2_FRU_6   RFU6 @S9S_MB_2U_LIB.S9S_MB_2U(SCH_1):TP_CHC_CPU1_DIMM2_FRU_6
 207 RST_M_CD_CPU1_FPGA_N RESET_N @S9S_MB_2U_LIB.S9S_MB_2U(SCH_1):RST_M_CD_CPU1_FPGA_N
 147 PWRGD_CHC_CPU1_DIMM2 PWR_GOOD||FAIL_N @S9S_MB_2U_LIB.S9S_MB_2U(SCH_1):PWRGD_CHC_CPU1_DIMM2
 227 M_C_CPU1_SB_PAR  PAR_B @S9S_MB_2U_LIB.S9S_MB_2U(SCH_1):M_C_CPU1_SB_PAR
  74 M_C_CPU1_SA_PAR  PAR_A @S9S_MB_2U_LIB.S9S_MB_2U(SCH_1):M_C_CPU1_SA_PAR
  87 M_C_CPU1_SB_RSP<1> LBS||RSP_B_N @S9S_MB_2U_LIB.S9S_MB_2U(SCH_1):M_C_CPU1_SB_RSP(1)
  86 M_C_CPU1_SA_RSP<1> LBD||RSP_A_N @S9S_MB_2U_LIB.S9S_MB_2U(SCH_1):M_C_CPU1_SA_RSP(1)
   5 I3C_SPD_DDRABCD_CPU1_LVC1_SDA   HSDA @S9S_MB_2U_LIB.S9S_MB_2U(SCH_1):I3C_SPD_DDRABCD_CPU1_LVC1_SDA
   4 I3C_SPD_DDRABCD_CPU1_LVC1_SCL_5   HSCL @S9S_MB_2U_LIB.S9S_MB_2U(SCH_1):I3C_SPD_DDRABCD_CPU1_LVC1_SCL_R6
 148 PD_CHC_CPU1_DIMM2_SAA    HSA @S9S_MB_2U_LIB.S9S_MB_2U(SCH_1):PD_CHC_CPU1_DIMM2_SAA
 100 M_C_CPU1_SB_DQ<0>  DQ0_B @S9S_MB_2U_LIB.S9S_MB_2U(SCH_1):M_C_CPU1_SB_DQ(0)
 102 M_C_CPU1_SB_DQ<1>  DQ1_B @S9S_MB_2U_LIB.S9S_MB_2U(SCH_1):M_C_CPU1_SB_DQ(1)
 245 M_C_CPU1_SB_DQ<2>  DQ2_B @S9S_MB_2U_LIB.S9S_MB_2U(SCH_1):M_C_CPU1_SB_DQ(2)
 247 M_C_CPU1_SB_DQ<3>  DQ3_B @S9S_MB_2U_LIB.S9S_MB_2U(SCH_1):M_C_CPU1_SB_DQ(3)
 107 M_C_CPU1_SB_DQ<4>  DQ4_B @S9S_MB_2U_LIB.S9S_MB_2U(SCH_1):M_C_CPU1_SB_DQ(4)
 109 M_C_CPU1_SB_DQ<5>  DQ5_B @S9S_MB_2U_LIB.S9S_MB_2U(SCH_1):M_C_CPU1_SB_DQ(5)
 252 M_C_CPU1_SB_DQ<6>  DQ6_B @S9S_MB_2U_LIB.S9S_MB_2U(SCH_1):M_C_CPU1_SB_DQ(6)
 254 M_C_CPU1_SB_DQ<7>  DQ7_B @S9S_MB_2U_LIB.S9S_MB_2U(SCH_1):M_C_CPU1_SB_DQ(7)
 111 M_C_CPU1_SB_DQ<8>  DQ8_B @S9S_MB_2U_LIB.S9S_MB_2U(SCH_1):M_C_CPU1_SB_DQ(8)
 113 M_C_CPU1_SB_DQ<9>  DQ9_B @S9S_MB_2U_LIB.S9S_MB_2U(SCH_1):M_C_CPU1_SB_DQ(9)
 256 M_C_CPU1_SB_DQ<10> DQ10_B @S9S_MB_2U_LIB.S9S_MB_2U(SCH_1):M_C_CPU1_SB_DQ(10)
 258 M_C_CPU1_SB_DQ<11> DQ11_B @S9S_MB_2U_LIB.S9S_MB_2U(SCH_1):M_C_CPU1_SB_DQ(11)
 118 M_C_CPU1_SB_DQ<12> DQ12_B @S9S_MB_2U_LIB.S9S_MB_2U(SCH_1):M_C_CPU1_SB_DQ(12)
 120 M_C_CPU1_SB_DQ<13> DQ13_B @S9S_MB_2U_LIB.S9S_MB_2U(SCH_1):M_C_CPU1_SB_DQ(13)
 263 M_C_CPU1_SB_DQ<14> DQ14_B @S9S_MB_2U_LIB.S9S_MB_2U(SCH_1):M_C_CPU1_SB_DQ(14)
 265 M_C_CPU1_SB_DQ<15> DQ15_B @S9S_MB_2U_LIB.S9S_MB_2U(SCH_1):M_C_CPU1_SB_DQ(15)
 122 M_C_CPU1_SB_DQ<16> DQ16_B @S9S_MB_2U_LIB.S9S_MB_2U(SCH_1):M_C_CPU1_SB_DQ(16)
 124 M_C_CPU1_SB_DQ<17> DQ17_B @S9S_MB_2U_LIB.S9S_MB_2U(SCH_1):M_C_CPU1_SB_DQ(17)
 267 M_C_CPU1_SB_DQ<18> DQ18_B @S9S_MB_2U_LIB.S9S_MB_2U(SCH_1):M_C_CPU1_SB_DQ(18)
 269 M_C_CPU1_SB_DQ<19> DQ19_B @S9S_MB_2U_LIB.S9S_MB_2U(SCH_1):M_C_CPU1_SB_DQ(19)
 129 M_C_CPU1_SB_DQ<20> DQ20_B @S9S_MB_2U_LIB.S9S_MB_2U(SCH_1):M_C_CPU1_SB_DQ(20)
 131 M_C_CPU1_SB_DQ<21> DQ21_B @S9S_MB_2U_LIB.S9S_MB_2U(SCH_1):M_C_CPU1_SB_DQ(21)
 274 M_C_CPU1_SB_DQ<22> DQ22_B @S9S_MB_2U_LIB.S9S_MB_2U(SCH_1):M_C_CPU1_SB_DQ(22)
 276 M_C_CPU1_SB_DQ<23> DQ23_B @S9S_MB_2U_LIB.S9S_MB_2U(SCH_1):M_C_CPU1_SB_DQ(23)
 133 M_C_CPU1_SB_DQ<24> DQ24_B @S9S_MB_2U_LIB.S9S_MB_2U(SCH_1):M_C_CPU1_SB_DQ(24)
 135 M_C_CPU1_SB_DQ<25> DQ25_B @S9S_MB_2U_LIB.S9S_MB_2U(SCH_1):M_C_CPU1_SB_DQ(25)
 278 M_C_CPU1_SB_DQ<26> DQ26_B @S9S_MB_2U_LIB.S9S_MB_2U(SCH_1):M_C_CPU1_SB_DQ(26)
 280 M_C_CPU1_SB_DQ<27> DQ27_B @S9S_MB_2U_LIB.S9S_MB_2U(SCH_1):M_C_CPU1_SB_DQ(27)
 140 M_C_CPU1_SB_DQ<28> DQ28_B @S9S_MB_2U_LIB.S9S_MB_2U(SCH_1):M_C_CPU1_SB_DQ(28)
 142 M_C_CPU1_SB_DQ<29> DQ29_B @S9S_MB_2U_LIB.S9S_MB_2U(SCH_1):M_C_CPU1_SB_DQ(29)
 285 M_C_CPU1_SB_DQ<30> DQ30_B @S9S_MB_2U_LIB.S9S_MB_2U(SCH_1):M_C_CPU1_SB_DQ(30)
 287 M_C_CPU1_SB_DQ<31> DQ31_B @S9S_MB_2U_LIB.S9S_MB_2U(SCH_1):M_C_CPU1_SB_DQ(31)
   7 M_C_CPU1_SA_DQ<0>  DQ0_A @S9S_MB_2U_LIB.S9S_MB_2U(SCH_1):M_C_CPU1_SA_DQ(0)
   9 M_C_CPU1_SA_DQ<1>  DQ1_A @S9S_MB_2U_LIB.S9S_MB_2U(SCH_1):M_C_CPU1_SA_DQ(1)
 152 M_C_CPU1_SA_DQ<2>  DQ2_A @S9S_MB_2U_LIB.S9S_MB_2U(SCH_1):M_C_CPU1_SA_DQ(2)
 154 M_C_CPU1_SA_DQ<3>  DQ3_A @S9S_MB_2U_LIB.S9S_MB_2U(SCH_1):M_C_CPU1_SA_DQ(3)
  14 M_C_CPU1_SA_DQ<4>  DQ4_A @S9S_MB_2U_LIB.S9S_MB_2U(SCH_1):M_C_CPU1_SA_DQ(4)
  16 M_C_CPU1_SA_DQ<5>  DQ5_A @S9S_MB_2U_LIB.S9S_MB_2U(SCH_1):M_C_CPU1_SA_DQ(5)
 159 M_C_CPU1_SA_DQ<6>  DQ6_A @S9S_MB_2U_LIB.S9S_MB_2U(SCH_1):M_C_CPU1_SA_DQ(6)
 161 M_C_CPU1_SA_DQ<7>  DQ7_A @S9S_MB_2U_LIB.S9S_MB_2U(SCH_1):M_C_CPU1_SA_DQ(7)
  18 M_C_CPU1_SA_DQ<8>  DQ8_A @S9S_MB_2U_LIB.S9S_MB_2U(SCH_1):M_C_CPU1_SA_DQ(8)
  20 M_C_CPU1_SA_DQ<9>  DQ9_A @S9S_MB_2U_LIB.S9S_MB_2U(SCH_1):M_C_CPU1_SA_DQ(9)
 163 M_C_CPU1_SA_DQ<10> DQ10_A @S9S_MB_2U_LIB.S9S_MB_2U(SCH_1):M_C_CPU1_SA_DQ(10)
 165 M_C_CPU1_SA_DQ<11> DQ11_A @S9S_MB_2U_LIB.S9S_MB_2U(SCH_1):M_C_CPU1_SA_DQ(11)
  25 M_C_CPU1_SA_DQ<12> DQ12_A @S9S_MB_2U_LIB.S9S_MB_2U(SCH_1):M_C_CPU1_SA_DQ(12)
  27 M_C_CPU1_SA_DQ<13> DQ13_A @S9S_MB_2U_LIB.S9S_MB_2U(SCH_1):M_C_CPU1_SA_DQ(13)
 170 M_C_CPU1_SA_DQ<14> DQ14_A @S9S_MB_2U_LIB.S9S_MB_2U(SCH_1):M_C_CPU1_SA_DQ(14)
 172 M_C_CPU1_SA_DQ<15> DQ15_A @S9S_MB_2U_LIB.S9S_MB_2U(SCH_1):M_C_CPU1_SA_DQ(15)
  29 M_C_CPU1_SA_DQ<16> DQ16_A @S9S_MB_2U_LIB.S9S_MB_2U(SCH_1):M_C_CPU1_SA_DQ(16)
  31 M_C_CPU1_SA_DQ<17> DQ17_A @S9S_MB_2U_LIB.S9S_MB_2U(SCH_1):M_C_CPU1_SA_DQ(17)
 174 M_C_CPU1_SA_DQ<18> DQ18_A @S9S_MB_2U_LIB.S9S_MB_2U(SCH_1):M_C_CPU1_SA_DQ(18)
 176 M_C_CPU1_SA_DQ<19> DQ19_A @S9S_MB_2U_LIB.S9S_MB_2U(SCH_1):M_C_CPU1_SA_DQ(19)
  36 M_C_CPU1_SA_DQ<20> DQ20_A @S9S_MB_2U_LIB.S9S_MB_2U(SCH_1):M_C_CPU1_SA_DQ(20)
  38 M_C_CPU1_SA_DQ<21> DQ21_A @S9S_MB_2U_LIB.S9S_MB_2U(SCH_1):M_C_CPU1_SA_DQ(21)
 181 M_C_CPU1_SA_DQ<22> DQ22_A @S9S_MB_2U_LIB.S9S_MB_2U(SCH_1):M_C_CPU1_SA_DQ(22)
 183 M_C_CPU1_SA_DQ<23> DQ23_A @S9S_MB_2U_LIB.S9S_MB_2U(SCH_1):M_C_CPU1_SA_DQ(23)
  40 M_C_CPU1_SA_DQ<24> DQ24_A @S9S_MB_2U_LIB.S9S_MB_2U(SCH_1):M_C_CPU1_SA_DQ(24)
  42 M_C_CPU1_SA_DQ<25> DQ25_A @S9S_MB_2U_LIB.S9S_MB_2U(SCH_1):M_C_CPU1_SA_DQ(25)
 185 M_C_CPU1_SA_DQ<26> DQ26_A @S9S_MB_2U_LIB.S9S_MB_2U(SCH_1):M_C_CPU1_SA_DQ(26)
 187 M_C_CPU1_SA_DQ<27> DQ27_A @S9S_MB_2U_LIB.S9S_MB_2U(SCH_1):M_C_CPU1_SA_DQ(27)
  47 M_C_CPU1_SA_DQ<28> DQ28_A @S9S_MB_2U_LIB.S9S_MB_2U(SCH_1):M_C_CPU1_SA_DQ(28)
  49 M_C_CPU1_SA_DQ<29> DQ29_A @S9S_MB_2U_LIB.S9S_MB_2U(SCH_1):M_C_CPU1_SA_DQ(29)
 192 M_C_CPU1_SA_DQ<30> DQ30_A @S9S_MB_2U_LIB.S9S_MB_2U(SCH_1):M_C_CPU1_SA_DQ(30)
 229 M_C_CPU1_SB_CS_N<3> CS1_B_N @S9S_MB_2U_LIB.S9S_MB_2U(SCH_1):M_C_CPU1_SB_CS_N(3)
 209 M_C_CPU1_SA_CS_N<3> CS1_A_N @S9S_MB_2U_LIB.S9S_MB_2U(SCH_1):M_C_CPU1_SA_CS_N(3)
  84 M_C_CPU1_SB_CS_N<2> CS0_B_N @S9S_MB_2U_LIB.S9S_MB_2U(SCH_1):M_C_CPU1_SB_CS_N(2)
  64 M_C_CPU1_SA_CS_N<2> CS0_A_N @S9S_MB_2U_LIB.S9S_MB_2U(SCH_1):M_C_CPU1_SA_CS_N(2)
 217 M_C_CPU1_CLK_DP<1>   CK_T @S9S_MB_2U_LIB.S9S_MB_2U(SCH_1):M_C_CPU1_CLK_DP(1)
 218 M_C_CPU1_CLK_DN<1>   CK_C @S9S_MB_2U_LIB.S9S_MB_2U(SCH_1):M_C_CPU1_CLK_DN(1)
  96 M_C_CPU1_SB_CB<0>  CB0_B @S9S_MB_2U_LIB.S9S_MB_2U(SCH_1):M_C_CPU1_SB_CB(0)
  98 M_C_CPU1_SB_CB<1>  CB1_B @S9S_MB_2U_LIB.S9S_MB_2U(SCH_1):M_C_CPU1_SB_CB(1)
 241 M_C_CPU1_SB_CB<2>  CB2_B @S9S_MB_2U_LIB.S9S_MB_2U(SCH_1):M_C_CPU1_SB_CB(2)
 243 M_C_CPU1_SB_CB<3>  CB3_B @S9S_MB_2U_LIB.S9S_MB_2U(SCH_1):M_C_CPU1_SB_CB(3)
  89 M_C_CPU1_SB_CB<4>  CB4_B @S9S_MB_2U_LIB.S9S_MB_2U(SCH_1):M_C_CPU1_SB_CB(4)
  91 M_C_CPU1_SB_CB<5>  CB5_B @S9S_MB_2U_LIB.S9S_MB_2U(SCH_1):M_C_CPU1_SB_CB(5)
 234 M_C_CPU1_SB_CB<6>  CB6_B @S9S_MB_2U_LIB.S9S_MB_2U(SCH_1):M_C_CPU1_SB_CB(6)
  51 M_C_CPU1_SA_CB<0>  CB0_A @S9S_MB_2U_LIB.S9S_MB_2U(SCH_1):M_C_CPU1_SA_CB(0)
 196 M_C_CPU1_SA_CB<2>  CB2_A @S9S_MB_2U_LIB.S9S_MB_2U(SCH_1):M_C_CPU1_SA_CB(2)
 198 M_C_CPU1_SA_CB<3>  CB3_A @S9S_MB_2U_LIB.S9S_MB_2U(SCH_1):M_C_CPU1_SA_CB(3)
  60 M_C_CPU1_SA_CB<5>  CB5_A @S9S_MB_2U_LIB.S9S_MB_2U(SCH_1):M_C_CPU1_SA_CB(5)
 203 M_C_CPU1_SA_CB<6>  CB6_A @S9S_MB_2U_LIB.S9S_MB_2U(SCH_1):M_C_CPU1_SA_CB(6)
  82 M_C_CPU1_SB_CA<6>  CA6_B @S9S_MB_2U_LIB.S9S_MB_2U(SCH_1):M_C_CPU1_SB_CA(6)
  72 M_C_CPU1_SA_CA<6>  CA6_A @S9S_MB_2U_LIB.S9S_MB_2U(SCH_1):M_C_CPU1_SA_CA(6)
 225 M_C_CPU1_SB_CA<5>  CA5_B @S9S_MB_2U_LIB.S9S_MB_2U(SCH_1):M_C_CPU1_SB_CA(5)
 215 M_C_CPU1_SA_CA<5>  CA5_A @S9S_MB_2U_LIB.S9S_MB_2U(SCH_1):M_C_CPU1_SA_CA(5)
  80 M_C_CPU1_SB_CA<4>  CA4_B @S9S_MB_2U_LIB.S9S_MB_2U(SCH_1):M_C_CPU1_SB_CA(4)
  70 M_C_CPU1_SA_CA<4>  CA4_A @S9S_MB_2U_LIB.S9S_MB_2U(SCH_1):M_C_CPU1_SA_CA(4)
 223 M_C_CPU1_SB_CA<3>  CA3_B @S9S_MB_2U_LIB.S9S_MB_2U(SCH_1):M_C_CPU1_SB_CA(3)
 213 M_C_CPU1_SA_CA<3>  CA3_A @S9S_MB_2U_LIB.S9S_MB_2U(SCH_1):M_C_CPU1_SA_CA(3)
  78 M_C_CPU1_SB_CA<2>  CA2_B @S9S_MB_2U_LIB.S9S_MB_2U(SCH_1):M_C_CPU1_SB_CA(2)
  68 M_C_CPU1_SA_CA<2>  CA2_A @S9S_MB_2U_LIB.S9S_MB_2U(SCH_1):M_C_CPU1_SA_CA(2)
 221 M_C_CPU1_SB_CA<1>  CA1_B @S9S_MB_2U_LIB.S9S_MB_2U(SCH_1):M_C_CPU1_SB_CA(1)
 211 M_C_CPU1_SA_CA<1>  CA1_A @S9S_MB_2U_LIB.S9S_MB_2U(SCH_1):M_C_CPU1_SA_CA(1)
  76 M_C_CPU1_SB_CA<0>  CA0_B @S9S_MB_2U_LIB.S9S_MB_2U(SCH_1):M_C_CPU1_SB_CA(0)
  66 M_C_CPU1_SA_CA<0>  CA0_A @S9S_MB_2U_LIB.S9S_MB_2U(SCH_1):M_C_CPU1_SA_CA(0)
  62 M_C_CPU1_ALERT_N ALERT_N @S9S_MB_2U_LIB.S9S_MB_2U(SCH_1):M_C_CPU1_ALERT_N
 236 M_C_CPU1_SB_CB<7>  CB7_B @S9S_MB_2U_LIB.S9S_MB_2U(SCH_1):M_C_CPU1_SB_CB(7)
  53 M_C_CPU1_SA_CB<1>  CB1_A @S9S_MB_2U_LIB.S9S_MB_2U(SCH_1):M_C_CPU1_SA_CB(1)
  58 M_C_CPU1_SA_CB<4>  CB4_A @S9S_MB_2U_LIB.S9S_MB_2U(SCH_1):M_C_CPU1_SA_CB(4)
 205 M_C_CPU1_SA_CB<7>  CB7_A @S9S_MB_2U_LIB.S9S_MB_2U(SCH_1):M_C_CPU1_SA_CB(7)
 194 M_C_CPU1_SA_DQ<31> DQ31_A @S9S_MB_2U_LIB.S9S_MB_2U(SCH_1):M_C_CPU1_SA_DQ(31)

Q_CAP_C0402-2.2UF,6.3V,20%,X6SA  I122  C65
   1 P3V3_AUX      A @S9S_MB_2U_LIB.S9S_MB_2U(SCH_1):P3V3_AUX
   2    GND      B @S9S_MB_2U_LIB.S9S_MB_2U(SCH_1):GND

Q_CAP_C0805-10UF,16V,10%,X6S,CA  I126  C66
   1 P12V_S3_AUX_CPU1_NVDIMM      A @S9S_MB_2U_LIB.S9S_MB_2U(SCH_1):P12V_S3_AUX_CPU1_NVDIMM
   2    GND      B @S9S_MB_2U_LIB.S9S_MB_2U(SCH_1):GND

Q_CAP_C0805-10UF,16V,10%,X6S,CA  I128  C67
   1 P12V_S3_AUX_CPU1_NVDIMM      A @S9S_MB_2U_LIB.S9S_MB_2U(SCH_1):P12V_S3_AUX_CPU1_NVDIMM
   2    GND      B @S9S_MB_2U_LIB.S9S_MB_2U(SCH_1):GND

SCONN288_ADR50017P087CC-SCONN2A  I176  J22
   6    GND   VSS0 @S9S_MB_2U_LIB.S9S_MB_2U(SCH_1):GND
   8    GND   VSS1 @S9S_MB_2U_LIB.S9S_MB_2U(SCH_1):GND
  10    GND   VSS2 @S9S_MB_2U_LIB.S9S_MB_2U(SCH_1):GND
  13    GND   VSS3 @S9S_MB_2U_LIB.S9S_MB_2U(SCH_1):GND
  15    GND   VSS4 @S9S_MB_2U_LIB.S9S_MB_2U(SCH_1):GND
  17    GND   VSS5 @S9S_MB_2U_LIB.S9S_MB_2U(SCH_1):GND
  19    GND   VSS6 @S9S_MB_2U_LIB.S9S_MB_2U(SCH_1):GND
  21    GND   VSS7 @S9S_MB_2U_LIB.S9S_MB_2U(SCH_1):GND
  24    GND   VSS8 @S9S_MB_2U_LIB.S9S_MB_2U(SCH_1):GND
  26    GND   VSS9 @S9S_MB_2U_LIB.S9S_MB_2U(SCH_1):GND
  28    GND  VSS10 @S9S_MB_2U_LIB.S9S_MB_2U(SCH_1):GND
  30    GND  VSS11 @S9S_MB_2U_LIB.S9S_MB_2U(SCH_1):GND
  32    GND  VSS12 @S9S_MB_2U_LIB.S9S_MB_2U(SCH_1):GND
  35    GND  VSS13 @S9S_MB_2U_LIB.S9S_MB_2U(SCH_1):GND
  37    GND  VSS14 @S9S_MB_2U_LIB.S9S_MB_2U(SCH_1):GND
  39    GND  VSS15 @S9S_MB_2U_LIB.S9S_MB_2U(SCH_1):GND
  41    GND  VSS16 @S9S_MB_2U_LIB.S9S_MB_2U(SCH_1):GND
  43    GND  VSS17 @S9S_MB_2U_LIB.S9S_MB_2U(SCH_1):GND
  46    GND  VSS18 @S9S_MB_2U_LIB.S9S_MB_2U(SCH_1):GND
  48    GND  VSS19 @S9S_MB_2U_LIB.S9S_MB_2U(SCH_1):GND
  50    GND  VSS20 @S9S_MB_2U_LIB.S9S_MB_2U(SCH_1):GND
  52    GND  VSS21 @S9S_MB_2U_LIB.S9S_MB_2U(SCH_1):GND
  54    GND  VSS22 @S9S_MB_2U_LIB.S9S_MB_2U(SCH_1):GND
  57    GND  VSS23 @S9S_MB_2U_LIB.S9S_MB_2U(SCH_1):GND
  59    GND  VSS24 @S9S_MB_2U_LIB.S9S_MB_2U(SCH_1):GND
  61    GND  VSS25 @S9S_MB_2U_LIB.S9S_MB_2U(SCH_1):GND
  63    GND  VSS26 @S9S_MB_2U_LIB.S9S_MB_2U(SCH_1):GND
  65    GND  VSS27 @S9S_MB_2U_LIB.S9S_MB_2U(SCH_1):GND
  67    GND  VSS28 @S9S_MB_2U_LIB.S9S_MB_2U(SCH_1):GND
  69    GND  VSS29 @S9S_MB_2U_LIB.S9S_MB_2U(SCH_1):GND
  71    GND  VSS30 @S9S_MB_2U_LIB.S9S_MB_2U(SCH_1):GND
  73    GND  VSS31 @S9S_MB_2U_LIB.S9S_MB_2U(SCH_1):GND
  75    GND  VSS32 @S9S_MB_2U_LIB.S9S_MB_2U(SCH_1):GND
  77    GND  VSS33 @S9S_MB_2U_LIB.S9S_MB_2U(SCH_1):GND
  79    GND  VSS34 @S9S_MB_2U_LIB.S9S_MB_2U(SCH_1):GND
  81    GND  VSS35 @S9S_MB_2U_LIB.S9S_MB_2U(SCH_1):GND
  83    GND  VSS36 @S9S_MB_2U_LIB.S9S_MB_2U(SCH_1):GND
  85    GND  VSS37 @S9S_MB_2U_LIB.S9S_MB_2U(SCH_1):GND
  88    GND  VSS38 @S9S_MB_2U_LIB.S9S_MB_2U(SCH_1):GND
  90    GND  VSS39 @S9S_MB_2U_LIB.S9S_MB_2U(SCH_1):GND
  92    GND  VSS40 @S9S_MB_2U_LIB.S9S_MB_2U(SCH_1):GND
  95    GND  VSS41 @S9S_MB_2U_LIB.S9S_MB_2U(SCH_1):GND
  97    GND  VSS42 @S9S_MB_2U_LIB.S9S_MB_2U(SCH_1):GND
  99    GND  VSS43 @S9S_MB_2U_LIB.S9S_MB_2U(SCH_1):GND
 101    GND  VSS44 @S9S_MB_2U_LIB.S9S_MB_2U(SCH_1):GND
 103    GND  VSS45 @S9S_MB_2U_LIB.S9S_MB_2U(SCH_1):GND
 106    GND  VSS46 @S9S_MB_2U_LIB.S9S_MB_2U(SCH_1):GND
 108    GND  VSS47 @S9S_MB_2U_LIB.S9S_MB_2U(SCH_1):GND
 110    GND  VSS48 @S9S_MB_2U_LIB.S9S_MB_2U(SCH_1):GND
 112    GND  VSS49 @S9S_MB_2U_LIB.S9S_MB_2U(SCH_1):GND
 114    GND  VSS50 @S9S_MB_2U_LIB.S9S_MB_2U(SCH_1):GND
 117    GND  VSS51 @S9S_MB_2U_LIB.S9S_MB_2U(SCH_1):GND
 119    GND  VSS52 @S9S_MB_2U_LIB.S9S_MB_2U(SCH_1):GND
 121    GND  VSS53 @S9S_MB_2U_LIB.S9S_MB_2U(SCH_1):GND
 123    GND  VSS54 @S9S_MB_2U_LIB.S9S_MB_2U(SCH_1):GND
 125    GND  VSS55 @S9S_MB_2U_LIB.S9S_MB_2U(SCH_1):GND
 128    GND  VSS56 @S9S_MB_2U_LIB.S9S_MB_2U(SCH_1):GND
 130    GND  VSS57 @S9S_MB_2U_LIB.S9S_MB_2U(SCH_1):GND
 134    GND  VSS59 @S9S_MB_2U_LIB.S9S_MB_2U(SCH_1):GND
 143    GND  VSS63 @S9S_MB_2U_LIB.S9S_MB_2U(SCH_1):GND
 151    GND  VSS64 @S9S_MB_2U_LIB.S9S_MB_2U(SCH_1):GND
 153    GND  VSS65 @S9S_MB_2U_LIB.S9S_MB_2U(SCH_1):GND
 155    GND  VSS66 @S9S_MB_2U_LIB.S9S_MB_2U(SCH_1):GND
 158    GND  VSS67 @S9S_MB_2U_LIB.S9S_MB_2U(SCH_1):GND
 160    GND  VSS68 @S9S_MB_2U_LIB.S9S_MB_2U(SCH_1):GND
 162    GND  VSS69 @S9S_MB_2U_LIB.S9S_MB_2U(SCH_1):GND
 164    GND  VSS70 @S9S_MB_2U_LIB.S9S_MB_2U(SCH_1):GND
 166    GND  VSS71 @S9S_MB_2U_LIB.S9S_MB_2U(SCH_1):GND
 169    GND  VSS72 @S9S_MB_2U_LIB.S9S_MB_2U(SCH_1):GND
 171    GND  VSS73 @S9S_MB_2U_LIB.S9S_MB_2U(SCH_1):GND
 173    GND  VSS74 @S9S_MB_2U_LIB.S9S_MB_2U(SCH_1):GND
 175    GND  VSS75 @S9S_MB_2U_LIB.S9S_MB_2U(SCH_1):GND
 177    GND  VSS76 @S9S_MB_2U_LIB.S9S_MB_2U(SCH_1):GND
 180    GND  VSS77 @S9S_MB_2U_LIB.S9S_MB_2U(SCH_1):GND
 182    GND  VSS78 @S9S_MB_2U_LIB.S9S_MB_2U(SCH_1):GND
 184    GND  VSS79 @S9S_MB_2U_LIB.S9S_MB_2U(SCH_1):GND
 186    GND  VSS80 @S9S_MB_2U_LIB.S9S_MB_2U(SCH_1):GND
 188    GND  VSS81 @S9S_MB_2U_LIB.S9S_MB_2U(SCH_1):GND
 191    GND  VSS82 @S9S_MB_2U_LIB.S9S_MB_2U(SCH_1):GND
 193    GND  VSS83 @S9S_MB_2U_LIB.S9S_MB_2U(SCH_1):GND
 195    GND  VSS84 @S9S_MB_2U_LIB.S9S_MB_2U(SCH_1):GND
 197    GND  VSS85 @S9S_MB_2U_LIB.S9S_MB_2U(SCH_1):GND
 199    GND  VSS86 @S9S_MB_2U_LIB.S9S_MB_2U(SCH_1):GND
 202    GND  VSS87 @S9S_MB_2U_LIB.S9S_MB_2U(SCH_1):GND
 204    GND  VSS88 @S9S_MB_2U_LIB.S9S_MB_2U(SCH_1):GND
 206    GND  VSS89 @S9S_MB_2U_LIB.S9S_MB_2U(SCH_1):GND
 208    GND  VSS90 @S9S_MB_2U_LIB.S9S_MB_2U(SCH_1):GND
 210    GND  VSS91 @S9S_MB_2U_LIB.S9S_MB_2U(SCH_1):GND
 212    GND  VSS92 @S9S_MB_2U_LIB.S9S_MB_2U(SCH_1):GND
 214    GND  VSS93 @S9S_MB_2U_LIB.S9S_MB_2U(SCH_1):GND
 216    GND  VSS94 @S9S_MB_2U_LIB.S9S_MB_2U(SCH_1):GND
 219    GND  VSS95 @S9S_MB_2U_LIB.S9S_MB_2U(SCH_1):GND
 222    GND  VSS96 @S9S_MB_2U_LIB.S9S_MB_2U(SCH_1):GND
 224    GND  VSS97 @S9S_MB_2U_LIB.S9S_MB_2U(SCH_1):GND
 226    GND  VSS98 @S9S_MB_2U_LIB.S9S_MB_2U(SCH_1):GND
 228    GND  VSS99 @S9S_MB_2U_LIB.S9S_MB_2U(SCH_1):GND
 233    GND VSS101 @S9S_MB_2U_LIB.S9S_MB_2U(SCH_1):GND
 237    GND VSS103 @S9S_MB_2U_LIB.S9S_MB_2U(SCH_1):GND
 242    GND VSS105 @S9S_MB_2U_LIB.S9S_MB_2U(SCH_1):GND
 244    GND VSS106 @S9S_MB_2U_LIB.S9S_MB_2U(SCH_1):GND
 246    GND VSS107 @S9S_MB_2U_LIB.S9S_MB_2U(SCH_1):GND
 248    GND VSS108 @S9S_MB_2U_LIB.S9S_MB_2U(SCH_1):GND
 251    GND VSS109 @S9S_MB_2U_LIB.S9S_MB_2U(SCH_1):GND
 253    GND VSS110 @S9S_MB_2U_LIB.S9S_MB_2U(SCH_1):GND
 255    GND VSS111 @S9S_MB_2U_LIB.S9S_MB_2U(SCH_1):GND
 257    GND VSS112 @S9S_MB_2U_LIB.S9S_MB_2U(SCH_1):GND
 259    GND VSS113 @S9S_MB_2U_LIB.S9S_MB_2U(SCH_1):GND
 262    GND VSS114 @S9S_MB_2U_LIB.S9S_MB_2U(SCH_1):GND
 264    GND VSS115 @S9S_MB_2U_LIB.S9S_MB_2U(SCH_1):GND
 266    GND VSS116 @S9S_MB_2U_LIB.S9S_MB_2U(SCH_1):GND
 268    GND VSS117 @S9S_MB_2U_LIB.S9S_MB_2U(SCH_1):GND
 270    GND VSS118 @S9S_MB_2U_LIB.S9S_MB_2U(SCH_1):GND
 273    GND VSS119 @S9S_MB_2U_LIB.S9S_MB_2U(SCH_1):GND
 275    GND VSS120 @S9S_MB_2U_LIB.S9S_MB_2U(SCH_1):GND
 277    GND VSS121 @S9S_MB_2U_LIB.S9S_MB_2U(SCH_1):GND
 279    GND VSS122 @S9S_MB_2U_LIB.S9S_MB_2U(SCH_1):GND
 281    GND VSS123 @S9S_MB_2U_LIB.S9S_MB_2U(SCH_1):GND
 284    GND VSS124 @S9S_MB_2U_LIB.S9S_MB_2U(SCH_1):GND
 286    GND VSS125 @S9S_MB_2U_LIB.S9S_MB_2U(SCH_1):GND
 288    GND VSS126 @S9S_MB_2U_LIB.S9S_MB_2U(SCH_1):GND
   1 P12V_S3_AUX_CPU1_NVDIMM VIN_BULK0 @S9S_MB_2U_LIB.S9S_MB_2U(SCH_1):P12V_S3_AUX_CPU1_NVDIMM
 145 P12V_S3_AUX_CPU1_NVDIMM VIN_BULK1 @S9S_MB_2U_LIB.S9S_MB_2U(SCH_1):P12V_S3_AUX_CPU1_NVDIMM
 146 P12V_S3_AUX_CPU1_NVDIMM VIN_BULK2 @S9S_MB_2U_LIB.S9S_MB_2U(SCH_1):P12V_S3_AUX_CPU1_NVDIMM
 230    GND VSS100 @S9S_MB_2U_LIB.S9S_MB_2U(SCH_1):GND
 235    GND VSS102 @S9S_MB_2U_LIB.S9S_MB_2U(SCH_1):GND
 240    GND VSS104 @S9S_MB_2U_LIB.S9S_MB_2U(SCH_1):GND
 132    GND  VSS58 @S9S_MB_2U_LIB.S9S_MB_2U(SCH_1):GND
 136    GND  VSS60 @S9S_MB_2U_LIB.S9S_MB_2U(SCH_1):GND
 139    GND  VSS61 @S9S_MB_2U_LIB.S9S_MB_2U(SCH_1):GND
 141    GND  VSS62 @S9S_MB_2U_LIB.S9S_MB_2U(SCH_1):GND
  G1    GND     G1 @S9S_MB_2U_LIB.S9S_MB_2U(SCH_1):GND
  G2    GND     G2 @S9S_MB_2U_LIB.S9S_MB_2U(SCH_1):GND
  G3    GND     G3 @S9S_MB_2U_LIB.S9S_MB_2U(SCH_1):GND

SCONN288_ADR50017P087CC-SCONN2A  I178  J22
  93 M_C_CPU1_SB_DQS_DP<9> DQS9_B_T||TDQS9_B_T||DBI4_B_N @S9S_MB_2U_LIB.S9S_MB_2U(SCH_1):M_C_CPU1_SB_DQS_DP(9)
  94 M_C_CPU1_SB_DQS_DN<9> DQS9_B_C||TDQS9_B_C @S9S_MB_2U_LIB.S9S_MB_2U(SCH_1):M_C_CPU1_SB_DQS_DN(9)
 201 M_C_CPU1_SA_DQS_DP<9> DQS9_A_T||TDQS9_A_T @S9S_MB_2U_LIB.S9S_MB_2U(SCH_1):M_C_CPU1_SA_DQS_DP(9)
 200 M_C_CPU1_SA_DQS_DN<9> DQS9_A_C||TDQS9_A_C @S9S_MB_2U_LIB.S9S_MB_2U(SCH_1):M_C_CPU1_SA_DQS_DN(9)
 190 M_C_CPU1_SA_DQS_DP<8> DQS8_A_T||TDQS8_A_T @S9S_MB_2U_LIB.S9S_MB_2U(SCH_1):M_C_CPU1_SA_DQS_DP(8)
 189 M_C_CPU1_SA_DQS_DN<8> DQS8_A_C||TDQS8_A_C @S9S_MB_2U_LIB.S9S_MB_2U(SCH_1):M_C_CPU1_SA_DQS_DN(8)
 271 M_C_CPU1_SB_DQS_DN<7> DQS7_B_C||TDQS7_B_C @S9S_MB_2U_LIB.S9S_MB_2U(SCH_1):M_C_CPU1_SB_DQS_DN(7)
 179 M_C_CPU1_SA_DQS_DP<7> DQS7_A_T||TDQS7_A_T @S9S_MB_2U_LIB.S9S_MB_2U(SCH_1):M_C_CPU1_SA_DQS_DP(7)
 261 M_C_CPU1_SB_DQS_DP<6> DQS6_B_T||TDQS6_B_T @S9S_MB_2U_LIB.S9S_MB_2U(SCH_1):M_C_CPU1_SB_DQS_DP(6)
 260 M_C_CPU1_SB_DQS_DN<6> DQS6_B_C||TDQS6_B_C @S9S_MB_2U_LIB.S9S_MB_2U(SCH_1):M_C_CPU1_SB_DQS_DN(6)
 167 M_C_CPU1_SA_DQS_DN<6> DQS6_A_C||TDQS6_A_C||DQS6_A_T||TDQS6_A_T @S9S_MB_2U_LIB.S9S_MB_2U(SCH_1):M_C_CPU1_SA_DQS_DN(6)
 250 M_C_CPU1_SB_DQS_DP<5> DQS5_B_T||TDQS5_B_T @S9S_MB_2U_LIB.S9S_MB_2U(SCH_1):M_C_CPU1_SB_DQS_DP(5)
 249 M_C_CPU1_SB_DQS_DN<5> DQS5_B_C||TDQS5_B_C @S9S_MB_2U_LIB.S9S_MB_2U(SCH_1):M_C_CPU1_SB_DQS_DN(5)
 157 M_C_CPU1_SA_DQS_DP<5> DQS5_A_T||TDQS5_A_T @S9S_MB_2U_LIB.S9S_MB_2U(SCH_1):M_C_CPU1_SA_DQS_DP(5)
 156 M_C_CPU1_SA_DQS_DN<5> DQS5_A_C||TDQS5_A_C||DQS5_A_T||TDQS5_A_T @S9S_MB_2U_LIB.S9S_MB_2U(SCH_1):M_C_CPU1_SA_DQS_DN(5)
 239 M_C_CPU1_SB_DQS_DP<4> DQS4_B_T @S9S_MB_2U_LIB.S9S_MB_2U(SCH_1):M_C_CPU1_SB_DQS_DP(4)
 238 M_C_CPU1_SB_DQS_DN<4> DQS4_B_C @S9S_MB_2U_LIB.S9S_MB_2U(SCH_1):M_C_CPU1_SB_DQS_DN(4)
  55 M_C_CPU1_SA_DQS_DP<4> DQS4_A_T @S9S_MB_2U_LIB.S9S_MB_2U(SCH_1):M_C_CPU1_SA_DQS_DP(4)
  56 M_C_CPU1_SA_DQS_DN<4> DQS4_A_C @S9S_MB_2U_LIB.S9S_MB_2U(SCH_1):M_C_CPU1_SA_DQS_DN(4)
 137 M_C_CPU1_SB_DQS_DP<3> DQS3_B_T @S9S_MB_2U_LIB.S9S_MB_2U(SCH_1):M_C_CPU1_SB_DQS_DP(3)
 138 M_C_CPU1_SB_DQS_DN<3> DQS3_B_C @S9S_MB_2U_LIB.S9S_MB_2U(SCH_1):M_C_CPU1_SB_DQS_DN(3)
  44 M_C_CPU1_SA_DQS_DP<3> DQS3_A_T @S9S_MB_2U_LIB.S9S_MB_2U(SCH_1):M_C_CPU1_SA_DQS_DP(3)
  45 M_C_CPU1_SA_DQS_DN<3> DQS3_A_C @S9S_MB_2U_LIB.S9S_MB_2U(SCH_1):M_C_CPU1_SA_DQS_DN(3)
 126 M_C_CPU1_SB_DQS_DP<2> DQS2_B_T @S9S_MB_2U_LIB.S9S_MB_2U(SCH_1):M_C_CPU1_SB_DQS_DP(2)
 127 M_C_CPU1_SB_DQS_DN<2> DQS2_B_C @S9S_MB_2U_LIB.S9S_MB_2U(SCH_1):M_C_CPU1_SB_DQS_DN(2)
  33 M_C_CPU1_SA_DQS_DP<2> DQS2_A_T @S9S_MB_2U_LIB.S9S_MB_2U(SCH_1):M_C_CPU1_SA_DQS_DP(2)
  34 M_C_CPU1_SA_DQS_DN<2> DQS2_A_C @S9S_MB_2U_LIB.S9S_MB_2U(SCH_1):M_C_CPU1_SA_DQS_DN(2)
 115 M_C_CPU1_SB_DQS_DP<1> DQS1_B_T @S9S_MB_2U_LIB.S9S_MB_2U(SCH_1):M_C_CPU1_SB_DQS_DP(1)
 116 M_C_CPU1_SB_DQS_DN<1> DQS1_B_C @S9S_MB_2U_LIB.S9S_MB_2U(SCH_1):M_C_CPU1_SB_DQS_DN(1)
  22 M_C_CPU1_SA_DQS_DP<1> DQS1_A_T @S9S_MB_2U_LIB.S9S_MB_2U(SCH_1):M_C_CPU1_SA_DQS_DP(1)
  23 M_C_CPU1_SA_DQS_DN<1> DQS1_A_C @S9S_MB_2U_LIB.S9S_MB_2U(SCH_1):M_C_CPU1_SA_DQS_DN(1)
 104 M_C_CPU1_SB_DQS_DP<0> DQS0_B_T @S9S_MB_2U_LIB.S9S_MB_2U(SCH_1):M_C_CPU1_SB_DQS_DP(0)
 105 M_C_CPU1_SB_DQS_DN<0> DQS0_B_C @S9S_MB_2U_LIB.S9S_MB_2U(SCH_1):M_C_CPU1_SB_DQS_DN(0)
  11 M_C_CPU1_SA_DQS_DP<0> DQS0_A_T @S9S_MB_2U_LIB.S9S_MB_2U(SCH_1):M_C_CPU1_SA_DQS_DP(0)
  12 M_C_CPU1_SA_DQS_DN<0> DQS0_A_C @S9S_MB_2U_LIB.S9S_MB_2U(SCH_1):M_C_CPU1_SA_DQS_DN(0)
 272 M_C_CPU1_SB_DQS_DP<7> DQS7_B_T||TDQS7_B_T @S9S_MB_2U_LIB.S9S_MB_2U(SCH_1):M_C_CPU1_SB_DQS_DP(7)
 282 M_C_CPU1_SB_DQS_DN<8> DQS8_B_C||TDQS8_B_C @S9S_MB_2U_LIB.S9S_MB_2U(SCH_1):M_C_CPU1_SB_DQS_DN(8)
 283 M_C_CPU1_SB_DQS_DP<8> DQS8_B_T||TDQS8_B_T @S9S_MB_2U_LIB.S9S_MB_2U(SCH_1):M_C_CPU1_SB_DQS_DP(8)
 168 M_C_CPU1_SA_DQS_DP<6> DQS6_A_T||TDQS6_A_T @S9S_MB_2U_LIB.S9S_MB_2U(SCH_1):M_C_CPU1_SA_DQS_DP(6)
 178 M_C_CPU1_SA_DQS_DN<7> DQS7_A_C||TDQS7_A_C @S9S_MB_2U_LIB.S9S_MB_2U(SCH_1):M_C_CPU1_SA_DQS_DN(7)

Q_RES_0402LF-49.9,1%,1/16W,CHIA  I180  R3896
   1 I3C_SPD_DDRABCD_CPU1_LVC1_SCL_5      A @S9S_MB_2U_LIB.S9S_MB_2U(SCH_1):I3C_SPD_DDRABCD_CPU1_LVC1_SCL_R6
   2 I3C_SPD_DDRABCD_CPU1_LVC1_SCL      B @S9S_MB_2U_LIB.S9S_MB_2U(SCH_1):I3C_SPD_DDRABCD_CPU1_LVC1_SCL


DRAWING: @S9S_MB_2U_LIB.S9S_MB_2U(SCH_1):PAGE104 

Q_RES_0402LF-127K,1%,1/16W,CHIA  I2  R48
   1 PD_CHD_CPU1_DIMM1_SAA      A @S9S_MB_2U_LIB.S9S_MB_2U(SCH_1):PD_CHD_CPU1_DIMM1_SAA
   2    GND      B @S9S_MB_2U_LIB.S9S_MB_2U(SCH_1):GND

SCONN288_ADR50017P130CC-SCONN2A  I25  J23
   3 P3V3_AUX VIN_MGMT @S9S_MB_2U_LIB.S9S_MB_2U(SCH_1):P3V3_AUX
   2 TP_CHD_CPU1_DIMM1_FRU_0   RFU0 @S9S_MB_2U_LIB.S9S_MB_2U(SCH_1):TP_CHD_CPU1_DIMM1_FRU_0
 144 TP_CHD_CPU1_DIMM1_FRU_1   RFU1 @S9S_MB_2U_LIB.S9S_MB_2U(SCH_1):TP_CHD_CPU1_DIMM1_FRU_1
 149 TP_CHD_CPU1_DIMM1_FRU_2   RFU2 @S9S_MB_2U_LIB.S9S_MB_2U(SCH_1):TP_CHD_CPU1_DIMM1_FRU_2
 150 TP_CHD_CPU1_DIMM1_FRU_3   RFU3 @S9S_MB_2U_LIB.S9S_MB_2U(SCH_1):TP_CHD_CPU1_DIMM1_FRU_3
 220 TP_CHD_CPU1_DIMM1_FRU_4   RFU4 @S9S_MB_2U_LIB.S9S_MB_2U(SCH_1):TP_CHD_CPU1_DIMM1_FRU_4
 231 TP_CHD_CPU1_DIMM1_FRU_5   RFU5 @S9S_MB_2U_LIB.S9S_MB_2U(SCH_1):TP_CHD_CPU1_DIMM1_FRU_5
 232 TP_CHD_CPU1_DIMM1_FRU_6   RFU6 @S9S_MB_2U_LIB.S9S_MB_2U(SCH_1):TP_CHD_CPU1_DIMM1_FRU_6
 207 RST_M_CD_CPU1_FPGA_N RESET_N @S9S_MB_2U_LIB.S9S_MB_2U(SCH_1):RST_M_CD_CPU1_FPGA_N
 147 PWRGD_CHD_CPU1_DIMM1 PWR_GOOD||FAIL_N @S9S_MB_2U_LIB.S9S_MB_2U(SCH_1):PWRGD_CHD_CPU1_DIMM1
 227 M_D_CPU1_SB_PAR  PAR_B @S9S_MB_2U_LIB.S9S_MB_2U(SCH_1):M_D_CPU1_SB_PAR
  74 M_D_CPU1_SA_PAR  PAR_A @S9S_MB_2U_LIB.S9S_MB_2U(SCH_1):M_D_CPU1_SA_PAR
  87 M_D_CPU1_SB_RSP<0> LBS||RSP_B_N @S9S_MB_2U_LIB.S9S_MB_2U(SCH_1):M_D_CPU1_SB_RSP(0)
  86 M_D_CPU1_SA_RSP<0> LBD||RSP_A_N @S9S_MB_2U_LIB.S9S_MB_2U(SCH_1):M_D_CPU1_SA_RSP(0)
   5 I3C_SPD_DDRABCD_CPU1_LVC1_SDA   HSDA @S9S_MB_2U_LIB.S9S_MB_2U(SCH_1):I3C_SPD_DDRABCD_CPU1_LVC1_SDA
   4 I3C_SPD_DDRABCD_CPU1_LVC1_SCL_6   HSCL @S9S_MB_2U_LIB.S9S_MB_2U(SCH_1):I3C_SPD_DDRABCD_CPU1_LVC1_SCL_R7
 148 PD_CHD_CPU1_DIMM1_SAA    HSA @S9S_MB_2U_LIB.S9S_MB_2U(SCH_1):PD_CHD_CPU1_DIMM1_SAA
 100 M_D_CPU1_SB_DQ<0>  DQ0_B @S9S_MB_2U_LIB.S9S_MB_2U(SCH_1):M_D_CPU1_SB_DQ(0)
 102 M_D_CPU1_SB_DQ<1>  DQ1_B @S9S_MB_2U_LIB.S9S_MB_2U(SCH_1):M_D_CPU1_SB_DQ(1)
 245 M_D_CPU1_SB_DQ<2>  DQ2_B @S9S_MB_2U_LIB.S9S_MB_2U(SCH_1):M_D_CPU1_SB_DQ(2)
 247 M_D_CPU1_SB_DQ<3>  DQ3_B @S9S_MB_2U_LIB.S9S_MB_2U(SCH_1):M_D_CPU1_SB_DQ(3)
 107 M_D_CPU1_SB_DQ<4>  DQ4_B @S9S_MB_2U_LIB.S9S_MB_2U(SCH_1):M_D_CPU1_SB_DQ(4)
 109 M_D_CPU1_SB_DQ<5>  DQ5_B @S9S_MB_2U_LIB.S9S_MB_2U(SCH_1):M_D_CPU1_SB_DQ(5)
 252 M_D_CPU1_SB_DQ<6>  DQ6_B @S9S_MB_2U_LIB.S9S_MB_2U(SCH_1):M_D_CPU1_SB_DQ(6)
 254 M_D_CPU1_SB_DQ<7>  DQ7_B @S9S_MB_2U_LIB.S9S_MB_2U(SCH_1):M_D_CPU1_SB_DQ(7)
 111 M_D_CPU1_SB_DQ<8>  DQ8_B @S9S_MB_2U_LIB.S9S_MB_2U(SCH_1):M_D_CPU1_SB_DQ(8)
 113 M_D_CPU1_SB_DQ<9>  DQ9_B @S9S_MB_2U_LIB.S9S_MB_2U(SCH_1):M_D_CPU1_SB_DQ(9)
 256 M_D_CPU1_SB_DQ<10> DQ10_B @S9S_MB_2U_LIB.S9S_MB_2U(SCH_1):M_D_CPU1_SB_DQ(10)
 258 M_D_CPU1_SB_DQ<11> DQ11_B @S9S_MB_2U_LIB.S9S_MB_2U(SCH_1):M_D_CPU1_SB_DQ(11)
 118 M_D_CPU1_SB_DQ<12> DQ12_B @S9S_MB_2U_LIB.S9S_MB_2U(SCH_1):M_D_CPU1_SB_DQ(12)
 120 M_D_CPU1_SB_DQ<13> DQ13_B @S9S_MB_2U_LIB.S9S_MB_2U(SCH_1):M_D_CPU1_SB_DQ(13)
 263 M_D_CPU1_SB_DQ<14> DQ14_B @S9S_MB_2U_LIB.S9S_MB_2U(SCH_1):M_D_CPU1_SB_DQ(14)
 265 M_D_CPU1_SB_DQ<15> DQ15_B @S9S_MB_2U_LIB.S9S_MB_2U(SCH_1):M_D_CPU1_SB_DQ(15)
 122 M_D_CPU1_SB_DQ<16> DQ16_B @S9S_MB_2U_LIB.S9S_MB_2U(SCH_1):M_D_CPU1_SB_DQ(16)
 124 M_D_CPU1_SB_DQ<17> DQ17_B @S9S_MB_2U_LIB.S9S_MB_2U(SCH_1):M_D_CPU1_SB_DQ(17)
 267 M_D_CPU1_SB_DQ<18> DQ18_B @S9S_MB_2U_LIB.S9S_MB_2U(SCH_1):M_D_CPU1_SB_DQ(18)
 269 M_D_CPU1_SB_DQ<19> DQ19_B @S9S_MB_2U_LIB.S9S_MB_2U(SCH_1):M_D_CPU1_SB_DQ(19)
 129 M_D_CPU1_SB_DQ<20> DQ20_B @S9S_MB_2U_LIB.S9S_MB_2U(SCH_1):M_D_CPU1_SB_DQ(20)
 131 M_D_CPU1_SB_DQ<21> DQ21_B @S9S_MB_2U_LIB.S9S_MB_2U(SCH_1):M_D_CPU1_SB_DQ(21)
 274 M_D_CPU1_SB_DQ<22> DQ22_B @S9S_MB_2U_LIB.S9S_MB_2U(SCH_1):M_D_CPU1_SB_DQ(22)
 276 M_D_CPU1_SB_DQ<23> DQ23_B @S9S_MB_2U_LIB.S9S_MB_2U(SCH_1):M_D_CPU1_SB_DQ(23)
 133 M_D_CPU1_SB_DQ<24> DQ24_B @S9S_MB_2U_LIB.S9S_MB_2U(SCH_1):M_D_CPU1_SB_DQ(24)
 135 M_D_CPU1_SB_DQ<25> DQ25_B @S9S_MB_2U_LIB.S9S_MB_2U(SCH_1):M_D_CPU1_SB_DQ(25)
 278 M_D_CPU1_SB_DQ<26> DQ26_B @S9S_MB_2U_LIB.S9S_MB_2U(SCH_1):M_D_CPU1_SB_DQ(26)
 280 M_D_CPU1_SB_DQ<27> DQ27_B @S9S_MB_2U_LIB.S9S_MB_2U(SCH_1):M_D_CPU1_SB_DQ(27)
 140 M_D_CPU1_SB_DQ<28> DQ28_B @S9S_MB_2U_LIB.S9S_MB_2U(SCH_1):M_D_CPU1_SB_DQ(28)
 142 M_D_CPU1_SB_DQ<29> DQ29_B @S9S_MB_2U_LIB.S9S_MB_2U(SCH_1):M_D_CPU1_SB_DQ(29)
 285 M_D_CPU1_SB_DQ<30> DQ30_B @S9S_MB_2U_LIB.S9S_MB_2U(SCH_1):M_D_CPU1_SB_DQ(30)
 287 M_D_CPU1_SB_DQ<31> DQ31_B @S9S_MB_2U_LIB.S9S_MB_2U(SCH_1):M_D_CPU1_SB_DQ(31)
   7 M_D_CPU1_SA_DQ<0>  DQ0_A @S9S_MB_2U_LIB.S9S_MB_2U(SCH_1):M_D_CPU1_SA_DQ(0)
   9 M_D_CPU1_SA_DQ<1>  DQ1_A @S9S_MB_2U_LIB.S9S_MB_2U(SCH_1):M_D_CPU1_SA_DQ(1)
 152 M_D_CPU1_SA_DQ<2>  DQ2_A @S9S_MB_2U_LIB.S9S_MB_2U(SCH_1):M_D_CPU1_SA_DQ(2)
 154 M_D_CPU1_SA_DQ<3>  DQ3_A @S9S_MB_2U_LIB.S9S_MB_2U(SCH_1):M_D_CPU1_SA_DQ(3)
  14 M_D_CPU1_SA_DQ<4>  DQ4_A @S9S_MB_2U_LIB.S9S_MB_2U(SCH_1):M_D_CPU1_SA_DQ(4)
  16 M_D_CPU1_SA_DQ<5>  DQ5_A @S9S_MB_2U_LIB.S9S_MB_2U(SCH_1):M_D_CPU1_SA_DQ(5)
 159 M_D_CPU1_SA_DQ<6>  DQ6_A @S9S_MB_2U_LIB.S9S_MB_2U(SCH_1):M_D_CPU1_SA_DQ(6)
 161 M_D_CPU1_SA_DQ<7>  DQ7_A @S9S_MB_2U_LIB.S9S_MB_2U(SCH_1):M_D_CPU1_SA_DQ(7)
  18 M_D_CPU1_SA_DQ<8>  DQ8_A @S9S_MB_2U_LIB.S9S_MB_2U(SCH_1):M_D_CPU1_SA_DQ(8)
  20 M_D_CPU1_SA_DQ<9>  DQ9_A @S9S_MB_2U_LIB.S9S_MB_2U(SCH_1):M_D_CPU1_SA_DQ(9)
 163 M_D_CPU1_SA_DQ<10> DQ10_A @S9S_MB_2U_LIB.S9S_MB_2U(SCH_1):M_D_CPU1_SA_DQ(10)
 165 M_D_CPU1_SA_DQ<11> DQ11_A @S9S_MB_2U_LIB.S9S_MB_2U(SCH_1):M_D_CPU1_SA_DQ(11)
  25 M_D_CPU1_SA_DQ<12> DQ12_A @S9S_MB_2U_LIB.S9S_MB_2U(SCH_1):M_D_CPU1_SA_DQ(12)
  27 M_D_CPU1_SA_DQ<13> DQ13_A @S9S_MB_2U_LIB.S9S_MB_2U(SCH_1):M_D_CPU1_SA_DQ(13)
 170 M_D_CPU1_SA_DQ<14> DQ14_A @S9S_MB_2U_LIB.S9S_MB_2U(SCH_1):M_D_CPU1_SA_DQ(14)
 172 M_D_CPU1_SA_DQ<15> DQ15_A @S9S_MB_2U_LIB.S9S_MB_2U(SCH_1):M_D_CPU1_SA_DQ(15)
  29 M_D_CPU1_SA_DQ<16> DQ16_A @S9S_MB_2U_LIB.S9S_MB_2U(SCH_1):M_D_CPU1_SA_DQ(16)
  31 M_D_CPU1_SA_DQ<17> DQ17_A @S9S_MB_2U_LIB.S9S_MB_2U(SCH_1):M_D_CPU1_SA_DQ(17)
 174 M_D_CPU1_SA_DQ<18> DQ18_A @S9S_MB_2U_LIB.S9S_MB_2U(SCH_1):M_D_CPU1_SA_DQ(18)
 176 M_D_CPU1_SA_DQ<19> DQ19_A @S9S_MB_2U_LIB.S9S_MB_2U(SCH_1):M_D_CPU1_SA_DQ(19)
  36 M_D_CPU1_SA_DQ<20> DQ20_A @S9S_MB_2U_LIB.S9S_MB_2U(SCH_1):M_D_CPU1_SA_DQ(20)
  38 M_D_CPU1_SA_DQ<21> DQ21_A @S9S_MB_2U_LIB.S9S_MB_2U(SCH_1):M_D_CPU1_SA_DQ(21)
 181 M_D_CPU1_SA_DQ<22> DQ22_A @S9S_MB_2U_LIB.S9S_MB_2U(SCH_1):M_D_CPU1_SA_DQ(22)
 183 M_D_CPU1_SA_DQ<23> DQ23_A @S9S_MB_2U_LIB.S9S_MB_2U(SCH_1):M_D_CPU1_SA_DQ(23)
  40 M_D_CPU1_SA_DQ<24> DQ24_A @S9S_MB_2U_LIB.S9S_MB_2U(SCH_1):M_D_CPU1_SA_DQ(24)
  42 M_D_CPU1_SA_DQ<25> DQ25_A @S9S_MB_2U_LIB.S9S_MB_2U(SCH_1):M_D_CPU1_SA_DQ(25)
 185 M_D_CPU1_SA_DQ<26> DQ26_A @S9S_MB_2U_LIB.S9S_MB_2U(SCH_1):M_D_CPU1_SA_DQ(26)
 187 M_D_CPU1_SA_DQ<27> DQ27_A @S9S_MB_2U_LIB.S9S_MB_2U(SCH_1):M_D_CPU1_SA_DQ(27)
  47 M_D_CPU1_SA_DQ<28> DQ28_A @S9S_MB_2U_LIB.S9S_MB_2U(SCH_1):M_D_CPU1_SA_DQ(28)
  49 M_D_CPU1_SA_DQ<29> DQ29_A @S9S_MB_2U_LIB.S9S_MB_2U(SCH_1):M_D_CPU1_SA_DQ(29)
 192 M_D_CPU1_SA_DQ<30> DQ30_A @S9S_MB_2U_LIB.S9S_MB_2U(SCH_1):M_D_CPU1_SA_DQ(30)
 229 M_D_CPU1_SB_CS_N<1> CS1_B_N @S9S_MB_2U_LIB.S9S_MB_2U(SCH_1):M_D_CPU1_SB_CS_N(1)
 209 M_D_CPU1_SA_CS_N<1> CS1_A_N @S9S_MB_2U_LIB.S9S_MB_2U(SCH_1):M_D_CPU1_SA_CS_N(1)
  84 M_D_CPU1_SB_CS_N<0> CS0_B_N @S9S_MB_2U_LIB.S9S_MB_2U(SCH_1):M_D_CPU1_SB_CS_N(0)
  64 M_D_CPU1_SA_CS_N<0> CS0_A_N @S9S_MB_2U_LIB.S9S_MB_2U(SCH_1):M_D_CPU1_SA_CS_N(0)
 217 M_D_CPU1_CLK_DP<0>   CK_T @S9S_MB_2U_LIB.S9S_MB_2U(SCH_1):M_D_CPU1_CLK_DP(0)
 218 M_D_CPU1_CLK_DN<0>   CK_C @S9S_MB_2U_LIB.S9S_MB_2U(SCH_1):M_D_CPU1_CLK_DN(0)
  96 M_D_CPU1_SB_CB<0>  CB0_B @S9S_MB_2U_LIB.S9S_MB_2U(SCH_1):M_D_CPU1_SB_CB(0)
  98 M_D_CPU1_SB_CB<1>  CB1_B @S9S_MB_2U_LIB.S9S_MB_2U(SCH_1):M_D_CPU1_SB_CB(1)
 241 M_D_CPU1_SB_CB<2>  CB2_B @S9S_MB_2U_LIB.S9S_MB_2U(SCH_1):M_D_CPU1_SB_CB(2)
 243 M_D_CPU1_SB_CB<3>  CB3_B @S9S_MB_2U_LIB.S9S_MB_2U(SCH_1):M_D_CPU1_SB_CB(3)
  89 M_D_CPU1_SB_CB<4>  CB4_B @S9S_MB_2U_LIB.S9S_MB_2U(SCH_1):M_D_CPU1_SB_CB(4)
  91 M_D_CPU1_SB_CB<5>  CB5_B @S9S_MB_2U_LIB.S9S_MB_2U(SCH_1):M_D_CPU1_SB_CB(5)
 234 M_D_CPU1_SB_CB<6>  CB6_B @S9S_MB_2U_LIB.S9S_MB_2U(SCH_1):M_D_CPU1_SB_CB(6)
  51 M_D_CPU1_SA_CB<0>  CB0_A @S9S_MB_2U_LIB.S9S_MB_2U(SCH_1):M_D_CPU1_SA_CB(0)
 196 M_D_CPU1_SA_CB<2>  CB2_A @S9S_MB_2U_LIB.S9S_MB_2U(SCH_1):M_D_CPU1_SA_CB(2)
 198 M_D_CPU1_SA_CB<3>  CB3_A @S9S_MB_2U_LIB.S9S_MB_2U(SCH_1):M_D_CPU1_SA_CB(3)
  60 M_D_CPU1_SA_CB<5>  CB5_A @S9S_MB_2U_LIB.S9S_MB_2U(SCH_1):M_D_CPU1_SA_CB(5)
 203 M_D_CPU1_SA_CB<6>  CB6_A @S9S_MB_2U_LIB.S9S_MB_2U(SCH_1):M_D_CPU1_SA_CB(6)
  82 M_D_CPU1_SB_CA<6>  CA6_B @S9S_MB_2U_LIB.S9S_MB_2U(SCH_1):M_D_CPU1_SB_CA(6)
  72 M_D_CPU1_SA_CA<6>  CA6_A @S9S_MB_2U_LIB.S9S_MB_2U(SCH_1):M_D_CPU1_SA_CA(6)
 225 M_D_CPU1_SB_CA<5>  CA5_B @S9S_MB_2U_LIB.S9S_MB_2U(SCH_1):M_D_CPU1_SB_CA(5)
 215 M_D_CPU1_SA_CA<5>  CA5_A @S9S_MB_2U_LIB.S9S_MB_2U(SCH_1):M_D_CPU1_SA_CA(5)
  80 M_D_CPU1_SB_CA<4>  CA4_B @S9S_MB_2U_LIB.S9S_MB_2U(SCH_1):M_D_CPU1_SB_CA(4)
  70 M_D_CPU1_SA_CA<4>  CA4_A @S9S_MB_2U_LIB.S9S_MB_2U(SCH_1):M_D_CPU1_SA_CA(4)
 223 M_D_CPU1_SB_CA<3>  CA3_B @S9S_MB_2U_LIB.S9S_MB_2U(SCH_1):M_D_CPU1_SB_CA(3)
 213 M_D_CPU1_SA_CA<3>  CA3_A @S9S_MB_2U_LIB.S9S_MB_2U(SCH_1):M_D_CPU1_SA_CA(3)
  78 M_D_CPU1_SB_CA<2>  CA2_B @S9S_MB_2U_LIB.S9S_MB_2U(SCH_1):M_D_CPU1_SB_CA(2)
  68 M_D_CPU1_SA_CA<2>  CA2_A @S9S_MB_2U_LIB.S9S_MB_2U(SCH_1):M_D_CPU1_SA_CA(2)
 221 M_D_CPU1_SB_CA<1>  CA1_B @S9S_MB_2U_LIB.S9S_MB_2U(SCH_1):M_D_CPU1_SB_CA(1)
 211 M_D_CPU1_SA_CA<1>  CA1_A @S9S_MB_2U_LIB.S9S_MB_2U(SCH_1):M_D_CPU1_SA_CA(1)
  76 M_D_CPU1_SB_CA<0>  CA0_B @S9S_MB_2U_LIB.S9S_MB_2U(SCH_1):M_D_CPU1_SB_CA(0)
  66 M_D_CPU1_SA_CA<0>  CA0_A @S9S_MB_2U_LIB.S9S_MB_2U(SCH_1):M_D_CPU1_SA_CA(0)
  62 M_D_CPU1_ALERT_N ALERT_N @S9S_MB_2U_LIB.S9S_MB_2U(SCH_1):M_D_CPU1_ALERT_N
 236 M_D_CPU1_SB_CB<7>  CB7_B @S9S_MB_2U_LIB.S9S_MB_2U(SCH_1):M_D_CPU1_SB_CB(7)
  53 M_D_CPU1_SA_CB<1>  CB1_A @S9S_MB_2U_LIB.S9S_MB_2U(SCH_1):M_D_CPU1_SA_CB(1)
  58 M_D_CPU1_SA_CB<4>  CB4_A @S9S_MB_2U_LIB.S9S_MB_2U(SCH_1):M_D_CPU1_SA_CB(4)
 205 M_D_CPU1_SA_CB<7>  CB7_A @S9S_MB_2U_LIB.S9S_MB_2U(SCH_1):M_D_CPU1_SA_CB(7)
 194 M_D_CPU1_SA_DQ<31> DQ31_A @S9S_MB_2U_LIB.S9S_MB_2U(SCH_1):M_D_CPU1_SA_DQ(31)

Q_CAP_C0402-2.2UF,6.3V,20%,X6SA  I122  C68
   1 P3V3_AUX      A @S9S_MB_2U_LIB.S9S_MB_2U(SCH_1):P3V3_AUX
   2    GND      B @S9S_MB_2U_LIB.S9S_MB_2U(SCH_1):GND

Q_CAP_C0805-10UF,16V,10%,X6S,CA  I127  C69
   1 P12V_S3_AUX_CPU1_NVDIMM      A @S9S_MB_2U_LIB.S9S_MB_2U(SCH_1):P12V_S3_AUX_CPU1_NVDIMM
   2    GND      B @S9S_MB_2U_LIB.S9S_MB_2U(SCH_1):GND

Q_CAP_C0805-10UF,16V,10%,X6S,CA  I129  C70
   1 P12V_S3_AUX_CPU1_NVDIMM      A @S9S_MB_2U_LIB.S9S_MB_2U(SCH_1):P12V_S3_AUX_CPU1_NVDIMM
   2    GND      B @S9S_MB_2U_LIB.S9S_MB_2U(SCH_1):GND

SCONN288_ADR50017P130CC-SCONN2A  I175  J23
   6    GND   VSS0 @S9S_MB_2U_LIB.S9S_MB_2U(SCH_1):GND
   8    GND   VSS1 @S9S_MB_2U_LIB.S9S_MB_2U(SCH_1):GND
  10    GND   VSS2 @S9S_MB_2U_LIB.S9S_MB_2U(SCH_1):GND
  13    GND   VSS3 @S9S_MB_2U_LIB.S9S_MB_2U(SCH_1):GND
  15    GND   VSS4 @S9S_MB_2U_LIB.S9S_MB_2U(SCH_1):GND
  17    GND   VSS5 @S9S_MB_2U_LIB.S9S_MB_2U(SCH_1):GND
  19    GND   VSS6 @S9S_MB_2U_LIB.S9S_MB_2U(SCH_1):GND
  21    GND   VSS7 @S9S_MB_2U_LIB.S9S_MB_2U(SCH_1):GND
  24    GND   VSS8 @S9S_MB_2U_LIB.S9S_MB_2U(SCH_1):GND
  26    GND   VSS9 @S9S_MB_2U_LIB.S9S_MB_2U(SCH_1):GND
  28    GND  VSS10 @S9S_MB_2U_LIB.S9S_MB_2U(SCH_1):GND
  30    GND  VSS11 @S9S_MB_2U_LIB.S9S_MB_2U(SCH_1):GND
  32    GND  VSS12 @S9S_MB_2U_LIB.S9S_MB_2U(SCH_1):GND
  35    GND  VSS13 @S9S_MB_2U_LIB.S9S_MB_2U(SCH_1):GND
  37    GND  VSS14 @S9S_MB_2U_LIB.S9S_MB_2U(SCH_1):GND
  39    GND  VSS15 @S9S_MB_2U_LIB.S9S_MB_2U(SCH_1):GND
  41    GND  VSS16 @S9S_MB_2U_LIB.S9S_MB_2U(SCH_1):GND
  43    GND  VSS17 @S9S_MB_2U_LIB.S9S_MB_2U(SCH_1):GND
  46    GND  VSS18 @S9S_MB_2U_LIB.S9S_MB_2U(SCH_1):GND
  48    GND  VSS19 @S9S_MB_2U_LIB.S9S_MB_2U(SCH_1):GND
  50    GND  VSS20 @S9S_MB_2U_LIB.S9S_MB_2U(SCH_1):GND
  52    GND  VSS21 @S9S_MB_2U_LIB.S9S_MB_2U(SCH_1):GND
  54    GND  VSS22 @S9S_MB_2U_LIB.S9S_MB_2U(SCH_1):GND
  57    GND  VSS23 @S9S_MB_2U_LIB.S9S_MB_2U(SCH_1):GND
  59    GND  VSS24 @S9S_MB_2U_LIB.S9S_MB_2U(SCH_1):GND
  61    GND  VSS25 @S9S_MB_2U_LIB.S9S_MB_2U(SCH_1):GND
  63    GND  VSS26 @S9S_MB_2U_LIB.S9S_MB_2U(SCH_1):GND
  65    GND  VSS27 @S9S_MB_2U_LIB.S9S_MB_2U(SCH_1):GND
  67    GND  VSS28 @S9S_MB_2U_LIB.S9S_MB_2U(SCH_1):GND
  69    GND  VSS29 @S9S_MB_2U_LIB.S9S_MB_2U(SCH_1):GND
  71    GND  VSS30 @S9S_MB_2U_LIB.S9S_MB_2U(SCH_1):GND
  73    GND  VSS31 @S9S_MB_2U_LIB.S9S_MB_2U(SCH_1):GND
  75    GND  VSS32 @S9S_MB_2U_LIB.S9S_MB_2U(SCH_1):GND
  77    GND  VSS33 @S9S_MB_2U_LIB.S9S_MB_2U(SCH_1):GND
  79    GND  VSS34 @S9S_MB_2U_LIB.S9S_MB_2U(SCH_1):GND
  81    GND  VSS35 @S9S_MB_2U_LIB.S9S_MB_2U(SCH_1):GND
  83    GND  VSS36 @S9S_MB_2U_LIB.S9S_MB_2U(SCH_1):GND
  85    GND  VSS37 @S9S_MB_2U_LIB.S9S_MB_2U(SCH_1):GND
  88    GND  VSS38 @S9S_MB_2U_LIB.S9S_MB_2U(SCH_1):GND
  90    GND  VSS39 @S9S_MB_2U_LIB.S9S_MB_2U(SCH_1):GND
  92    GND  VSS40 @S9S_MB_2U_LIB.S9S_MB_2U(SCH_1):GND
  95    GND  VSS41 @S9S_MB_2U_LIB.S9S_MB_2U(SCH_1):GND
  97    GND  VSS42 @S9S_MB_2U_LIB.S9S_MB_2U(SCH_1):GND
  99    GND  VSS43 @S9S_MB_2U_LIB.S9S_MB_2U(SCH_1):GND
 101    GND  VSS44 @S9S_MB_2U_LIB.S9S_MB_2U(SCH_1):GND
 103    GND  VSS45 @S9S_MB_2U_LIB.S9S_MB_2U(SCH_1):GND
 106    GND  VSS46 @S9S_MB_2U_LIB.S9S_MB_2U(SCH_1):GND
 108    GND  VSS47 @S9S_MB_2U_LIB.S9S_MB_2U(SCH_1):GND
 110    GND  VSS48 @S9S_MB_2U_LIB.S9S_MB_2U(SCH_1):GND
 112    GND  VSS49 @S9S_MB_2U_LIB.S9S_MB_2U(SCH_1):GND
 114    GND  VSS50 @S9S_MB_2U_LIB.S9S_MB_2U(SCH_1):GND
 117    GND  VSS51 @S9S_MB_2U_LIB.S9S_MB_2U(SCH_1):GND
 119    GND  VSS52 @S9S_MB_2U_LIB.S9S_MB_2U(SCH_1):GND
 121    GND  VSS53 @S9S_MB_2U_LIB.S9S_MB_2U(SCH_1):GND
 123    GND  VSS54 @S9S_MB_2U_LIB.S9S_MB_2U(SCH_1):GND
 125    GND  VSS55 @S9S_MB_2U_LIB.S9S_MB_2U(SCH_1):GND
 128    GND  VSS56 @S9S_MB_2U_LIB.S9S_MB_2U(SCH_1):GND
 130    GND  VSS57 @S9S_MB_2U_LIB.S9S_MB_2U(SCH_1):GND
 134    GND  VSS59 @S9S_MB_2U_LIB.S9S_MB_2U(SCH_1):GND
 143    GND  VSS63 @S9S_MB_2U_LIB.S9S_MB_2U(SCH_1):GND
 151    GND  VSS64 @S9S_MB_2U_LIB.S9S_MB_2U(SCH_1):GND
 153    GND  VSS65 @S9S_MB_2U_LIB.S9S_MB_2U(SCH_1):GND
 155    GND  VSS66 @S9S_MB_2U_LIB.S9S_MB_2U(SCH_1):GND
 158    GND  VSS67 @S9S_MB_2U_LIB.S9S_MB_2U(SCH_1):GND
 160    GND  VSS68 @S9S_MB_2U_LIB.S9S_MB_2U(SCH_1):GND
 162    GND  VSS69 @S9S_MB_2U_LIB.S9S_MB_2U(SCH_1):GND
 164    GND  VSS70 @S9S_MB_2U_LIB.S9S_MB_2U(SCH_1):GND
 166    GND  VSS71 @S9S_MB_2U_LIB.S9S_MB_2U(SCH_1):GND
 169    GND  VSS72 @S9S_MB_2U_LIB.S9S_MB_2U(SCH_1):GND
 171    GND  VSS73 @S9S_MB_2U_LIB.S9S_MB_2U(SCH_1):GND
 173    GND  VSS74 @S9S_MB_2U_LIB.S9S_MB_2U(SCH_1):GND
 175    GND  VSS75 @S9S_MB_2U_LIB.S9S_MB_2U(SCH_1):GND
 177    GND  VSS76 @S9S_MB_2U_LIB.S9S_MB_2U(SCH_1):GND
 180    GND  VSS77 @S9S_MB_2U_LIB.S9S_MB_2U(SCH_1):GND
 182    GND  VSS78 @S9S_MB_2U_LIB.S9S_MB_2U(SCH_1):GND
 184    GND  VSS79 @S9S_MB_2U_LIB.S9S_MB_2U(SCH_1):GND
 186    GND  VSS80 @S9S_MB_2U_LIB.S9S_MB_2U(SCH_1):GND
 188    GND  VSS81 @S9S_MB_2U_LIB.S9S_MB_2U(SCH_1):GND
 191    GND  VSS82 @S9S_MB_2U_LIB.S9S_MB_2U(SCH_1):GND
 193    GND  VSS83 @S9S_MB_2U_LIB.S9S_MB_2U(SCH_1):GND
 195    GND  VSS84 @S9S_MB_2U_LIB.S9S_MB_2U(SCH_1):GND
 197    GND  VSS85 @S9S_MB_2U_LIB.S9S_MB_2U(SCH_1):GND
 199    GND  VSS86 @S9S_MB_2U_LIB.S9S_MB_2U(SCH_1):GND
 202    GND  VSS87 @S9S_MB_2U_LIB.S9S_MB_2U(SCH_1):GND
 204    GND  VSS88 @S9S_MB_2U_LIB.S9S_MB_2U(SCH_1):GND
 206    GND  VSS89 @S9S_MB_2U_LIB.S9S_MB_2U(SCH_1):GND
 208    GND  VSS90 @S9S_MB_2U_LIB.S9S_MB_2U(SCH_1):GND
 210    GND  VSS91 @S9S_MB_2U_LIB.S9S_MB_2U(SCH_1):GND
 212    GND  VSS92 @S9S_MB_2U_LIB.S9S_MB_2U(SCH_1):GND
 214    GND  VSS93 @S9S_MB_2U_LIB.S9S_MB_2U(SCH_1):GND
 216    GND  VSS94 @S9S_MB_2U_LIB.S9S_MB_2U(SCH_1):GND
 219    GND  VSS95 @S9S_MB_2U_LIB.S9S_MB_2U(SCH_1):GND
 222    GND  VSS96 @S9S_MB_2U_LIB.S9S_MB_2U(SCH_1):GND
 224    GND  VSS97 @S9S_MB_2U_LIB.S9S_MB_2U(SCH_1):GND
 226    GND  VSS98 @S9S_MB_2U_LIB.S9S_MB_2U(SCH_1):GND
 228    GND  VSS99 @S9S_MB_2U_LIB.S9S_MB_2U(SCH_1):GND
 233    GND VSS101 @S9S_MB_2U_LIB.S9S_MB_2U(SCH_1):GND
 237    GND VSS103 @S9S_MB_2U_LIB.S9S_MB_2U(SCH_1):GND
 242    GND VSS105 @S9S_MB_2U_LIB.S9S_MB_2U(SCH_1):GND
 244    GND VSS106 @S9S_MB_2U_LIB.S9S_MB_2U(SCH_1):GND
 246    GND VSS107 @S9S_MB_2U_LIB.S9S_MB_2U(SCH_1):GND
 248    GND VSS108 @S9S_MB_2U_LIB.S9S_MB_2U(SCH_1):GND
 251    GND VSS109 @S9S_MB_2U_LIB.S9S_MB_2U(SCH_1):GND
 253    GND VSS110 @S9S_MB_2U_LIB.S9S_MB_2U(SCH_1):GND
 255    GND VSS111 @S9S_MB_2U_LIB.S9S_MB_2U(SCH_1):GND
 257    GND VSS112 @S9S_MB_2U_LIB.S9S_MB_2U(SCH_1):GND
 259    GND VSS113 @S9S_MB_2U_LIB.S9S_MB_2U(SCH_1):GND
 262    GND VSS114 @S9S_MB_2U_LIB.S9S_MB_2U(SCH_1):GND
 264    GND VSS115 @S9S_MB_2U_LIB.S9S_MB_2U(SCH_1):GND
 266    GND VSS116 @S9S_MB_2U_LIB.S9S_MB_2U(SCH_1):GND
 268    GND VSS117 @S9S_MB_2U_LIB.S9S_MB_2U(SCH_1):GND
 270    GND VSS118 @S9S_MB_2U_LIB.S9S_MB_2U(SCH_1):GND
 273    GND VSS119 @S9S_MB_2U_LIB.S9S_MB_2U(SCH_1):GND
 275    GND VSS120 @S9S_MB_2U_LIB.S9S_MB_2U(SCH_1):GND
 277    GND VSS121 @S9S_MB_2U_LIB.S9S_MB_2U(SCH_1):GND
 279    GND VSS122 @S9S_MB_2U_LIB.S9S_MB_2U(SCH_1):GND
 281    GND VSS123 @S9S_MB_2U_LIB.S9S_MB_2U(SCH_1):GND
 284    GND VSS124 @S9S_MB_2U_LIB.S9S_MB_2U(SCH_1):GND
 286    GND VSS125 @S9S_MB_2U_LIB.S9S_MB_2U(SCH_1):GND
 288    GND VSS126 @S9S_MB_2U_LIB.S9S_MB_2U(SCH_1):GND
   1 P12V_S3_AUX_CPU1_NVDIMM VIN_BULK0 @S9S_MB_2U_LIB.S9S_MB_2U(SCH_1):P12V_S3_AUX_CPU1_NVDIMM
 145 P12V_S3_AUX_CPU1_NVDIMM VIN_BULK1 @S9S_MB_2U_LIB.S9S_MB_2U(SCH_1):P12V_S3_AUX_CPU1_NVDIMM
 146 P12V_S3_AUX_CPU1_NVDIMM VIN_BULK2 @S9S_MB_2U_LIB.S9S_MB_2U(SCH_1):P12V_S3_AUX_CPU1_NVDIMM
 230    GND VSS100 @S9S_MB_2U_LIB.S9S_MB_2U(SCH_1):GND
 235    GND VSS102 @S9S_MB_2U_LIB.S9S_MB_2U(SCH_1):GND
 240    GND VSS104 @S9S_MB_2U_LIB.S9S_MB_2U(SCH_1):GND
 132    GND  VSS58 @S9S_MB_2U_LIB.S9S_MB_2U(SCH_1):GND
 136    GND  VSS60 @S9S_MB_2U_LIB.S9S_MB_2U(SCH_1):GND
 139    GND  VSS61 @S9S_MB_2U_LIB.S9S_MB_2U(SCH_1):GND
 141    GND  VSS62 @S9S_MB_2U_LIB.S9S_MB_2U(SCH_1):GND
  G1    GND     G1 @S9S_MB_2U_LIB.S9S_MB_2U(SCH_1):GND
  G2    GND     G2 @S9S_MB_2U_LIB.S9S_MB_2U(SCH_1):GND
  G3    GND     G3 @S9S_MB_2U_LIB.S9S_MB_2U(SCH_1):GND

SCONN288_ADR50017P130CC-SCONN2A  I178  J23
  93 M_D_CPU1_SB_DQS_DP<9> DQS9_B_T||TDQS9_B_T||DBI4_B_N @S9S_MB_2U_LIB.S9S_MB_2U(SCH_1):M_D_CPU1_SB_DQS_DP(9)
  94 M_D_CPU1_SB_DQS_DN<9> DQS9_B_C||TDQS9_B_C @S9S_MB_2U_LIB.S9S_MB_2U(SCH_1):M_D_CPU1_SB_DQS_DN(9)
 201 M_D_CPU1_SA_DQS_DP<9> DQS9_A_T||TDQS9_A_T @S9S_MB_2U_LIB.S9S_MB_2U(SCH_1):M_D_CPU1_SA_DQS_DP(9)
 200 M_D_CPU1_SA_DQS_DN<9> DQS9_A_C||TDQS9_A_C @S9S_MB_2U_LIB.S9S_MB_2U(SCH_1):M_D_CPU1_SA_DQS_DN(9)
 190 M_D_CPU1_SA_DQS_DP<8> DQS8_A_T||TDQS8_A_T @S9S_MB_2U_LIB.S9S_MB_2U(SCH_1):M_D_CPU1_SA_DQS_DP(8)
 189 M_D_CPU1_SA_DQS_DN<8> DQS8_A_C||TDQS8_A_C @S9S_MB_2U_LIB.S9S_MB_2U(SCH_1):M_D_CPU1_SA_DQS_DN(8)
 271 M_D_CPU1_SB_DQS_DN<7> DQS7_B_C||TDQS7_B_C @S9S_MB_2U_LIB.S9S_MB_2U(SCH_1):M_D_CPU1_SB_DQS_DN(7)
 179 M_D_CPU1_SA_DQS_DP<7> DQS7_A_T||TDQS7_A_T @S9S_MB_2U_LIB.S9S_MB_2U(SCH_1):M_D_CPU1_SA_DQS_DP(7)
 261 M_D_CPU1_SB_DQS_DP<6> DQS6_B_T||TDQS6_B_T @S9S_MB_2U_LIB.S9S_MB_2U(SCH_1):M_D_CPU1_SB_DQS_DP(6)
 260 M_D_CPU1_SB_DQS_DN<6> DQS6_B_C||TDQS6_B_C @S9S_MB_2U_LIB.S9S_MB_2U(SCH_1):M_D_CPU1_SB_DQS_DN(6)
 167 M_D_CPU1_SA_DQS_DN<6> DQS6_A_C||TDQS6_A_C||DQS6_A_T||TDQS6_A_T @S9S_MB_2U_LIB.S9S_MB_2U(SCH_1):M_D_CPU1_SA_DQS_DN(6)
 250 M_D_CPU1_SB_DQS_DP<5> DQS5_B_T||TDQS5_B_T @S9S_MB_2U_LIB.S9S_MB_2U(SCH_1):M_D_CPU1_SB_DQS_DP(5)
 249 M_D_CPU1_SB_DQS_DN<5> DQS5_B_C||TDQS5_B_C @S9S_MB_2U_LIB.S9S_MB_2U(SCH_1):M_D_CPU1_SB_DQS_DN(5)
 157 M_D_CPU1_SA_DQS_DP<5> DQS5_A_T||TDQS5_A_T @S9S_MB_2U_LIB.S9S_MB_2U(SCH_1):M_D_CPU1_SA_DQS_DP(5)
 156 M_D_CPU1_SA_DQS_DN<5> DQS5_A_C||TDQS5_A_C||DQS5_A_T||TDQS5_A_T @S9S_MB_2U_LIB.S9S_MB_2U(SCH_1):M_D_CPU1_SA_DQS_DN(5)
 239 M_D_CPU1_SB_DQS_DP<4> DQS4_B_T @S9S_MB_2U_LIB.S9S_MB_2U(SCH_1):M_D_CPU1_SB_DQS_DP(4)
 238 M_D_CPU1_SB_DQS_DN<4> DQS4_B_C @S9S_MB_2U_LIB.S9S_MB_2U(SCH_1):M_D_CPU1_SB_DQS_DN(4)
  55 M_D_CPU1_SA_DQS_DP<4> DQS4_A_T @S9S_MB_2U_LIB.S9S_MB_2U(SCH_1):M_D_CPU1_SA_DQS_DP(4)
  56 M_D_CPU1_SA_DQS_DN<4> DQS4_A_C @S9S_MB_2U_LIB.S9S_MB_2U(SCH_1):M_D_CPU1_SA_DQS_DN(4)
 137 M_D_CPU1_SB_DQS_DP<3> DQS3_B_T @S9S_MB_2U_LIB.S9S_MB_2U(SCH_1):M_D_CPU1_SB_DQS_DP(3)
 138 M_D_CPU1_SB_DQS_DN<3> DQS3_B_C @S9S_MB_2U_LIB.S9S_MB_2U(SCH_1):M_D_CPU1_SB_DQS_DN(3)
  44 M_D_CPU1_SA_DQS_DP<3> DQS3_A_T @S9S_MB_2U_LIB.S9S_MB_2U(SCH_1):M_D_CPU1_SA_DQS_DP(3)
  45 M_D_CPU1_SA_DQS_DN<3> DQS3_A_C @S9S_MB_2U_LIB.S9S_MB_2U(SCH_1):M_D_CPU1_SA_DQS_DN(3)
 126 M_D_CPU1_SB_DQS_DP<2> DQS2_B_T @S9S_MB_2U_LIB.S9S_MB_2U(SCH_1):M_D_CPU1_SB_DQS_DP(2)
 127 M_D_CPU1_SB_DQS_DN<2> DQS2_B_C @S9S_MB_2U_LIB.S9S_MB_2U(SCH_1):M_D_CPU1_SB_DQS_DN(2)
  33 M_D_CPU1_SA_DQS_DP<2> DQS2_A_T @S9S_MB_2U_LIB.S9S_MB_2U(SCH_1):M_D_CPU1_SA_DQS_DP(2)
  34 M_D_CPU1_SA_DQS_DN<2> DQS2_A_C @S9S_MB_2U_LIB.S9S_MB_2U(SCH_1):M_D_CPU1_SA_DQS_DN(2)
 115 M_D_CPU1_SB_DQS_DP<1> DQS1_B_T @S9S_MB_2U_LIB.S9S_MB_2U(SCH_1):M_D_CPU1_SB_DQS_DP(1)
 116 M_D_CPU1_SB_DQS_DN<1> DQS1_B_C @S9S_MB_2U_LIB.S9S_MB_2U(SCH_1):M_D_CPU1_SB_DQS_DN(1)
  22 M_D_CPU1_SA_DQS_DP<1> DQS1_A_T @S9S_MB_2U_LIB.S9S_MB_2U(SCH_1):M_D_CPU1_SA_DQS_DP(1)
  23 M_D_CPU1_SA_DQS_DN<1> DQS1_A_C @S9S_MB_2U_LIB.S9S_MB_2U(SCH_1):M_D_CPU1_SA_DQS_DN(1)
 104 M_D_CPU1_SB_DQS_DP<0> DQS0_B_T @S9S_MB_2U_LIB.S9S_MB_2U(SCH_1):M_D_CPU1_SB_DQS_DP(0)
 105 M_D_CPU1_SB_DQS_DN<0> DQS0_B_C @S9S_MB_2U_LIB.S9S_MB_2U(SCH_1):M_D_CPU1_SB_DQS_DN(0)
  11 M_D_CPU1_SA_DQS_DP<0> DQS0_A_T @S9S_MB_2U_LIB.S9S_MB_2U(SCH_1):M_D_CPU1_SA_DQS_DP(0)
  12 M_D_CPU1_SA_DQS_DN<0> DQS0_A_C @S9S_MB_2U_LIB.S9S_MB_2U(SCH_1):M_D_CPU1_SA_DQS_DN(0)
 272 M_D_CPU1_SB_DQS_DP<7> DQS7_B_T||TDQS7_B_T @S9S_MB_2U_LIB.S9S_MB_2U(SCH_1):M_D_CPU1_SB_DQS_DP(7)
 282 M_D_CPU1_SB_DQS_DN<8> DQS8_B_C||TDQS8_B_C @S9S_MB_2U_LIB.S9S_MB_2U(SCH_1):M_D_CPU1_SB_DQS_DN(8)
 283 M_D_CPU1_SB_DQS_DP<8> DQS8_B_T||TDQS8_B_T @S9S_MB_2U_LIB.S9S_MB_2U(SCH_1):M_D_CPU1_SB_DQS_DP(8)
 168 M_D_CPU1_SA_DQS_DP<6> DQS6_A_T||TDQS6_A_T @S9S_MB_2U_LIB.S9S_MB_2U(SCH_1):M_D_CPU1_SA_DQS_DP(6)
 178 M_D_CPU1_SA_DQS_DN<7> DQS7_A_C||TDQS7_A_C @S9S_MB_2U_LIB.S9S_MB_2U(SCH_1):M_D_CPU1_SA_DQS_DN(7)

Q_RES_0402LF-49.9,1%,1/16W,CHIA  I180  R3897
   1 I3C_SPD_DDRABCD_CPU1_LVC1_SCL_6      A @S9S_MB_2U_LIB.S9S_MB_2U(SCH_1):I3C_SPD_DDRABCD_CPU1_LVC1_SCL_R7
   2 I3C_SPD_DDRABCD_CPU1_LVC1_SCL      B @S9S_MB_2U_LIB.S9S_MB_2U(SCH_1):I3C_SPD_DDRABCD_CPU1_LVC1_SCL


DRAWING: @S9S_MB_2U_LIB.S9S_MB_2U(SCH_1):PAGE105 

Q_RES_0402LF-196K,1%,1/16W,CHIA  I2  R80
   1 PD_CHD_CPU1_DIMM2_SAA      A @S9S_MB_2U_LIB.S9S_MB_2U(SCH_1):PD_CHD_CPU1_DIMM2_SAA
   2    GND      B @S9S_MB_2U_LIB.S9S_MB_2U(SCH_1):GND

Q_CAP_C0402-2.2UF,6.3V,20%,X6SA  I123  C96
   1 P3V3_AUX      A @S9S_MB_2U_LIB.S9S_MB_2U(SCH_1):P3V3_AUX
   2    GND      B @S9S_MB_2U_LIB.S9S_MB_2U(SCH_1):GND

Q_CAP_C0805-10UF,16V,10%,X6S,CA  I124  C97
   1 P12V_S3_AUX_CPU1_NVDIMM      A @S9S_MB_2U_LIB.S9S_MB_2U(SCH_1):P12V_S3_AUX_CPU1_NVDIMM
   2    GND      B @S9S_MB_2U_LIB.S9S_MB_2U(SCH_1):GND

Q_CAP_C0805-10UF,16V,10%,X6S,CA  I146  C98
   1 P12V_S3_AUX_CPU1_NVDIMM      A @S9S_MB_2U_LIB.S9S_MB_2U(SCH_1):P12V_S3_AUX_CPU1_NVDIMM
   2    GND      B @S9S_MB_2U_LIB.S9S_MB_2U(SCH_1):GND

SCONN288_ADR50017P087CC-SCONN2A  I178  J24
   3 P3V3_AUX VIN_MGMT @S9S_MB_2U_LIB.S9S_MB_2U(SCH_1):P3V3_AUX
   2 TP_CHD_CPU1_DIMM2_FRU_0   RFU0 @S9S_MB_2U_LIB.S9S_MB_2U(SCH_1):TP_CHD_CPU1_DIMM2_FRU_0
 144 TP_CHD_CPU1_DIMM2_FRU_1   RFU1 @S9S_MB_2U_LIB.S9S_MB_2U(SCH_1):TP_CHD_CPU1_DIMM2_FRU_1
 149 TP_CHD_CPU1_DIMM2_FRU_2   RFU2 @S9S_MB_2U_LIB.S9S_MB_2U(SCH_1):TP_CHD_CPU1_DIMM2_FRU_2
 150 TP_CHD_CPU1_DIMM2_FRU_3   RFU3 @S9S_MB_2U_LIB.S9S_MB_2U(SCH_1):TP_CHD_CPU1_DIMM2_FRU_3
 220 TP_CHD_CPU1_DIMM2_FRU_4   RFU4 @S9S_MB_2U_LIB.S9S_MB_2U(SCH_1):TP_CHD_CPU1_DIMM2_FRU_4
 231 TP_CHD_CPU1_DIMM2_FRU_5   RFU5 @S9S_MB_2U_LIB.S9S_MB_2U(SCH_1):TP_CHD_CPU1_DIMM2_FRU_5
 232 TP_CHD_CPU1_DIMM2_FRU_6   RFU6 @S9S_MB_2U_LIB.S9S_MB_2U(SCH_1):TP_CHD_CPU1_DIMM2_FRU_6
 207 RST_M_CD_CPU1_FPGA_N RESET_N @S9S_MB_2U_LIB.S9S_MB_2U(SCH_1):RST_M_CD_CPU1_FPGA_N
 147 PWRGD_CHD_CPU1_DIMM2 PWR_GOOD||FAIL_N @S9S_MB_2U_LIB.S9S_MB_2U(SCH_1):PWRGD_CHD_CPU1_DIMM2
 227 M_D_CPU1_SB_PAR  PAR_B @S9S_MB_2U_LIB.S9S_MB_2U(SCH_1):M_D_CPU1_SB_PAR
  74 M_D_CPU1_SA_PAR  PAR_A @S9S_MB_2U_LIB.S9S_MB_2U(SCH_1):M_D_CPU1_SA_PAR
  87 M_D_CPU1_SB_RSP<1> LBS||RSP_B_N @S9S_MB_2U_LIB.S9S_MB_2U(SCH_1):M_D_CPU1_SB_RSP(1)
  86 M_D_CPU1_SA_RSP<1> LBD||RSP_A_N @S9S_MB_2U_LIB.S9S_MB_2U(SCH_1):M_D_CPU1_SA_RSP(1)
   5 I3C_SPD_DDRABCD_CPU1_LVC1_SDA   HSDA @S9S_MB_2U_LIB.S9S_MB_2U(SCH_1):I3C_SPD_DDRABCD_CPU1_LVC1_SDA
   4 I3C_SPD_DDRABCD_CPU1_LVC1_SCL_7   HSCL @S9S_MB_2U_LIB.S9S_MB_2U(SCH_1):I3C_SPD_DDRABCD_CPU1_LVC1_SCL_R8
 148 PD_CHD_CPU1_DIMM2_SAA    HSA @S9S_MB_2U_LIB.S9S_MB_2U(SCH_1):PD_CHD_CPU1_DIMM2_SAA
 100 M_D_CPU1_SB_DQ<0>  DQ0_B @S9S_MB_2U_LIB.S9S_MB_2U(SCH_1):M_D_CPU1_SB_DQ(0)
 102 M_D_CPU1_SB_DQ<1>  DQ1_B @S9S_MB_2U_LIB.S9S_MB_2U(SCH_1):M_D_CPU1_SB_DQ(1)
 245 M_D_CPU1_SB_DQ<2>  DQ2_B @S9S_MB_2U_LIB.S9S_MB_2U(SCH_1):M_D_CPU1_SB_DQ(2)
 247 M_D_CPU1_SB_DQ<3>  DQ3_B @S9S_MB_2U_LIB.S9S_MB_2U(SCH_1):M_D_CPU1_SB_DQ(3)
 107 M_D_CPU1_SB_DQ<4>  DQ4_B @S9S_MB_2U_LIB.S9S_MB_2U(SCH_1):M_D_CPU1_SB_DQ(4)
 109 M_D_CPU1_SB_DQ<5>  DQ5_B @S9S_MB_2U_LIB.S9S_MB_2U(SCH_1):M_D_CPU1_SB_DQ(5)
 252 M_D_CPU1_SB_DQ<6>  DQ6_B @S9S_MB_2U_LIB.S9S_MB_2U(SCH_1):M_D_CPU1_SB_DQ(6)
 254 M_D_CPU1_SB_DQ<7>  DQ7_B @S9S_MB_2U_LIB.S9S_MB_2U(SCH_1):M_D_CPU1_SB_DQ(7)
 111 M_D_CPU1_SB_DQ<8>  DQ8_B @S9S_MB_2U_LIB.S9S_MB_2U(SCH_1):M_D_CPU1_SB_DQ(8)
 113 M_D_CPU1_SB_DQ<9>  DQ9_B @S9S_MB_2U_LIB.S9S_MB_2U(SCH_1):M_D_CPU1_SB_DQ(9)
 256 M_D_CPU1_SB_DQ<10> DQ10_B @S9S_MB_2U_LIB.S9S_MB_2U(SCH_1):M_D_CPU1_SB_DQ(10)
 258 M_D_CPU1_SB_DQ<11> DQ11_B @S9S_MB_2U_LIB.S9S_MB_2U(SCH_1):M_D_CPU1_SB_DQ(11)
 118 M_D_CPU1_SB_DQ<12> DQ12_B @S9S_MB_2U_LIB.S9S_MB_2U(SCH_1):M_D_CPU1_SB_DQ(12)
 120 M_D_CPU1_SB_DQ<13> DQ13_B @S9S_MB_2U_LIB.S9S_MB_2U(SCH_1):M_D_CPU1_SB_DQ(13)
 263 M_D_CPU1_SB_DQ<14> DQ14_B @S9S_MB_2U_LIB.S9S_MB_2U(SCH_1):M_D_CPU1_SB_DQ(14)
 265 M_D_CPU1_SB_DQ<15> DQ15_B @S9S_MB_2U_LIB.S9S_MB_2U(SCH_1):M_D_CPU1_SB_DQ(15)
 122 M_D_CPU1_SB_DQ<16> DQ16_B @S9S_MB_2U_LIB.S9S_MB_2U(SCH_1):M_D_CPU1_SB_DQ(16)
 124 M_D_CPU1_SB_DQ<17> DQ17_B @S9S_MB_2U_LIB.S9S_MB_2U(SCH_1):M_D_CPU1_SB_DQ(17)
 267 M_D_CPU1_SB_DQ<18> DQ18_B @S9S_MB_2U_LIB.S9S_MB_2U(SCH_1):M_D_CPU1_SB_DQ(18)
 269 M_D_CPU1_SB_DQ<19> DQ19_B @S9S_MB_2U_LIB.S9S_MB_2U(SCH_1):M_D_CPU1_SB_DQ(19)
 129 M_D_CPU1_SB_DQ<20> DQ20_B @S9S_MB_2U_LIB.S9S_MB_2U(SCH_1):M_D_CPU1_SB_DQ(20)
 131 M_D_CPU1_SB_DQ<21> DQ21_B @S9S_MB_2U_LIB.S9S_MB_2U(SCH_1):M_D_CPU1_SB_DQ(21)
 274 M_D_CPU1_SB_DQ<22> DQ22_B @S9S_MB_2U_LIB.S9S_MB_2U(SCH_1):M_D_CPU1_SB_DQ(22)
 276 M_D_CPU1_SB_DQ<23> DQ23_B @S9S_MB_2U_LIB.S9S_MB_2U(SCH_1):M_D_CPU1_SB_DQ(23)
 133 M_D_CPU1_SB_DQ<24> DQ24_B @S9S_MB_2U_LIB.S9S_MB_2U(SCH_1):M_D_CPU1_SB_DQ(24)
 135 M_D_CPU1_SB_DQ<25> DQ25_B @S9S_MB_2U_LIB.S9S_MB_2U(SCH_1):M_D_CPU1_SB_DQ(25)
 278 M_D_CPU1_SB_DQ<26> DQ26_B @S9S_MB_2U_LIB.S9S_MB_2U(SCH_1):M_D_CPU1_SB_DQ(26)
 280 M_D_CPU1_SB_DQ<27> DQ27_B @S9S_MB_2U_LIB.S9S_MB_2U(SCH_1):M_D_CPU1_SB_DQ(27)
 140 M_D_CPU1_SB_DQ<28> DQ28_B @S9S_MB_2U_LIB.S9S_MB_2U(SCH_1):M_D_CPU1_SB_DQ(28)
 142 M_D_CPU1_SB_DQ<29> DQ29_B @S9S_MB_2U_LIB.S9S_MB_2U(SCH_1):M_D_CPU1_SB_DQ(29)
 285 M_D_CPU1_SB_DQ<30> DQ30_B @S9S_MB_2U_LIB.S9S_MB_2U(SCH_1):M_D_CPU1_SB_DQ(30)
 287 M_D_CPU1_SB_DQ<31> DQ31_B @S9S_MB_2U_LIB.S9S_MB_2U(SCH_1):M_D_CPU1_SB_DQ(31)
   7 M_D_CPU1_SA_DQ<0>  DQ0_A @S9S_MB_2U_LIB.S9S_MB_2U(SCH_1):M_D_CPU1_SA_DQ(0)
   9 M_D_CPU1_SA_DQ<1>  DQ1_A @S9S_MB_2U_LIB.S9S_MB_2U(SCH_1):M_D_CPU1_SA_DQ(1)
 152 M_D_CPU1_SA_DQ<2>  DQ2_A @S9S_MB_2U_LIB.S9S_MB_2U(SCH_1):M_D_CPU1_SA_DQ(2)
 154 M_D_CPU1_SA_DQ<3>  DQ3_A @S9S_MB_2U_LIB.S9S_MB_2U(SCH_1):M_D_CPU1_SA_DQ(3)
  14 M_D_CPU1_SA_DQ<4>  DQ4_A @S9S_MB_2U_LIB.S9S_MB_2U(SCH_1):M_D_CPU1_SA_DQ(4)
  16 M_D_CPU1_SA_DQ<5>  DQ5_A @S9S_MB_2U_LIB.S9S_MB_2U(SCH_1):M_D_CPU1_SA_DQ(5)
 159 M_D_CPU1_SA_DQ<6>  DQ6_A @S9S_MB_2U_LIB.S9S_MB_2U(SCH_1):M_D_CPU1_SA_DQ(6)
 161 M_D_CPU1_SA_DQ<7>  DQ7_A @S9S_MB_2U_LIB.S9S_MB_2U(SCH_1):M_D_CPU1_SA_DQ(7)
  18 M_D_CPU1_SA_DQ<8>  DQ8_A @S9S_MB_2U_LIB.S9S_MB_2U(SCH_1):M_D_CPU1_SA_DQ(8)
  20 M_D_CPU1_SA_DQ<9>  DQ9_A @S9S_MB_2U_LIB.S9S_MB_2U(SCH_1):M_D_CPU1_SA_DQ(9)
 163 M_D_CPU1_SA_DQ<10> DQ10_A @S9S_MB_2U_LIB.S9S_MB_2U(SCH_1):M_D_CPU1_SA_DQ(10)
 165 M_D_CPU1_SA_DQ<11> DQ11_A @S9S_MB_2U_LIB.S9S_MB_2U(SCH_1):M_D_CPU1_SA_DQ(11)
  25 M_D_CPU1_SA_DQ<12> DQ12_A @S9S_MB_2U_LIB.S9S_MB_2U(SCH_1):M_D_CPU1_SA_DQ(12)
  27 M_D_CPU1_SA_DQ<13> DQ13_A @S9S_MB_2U_LIB.S9S_MB_2U(SCH_1):M_D_CPU1_SA_DQ(13)
 170 M_D_CPU1_SA_DQ<14> DQ14_A @S9S_MB_2U_LIB.S9S_MB_2U(SCH_1):M_D_CPU1_SA_DQ(14)
 172 M_D_CPU1_SA_DQ<15> DQ15_A @S9S_MB_2U_LIB.S9S_MB_2U(SCH_1):M_D_CPU1_SA_DQ(15)
  29 M_D_CPU1_SA_DQ<16> DQ16_A @S9S_MB_2U_LIB.S9S_MB_2U(SCH_1):M_D_CPU1_SA_DQ(16)
  31 M_D_CPU1_SA_DQ<17> DQ17_A @S9S_MB_2U_LIB.S9S_MB_2U(SCH_1):M_D_CPU1_SA_DQ(17)
 174 M_D_CPU1_SA_DQ<18> DQ18_A @S9S_MB_2U_LIB.S9S_MB_2U(SCH_1):M_D_CPU1_SA_DQ(18)
 176 M_D_CPU1_SA_DQ<19> DQ19_A @S9S_MB_2U_LIB.S9S_MB_2U(SCH_1):M_D_CPU1_SA_DQ(19)
  36 M_D_CPU1_SA_DQ<20> DQ20_A @S9S_MB_2U_LIB.S9S_MB_2U(SCH_1):M_D_CPU1_SA_DQ(20)
  38 M_D_CPU1_SA_DQ<21> DQ21_A @S9S_MB_2U_LIB.S9S_MB_2U(SCH_1):M_D_CPU1_SA_DQ(21)
 181 M_D_CPU1_SA_DQ<22> DQ22_A @S9S_MB_2U_LIB.S9S_MB_2U(SCH_1):M_D_CPU1_SA_DQ(22)
 183 M_D_CPU1_SA_DQ<23> DQ23_A @S9S_MB_2U_LIB.S9S_MB_2U(SCH_1):M_D_CPU1_SA_DQ(23)
  40 M_D_CPU1_SA_DQ<24> DQ24_A @S9S_MB_2U_LIB.S9S_MB_2U(SCH_1):M_D_CPU1_SA_DQ(24)
  42 M_D_CPU1_SA_DQ<25> DQ25_A @S9S_MB_2U_LIB.S9S_MB_2U(SCH_1):M_D_CPU1_SA_DQ(25)
 185 M_D_CPU1_SA_DQ<26> DQ26_A @S9S_MB_2U_LIB.S9S_MB_2U(SCH_1):M_D_CPU1_SA_DQ(26)
 187 M_D_CPU1_SA_DQ<27> DQ27_A @S9S_MB_2U_LIB.S9S_MB_2U(SCH_1):M_D_CPU1_SA_DQ(27)
  47 M_D_CPU1_SA_DQ<28> DQ28_A @S9S_MB_2U_LIB.S9S_MB_2U(SCH_1):M_D_CPU1_SA_DQ(28)
  49 M_D_CPU1_SA_DQ<29> DQ29_A @S9S_MB_2U_LIB.S9S_MB_2U(SCH_1):M_D_CPU1_SA_DQ(29)
 192 M_D_CPU1_SA_DQ<30> DQ30_A @S9S_MB_2U_LIB.S9S_MB_2U(SCH_1):M_D_CPU1_SA_DQ(30)
 229 M_D_CPU1_SB_CS_N<3> CS1_B_N @S9S_MB_2U_LIB.S9S_MB_2U(SCH_1):M_D_CPU1_SB_CS_N(3)
 209 M_D_CPU1_SA_CS_N<3> CS1_A_N @S9S_MB_2U_LIB.S9S_MB_2U(SCH_1):M_D_CPU1_SA_CS_N(3)
  84 M_D_CPU1_SB_CS_N<2> CS0_B_N @S9S_MB_2U_LIB.S9S_MB_2U(SCH_1):M_D_CPU1_SB_CS_N(2)
  64 M_D_CPU1_SA_CS_N<2> CS0_A_N @S9S_MB_2U_LIB.S9S_MB_2U(SCH_1):M_D_CPU1_SA_CS_N(2)
 217 M_D_CPU1_CLK_DP<1>   CK_T @S9S_MB_2U_LIB.S9S_MB_2U(SCH_1):M_D_CPU1_CLK_DP(1)
 218 M_D_CPU1_CLK_DN<1>   CK_C @S9S_MB_2U_LIB.S9S_MB_2U(SCH_1):M_D_CPU1_CLK_DN(1)
  96 M_D_CPU1_SB_CB<0>  CB0_B @S9S_MB_2U_LIB.S9S_MB_2U(SCH_1):M_D_CPU1_SB_CB(0)
  98 M_D_CPU1_SB_CB<1>  CB1_B @S9S_MB_2U_LIB.S9S_MB_2U(SCH_1):M_D_CPU1_SB_CB(1)
 241 M_D_CPU1_SB_CB<2>  CB2_B @S9S_MB_2U_LIB.S9S_MB_2U(SCH_1):M_D_CPU1_SB_CB(2)
 243 M_D_CPU1_SB_CB<3>  CB3_B @S9S_MB_2U_LIB.S9S_MB_2U(SCH_1):M_D_CPU1_SB_CB(3)
  89 M_D_CPU1_SB_CB<4>  CB4_B @S9S_MB_2U_LIB.S9S_MB_2U(SCH_1):M_D_CPU1_SB_CB(4)
  91 M_D_CPU1_SB_CB<5>  CB5_B @S9S_MB_2U_LIB.S9S_MB_2U(SCH_1):M_D_CPU1_SB_CB(5)
 234 M_D_CPU1_SB_CB<6>  CB6_B @S9S_MB_2U_LIB.S9S_MB_2U(SCH_1):M_D_CPU1_SB_CB(6)
  51 M_D_CPU1_SA_CB<0>  CB0_A @S9S_MB_2U_LIB.S9S_MB_2U(SCH_1):M_D_CPU1_SA_CB(0)
 196 M_D_CPU1_SA_CB<2>  CB2_A @S9S_MB_2U_LIB.S9S_MB_2U(SCH_1):M_D_CPU1_SA_CB(2)
 198 M_D_CPU1_SA_CB<3>  CB3_A @S9S_MB_2U_LIB.S9S_MB_2U(SCH_1):M_D_CPU1_SA_CB(3)
  60 M_D_CPU1_SA_CB<5>  CB5_A @S9S_MB_2U_LIB.S9S_MB_2U(SCH_1):M_D_CPU1_SA_CB(5)
 203 M_D_CPU1_SA_CB<6>  CB6_A @S9S_MB_2U_LIB.S9S_MB_2U(SCH_1):M_D_CPU1_SA_CB(6)
  82 M_D_CPU1_SB_CA<6>  CA6_B @S9S_MB_2U_LIB.S9S_MB_2U(SCH_1):M_D_CPU1_SB_CA(6)
  72 M_D_CPU1_SA_CA<6>  CA6_A @S9S_MB_2U_LIB.S9S_MB_2U(SCH_1):M_D_CPU1_SA_CA(6)
 225 M_D_CPU1_SB_CA<5>  CA5_B @S9S_MB_2U_LIB.S9S_MB_2U(SCH_1):M_D_CPU1_SB_CA(5)
 215 M_D_CPU1_SA_CA<5>  CA5_A @S9S_MB_2U_LIB.S9S_MB_2U(SCH_1):M_D_CPU1_SA_CA(5)
  80 M_D_CPU1_SB_CA<4>  CA4_B @S9S_MB_2U_LIB.S9S_MB_2U(SCH_1):M_D_CPU1_SB_CA(4)
  70 M_D_CPU1_SA_CA<4>  CA4_A @S9S_MB_2U_LIB.S9S_MB_2U(SCH_1):M_D_CPU1_SA_CA(4)
 223 M_D_CPU1_SB_CA<3>  CA3_B @S9S_MB_2U_LIB.S9S_MB_2U(SCH_1):M_D_CPU1_SB_CA(3)
 213 M_D_CPU1_SA_CA<3>  CA3_A @S9S_MB_2U_LIB.S9S_MB_2U(SCH_1):M_D_CPU1_SA_CA(3)
  78 M_D_CPU1_SB_CA<2>  CA2_B @S9S_MB_2U_LIB.S9S_MB_2U(SCH_1):M_D_CPU1_SB_CA(2)
  68 M_D_CPU1_SA_CA<2>  CA2_A @S9S_MB_2U_LIB.S9S_MB_2U(SCH_1):M_D_CPU1_SA_CA(2)
 221 M_D_CPU1_SB_CA<1>  CA1_B @S9S_MB_2U_LIB.S9S_MB_2U(SCH_1):M_D_CPU1_SB_CA(1)
 211 M_D_CPU1_SA_CA<1>  CA1_A @S9S_MB_2U_LIB.S9S_MB_2U(SCH_1):M_D_CPU1_SA_CA(1)
  76 M_D_CPU1_SB_CA<0>  CA0_B @S9S_MB_2U_LIB.S9S_MB_2U(SCH_1):M_D_CPU1_SB_CA(0)
  66 M_D_CPU1_SA_CA<0>  CA0_A @S9S_MB_2U_LIB.S9S_MB_2U(SCH_1):M_D_CPU1_SA_CA(0)
  62 M_D_CPU1_ALERT_N ALERT_N @S9S_MB_2U_LIB.S9S_MB_2U(SCH_1):M_D_CPU1_ALERT_N
 236 M_D_CPU1_SB_CB<7>  CB7_B @S9S_MB_2U_LIB.S9S_MB_2U(SCH_1):M_D_CPU1_SB_CB(7)
  53 M_D_CPU1_SA_CB<1>  CB1_A @S9S_MB_2U_LIB.S9S_MB_2U(SCH_1):M_D_CPU1_SA_CB(1)
  58 M_D_CPU1_SA_CB<4>  CB4_A @S9S_MB_2U_LIB.S9S_MB_2U(SCH_1):M_D_CPU1_SA_CB(4)
 205 M_D_CPU1_SA_CB<7>  CB7_A @S9S_MB_2U_LIB.S9S_MB_2U(SCH_1):M_D_CPU1_SA_CB(7)
 194 M_D_CPU1_SA_DQ<31> DQ31_A @S9S_MB_2U_LIB.S9S_MB_2U(SCH_1):M_D_CPU1_SA_DQ(31)

SCONN288_ADR50017P087CC-SCONN2A  I180  J24
   6    GND   VSS0 @S9S_MB_2U_LIB.S9S_MB_2U(SCH_1):GND
   8    GND   VSS1 @S9S_MB_2U_LIB.S9S_MB_2U(SCH_1):GND
  10    GND   VSS2 @S9S_MB_2U_LIB.S9S_MB_2U(SCH_1):GND
  13    GND   VSS3 @S9S_MB_2U_LIB.S9S_MB_2U(SCH_1):GND
  15    GND   VSS4 @S9S_MB_2U_LIB.S9S_MB_2U(SCH_1):GND
  17    GND   VSS5 @S9S_MB_2U_LIB.S9S_MB_2U(SCH_1):GND
  19    GND   VSS6 @S9S_MB_2U_LIB.S9S_MB_2U(SCH_1):GND
  21    GND   VSS7 @S9S_MB_2U_LIB.S9S_MB_2U(SCH_1):GND
  24    GND   VSS8 @S9S_MB_2U_LIB.S9S_MB_2U(SCH_1):GND
  26    GND   VSS9 @S9S_MB_2U_LIB.S9S_MB_2U(SCH_1):GND
  28    GND  VSS10 @S9S_MB_2U_LIB.S9S_MB_2U(SCH_1):GND
  30    GND  VSS11 @S9S_MB_2U_LIB.S9S_MB_2U(SCH_1):GND
  32    GND  VSS12 @S9S_MB_2U_LIB.S9S_MB_2U(SCH_1):GND
  35    GND  VSS13 @S9S_MB_2U_LIB.S9S_MB_2U(SCH_1):GND
  37    GND  VSS14 @S9S_MB_2U_LIB.S9S_MB_2U(SCH_1):GND
  39    GND  VSS15 @S9S_MB_2U_LIB.S9S_MB_2U(SCH_1):GND
  41    GND  VSS16 @S9S_MB_2U_LIB.S9S_MB_2U(SCH_1):GND
  43    GND  VSS17 @S9S_MB_2U_LIB.S9S_MB_2U(SCH_1):GND
  46    GND  VSS18 @S9S_MB_2U_LIB.S9S_MB_2U(SCH_1):GND
  48    GND  VSS19 @S9S_MB_2U_LIB.S9S_MB_2U(SCH_1):GND
  50    GND  VSS20 @S9S_MB_2U_LIB.S9S_MB_2U(SCH_1):GND
  52    GND  VSS21 @S9S_MB_2U_LIB.S9S_MB_2U(SCH_1):GND
  54    GND  VSS22 @S9S_MB_2U_LIB.S9S_MB_2U(SCH_1):GND
  57    GND  VSS23 @S9S_MB_2U_LIB.S9S_MB_2U(SCH_1):GND
  59    GND  VSS24 @S9S_MB_2U_LIB.S9S_MB_2U(SCH_1):GND
  61    GND  VSS25 @S9S_MB_2U_LIB.S9S_MB_2U(SCH_1):GND
  63    GND  VSS26 @S9S_MB_2U_LIB.S9S_MB_2U(SCH_1):GND
  65    GND  VSS27 @S9S_MB_2U_LIB.S9S_MB_2U(SCH_1):GND
  67    GND  VSS28 @S9S_MB_2U_LIB.S9S_MB_2U(SCH_1):GND
  69    GND  VSS29 @S9S_MB_2U_LIB.S9S_MB_2U(SCH_1):GND
  71    GND  VSS30 @S9S_MB_2U_LIB.S9S_MB_2U(SCH_1):GND
  73    GND  VSS31 @S9S_MB_2U_LIB.S9S_MB_2U(SCH_1):GND
  75    GND  VSS32 @S9S_MB_2U_LIB.S9S_MB_2U(SCH_1):GND
  77    GND  VSS33 @S9S_MB_2U_LIB.S9S_MB_2U(SCH_1):GND
  79    GND  VSS34 @S9S_MB_2U_LIB.S9S_MB_2U(SCH_1):GND
  81    GND  VSS35 @S9S_MB_2U_LIB.S9S_MB_2U(SCH_1):GND
  83    GND  VSS36 @S9S_MB_2U_LIB.S9S_MB_2U(SCH_1):GND
  85    GND  VSS37 @S9S_MB_2U_LIB.S9S_MB_2U(SCH_1):GND
  88    GND  VSS38 @S9S_MB_2U_LIB.S9S_MB_2U(SCH_1):GND
  90    GND  VSS39 @S9S_MB_2U_LIB.S9S_MB_2U(SCH_1):GND
  92    GND  VSS40 @S9S_MB_2U_LIB.S9S_MB_2U(SCH_1):GND
  95    GND  VSS41 @S9S_MB_2U_LIB.S9S_MB_2U(SCH_1):GND
  97    GND  VSS42 @S9S_MB_2U_LIB.S9S_MB_2U(SCH_1):GND
  99    GND  VSS43 @S9S_MB_2U_LIB.S9S_MB_2U(SCH_1):GND
 101    GND  VSS44 @S9S_MB_2U_LIB.S9S_MB_2U(SCH_1):GND
 103    GND  VSS45 @S9S_MB_2U_LIB.S9S_MB_2U(SCH_1):GND
 106    GND  VSS46 @S9S_MB_2U_LIB.S9S_MB_2U(SCH_1):GND
 108    GND  VSS47 @S9S_MB_2U_LIB.S9S_MB_2U(SCH_1):GND
 110    GND  VSS48 @S9S_MB_2U_LIB.S9S_MB_2U(SCH_1):GND
 112    GND  VSS49 @S9S_MB_2U_LIB.S9S_MB_2U(SCH_1):GND
 114    GND  VSS50 @S9S_MB_2U_LIB.S9S_MB_2U(SCH_1):GND
 117    GND  VSS51 @S9S_MB_2U_LIB.S9S_MB_2U(SCH_1):GND
 119    GND  VSS52 @S9S_MB_2U_LIB.S9S_MB_2U(SCH_1):GND
 121    GND  VSS53 @S9S_MB_2U_LIB.S9S_MB_2U(SCH_1):GND
 123    GND  VSS54 @S9S_MB_2U_LIB.S9S_MB_2U(SCH_1):GND
 125    GND  VSS55 @S9S_MB_2U_LIB.S9S_MB_2U(SCH_1):GND
 128    GND  VSS56 @S9S_MB_2U_LIB.S9S_MB_2U(SCH_1):GND
 130    GND  VSS57 @S9S_MB_2U_LIB.S9S_MB_2U(SCH_1):GND
 134    GND  VSS59 @S9S_MB_2U_LIB.S9S_MB_2U(SCH_1):GND
 143    GND  VSS63 @S9S_MB_2U_LIB.S9S_MB_2U(SCH_1):GND
 151    GND  VSS64 @S9S_MB_2U_LIB.S9S_MB_2U(SCH_1):GND
 153    GND  VSS65 @S9S_MB_2U_LIB.S9S_MB_2U(SCH_1):GND
 155    GND  VSS66 @S9S_MB_2U_LIB.S9S_MB_2U(SCH_1):GND
 158    GND  VSS67 @S9S_MB_2U_LIB.S9S_MB_2U(SCH_1):GND
 160    GND  VSS68 @S9S_MB_2U_LIB.S9S_MB_2U(SCH_1):GND
 162    GND  VSS69 @S9S_MB_2U_LIB.S9S_MB_2U(SCH_1):GND
 164    GND  VSS70 @S9S_MB_2U_LIB.S9S_MB_2U(SCH_1):GND
 166    GND  VSS71 @S9S_MB_2U_LIB.S9S_MB_2U(SCH_1):GND
 169    GND  VSS72 @S9S_MB_2U_LIB.S9S_MB_2U(SCH_1):GND
 171    GND  VSS73 @S9S_MB_2U_LIB.S9S_MB_2U(SCH_1):GND
 173    GND  VSS74 @S9S_MB_2U_LIB.S9S_MB_2U(SCH_1):GND
 175    GND  VSS75 @S9S_MB_2U_LIB.S9S_MB_2U(SCH_1):GND
 177    GND  VSS76 @S9S_MB_2U_LIB.S9S_MB_2U(SCH_1):GND
 180    GND  VSS77 @S9S_MB_2U_LIB.S9S_MB_2U(SCH_1):GND
 182    GND  VSS78 @S9S_MB_2U_LIB.S9S_MB_2U(SCH_1):GND
 184    GND  VSS79 @S9S_MB_2U_LIB.S9S_MB_2U(SCH_1):GND
 186    GND  VSS80 @S9S_MB_2U_LIB.S9S_MB_2U(SCH_1):GND
 188    GND  VSS81 @S9S_MB_2U_LIB.S9S_MB_2U(SCH_1):GND
 191    GND  VSS82 @S9S_MB_2U_LIB.S9S_MB_2U(SCH_1):GND
 193    GND  VSS83 @S9S_MB_2U_LIB.S9S_MB_2U(SCH_1):GND
 195    GND  VSS84 @S9S_MB_2U_LIB.S9S_MB_2U(SCH_1):GND
 197    GND  VSS85 @S9S_MB_2U_LIB.S9S_MB_2U(SCH_1):GND
 199    GND  VSS86 @S9S_MB_2U_LIB.S9S_MB_2U(SCH_1):GND
 202    GND  VSS87 @S9S_MB_2U_LIB.S9S_MB_2U(SCH_1):GND
 204    GND  VSS88 @S9S_MB_2U_LIB.S9S_MB_2U(SCH_1):GND
 206    GND  VSS89 @S9S_MB_2U_LIB.S9S_MB_2U(SCH_1):GND
 208    GND  VSS90 @S9S_MB_2U_LIB.S9S_MB_2U(SCH_1):GND
 210    GND  VSS91 @S9S_MB_2U_LIB.S9S_MB_2U(SCH_1):GND
 212    GND  VSS92 @S9S_MB_2U_LIB.S9S_MB_2U(SCH_1):GND
 214    GND  VSS93 @S9S_MB_2U_LIB.S9S_MB_2U(SCH_1):GND
 216    GND  VSS94 @S9S_MB_2U_LIB.S9S_MB_2U(SCH_1):GND
 219    GND  VSS95 @S9S_MB_2U_LIB.S9S_MB_2U(SCH_1):GND
 222    GND  VSS96 @S9S_MB_2U_LIB.S9S_MB_2U(SCH_1):GND
 224    GND  VSS97 @S9S_MB_2U_LIB.S9S_MB_2U(SCH_1):GND
 226    GND  VSS98 @S9S_MB_2U_LIB.S9S_MB_2U(SCH_1):GND
 228    GND  VSS99 @S9S_MB_2U_LIB.S9S_MB_2U(SCH_1):GND
 233    GND VSS101 @S9S_MB_2U_LIB.S9S_MB_2U(SCH_1):GND
 237    GND VSS103 @S9S_MB_2U_LIB.S9S_MB_2U(SCH_1):GND
 242    GND VSS105 @S9S_MB_2U_LIB.S9S_MB_2U(SCH_1):GND
 244    GND VSS106 @S9S_MB_2U_LIB.S9S_MB_2U(SCH_1):GND
 246    GND VSS107 @S9S_MB_2U_LIB.S9S_MB_2U(SCH_1):GND
 248    GND VSS108 @S9S_MB_2U_LIB.S9S_MB_2U(SCH_1):GND
 251    GND VSS109 @S9S_MB_2U_LIB.S9S_MB_2U(SCH_1):GND
 253    GND VSS110 @S9S_MB_2U_LIB.S9S_MB_2U(SCH_1):GND
 255    GND VSS111 @S9S_MB_2U_LIB.S9S_MB_2U(SCH_1):GND
 257    GND VSS112 @S9S_MB_2U_LIB.S9S_MB_2U(SCH_1):GND
 259    GND VSS113 @S9S_MB_2U_LIB.S9S_MB_2U(SCH_1):GND
 262    GND VSS114 @S9S_MB_2U_LIB.S9S_MB_2U(SCH_1):GND
 264    GND VSS115 @S9S_MB_2U_LIB.S9S_MB_2U(SCH_1):GND
 266    GND VSS116 @S9S_MB_2U_LIB.S9S_MB_2U(SCH_1):GND
 268    GND VSS117 @S9S_MB_2U_LIB.S9S_MB_2U(SCH_1):GND
 270    GND VSS118 @S9S_MB_2U_LIB.S9S_MB_2U(SCH_1):GND
 273    GND VSS119 @S9S_MB_2U_LIB.S9S_MB_2U(SCH_1):GND
 275    GND VSS120 @S9S_MB_2U_LIB.S9S_MB_2U(SCH_1):GND
 277    GND VSS121 @S9S_MB_2U_LIB.S9S_MB_2U(SCH_1):GND
 279    GND VSS122 @S9S_MB_2U_LIB.S9S_MB_2U(SCH_1):GND
 281    GND VSS123 @S9S_MB_2U_LIB.S9S_MB_2U(SCH_1):GND
 284    GND VSS124 @S9S_MB_2U_LIB.S9S_MB_2U(SCH_1):GND
 286    GND VSS125 @S9S_MB_2U_LIB.S9S_MB_2U(SCH_1):GND
 288    GND VSS126 @S9S_MB_2U_LIB.S9S_MB_2U(SCH_1):GND
   1 P12V_S3_AUX_CPU1_NVDIMM VIN_BULK0 @S9S_MB_2U_LIB.S9S_MB_2U(SCH_1):P12V_S3_AUX_CPU1_NVDIMM
 145 P12V_S3_AUX_CPU1_NVDIMM VIN_BULK1 @S9S_MB_2U_LIB.S9S_MB_2U(SCH_1):P12V_S3_AUX_CPU1_NVDIMM
 146 P12V_S3_AUX_CPU1_NVDIMM VIN_BULK2 @S9S_MB_2U_LIB.S9S_MB_2U(SCH_1):P12V_S3_AUX_CPU1_NVDIMM
 230    GND VSS100 @S9S_MB_2U_LIB.S9S_MB_2U(SCH_1):GND
 235    GND VSS102 @S9S_MB_2U_LIB.S9S_MB_2U(SCH_1):GND
 240    GND VSS104 @S9S_MB_2U_LIB.S9S_MB_2U(SCH_1):GND
 132    GND  VSS58 @S9S_MB_2U_LIB.S9S_MB_2U(SCH_1):GND
 136    GND  VSS60 @S9S_MB_2U_LIB.S9S_MB_2U(SCH_1):GND
 139    GND  VSS61 @S9S_MB_2U_LIB.S9S_MB_2U(SCH_1):GND
 141    GND  VSS62 @S9S_MB_2U_LIB.S9S_MB_2U(SCH_1):GND
  G1    GND     G1 @S9S_MB_2U_LIB.S9S_MB_2U(SCH_1):GND
  G2    GND     G2 @S9S_MB_2U_LIB.S9S_MB_2U(SCH_1):GND
  G3    GND     G3 @S9S_MB_2U_LIB.S9S_MB_2U(SCH_1):GND

SCONN288_ADR50017P087CC-SCONN2A  I181  J24
  93 M_D_CPU1_SB_DQS_DP<9> DQS9_B_T||TDQS9_B_T||DBI4_B_N @S9S_MB_2U_LIB.S9S_MB_2U(SCH_1):M_D_CPU1_SB_DQS_DP(9)
  94 M_D_CPU1_SB_DQS_DN<9> DQS9_B_C||TDQS9_B_C @S9S_MB_2U_LIB.S9S_MB_2U(SCH_1):M_D_CPU1_SB_DQS_DN(9)
 201 M_D_CPU1_SA_DQS_DP<9> DQS9_A_T||TDQS9_A_T @S9S_MB_2U_LIB.S9S_MB_2U(SCH_1):M_D_CPU1_SA_DQS_DP(9)
 200 M_D_CPU1_SA_DQS_DN<9> DQS9_A_C||TDQS9_A_C @S9S_MB_2U_LIB.S9S_MB_2U(SCH_1):M_D_CPU1_SA_DQS_DN(9)
 190 M_D_CPU1_SA_DQS_DP<8> DQS8_A_T||TDQS8_A_T @S9S_MB_2U_LIB.S9S_MB_2U(SCH_1):M_D_CPU1_SA_DQS_DP(8)
 189 M_D_CPU1_SA_DQS_DN<8> DQS8_A_C||TDQS8_A_C @S9S_MB_2U_LIB.S9S_MB_2U(SCH_1):M_D_CPU1_SA_DQS_DN(8)
 271 M_D_CPU1_SB_DQS_DN<7> DQS7_B_C||TDQS7_B_C @S9S_MB_2U_LIB.S9S_MB_2U(SCH_1):M_D_CPU1_SB_DQS_DN(7)
 179 M_D_CPU1_SA_DQS_DP<7> DQS7_A_T||TDQS7_A_T @S9S_MB_2U_LIB.S9S_MB_2U(SCH_1):M_D_CPU1_SA_DQS_DP(7)
 261 M_D_CPU1_SB_DQS_DP<6> DQS6_B_T||TDQS6_B_T @S9S_MB_2U_LIB.S9S_MB_2U(SCH_1):M_D_CPU1_SB_DQS_DP(6)
 260 M_D_CPU1_SB_DQS_DN<6> DQS6_B_C||TDQS6_B_C @S9S_MB_2U_LIB.S9S_MB_2U(SCH_1):M_D_CPU1_SB_DQS_DN(6)
 167 M_D_CPU1_SA_DQS_DN<6> DQS6_A_C||TDQS6_A_C||DQS6_A_T||TDQS6_A_T @S9S_MB_2U_LIB.S9S_MB_2U(SCH_1):M_D_CPU1_SA_DQS_DN(6)
 250 M_D_CPU1_SB_DQS_DP<5> DQS5_B_T||TDQS5_B_T @S9S_MB_2U_LIB.S9S_MB_2U(SCH_1):M_D_CPU1_SB_DQS_DP(5)
 249 M_D_CPU1_SB_DQS_DN<5> DQS5_B_C||TDQS5_B_C @S9S_MB_2U_LIB.S9S_MB_2U(SCH_1):M_D_CPU1_SB_DQS_DN(5)
 157 M_D_CPU1_SA_DQS_DP<5> DQS5_A_T||TDQS5_A_T @S9S_MB_2U_LIB.S9S_MB_2U(SCH_1):M_D_CPU1_SA_DQS_DP(5)
 156 M_D_CPU1_SA_DQS_DN<5> DQS5_A_C||TDQS5_A_C||DQS5_A_T||TDQS5_A_T @S9S_MB_2U_LIB.S9S_MB_2U(SCH_1):M_D_CPU1_SA_DQS_DN(5)
 239 M_D_CPU1_SB_DQS_DP<4> DQS4_B_T @S9S_MB_2U_LIB.S9S_MB_2U(SCH_1):M_D_CPU1_SB_DQS_DP(4)
 238 M_D_CPU1_SB_DQS_DN<4> DQS4_B_C @S9S_MB_2U_LIB.S9S_MB_2U(SCH_1):M_D_CPU1_SB_DQS_DN(4)
  55 M_D_CPU1_SA_DQS_DP<4> DQS4_A_T @S9S_MB_2U_LIB.S9S_MB_2U(SCH_1):M_D_CPU1_SA_DQS_DP(4)
  56 M_D_CPU1_SA_DQS_DN<4> DQS4_A_C @S9S_MB_2U_LIB.S9S_MB_2U(SCH_1):M_D_CPU1_SA_DQS_DN(4)
 137 M_D_CPU1_SB_DQS_DP<3> DQS3_B_T @S9S_MB_2U_LIB.S9S_MB_2U(SCH_1):M_D_CPU1_SB_DQS_DP(3)
 138 M_D_CPU1_SB_DQS_DN<3> DQS3_B_C @S9S_MB_2U_LIB.S9S_MB_2U(SCH_1):M_D_CPU1_SB_DQS_DN(3)
  44 M_D_CPU1_SA_DQS_DP<3> DQS3_A_T @S9S_MB_2U_LIB.S9S_MB_2U(SCH_1):M_D_CPU1_SA_DQS_DP(3)
  45 M_D_CPU1_SA_DQS_DN<3> DQS3_A_C @S9S_MB_2U_LIB.S9S_MB_2U(SCH_1):M_D_CPU1_SA_DQS_DN(3)
 126 M_D_CPU1_SB_DQS_DP<2> DQS2_B_T @S9S_MB_2U_LIB.S9S_MB_2U(SCH_1):M_D_CPU1_SB_DQS_DP(2)
 127 M_D_CPU1_SB_DQS_DN<2> DQS2_B_C @S9S_MB_2U_LIB.S9S_MB_2U(SCH_1):M_D_CPU1_SB_DQS_DN(2)
  33 M_D_CPU1_SA_DQS_DP<2> DQS2_A_T @S9S_MB_2U_LIB.S9S_MB_2U(SCH_1):M_D_CPU1_SA_DQS_DP(2)
  34 M_D_CPU1_SA_DQS_DN<2> DQS2_A_C @S9S_MB_2U_LIB.S9S_MB_2U(SCH_1):M_D_CPU1_SA_DQS_DN(2)
 115 M_D_CPU1_SB_DQS_DP<1> DQS1_B_T @S9S_MB_2U_LIB.S9S_MB_2U(SCH_1):M_D_CPU1_SB_DQS_DP(1)
 116 M_D_CPU1_SB_DQS_DN<1> DQS1_B_C @S9S_MB_2U_LIB.S9S_MB_2U(SCH_1):M_D_CPU1_SB_DQS_DN(1)
  22 M_D_CPU1_SA_DQS_DP<1> DQS1_A_T @S9S_MB_2U_LIB.S9S_MB_2U(SCH_1):M_D_CPU1_SA_DQS_DP(1)
  23 M_D_CPU1_SA_DQS_DN<1> DQS1_A_C @S9S_MB_2U_LIB.S9S_MB_2U(SCH_1):M_D_CPU1_SA_DQS_DN(1)
 104 M_D_CPU1_SB_DQS_DP<0> DQS0_B_T @S9S_MB_2U_LIB.S9S_MB_2U(SCH_1):M_D_CPU1_SB_DQS_DP(0)
 105 M_D_CPU1_SB_DQS_DN<0> DQS0_B_C @S9S_MB_2U_LIB.S9S_MB_2U(SCH_1):M_D_CPU1_SB_DQS_DN(0)
  11 M_D_CPU1_SA_DQS_DP<0> DQS0_A_T @S9S_MB_2U_LIB.S9S_MB_2U(SCH_1):M_D_CPU1_SA_DQS_DP(0)
  12 M_D_CPU1_SA_DQS_DN<0> DQS0_A_C @S9S_MB_2U_LIB.S9S_MB_2U(SCH_1):M_D_CPU1_SA_DQS_DN(0)
 272 M_D_CPU1_SB_DQS_DP<7> DQS7_B_T||TDQS7_B_T @S9S_MB_2U_LIB.S9S_MB_2U(SCH_1):M_D_CPU1_SB_DQS_DP(7)
 282 M_D_CPU1_SB_DQS_DN<8> DQS8_B_C||TDQS8_B_C @S9S_MB_2U_LIB.S9S_MB_2U(SCH_1):M_D_CPU1_SB_DQS_DN(8)
 283 M_D_CPU1_SB_DQS_DP<8> DQS8_B_T||TDQS8_B_T @S9S_MB_2U_LIB.S9S_MB_2U(SCH_1):M_D_CPU1_SB_DQS_DP(8)
 168 M_D_CPU1_SA_DQS_DP<6> DQS6_A_T||TDQS6_A_T @S9S_MB_2U_LIB.S9S_MB_2U(SCH_1):M_D_CPU1_SA_DQS_DP(6)
 178 M_D_CPU1_SA_DQS_DN<7> DQS7_A_C||TDQS7_A_C @S9S_MB_2U_LIB.S9S_MB_2U(SCH_1):M_D_CPU1_SA_DQS_DN(7)

Q_RES_0402LF-49.9,1%,1/16W,CHIA  I183  R3898
   1 I3C_SPD_DDRABCD_CPU1_LVC1_SCL_7      A @S9S_MB_2U_LIB.S9S_MB_2U(SCH_1):I3C_SPD_DDRABCD_CPU1_LVC1_SCL_R8
   2 I3C_SPD_DDRABCD_CPU1_LVC1_SCL      B @S9S_MB_2U_LIB.S9S_MB_2U(SCH_1):I3C_SPD_DDRABCD_CPU1_LVC1_SCL


DRAWING: @S9S_MB_2U_LIB.S9S_MB_2U(SCH_1):PAGE106 

Q_RES_0402LF-10K,1%,1/16W,CHIPA  I2  R79
   1 PD_CHE_CPU1_DIMM1_SAA      A @S9S_MB_2U_LIB.S9S_MB_2U(SCH_1):PD_CHE_CPU1_DIMM1_SAA
   2    GND      B @S9S_MB_2U_LIB.S9S_MB_2U(SCH_1):GND

Q_CAP_C0402-2.2UF,6.3V,20%,X6SA  I122  C93
   1 P3V3_AUX      A @S9S_MB_2U_LIB.S9S_MB_2U(SCH_1):P3V3_AUX
   2    GND      B @S9S_MB_2U_LIB.S9S_MB_2U(SCH_1):GND

Q_CAP_C0805-10UF,16V,10%,X6S,CA  I127  C94
   1 P12V_S3_AUX_CPU1_NVDIMM      A @S9S_MB_2U_LIB.S9S_MB_2U(SCH_1):P12V_S3_AUX_CPU1_NVDIMM
   2    GND      B @S9S_MB_2U_LIB.S9S_MB_2U(SCH_1):GND

Q_CAP_C0805-10UF,16V,10%,X6S,CA  I130  C95
   1 P12V_S3_AUX_CPU1_NVDIMM      A @S9S_MB_2U_LIB.S9S_MB_2U(SCH_1):P12V_S3_AUX_CPU1_NVDIMM
   2    GND      B @S9S_MB_2U_LIB.S9S_MB_2U(SCH_1):GND

SCONN288_ADR50017P130CC-SCONN2A  I178  J25
   6    GND   VSS0 @S9S_MB_2U_LIB.S9S_MB_2U(SCH_1):GND
   8    GND   VSS1 @S9S_MB_2U_LIB.S9S_MB_2U(SCH_1):GND
  10    GND   VSS2 @S9S_MB_2U_LIB.S9S_MB_2U(SCH_1):GND
  13    GND   VSS3 @S9S_MB_2U_LIB.S9S_MB_2U(SCH_1):GND
  15    GND   VSS4 @S9S_MB_2U_LIB.S9S_MB_2U(SCH_1):GND
  17    GND   VSS5 @S9S_MB_2U_LIB.S9S_MB_2U(SCH_1):GND
  19    GND   VSS6 @S9S_MB_2U_LIB.S9S_MB_2U(SCH_1):GND
  21    GND   VSS7 @S9S_MB_2U_LIB.S9S_MB_2U(SCH_1):GND
  24    GND   VSS8 @S9S_MB_2U_LIB.S9S_MB_2U(SCH_1):GND
  26    GND   VSS9 @S9S_MB_2U_LIB.S9S_MB_2U(SCH_1):GND
  28    GND  VSS10 @S9S_MB_2U_LIB.S9S_MB_2U(SCH_1):GND
  30    GND  VSS11 @S9S_MB_2U_LIB.S9S_MB_2U(SCH_1):GND
  32    GND  VSS12 @S9S_MB_2U_LIB.S9S_MB_2U(SCH_1):GND
  35    GND  VSS13 @S9S_MB_2U_LIB.S9S_MB_2U(SCH_1):GND
  37    GND  VSS14 @S9S_MB_2U_LIB.S9S_MB_2U(SCH_1):GND
  39    GND  VSS15 @S9S_MB_2U_LIB.S9S_MB_2U(SCH_1):GND
  41    GND  VSS16 @S9S_MB_2U_LIB.S9S_MB_2U(SCH_1):GND
  43    GND  VSS17 @S9S_MB_2U_LIB.S9S_MB_2U(SCH_1):GND
  46    GND  VSS18 @S9S_MB_2U_LIB.S9S_MB_2U(SCH_1):GND
  48    GND  VSS19 @S9S_MB_2U_LIB.S9S_MB_2U(SCH_1):GND
  50    GND  VSS20 @S9S_MB_2U_LIB.S9S_MB_2U(SCH_1):GND
  52    GND  VSS21 @S9S_MB_2U_LIB.S9S_MB_2U(SCH_1):GND
  54    GND  VSS22 @S9S_MB_2U_LIB.S9S_MB_2U(SCH_1):GND
  57    GND  VSS23 @S9S_MB_2U_LIB.S9S_MB_2U(SCH_1):GND
  59    GND  VSS24 @S9S_MB_2U_LIB.S9S_MB_2U(SCH_1):GND
  61    GND  VSS25 @S9S_MB_2U_LIB.S9S_MB_2U(SCH_1):GND
  63    GND  VSS26 @S9S_MB_2U_LIB.S9S_MB_2U(SCH_1):GND
  65    GND  VSS27 @S9S_MB_2U_LIB.S9S_MB_2U(SCH_1):GND
  67    GND  VSS28 @S9S_MB_2U_LIB.S9S_MB_2U(SCH_1):GND
  69    GND  VSS29 @S9S_MB_2U_LIB.S9S_MB_2U(SCH_1):GND
  71    GND  VSS30 @S9S_MB_2U_LIB.S9S_MB_2U(SCH_1):GND
  73    GND  VSS31 @S9S_MB_2U_LIB.S9S_MB_2U(SCH_1):GND
  75    GND  VSS32 @S9S_MB_2U_LIB.S9S_MB_2U(SCH_1):GND
  77    GND  VSS33 @S9S_MB_2U_LIB.S9S_MB_2U(SCH_1):GND
  79    GND  VSS34 @S9S_MB_2U_LIB.S9S_MB_2U(SCH_1):GND
  81    GND  VSS35 @S9S_MB_2U_LIB.S9S_MB_2U(SCH_1):GND
  83    GND  VSS36 @S9S_MB_2U_LIB.S9S_MB_2U(SCH_1):GND
  85    GND  VSS37 @S9S_MB_2U_LIB.S9S_MB_2U(SCH_1):GND
  88    GND  VSS38 @S9S_MB_2U_LIB.S9S_MB_2U(SCH_1):GND
  90    GND  VSS39 @S9S_MB_2U_LIB.S9S_MB_2U(SCH_1):GND
  92    GND  VSS40 @S9S_MB_2U_LIB.S9S_MB_2U(SCH_1):GND
  95    GND  VSS41 @S9S_MB_2U_LIB.S9S_MB_2U(SCH_1):GND
  97    GND  VSS42 @S9S_MB_2U_LIB.S9S_MB_2U(SCH_1):GND
  99    GND  VSS43 @S9S_MB_2U_LIB.S9S_MB_2U(SCH_1):GND
 101    GND  VSS44 @S9S_MB_2U_LIB.S9S_MB_2U(SCH_1):GND
 103    GND  VSS45 @S9S_MB_2U_LIB.S9S_MB_2U(SCH_1):GND
 106    GND  VSS46 @S9S_MB_2U_LIB.S9S_MB_2U(SCH_1):GND
 108    GND  VSS47 @S9S_MB_2U_LIB.S9S_MB_2U(SCH_1):GND
 110    GND  VSS48 @S9S_MB_2U_LIB.S9S_MB_2U(SCH_1):GND
 112    GND  VSS49 @S9S_MB_2U_LIB.S9S_MB_2U(SCH_1):GND
 114    GND  VSS50 @S9S_MB_2U_LIB.S9S_MB_2U(SCH_1):GND
 117    GND  VSS51 @S9S_MB_2U_LIB.S9S_MB_2U(SCH_1):GND
 119    GND  VSS52 @S9S_MB_2U_LIB.S9S_MB_2U(SCH_1):GND
 121    GND  VSS53 @S9S_MB_2U_LIB.S9S_MB_2U(SCH_1):GND
 123    GND  VSS54 @S9S_MB_2U_LIB.S9S_MB_2U(SCH_1):GND
 125    GND  VSS55 @S9S_MB_2U_LIB.S9S_MB_2U(SCH_1):GND
 128    GND  VSS56 @S9S_MB_2U_LIB.S9S_MB_2U(SCH_1):GND
 130    GND  VSS57 @S9S_MB_2U_LIB.S9S_MB_2U(SCH_1):GND
 134    GND  VSS59 @S9S_MB_2U_LIB.S9S_MB_2U(SCH_1):GND
 143    GND  VSS63 @S9S_MB_2U_LIB.S9S_MB_2U(SCH_1):GND
 151    GND  VSS64 @S9S_MB_2U_LIB.S9S_MB_2U(SCH_1):GND
 153    GND  VSS65 @S9S_MB_2U_LIB.S9S_MB_2U(SCH_1):GND
 155    GND  VSS66 @S9S_MB_2U_LIB.S9S_MB_2U(SCH_1):GND
 158    GND  VSS67 @S9S_MB_2U_LIB.S9S_MB_2U(SCH_1):GND
 160    GND  VSS68 @S9S_MB_2U_LIB.S9S_MB_2U(SCH_1):GND
 162    GND  VSS69 @S9S_MB_2U_LIB.S9S_MB_2U(SCH_1):GND
 164    GND  VSS70 @S9S_MB_2U_LIB.S9S_MB_2U(SCH_1):GND
 166    GND  VSS71 @S9S_MB_2U_LIB.S9S_MB_2U(SCH_1):GND
 169    GND  VSS72 @S9S_MB_2U_LIB.S9S_MB_2U(SCH_1):GND
 171    GND  VSS73 @S9S_MB_2U_LIB.S9S_MB_2U(SCH_1):GND
 173    GND  VSS74 @S9S_MB_2U_LIB.S9S_MB_2U(SCH_1):GND
 175    GND  VSS75 @S9S_MB_2U_LIB.S9S_MB_2U(SCH_1):GND
 177    GND  VSS76 @S9S_MB_2U_LIB.S9S_MB_2U(SCH_1):GND
 180    GND  VSS77 @S9S_MB_2U_LIB.S9S_MB_2U(SCH_1):GND
 182    GND  VSS78 @S9S_MB_2U_LIB.S9S_MB_2U(SCH_1):GND
 184    GND  VSS79 @S9S_MB_2U_LIB.S9S_MB_2U(SCH_1):GND
 186    GND  VSS80 @S9S_MB_2U_LIB.S9S_MB_2U(SCH_1):GND
 188    GND  VSS81 @S9S_MB_2U_LIB.S9S_MB_2U(SCH_1):GND
 191    GND  VSS82 @S9S_MB_2U_LIB.S9S_MB_2U(SCH_1):GND
 193    GND  VSS83 @S9S_MB_2U_LIB.S9S_MB_2U(SCH_1):GND
 195    GND  VSS84 @S9S_MB_2U_LIB.S9S_MB_2U(SCH_1):GND
 197    GND  VSS85 @S9S_MB_2U_LIB.S9S_MB_2U(SCH_1):GND
 199    GND  VSS86 @S9S_MB_2U_LIB.S9S_MB_2U(SCH_1):GND
 202    GND  VSS87 @S9S_MB_2U_LIB.S9S_MB_2U(SCH_1):GND
 204    GND  VSS88 @S9S_MB_2U_LIB.S9S_MB_2U(SCH_1):GND
 206    GND  VSS89 @S9S_MB_2U_LIB.S9S_MB_2U(SCH_1):GND
 208    GND  VSS90 @S9S_MB_2U_LIB.S9S_MB_2U(SCH_1):GND
 210    GND  VSS91 @S9S_MB_2U_LIB.S9S_MB_2U(SCH_1):GND
 212    GND  VSS92 @S9S_MB_2U_LIB.S9S_MB_2U(SCH_1):GND
 214    GND  VSS93 @S9S_MB_2U_LIB.S9S_MB_2U(SCH_1):GND
 216    GND  VSS94 @S9S_MB_2U_LIB.S9S_MB_2U(SCH_1):GND
 219    GND  VSS95 @S9S_MB_2U_LIB.S9S_MB_2U(SCH_1):GND
 222    GND  VSS96 @S9S_MB_2U_LIB.S9S_MB_2U(SCH_1):GND
 224    GND  VSS97 @S9S_MB_2U_LIB.S9S_MB_2U(SCH_1):GND
 226    GND  VSS98 @S9S_MB_2U_LIB.S9S_MB_2U(SCH_1):GND
 228    GND  VSS99 @S9S_MB_2U_LIB.S9S_MB_2U(SCH_1):GND
 233    GND VSS101 @S9S_MB_2U_LIB.S9S_MB_2U(SCH_1):GND
 237    GND VSS103 @S9S_MB_2U_LIB.S9S_MB_2U(SCH_1):GND
 242    GND VSS105 @S9S_MB_2U_LIB.S9S_MB_2U(SCH_1):GND
 244    GND VSS106 @S9S_MB_2U_LIB.S9S_MB_2U(SCH_1):GND
 246    GND VSS107 @S9S_MB_2U_LIB.S9S_MB_2U(SCH_1):GND
 248    GND VSS108 @S9S_MB_2U_LIB.S9S_MB_2U(SCH_1):GND
 251    GND VSS109 @S9S_MB_2U_LIB.S9S_MB_2U(SCH_1):GND
 253    GND VSS110 @S9S_MB_2U_LIB.S9S_MB_2U(SCH_1):GND
 255    GND VSS111 @S9S_MB_2U_LIB.S9S_MB_2U(SCH_1):GND
 257    GND VSS112 @S9S_MB_2U_LIB.S9S_MB_2U(SCH_1):GND
 259    GND VSS113 @S9S_MB_2U_LIB.S9S_MB_2U(SCH_1):GND
 262    GND VSS114 @S9S_MB_2U_LIB.S9S_MB_2U(SCH_1):GND
 264    GND VSS115 @S9S_MB_2U_LIB.S9S_MB_2U(SCH_1):GND
 266    GND VSS116 @S9S_MB_2U_LIB.S9S_MB_2U(SCH_1):GND
 268    GND VSS117 @S9S_MB_2U_LIB.S9S_MB_2U(SCH_1):GND
 270    GND VSS118 @S9S_MB_2U_LIB.S9S_MB_2U(SCH_1):GND
 273    GND VSS119 @S9S_MB_2U_LIB.S9S_MB_2U(SCH_1):GND
 275    GND VSS120 @S9S_MB_2U_LIB.S9S_MB_2U(SCH_1):GND
 277    GND VSS121 @S9S_MB_2U_LIB.S9S_MB_2U(SCH_1):GND
 279    GND VSS122 @S9S_MB_2U_LIB.S9S_MB_2U(SCH_1):GND
 281    GND VSS123 @S9S_MB_2U_LIB.S9S_MB_2U(SCH_1):GND
 284    GND VSS124 @S9S_MB_2U_LIB.S9S_MB_2U(SCH_1):GND
 286    GND VSS125 @S9S_MB_2U_LIB.S9S_MB_2U(SCH_1):GND
 288    GND VSS126 @S9S_MB_2U_LIB.S9S_MB_2U(SCH_1):GND
   1 P12V_S3_AUX_CPU1_NVDIMM VIN_BULK0 @S9S_MB_2U_LIB.S9S_MB_2U(SCH_1):P12V_S3_AUX_CPU1_NVDIMM
 145 P12V_S3_AUX_CPU1_NVDIMM VIN_BULK1 @S9S_MB_2U_LIB.S9S_MB_2U(SCH_1):P12V_S3_AUX_CPU1_NVDIMM
 146 P12V_S3_AUX_CPU1_NVDIMM VIN_BULK2 @S9S_MB_2U_LIB.S9S_MB_2U(SCH_1):P12V_S3_AUX_CPU1_NVDIMM
 230    GND VSS100 @S9S_MB_2U_LIB.S9S_MB_2U(SCH_1):GND
 235    GND VSS102 @S9S_MB_2U_LIB.S9S_MB_2U(SCH_1):GND
 240    GND VSS104 @S9S_MB_2U_LIB.S9S_MB_2U(SCH_1):GND
 132    GND  VSS58 @S9S_MB_2U_LIB.S9S_MB_2U(SCH_1):GND
 136    GND  VSS60 @S9S_MB_2U_LIB.S9S_MB_2U(SCH_1):GND
 139    GND  VSS61 @S9S_MB_2U_LIB.S9S_MB_2U(SCH_1):GND
 141    GND  VSS62 @S9S_MB_2U_LIB.S9S_MB_2U(SCH_1):GND
  G1    GND     G1 @S9S_MB_2U_LIB.S9S_MB_2U(SCH_1):GND
  G2    GND     G2 @S9S_MB_2U_LIB.S9S_MB_2U(SCH_1):GND
  G3    GND     G3 @S9S_MB_2U_LIB.S9S_MB_2U(SCH_1):GND

SCONN288_ADR50017P130CC-SCONN2A  I180  J25
   3 P3V3_AUX VIN_MGMT @S9S_MB_2U_LIB.S9S_MB_2U(SCH_1):P3V3_AUX
   2 TP_CHE_CPU1_DIMM1_FRU_0   RFU0 @S9S_MB_2U_LIB.S9S_MB_2U(SCH_1):TP_CHE_CPU1_DIMM1_FRU_0
 144 TP_CHE_CPU1_DIMM1_FRU_1   RFU1 @S9S_MB_2U_LIB.S9S_MB_2U(SCH_1):TP_CHE_CPU1_DIMM1_FRU_1
 149 TP_CHE_CPU1_DIMM1_FRU_2   RFU2 @S9S_MB_2U_LIB.S9S_MB_2U(SCH_1):TP_CHE_CPU1_DIMM1_FRU_2
 150 TP_CHE_CPU1_DIMM1_FRU_3   RFU3 @S9S_MB_2U_LIB.S9S_MB_2U(SCH_1):TP_CHE_CPU1_DIMM1_FRU_3
 220 TP_CHE_CPU1_DIMM1_FRU_4   RFU4 @S9S_MB_2U_LIB.S9S_MB_2U(SCH_1):TP_CHE_CPU1_DIMM1_FRU_4
 231 TP_CHE_CPU1_DIMM1_FRU_5   RFU5 @S9S_MB_2U_LIB.S9S_MB_2U(SCH_1):TP_CHE_CPU1_DIMM1_FRU_5
 232 TP_CHE_CPU1_DIMM1_FRU_6   RFU6 @S9S_MB_2U_LIB.S9S_MB_2U(SCH_1):TP_CHE_CPU1_DIMM1_FRU_6
 207 RST_M_EF_CPU1_FPGA_N RESET_N @S9S_MB_2U_LIB.S9S_MB_2U(SCH_1):RST_M_EF_CPU1_FPGA_N
 147 PWRGD_CHE_CPU1_DIMM1 PWR_GOOD||FAIL_N @S9S_MB_2U_LIB.S9S_MB_2U(SCH_1):PWRGD_CHE_CPU1_DIMM1
 227 M_E_CPU1_SB_PAR  PAR_B @S9S_MB_2U_LIB.S9S_MB_2U(SCH_1):M_E_CPU1_SB_PAR
  74 M_E_CPU1_SA_PAR  PAR_A @S9S_MB_2U_LIB.S9S_MB_2U(SCH_1):M_E_CPU1_SA_PAR
  87 M_E_CPU1_SB_RSP<0> LBS||RSP_B_N @S9S_MB_2U_LIB.S9S_MB_2U(SCH_1):M_E_CPU1_SB_RSP(0)
  86 M_E_CPU1_SA_RSP<0> LBD||RSP_A_N @S9S_MB_2U_LIB.S9S_MB_2U(SCH_1):M_E_CPU1_SA_RSP(0)
   5 I3C_SPD_DDREFGH_CPU1_LVC1_SDA   HSDA @S9S_MB_2U_LIB.S9S_MB_2U(SCH_1):I3C_SPD_DDREFGH_CPU1_LVC1_SDA
   4 I3C_SPD_DDREFGH_CPU1_LVC1_SCL_R   HSCL @S9S_MB_2U_LIB.S9S_MB_2U(SCH_1):I3C_SPD_DDREFGH_CPU1_LVC1_SCL_R1
 148 PD_CHE_CPU1_DIMM1_SAA    HSA @S9S_MB_2U_LIB.S9S_MB_2U(SCH_1):PD_CHE_CPU1_DIMM1_SAA
 100 M_E_CPU1_SB_DQ<0>  DQ0_B @S9S_MB_2U_LIB.S9S_MB_2U(SCH_1):M_E_CPU1_SB_DQ(0)
 102 M_E_CPU1_SB_DQ<1>  DQ1_B @S9S_MB_2U_LIB.S9S_MB_2U(SCH_1):M_E_CPU1_SB_DQ(1)
 245 M_E_CPU1_SB_DQ<2>  DQ2_B @S9S_MB_2U_LIB.S9S_MB_2U(SCH_1):M_E_CPU1_SB_DQ(2)
 247 M_E_CPU1_SB_DQ<3>  DQ3_B @S9S_MB_2U_LIB.S9S_MB_2U(SCH_1):M_E_CPU1_SB_DQ(3)
 107 M_E_CPU1_SB_DQ<4>  DQ4_B @S9S_MB_2U_LIB.S9S_MB_2U(SCH_1):M_E_CPU1_SB_DQ(4)
 109 M_E_CPU1_SB_DQ<5>  DQ5_B @S9S_MB_2U_LIB.S9S_MB_2U(SCH_1):M_E_CPU1_SB_DQ(5)
 252 M_E_CPU1_SB_DQ<6>  DQ6_B @S9S_MB_2U_LIB.S9S_MB_2U(SCH_1):M_E_CPU1_SB_DQ(6)
 254 M_E_CPU1_SB_DQ<7>  DQ7_B @S9S_MB_2U_LIB.S9S_MB_2U(SCH_1):M_E_CPU1_SB_DQ(7)
 111 M_E_CPU1_SB_DQ<8>  DQ8_B @S9S_MB_2U_LIB.S9S_MB_2U(SCH_1):M_E_CPU1_SB_DQ(8)
 113 M_E_CPU1_SB_DQ<9>  DQ9_B @S9S_MB_2U_LIB.S9S_MB_2U(SCH_1):M_E_CPU1_SB_DQ(9)
 256 M_E_CPU1_SB_DQ<10> DQ10_B @S9S_MB_2U_LIB.S9S_MB_2U(SCH_1):M_E_CPU1_SB_DQ(10)
 258 M_E_CPU1_SB_DQ<11> DQ11_B @S9S_MB_2U_LIB.S9S_MB_2U(SCH_1):M_E_CPU1_SB_DQ(11)
 118 M_E_CPU1_SB_DQ<12> DQ12_B @S9S_MB_2U_LIB.S9S_MB_2U(SCH_1):M_E_CPU1_SB_DQ(12)
 120 M_E_CPU1_SB_DQ<13> DQ13_B @S9S_MB_2U_LIB.S9S_MB_2U(SCH_1):M_E_CPU1_SB_DQ(13)
 263 M_E_CPU1_SB_DQ<14> DQ14_B @S9S_MB_2U_LIB.S9S_MB_2U(SCH_1):M_E_CPU1_SB_DQ(14)
 265 M_E_CPU1_SB_DQ<15> DQ15_B @S9S_MB_2U_LIB.S9S_MB_2U(SCH_1):M_E_CPU1_SB_DQ(15)
 122 M_E_CPU1_SB_DQ<16> DQ16_B @S9S_MB_2U_LIB.S9S_MB_2U(SCH_1):M_E_CPU1_SB_DQ(16)
 124 M_E_CPU1_SB_DQ<17> DQ17_B @S9S_MB_2U_LIB.S9S_MB_2U(SCH_1):M_E_CPU1_SB_DQ(17)
 267 M_E_CPU1_SB_DQ<18> DQ18_B @S9S_MB_2U_LIB.S9S_MB_2U(SCH_1):M_E_CPU1_SB_DQ(18)
 269 M_E_CPU1_SB_DQ<19> DQ19_B @S9S_MB_2U_LIB.S9S_MB_2U(SCH_1):M_E_CPU1_SB_DQ(19)
 129 M_E_CPU1_SB_DQ<20> DQ20_B @S9S_MB_2U_LIB.S9S_MB_2U(SCH_1):M_E_CPU1_SB_DQ(20)
 131 M_E_CPU1_SB_DQ<21> DQ21_B @S9S_MB_2U_LIB.S9S_MB_2U(SCH_1):M_E_CPU1_SB_DQ(21)
 274 M_E_CPU1_SB_DQ<22> DQ22_B @S9S_MB_2U_LIB.S9S_MB_2U(SCH_1):M_E_CPU1_SB_DQ(22)
 276 M_E_CPU1_SB_DQ<23> DQ23_B @S9S_MB_2U_LIB.S9S_MB_2U(SCH_1):M_E_CPU1_SB_DQ(23)
 133 M_E_CPU1_SB_DQ<24> DQ24_B @S9S_MB_2U_LIB.S9S_MB_2U(SCH_1):M_E_CPU1_SB_DQ(24)
 135 M_E_CPU1_SB_DQ<25> DQ25_B @S9S_MB_2U_LIB.S9S_MB_2U(SCH_1):M_E_CPU1_SB_DQ(25)
 278 M_E_CPU1_SB_DQ<26> DQ26_B @S9S_MB_2U_LIB.S9S_MB_2U(SCH_1):M_E_CPU1_SB_DQ(26)
 280 M_E_CPU1_SB_DQ<27> DQ27_B @S9S_MB_2U_LIB.S9S_MB_2U(SCH_1):M_E_CPU1_SB_DQ(27)
 140 M_E_CPU1_SB_DQ<28> DQ28_B @S9S_MB_2U_LIB.S9S_MB_2U(SCH_1):M_E_CPU1_SB_DQ(28)
 142 M_E_CPU1_SB_DQ<29> DQ29_B @S9S_MB_2U_LIB.S9S_MB_2U(SCH_1):M_E_CPU1_SB_DQ(29)
 285 M_E_CPU1_SB_DQ<30> DQ30_B @S9S_MB_2U_LIB.S9S_MB_2U(SCH_1):M_E_CPU1_SB_DQ(30)
 287 M_E_CPU1_SB_DQ<31> DQ31_B @S9S_MB_2U_LIB.S9S_MB_2U(SCH_1):M_E_CPU1_SB_DQ(31)
   7 M_E_CPU1_SA_DQ<0>  DQ0_A @S9S_MB_2U_LIB.S9S_MB_2U(SCH_1):M_E_CPU1_SA_DQ(0)
   9 M_E_CPU1_SA_DQ<1>  DQ1_A @S9S_MB_2U_LIB.S9S_MB_2U(SCH_1):M_E_CPU1_SA_DQ(1)
 152 M_E_CPU1_SA_DQ<2>  DQ2_A @S9S_MB_2U_LIB.S9S_MB_2U(SCH_1):M_E_CPU1_SA_DQ(2)
 154 M_E_CPU1_SA_DQ<3>  DQ3_A @S9S_MB_2U_LIB.S9S_MB_2U(SCH_1):M_E_CPU1_SA_DQ(3)
  14 M_E_CPU1_SA_DQ<4>  DQ4_A @S9S_MB_2U_LIB.S9S_MB_2U(SCH_1):M_E_CPU1_SA_DQ(4)
  16 M_E_CPU1_SA_DQ<5>  DQ5_A @S9S_MB_2U_LIB.S9S_MB_2U(SCH_1):M_E_CPU1_SA_DQ(5)
 159 M_E_CPU1_SA_DQ<6>  DQ6_A @S9S_MB_2U_LIB.S9S_MB_2U(SCH_1):M_E_CPU1_SA_DQ(6)
 161 M_E_CPU1_SA_DQ<7>  DQ7_A @S9S_MB_2U_LIB.S9S_MB_2U(SCH_1):M_E_CPU1_SA_DQ(7)
  18 M_E_CPU1_SA_DQ<8>  DQ8_A @S9S_MB_2U_LIB.S9S_MB_2U(SCH_1):M_E_CPU1_SA_DQ(8)
  20 M_E_CPU1_SA_DQ<9>  DQ9_A @S9S_MB_2U_LIB.S9S_MB_2U(SCH_1):M_E_CPU1_SA_DQ(9)
 163 M_E_CPU1_SA_DQ<10> DQ10_A @S9S_MB_2U_LIB.S9S_MB_2U(SCH_1):M_E_CPU1_SA_DQ(10)
 165 M_E_CPU1_SA_DQ<11> DQ11_A @S9S_MB_2U_LIB.S9S_MB_2U(SCH_1):M_E_CPU1_SA_DQ(11)
  25 M_E_CPU1_SA_DQ<12> DQ12_A @S9S_MB_2U_LIB.S9S_MB_2U(SCH_1):M_E_CPU1_SA_DQ(12)
  27 M_E_CPU1_SA_DQ<13> DQ13_A @S9S_MB_2U_LIB.S9S_MB_2U(SCH_1):M_E_CPU1_SA_DQ(13)
 170 M_E_CPU1_SA_DQ<14> DQ14_A @S9S_MB_2U_LIB.S9S_MB_2U(SCH_1):M_E_CPU1_SA_DQ(14)
 172 M_E_CPU1_SA_DQ<15> DQ15_A @S9S_MB_2U_LIB.S9S_MB_2U(SCH_1):M_E_CPU1_SA_DQ(15)
  29 M_E_CPU1_SA_DQ<16> DQ16_A @S9S_MB_2U_LIB.S9S_MB_2U(SCH_1):M_E_CPU1_SA_DQ(16)
  31 M_E_CPU1_SA_DQ<17> DQ17_A @S9S_MB_2U_LIB.S9S_MB_2U(SCH_1):M_E_CPU1_SA_DQ(17)
 174 M_E_CPU1_SA_DQ<18> DQ18_A @S9S_MB_2U_LIB.S9S_MB_2U(SCH_1):M_E_CPU1_SA_DQ(18)
 176 M_E_CPU1_SA_DQ<19> DQ19_A @S9S_MB_2U_LIB.S9S_MB_2U(SCH_1):M_E_CPU1_SA_DQ(19)
  36 M_E_CPU1_SA_DQ<20> DQ20_A @S9S_MB_2U_LIB.S9S_MB_2U(SCH_1):M_E_CPU1_SA_DQ(20)
  38 M_E_CPU1_SA_DQ<21> DQ21_A @S9S_MB_2U_LIB.S9S_MB_2U(SCH_1):M_E_CPU1_SA_DQ(21)
 181 M_E_CPU1_SA_DQ<22> DQ22_A @S9S_MB_2U_LIB.S9S_MB_2U(SCH_1):M_E_CPU1_SA_DQ(22)
 183 M_E_CPU1_SA_DQ<23> DQ23_A @S9S_MB_2U_LIB.S9S_MB_2U(SCH_1):M_E_CPU1_SA_DQ(23)
  40 M_E_CPU1_SA_DQ<24> DQ24_A @S9S_MB_2U_LIB.S9S_MB_2U(SCH_1):M_E_CPU1_SA_DQ(24)
  42 M_E_CPU1_SA_DQ<25> DQ25_A @S9S_MB_2U_LIB.S9S_MB_2U(SCH_1):M_E_CPU1_SA_DQ(25)
 185 M_E_CPU1_SA_DQ<26> DQ26_A @S9S_MB_2U_LIB.S9S_MB_2U(SCH_1):M_E_CPU1_SA_DQ(26)
 187 M_E_CPU1_SA_DQ<27> DQ27_A @S9S_MB_2U_LIB.S9S_MB_2U(SCH_1):M_E_CPU1_SA_DQ(27)
  47 M_E_CPU1_SA_DQ<28> DQ28_A @S9S_MB_2U_LIB.S9S_MB_2U(SCH_1):M_E_CPU1_SA_DQ(28)
  49 M_E_CPU1_SA_DQ<29> DQ29_A @S9S_MB_2U_LIB.S9S_MB_2U(SCH_1):M_E_CPU1_SA_DQ(29)
 192 M_E_CPU1_SA_DQ<30> DQ30_A @S9S_MB_2U_LIB.S9S_MB_2U(SCH_1):M_E_CPU1_SA_DQ(30)
 229 M_E_CPU1_SB_CS_N<1> CS1_B_N @S9S_MB_2U_LIB.S9S_MB_2U(SCH_1):M_E_CPU1_SB_CS_N(1)
 209 M_E_CPU1_SA_CS_N<1> CS1_A_N @S9S_MB_2U_LIB.S9S_MB_2U(SCH_1):M_E_CPU1_SA_CS_N(1)
  84 M_E_CPU1_SB_CS_N<0> CS0_B_N @S9S_MB_2U_LIB.S9S_MB_2U(SCH_1):M_E_CPU1_SB_CS_N(0)
  64 M_E_CPU1_SA_CS_N<0> CS0_A_N @S9S_MB_2U_LIB.S9S_MB_2U(SCH_1):M_E_CPU1_SA_CS_N(0)
 217 M_E_CPU1_CLK_DP<0>   CK_T @S9S_MB_2U_LIB.S9S_MB_2U(SCH_1):M_E_CPU1_CLK_DP(0)
 218 M_E_CPU1_CLK_DN<0>   CK_C @S9S_MB_2U_LIB.S9S_MB_2U(SCH_1):M_E_CPU1_CLK_DN(0)
  96 M_E_CPU1_SB_CB<0>  CB0_B @S9S_MB_2U_LIB.S9S_MB_2U(SCH_1):M_E_CPU1_SB_CB(0)
  98 M_E_CPU1_SB_CB<1>  CB1_B @S9S_MB_2U_LIB.S9S_MB_2U(SCH_1):M_E_CPU1_SB_CB(1)
 241 M_E_CPU1_SB_CB<2>  CB2_B @S9S_MB_2U_LIB.S9S_MB_2U(SCH_1):M_E_CPU1_SB_CB(2)
 243 M_E_CPU1_SB_CB<3>  CB3_B @S9S_MB_2U_LIB.S9S_MB_2U(SCH_1):M_E_CPU1_SB_CB(3)
  89 M_E_CPU1_SB_CB<4>  CB4_B @S9S_MB_2U_LIB.S9S_MB_2U(SCH_1):M_E_CPU1_SB_CB(4)
  91 M_E_CPU1_SB_CB<5>  CB5_B @S9S_MB_2U_LIB.S9S_MB_2U(SCH_1):M_E_CPU1_SB_CB(5)
 234 M_E_CPU1_SB_CB<6>  CB6_B @S9S_MB_2U_LIB.S9S_MB_2U(SCH_1):M_E_CPU1_SB_CB(6)
  51 M_E_CPU1_SA_CB<0>  CB0_A @S9S_MB_2U_LIB.S9S_MB_2U(SCH_1):M_E_CPU1_SA_CB(0)
 196 M_E_CPU1_SA_CB<2>  CB2_A @S9S_MB_2U_LIB.S9S_MB_2U(SCH_1):M_E_CPU1_SA_CB(2)
 198 M_E_CPU1_SA_CB<3>  CB3_A @S9S_MB_2U_LIB.S9S_MB_2U(SCH_1):M_E_CPU1_SA_CB(3)
  60 M_E_CPU1_SA_CB<5>  CB5_A @S9S_MB_2U_LIB.S9S_MB_2U(SCH_1):M_E_CPU1_SA_CB(5)
 203 M_E_CPU1_SA_CB<6>  CB6_A @S9S_MB_2U_LIB.S9S_MB_2U(SCH_1):M_E_CPU1_SA_CB(6)
  82 M_E_CPU1_SB_CA<6>  CA6_B @S9S_MB_2U_LIB.S9S_MB_2U(SCH_1):M_E_CPU1_SB_CA(6)
  72 M_E_CPU1_SA_CA<6>  CA6_A @S9S_MB_2U_LIB.S9S_MB_2U(SCH_1):M_E_CPU1_SA_CA(6)
 225 M_E_CPU1_SB_CA<5>  CA5_B @S9S_MB_2U_LIB.S9S_MB_2U(SCH_1):M_E_CPU1_SB_CA(5)
 215 M_E_CPU1_SA_CA<5>  CA5_A @S9S_MB_2U_LIB.S9S_MB_2U(SCH_1):M_E_CPU1_SA_CA(5)
  80 M_E_CPU1_SB_CA<4>  CA4_B @S9S_MB_2U_LIB.S9S_MB_2U(SCH_1):M_E_CPU1_SB_CA(4)
  70 M_E_CPU1_SA_CA<4>  CA4_A @S9S_MB_2U_LIB.S9S_MB_2U(SCH_1):M_E_CPU1_SA_CA(4)
 223 M_E_CPU1_SB_CA<3>  CA3_B @S9S_MB_2U_LIB.S9S_MB_2U(SCH_1):M_E_CPU1_SB_CA(3)
 213 M_E_CPU1_SA_CA<3>  CA3_A @S9S_MB_2U_LIB.S9S_MB_2U(SCH_1):M_E_CPU1_SA_CA(3)
  78 M_E_CPU1_SB_CA<2>  CA2_B @S9S_MB_2U_LIB.S9S_MB_2U(SCH_1):M_E_CPU1_SB_CA(2)
  68 M_E_CPU1_SA_CA<2>  CA2_A @S9S_MB_2U_LIB.S9S_MB_2U(SCH_1):M_E_CPU1_SA_CA(2)
 221 M_E_CPU1_SB_CA<1>  CA1_B @S9S_MB_2U_LIB.S9S_MB_2U(SCH_1):M_E_CPU1_SB_CA(1)
 211 M_E_CPU1_SA_CA<1>  CA1_A @S9S_MB_2U_LIB.S9S_MB_2U(SCH_1):M_E_CPU1_SA_CA(1)
  76 M_E_CPU1_SB_CA<0>  CA0_B @S9S_MB_2U_LIB.S9S_MB_2U(SCH_1):M_E_CPU1_SB_CA(0)
  66 M_E_CPU1_SA_CA<0>  CA0_A @S9S_MB_2U_LIB.S9S_MB_2U(SCH_1):M_E_CPU1_SA_CA(0)
  62 M_E_CPU1_ALERT_N ALERT_N @S9S_MB_2U_LIB.S9S_MB_2U(SCH_1):M_E_CPU1_ALERT_N
 236 M_E_CPU1_SB_CB<7>  CB7_B @S9S_MB_2U_LIB.S9S_MB_2U(SCH_1):M_E_CPU1_SB_CB(7)
  53 M_E_CPU1_SA_CB<1>  CB1_A @S9S_MB_2U_LIB.S9S_MB_2U(SCH_1):M_E_CPU1_SA_CB(1)
  58 M_E_CPU1_SA_CB<4>  CB4_A @S9S_MB_2U_LIB.S9S_MB_2U(SCH_1):M_E_CPU1_SA_CB(4)
 205 M_E_CPU1_SA_CB<7>  CB7_A @S9S_MB_2U_LIB.S9S_MB_2U(SCH_1):M_E_CPU1_SA_CB(7)
 194 M_E_CPU1_SA_DQ<31> DQ31_A @S9S_MB_2U_LIB.S9S_MB_2U(SCH_1):M_E_CPU1_SA_DQ(31)

SCONN288_ADR50017P130CC-SCONN2A  I181  J25
  93 M_E_CPU1_SB_DQS_DP<9> DQS9_B_T||TDQS9_B_T||DBI4_B_N @S9S_MB_2U_LIB.S9S_MB_2U(SCH_1):M_E_CPU1_SB_DQS_DP(9)
  94 M_E_CPU1_SB_DQS_DN<9> DQS9_B_C||TDQS9_B_C @S9S_MB_2U_LIB.S9S_MB_2U(SCH_1):M_E_CPU1_SB_DQS_DN(9)
 201 M_E_CPU1_SA_DQS_DP<9> DQS9_A_T||TDQS9_A_T @S9S_MB_2U_LIB.S9S_MB_2U(SCH_1):M_E_CPU1_SA_DQS_DP(9)
 200 M_E_CPU1_SA_DQS_DN<9> DQS9_A_C||TDQS9_A_C @S9S_MB_2U_LIB.S9S_MB_2U(SCH_1):M_E_CPU1_SA_DQS_DN(9)
 190 M_E_CPU1_SA_DQS_DP<8> DQS8_A_T||TDQS8_A_T @S9S_MB_2U_LIB.S9S_MB_2U(SCH_1):M_E_CPU1_SA_DQS_DP(8)
 189 M_E_CPU1_SA_DQS_DN<8> DQS8_A_C||TDQS8_A_C @S9S_MB_2U_LIB.S9S_MB_2U(SCH_1):M_E_CPU1_SA_DQS_DN(8)
 271 M_E_CPU1_SB_DQS_DN<7> DQS7_B_C||TDQS7_B_C @S9S_MB_2U_LIB.S9S_MB_2U(SCH_1):M_E_CPU1_SB_DQS_DN(7)
 179 M_E_CPU1_SA_DQS_DP<7> DQS7_A_T||TDQS7_A_T @S9S_MB_2U_LIB.S9S_MB_2U(SCH_1):M_E_CPU1_SA_DQS_DP(7)
 261 M_E_CPU1_SB_DQS_DP<6> DQS6_B_T||TDQS6_B_T @S9S_MB_2U_LIB.S9S_MB_2U(SCH_1):M_E_CPU1_SB_DQS_DP(6)
 260 M_E_CPU1_SB_DQS_DN<6> DQS6_B_C||TDQS6_B_C @S9S_MB_2U_LIB.S9S_MB_2U(SCH_1):M_E_CPU1_SB_DQS_DN(6)
 167 M_E_CPU1_SA_DQS_DN<6> DQS6_A_C||TDQS6_A_C||DQS6_A_T||TDQS6_A_T @S9S_MB_2U_LIB.S9S_MB_2U(SCH_1):M_E_CPU1_SA_DQS_DN(6)
 250 M_E_CPU1_SB_DQS_DP<5> DQS5_B_T||TDQS5_B_T @S9S_MB_2U_LIB.S9S_MB_2U(SCH_1):M_E_CPU1_SB_DQS_DP(5)
 249 M_E_CPU1_SB_DQS_DN<5> DQS5_B_C||TDQS5_B_C @S9S_MB_2U_LIB.S9S_MB_2U(SCH_1):M_E_CPU1_SB_DQS_DN(5)
 157 M_E_CPU1_SA_DQS_DP<5> DQS5_A_T||TDQS5_A_T @S9S_MB_2U_LIB.S9S_MB_2U(SCH_1):M_E_CPU1_SA_DQS_DP(5)
 156 M_E_CPU1_SA_DQS_DN<5> DQS5_A_C||TDQS5_A_C||DQS5_A_T||TDQS5_A_T @S9S_MB_2U_LIB.S9S_MB_2U(SCH_1):M_E_CPU1_SA_DQS_DN(5)
 239 M_E_CPU1_SB_DQS_DP<4> DQS4_B_T @S9S_MB_2U_LIB.S9S_MB_2U(SCH_1):M_E_CPU1_SB_DQS_DP(4)
 238 M_E_CPU1_SB_DQS_DN<4> DQS4_B_C @S9S_MB_2U_LIB.S9S_MB_2U(SCH_1):M_E_CPU1_SB_DQS_DN(4)
  55 M_E_CPU1_SA_DQS_DP<4> DQS4_A_T @S9S_MB_2U_LIB.S9S_MB_2U(SCH_1):M_E_CPU1_SA_DQS_DP(4)
  56 M_E_CPU1_SA_DQS_DN<4> DQS4_A_C @S9S_MB_2U_LIB.S9S_MB_2U(SCH_1):M_E_CPU1_SA_DQS_DN(4)
 137 M_E_CPU1_SB_DQS_DP<3> DQS3_B_T @S9S_MB_2U_LIB.S9S_MB_2U(SCH_1):M_E_CPU1_SB_DQS_DP(3)
 138 M_E_CPU1_SB_DQS_DN<3> DQS3_B_C @S9S_MB_2U_LIB.S9S_MB_2U(SCH_1):M_E_CPU1_SB_DQS_DN(3)
  44 M_E_CPU1_SA_DQS_DP<3> DQS3_A_T @S9S_MB_2U_LIB.S9S_MB_2U(SCH_1):M_E_CPU1_SA_DQS_DP(3)
  45 M_E_CPU1_SA_DQS_DN<3> DQS3_A_C @S9S_MB_2U_LIB.S9S_MB_2U(SCH_1):M_E_CPU1_SA_DQS_DN(3)
 126 M_E_CPU1_SB_DQS_DP<2> DQS2_B_T @S9S_MB_2U_LIB.S9S_MB_2U(SCH_1):M_E_CPU1_SB_DQS_DP(2)
 127 M_E_CPU1_SB_DQS_DN<2> DQS2_B_C @S9S_MB_2U_LIB.S9S_MB_2U(SCH_1):M_E_CPU1_SB_DQS_DN(2)
  33 M_E_CPU1_SA_DQS_DP<2> DQS2_A_T @S9S_MB_2U_LIB.S9S_MB_2U(SCH_1):M_E_CPU1_SA_DQS_DP(2)
  34 M_E_CPU1_SA_DQS_DN<2> DQS2_A_C @S9S_MB_2U_LIB.S9S_MB_2U(SCH_1):M_E_CPU1_SA_DQS_DN(2)
 115 M_E_CPU1_SB_DQS_DP<1> DQS1_B_T @S9S_MB_2U_LIB.S9S_MB_2U(SCH_1):M_E_CPU1_SB_DQS_DP(1)
 116 M_E_CPU1_SB_DQS_DN<1> DQS1_B_C @S9S_MB_2U_LIB.S9S_MB_2U(SCH_1):M_E_CPU1_SB_DQS_DN(1)
  22 M_E_CPU1_SA_DQS_DP<1> DQS1_A_T @S9S_MB_2U_LIB.S9S_MB_2U(SCH_1):M_E_CPU1_SA_DQS_DP(1)
  23 M_E_CPU1_SA_DQS_DN<1> DQS1_A_C @S9S_MB_2U_LIB.S9S_MB_2U(SCH_1):M_E_CPU1_SA_DQS_DN(1)
 104 M_E_CPU1_SB_DQS_DP<0> DQS0_B_T @S9S_MB_2U_LIB.S9S_MB_2U(SCH_1):M_E_CPU1_SB_DQS_DP(0)
 105 M_E_CPU1_SB_DQS_DN<0> DQS0_B_C @S9S_MB_2U_LIB.S9S_MB_2U(SCH_1):M_E_CPU1_SB_DQS_DN(0)
  11 M_E_CPU1_SA_DQS_DP<0> DQS0_A_T @S9S_MB_2U_LIB.S9S_MB_2U(SCH_1):M_E_CPU1_SA_DQS_DP(0)
  12 M_E_CPU1_SA_DQS_DN<0> DQS0_A_C @S9S_MB_2U_LIB.S9S_MB_2U(SCH_1):M_E_CPU1_SA_DQS_DN(0)
 272 M_E_CPU1_SB_DQS_DP<7> DQS7_B_T||TDQS7_B_T @S9S_MB_2U_LIB.S9S_MB_2U(SCH_1):M_E_CPU1_SB_DQS_DP(7)
 282 M_E_CPU1_SB_DQS_DN<8> DQS8_B_C||TDQS8_B_C @S9S_MB_2U_LIB.S9S_MB_2U(SCH_1):M_E_CPU1_SB_DQS_DN(8)
 283 M_E_CPU1_SB_DQS_DP<8> DQS8_B_T||TDQS8_B_T @S9S_MB_2U_LIB.S9S_MB_2U(SCH_1):M_E_CPU1_SB_DQS_DP(8)
 168 M_E_CPU1_SA_DQS_DP<6> DQS6_A_T||TDQS6_A_T @S9S_MB_2U_LIB.S9S_MB_2U(SCH_1):M_E_CPU1_SA_DQS_DP(6)
 178 M_E_CPU1_SA_DQS_DN<7> DQS7_A_C||TDQS7_A_C @S9S_MB_2U_LIB.S9S_MB_2U(SCH_1):M_E_CPU1_SA_DQS_DN(7)

Q_RES_0402LF-49.9,1%,1/16W,CHIA  I183  R3899
   1 I3C_SPD_DDREFGH_CPU1_LVC1_SCL_R      A @S9S_MB_2U_LIB.S9S_MB_2U(SCH_1):I3C_SPD_DDREFGH_CPU1_LVC1_SCL_R1
   2 I3C_SPD_DDREFGH_CPU1_LVC1_SCL      B @S9S_MB_2U_LIB.S9S_MB_2U(SCH_1):I3C_SPD_DDREFGH_CPU1_LVC1_SCL


DRAWING: @S9S_MB_2U_LIB.S9S_MB_2U(SCH_1):PAGE107 

Q_RES_0402LF-15.4K,1%,1/16W,CHA  I2  R78
   1 PD_CHE_CPU1_DIMM2_SAA      A @S9S_MB_2U_LIB.S9S_MB_2U(SCH_1):PD_CHE_CPU1_DIMM2_SAA
   2    GND      B @S9S_MB_2U_LIB.S9S_MB_2U(SCH_1):GND

Q_CAP_C0402-2.2UF,6.3V,20%,X6SA  I122  C90
   1 P3V3_AUX      A @S9S_MB_2U_LIB.S9S_MB_2U(SCH_1):P3V3_AUX
   2    GND      B @S9S_MB_2U_LIB.S9S_MB_2U(SCH_1):GND

Q_CAP_C0805-10UF,16V,10%,X6S,CA  I126  C91
   1 P12V_S3_AUX_CPU1_NVDIMM      A @S9S_MB_2U_LIB.S9S_MB_2U(SCH_1):P12V_S3_AUX_CPU1_NVDIMM
   2    GND      B @S9S_MB_2U_LIB.S9S_MB_2U(SCH_1):GND

Q_CAP_C0805-10UF,16V,10%,X6S,CA  I128  C92
   1 P12V_S3_AUX_CPU1_NVDIMM      A @S9S_MB_2U_LIB.S9S_MB_2U(SCH_1):P12V_S3_AUX_CPU1_NVDIMM
   2    GND      B @S9S_MB_2U_LIB.S9S_MB_2U(SCH_1):GND

SCONN288_ADR50017P087CC-SCONN2A  I179  J26
   6    GND   VSS0 @S9S_MB_2U_LIB.S9S_MB_2U(SCH_1):GND
   8    GND   VSS1 @S9S_MB_2U_LIB.S9S_MB_2U(SCH_1):GND
  10    GND   VSS2 @S9S_MB_2U_LIB.S9S_MB_2U(SCH_1):GND
  13    GND   VSS3 @S9S_MB_2U_LIB.S9S_MB_2U(SCH_1):GND
  15    GND   VSS4 @S9S_MB_2U_LIB.S9S_MB_2U(SCH_1):GND
  17    GND   VSS5 @S9S_MB_2U_LIB.S9S_MB_2U(SCH_1):GND
  19    GND   VSS6 @S9S_MB_2U_LIB.S9S_MB_2U(SCH_1):GND
  21    GND   VSS7 @S9S_MB_2U_LIB.S9S_MB_2U(SCH_1):GND
  24    GND   VSS8 @S9S_MB_2U_LIB.S9S_MB_2U(SCH_1):GND
  26    GND   VSS9 @S9S_MB_2U_LIB.S9S_MB_2U(SCH_1):GND
  28    GND  VSS10 @S9S_MB_2U_LIB.S9S_MB_2U(SCH_1):GND
  30    GND  VSS11 @S9S_MB_2U_LIB.S9S_MB_2U(SCH_1):GND
  32    GND  VSS12 @S9S_MB_2U_LIB.S9S_MB_2U(SCH_1):GND
  35    GND  VSS13 @S9S_MB_2U_LIB.S9S_MB_2U(SCH_1):GND
  37    GND  VSS14 @S9S_MB_2U_LIB.S9S_MB_2U(SCH_1):GND
  39    GND  VSS15 @S9S_MB_2U_LIB.S9S_MB_2U(SCH_1):GND
  41    GND  VSS16 @S9S_MB_2U_LIB.S9S_MB_2U(SCH_1):GND
  43    GND  VSS17 @S9S_MB_2U_LIB.S9S_MB_2U(SCH_1):GND
  46    GND  VSS18 @S9S_MB_2U_LIB.S9S_MB_2U(SCH_1):GND
  48    GND  VSS19 @S9S_MB_2U_LIB.S9S_MB_2U(SCH_1):GND
  50    GND  VSS20 @S9S_MB_2U_LIB.S9S_MB_2U(SCH_1):GND
  52    GND  VSS21 @S9S_MB_2U_LIB.S9S_MB_2U(SCH_1):GND
  54    GND  VSS22 @S9S_MB_2U_LIB.S9S_MB_2U(SCH_1):GND
  57    GND  VSS23 @S9S_MB_2U_LIB.S9S_MB_2U(SCH_1):GND
  59    GND  VSS24 @S9S_MB_2U_LIB.S9S_MB_2U(SCH_1):GND
  61    GND  VSS25 @S9S_MB_2U_LIB.S9S_MB_2U(SCH_1):GND
  63    GND  VSS26 @S9S_MB_2U_LIB.S9S_MB_2U(SCH_1):GND
  65    GND  VSS27 @S9S_MB_2U_LIB.S9S_MB_2U(SCH_1):GND
  67    GND  VSS28 @S9S_MB_2U_LIB.S9S_MB_2U(SCH_1):GND
  69    GND  VSS29 @S9S_MB_2U_LIB.S9S_MB_2U(SCH_1):GND
  71    GND  VSS30 @S9S_MB_2U_LIB.S9S_MB_2U(SCH_1):GND
  73    GND  VSS31 @S9S_MB_2U_LIB.S9S_MB_2U(SCH_1):GND
  75    GND  VSS32 @S9S_MB_2U_LIB.S9S_MB_2U(SCH_1):GND
  77    GND  VSS33 @S9S_MB_2U_LIB.S9S_MB_2U(SCH_1):GND
  79    GND  VSS34 @S9S_MB_2U_LIB.S9S_MB_2U(SCH_1):GND
  81    GND  VSS35 @S9S_MB_2U_LIB.S9S_MB_2U(SCH_1):GND
  83    GND  VSS36 @S9S_MB_2U_LIB.S9S_MB_2U(SCH_1):GND
  85    GND  VSS37 @S9S_MB_2U_LIB.S9S_MB_2U(SCH_1):GND
  88    GND  VSS38 @S9S_MB_2U_LIB.S9S_MB_2U(SCH_1):GND
  90    GND  VSS39 @S9S_MB_2U_LIB.S9S_MB_2U(SCH_1):GND
  92    GND  VSS40 @S9S_MB_2U_LIB.S9S_MB_2U(SCH_1):GND
  95    GND  VSS41 @S9S_MB_2U_LIB.S9S_MB_2U(SCH_1):GND
  97    GND  VSS42 @S9S_MB_2U_LIB.S9S_MB_2U(SCH_1):GND
  99    GND  VSS43 @S9S_MB_2U_LIB.S9S_MB_2U(SCH_1):GND
 101    GND  VSS44 @S9S_MB_2U_LIB.S9S_MB_2U(SCH_1):GND
 103    GND  VSS45 @S9S_MB_2U_LIB.S9S_MB_2U(SCH_1):GND
 106    GND  VSS46 @S9S_MB_2U_LIB.S9S_MB_2U(SCH_1):GND
 108    GND  VSS47 @S9S_MB_2U_LIB.S9S_MB_2U(SCH_1):GND
 110    GND  VSS48 @S9S_MB_2U_LIB.S9S_MB_2U(SCH_1):GND
 112    GND  VSS49 @S9S_MB_2U_LIB.S9S_MB_2U(SCH_1):GND
 114    GND  VSS50 @S9S_MB_2U_LIB.S9S_MB_2U(SCH_1):GND
 117    GND  VSS51 @S9S_MB_2U_LIB.S9S_MB_2U(SCH_1):GND
 119    GND  VSS52 @S9S_MB_2U_LIB.S9S_MB_2U(SCH_1):GND
 121    GND  VSS53 @S9S_MB_2U_LIB.S9S_MB_2U(SCH_1):GND
 123    GND  VSS54 @S9S_MB_2U_LIB.S9S_MB_2U(SCH_1):GND
 125    GND  VSS55 @S9S_MB_2U_LIB.S9S_MB_2U(SCH_1):GND
 128    GND  VSS56 @S9S_MB_2U_LIB.S9S_MB_2U(SCH_1):GND
 130    GND  VSS57 @S9S_MB_2U_LIB.S9S_MB_2U(SCH_1):GND
 134    GND  VSS59 @S9S_MB_2U_LIB.S9S_MB_2U(SCH_1):GND
 143    GND  VSS63 @S9S_MB_2U_LIB.S9S_MB_2U(SCH_1):GND
 151    GND  VSS64 @S9S_MB_2U_LIB.S9S_MB_2U(SCH_1):GND
 153    GND  VSS65 @S9S_MB_2U_LIB.S9S_MB_2U(SCH_1):GND
 155    GND  VSS66 @S9S_MB_2U_LIB.S9S_MB_2U(SCH_1):GND
 158    GND  VSS67 @S9S_MB_2U_LIB.S9S_MB_2U(SCH_1):GND
 160    GND  VSS68 @S9S_MB_2U_LIB.S9S_MB_2U(SCH_1):GND
 162    GND  VSS69 @S9S_MB_2U_LIB.S9S_MB_2U(SCH_1):GND
 164    GND  VSS70 @S9S_MB_2U_LIB.S9S_MB_2U(SCH_1):GND
 166    GND  VSS71 @S9S_MB_2U_LIB.S9S_MB_2U(SCH_1):GND
 169    GND  VSS72 @S9S_MB_2U_LIB.S9S_MB_2U(SCH_1):GND
 171    GND  VSS73 @S9S_MB_2U_LIB.S9S_MB_2U(SCH_1):GND
 173    GND  VSS74 @S9S_MB_2U_LIB.S9S_MB_2U(SCH_1):GND
 175    GND  VSS75 @S9S_MB_2U_LIB.S9S_MB_2U(SCH_1):GND
 177    GND  VSS76 @S9S_MB_2U_LIB.S9S_MB_2U(SCH_1):GND
 180    GND  VSS77 @S9S_MB_2U_LIB.S9S_MB_2U(SCH_1):GND
 182    GND  VSS78 @S9S_MB_2U_LIB.S9S_MB_2U(SCH_1):GND
 184    GND  VSS79 @S9S_MB_2U_LIB.S9S_MB_2U(SCH_1):GND
 186    GND  VSS80 @S9S_MB_2U_LIB.S9S_MB_2U(SCH_1):GND
 188    GND  VSS81 @S9S_MB_2U_LIB.S9S_MB_2U(SCH_1):GND
 191    GND  VSS82 @S9S_MB_2U_LIB.S9S_MB_2U(SCH_1):GND
 193    GND  VSS83 @S9S_MB_2U_LIB.S9S_MB_2U(SCH_1):GND
 195    GND  VSS84 @S9S_MB_2U_LIB.S9S_MB_2U(SCH_1):GND
 197    GND  VSS85 @S9S_MB_2U_LIB.S9S_MB_2U(SCH_1):GND
 199    GND  VSS86 @S9S_MB_2U_LIB.S9S_MB_2U(SCH_1):GND
 202    GND  VSS87 @S9S_MB_2U_LIB.S9S_MB_2U(SCH_1):GND
 204    GND  VSS88 @S9S_MB_2U_LIB.S9S_MB_2U(SCH_1):GND
 206    GND  VSS89 @S9S_MB_2U_LIB.S9S_MB_2U(SCH_1):GND
 208    GND  VSS90 @S9S_MB_2U_LIB.S9S_MB_2U(SCH_1):GND
 210    GND  VSS91 @S9S_MB_2U_LIB.S9S_MB_2U(SCH_1):GND
 212    GND  VSS92 @S9S_MB_2U_LIB.S9S_MB_2U(SCH_1):GND
 214    GND  VSS93 @S9S_MB_2U_LIB.S9S_MB_2U(SCH_1):GND
 216    GND  VSS94 @S9S_MB_2U_LIB.S9S_MB_2U(SCH_1):GND
 219    GND  VSS95 @S9S_MB_2U_LIB.S9S_MB_2U(SCH_1):GND
 222    GND  VSS96 @S9S_MB_2U_LIB.S9S_MB_2U(SCH_1):GND
 224    GND  VSS97 @S9S_MB_2U_LIB.S9S_MB_2U(SCH_1):GND
 226    GND  VSS98 @S9S_MB_2U_LIB.S9S_MB_2U(SCH_1):GND
 228    GND  VSS99 @S9S_MB_2U_LIB.S9S_MB_2U(SCH_1):GND
 233    GND VSS101 @S9S_MB_2U_LIB.S9S_MB_2U(SCH_1):GND
 237    GND VSS103 @S9S_MB_2U_LIB.S9S_MB_2U(SCH_1):GND
 242    GND VSS105 @S9S_MB_2U_LIB.S9S_MB_2U(SCH_1):GND
 244    GND VSS106 @S9S_MB_2U_LIB.S9S_MB_2U(SCH_1):GND
 246    GND VSS107 @S9S_MB_2U_LIB.S9S_MB_2U(SCH_1):GND
 248    GND VSS108 @S9S_MB_2U_LIB.S9S_MB_2U(SCH_1):GND
 251    GND VSS109 @S9S_MB_2U_LIB.S9S_MB_2U(SCH_1):GND
 253    GND VSS110 @S9S_MB_2U_LIB.S9S_MB_2U(SCH_1):GND
 255    GND VSS111 @S9S_MB_2U_LIB.S9S_MB_2U(SCH_1):GND
 257    GND VSS112 @S9S_MB_2U_LIB.S9S_MB_2U(SCH_1):GND
 259    GND VSS113 @S9S_MB_2U_LIB.S9S_MB_2U(SCH_1):GND
 262    GND VSS114 @S9S_MB_2U_LIB.S9S_MB_2U(SCH_1):GND
 264    GND VSS115 @S9S_MB_2U_LIB.S9S_MB_2U(SCH_1):GND
 266    GND VSS116 @S9S_MB_2U_LIB.S9S_MB_2U(SCH_1):GND
 268    GND VSS117 @S9S_MB_2U_LIB.S9S_MB_2U(SCH_1):GND
 270    GND VSS118 @S9S_MB_2U_LIB.S9S_MB_2U(SCH_1):GND
 273    GND VSS119 @S9S_MB_2U_LIB.S9S_MB_2U(SCH_1):GND
 275    GND VSS120 @S9S_MB_2U_LIB.S9S_MB_2U(SCH_1):GND
 277    GND VSS121 @S9S_MB_2U_LIB.S9S_MB_2U(SCH_1):GND
 279    GND VSS122 @S9S_MB_2U_LIB.S9S_MB_2U(SCH_1):GND
 281    GND VSS123 @S9S_MB_2U_LIB.S9S_MB_2U(SCH_1):GND
 284    GND VSS124 @S9S_MB_2U_LIB.S9S_MB_2U(SCH_1):GND
 286    GND VSS125 @S9S_MB_2U_LIB.S9S_MB_2U(SCH_1):GND
 288    GND VSS126 @S9S_MB_2U_LIB.S9S_MB_2U(SCH_1):GND
   1 P12V_S3_AUX_CPU1_NVDIMM VIN_BULK0 @S9S_MB_2U_LIB.S9S_MB_2U(SCH_1):P12V_S3_AUX_CPU1_NVDIMM
 145 P12V_S3_AUX_CPU1_NVDIMM VIN_BULK1 @S9S_MB_2U_LIB.S9S_MB_2U(SCH_1):P12V_S3_AUX_CPU1_NVDIMM
 146 P12V_S3_AUX_CPU1_NVDIMM VIN_BULK2 @S9S_MB_2U_LIB.S9S_MB_2U(SCH_1):P12V_S3_AUX_CPU1_NVDIMM
 230    GND VSS100 @S9S_MB_2U_LIB.S9S_MB_2U(SCH_1):GND
 235    GND VSS102 @S9S_MB_2U_LIB.S9S_MB_2U(SCH_1):GND
 240    GND VSS104 @S9S_MB_2U_LIB.S9S_MB_2U(SCH_1):GND
 132    GND  VSS58 @S9S_MB_2U_LIB.S9S_MB_2U(SCH_1):GND
 136    GND  VSS60 @S9S_MB_2U_LIB.S9S_MB_2U(SCH_1):GND
 139    GND  VSS61 @S9S_MB_2U_LIB.S9S_MB_2U(SCH_1):GND
 141    GND  VSS62 @S9S_MB_2U_LIB.S9S_MB_2U(SCH_1):GND
  G1    GND     G1 @S9S_MB_2U_LIB.S9S_MB_2U(SCH_1):GND
  G2    GND     G2 @S9S_MB_2U_LIB.S9S_MB_2U(SCH_1):GND
  G3    GND     G3 @S9S_MB_2U_LIB.S9S_MB_2U(SCH_1):GND

SCONN288_ADR50017P087CC-SCONN2A  I180  J26
   3 P3V3_AUX VIN_MGMT @S9S_MB_2U_LIB.S9S_MB_2U(SCH_1):P3V3_AUX
   2 TP_CHE_CPU1_DIMM2_FRU_0   RFU0 @S9S_MB_2U_LIB.S9S_MB_2U(SCH_1):TP_CHE_CPU1_DIMM2_FRU_0
 144 TP_CHE_CPU1_DIMM2_FRU_1   RFU1 @S9S_MB_2U_LIB.S9S_MB_2U(SCH_1):TP_CHE_CPU1_DIMM2_FRU_1
 149 TP_CHE_CPU1_DIMM2_FRU_2   RFU2 @S9S_MB_2U_LIB.S9S_MB_2U(SCH_1):TP_CHE_CPU1_DIMM2_FRU_2
 150 TP_CHE_CPU1_DIMM2_FRU_3   RFU3 @S9S_MB_2U_LIB.S9S_MB_2U(SCH_1):TP_CHE_CPU1_DIMM2_FRU_3
 220 TP_CHE_CPU1_DIMM2_FRU_4   RFU4 @S9S_MB_2U_LIB.S9S_MB_2U(SCH_1):TP_CHE_CPU1_DIMM2_FRU_4
 231 TP_CHE_CPU1_DIMM2_FRU_5   RFU5 @S9S_MB_2U_LIB.S9S_MB_2U(SCH_1):TP_CHE_CPU1_DIMM2_FRU_5
 232 TP_CHE_CPU1_DIMM2_FRU_6   RFU6 @S9S_MB_2U_LIB.S9S_MB_2U(SCH_1):TP_CHE_CPU1_DIMM2_FRU_6
 207 RST_M_EF_CPU1_FPGA_N RESET_N @S9S_MB_2U_LIB.S9S_MB_2U(SCH_1):RST_M_EF_CPU1_FPGA_N
 147 PWRGD_CHE_CPU1_DIMM2 PWR_GOOD||FAIL_N @S9S_MB_2U_LIB.S9S_MB_2U(SCH_1):PWRGD_CHE_CPU1_DIMM2
 227 M_E_CPU1_SB_PAR  PAR_B @S9S_MB_2U_LIB.S9S_MB_2U(SCH_1):M_E_CPU1_SB_PAR
  74 M_E_CPU1_SA_PAR  PAR_A @S9S_MB_2U_LIB.S9S_MB_2U(SCH_1):M_E_CPU1_SA_PAR
  87 M_E_CPU1_SB_RSP<1> LBS||RSP_B_N @S9S_MB_2U_LIB.S9S_MB_2U(SCH_1):M_E_CPU1_SB_RSP(1)
  86 M_E_CPU1_SA_RSP<1> LBD||RSP_A_N @S9S_MB_2U_LIB.S9S_MB_2U(SCH_1):M_E_CPU1_SA_RSP(1)
   5 I3C_SPD_DDREFGH_CPU1_LVC1_SDA   HSDA @S9S_MB_2U_LIB.S9S_MB_2U(SCH_1):I3C_SPD_DDREFGH_CPU1_LVC1_SDA
   4 I3C_SPD_DDREFGH_CPU1_LVC1_SCL_1   HSCL @S9S_MB_2U_LIB.S9S_MB_2U(SCH_1):I3C_SPD_DDREFGH_CPU1_LVC1_SCL_R2
 148 PD_CHE_CPU1_DIMM2_SAA    HSA @S9S_MB_2U_LIB.S9S_MB_2U(SCH_1):PD_CHE_CPU1_DIMM2_SAA
 100 M_E_CPU1_SB_DQ<0>  DQ0_B @S9S_MB_2U_LIB.S9S_MB_2U(SCH_1):M_E_CPU1_SB_DQ(0)
 102 M_E_CPU1_SB_DQ<1>  DQ1_B @S9S_MB_2U_LIB.S9S_MB_2U(SCH_1):M_E_CPU1_SB_DQ(1)
 245 M_E_CPU1_SB_DQ<2>  DQ2_B @S9S_MB_2U_LIB.S9S_MB_2U(SCH_1):M_E_CPU1_SB_DQ(2)
 247 M_E_CPU1_SB_DQ<3>  DQ3_B @S9S_MB_2U_LIB.S9S_MB_2U(SCH_1):M_E_CPU1_SB_DQ(3)
 107 M_E_CPU1_SB_DQ<4>  DQ4_B @S9S_MB_2U_LIB.S9S_MB_2U(SCH_1):M_E_CPU1_SB_DQ(4)
 109 M_E_CPU1_SB_DQ<5>  DQ5_B @S9S_MB_2U_LIB.S9S_MB_2U(SCH_1):M_E_CPU1_SB_DQ(5)
 252 M_E_CPU1_SB_DQ<6>  DQ6_B @S9S_MB_2U_LIB.S9S_MB_2U(SCH_1):M_E_CPU1_SB_DQ(6)
 254 M_E_CPU1_SB_DQ<7>  DQ7_B @S9S_MB_2U_LIB.S9S_MB_2U(SCH_1):M_E_CPU1_SB_DQ(7)
 111 M_E_CPU1_SB_DQ<8>  DQ8_B @S9S_MB_2U_LIB.S9S_MB_2U(SCH_1):M_E_CPU1_SB_DQ(8)
 113 M_E_CPU1_SB_DQ<9>  DQ9_B @S9S_MB_2U_LIB.S9S_MB_2U(SCH_1):M_E_CPU1_SB_DQ(9)
 256 M_E_CPU1_SB_DQ<10> DQ10_B @S9S_MB_2U_LIB.S9S_MB_2U(SCH_1):M_E_CPU1_SB_DQ(10)
 258 M_E_CPU1_SB_DQ<11> DQ11_B @S9S_MB_2U_LIB.S9S_MB_2U(SCH_1):M_E_CPU1_SB_DQ(11)
 118 M_E_CPU1_SB_DQ<12> DQ12_B @S9S_MB_2U_LIB.S9S_MB_2U(SCH_1):M_E_CPU1_SB_DQ(12)
 120 M_E_CPU1_SB_DQ<13> DQ13_B @S9S_MB_2U_LIB.S9S_MB_2U(SCH_1):M_E_CPU1_SB_DQ(13)
 263 M_E_CPU1_SB_DQ<14> DQ14_B @S9S_MB_2U_LIB.S9S_MB_2U(SCH_1):M_E_CPU1_SB_DQ(14)
 265 M_E_CPU1_SB_DQ<15> DQ15_B @S9S_MB_2U_LIB.S9S_MB_2U(SCH_1):M_E_CPU1_SB_DQ(15)
 122 M_E_CPU1_SB_DQ<16> DQ16_B @S9S_MB_2U_LIB.S9S_MB_2U(SCH_1):M_E_CPU1_SB_DQ(16)
 124 M_E_CPU1_SB_DQ<17> DQ17_B @S9S_MB_2U_LIB.S9S_MB_2U(SCH_1):M_E_CPU1_SB_DQ(17)
 267 M_E_CPU1_SB_DQ<18> DQ18_B @S9S_MB_2U_LIB.S9S_MB_2U(SCH_1):M_E_CPU1_SB_DQ(18)
 269 M_E_CPU1_SB_DQ<19> DQ19_B @S9S_MB_2U_LIB.S9S_MB_2U(SCH_1):M_E_CPU1_SB_DQ(19)
 129 M_E_CPU1_SB_DQ<20> DQ20_B @S9S_MB_2U_LIB.S9S_MB_2U(SCH_1):M_E_CPU1_SB_DQ(20)
 131 M_E_CPU1_SB_DQ<21> DQ21_B @S9S_MB_2U_LIB.S9S_MB_2U(SCH_1):M_E_CPU1_SB_DQ(21)
 274 M_E_CPU1_SB_DQ<22> DQ22_B @S9S_MB_2U_LIB.S9S_MB_2U(SCH_1):M_E_CPU1_SB_DQ(22)
 276 M_E_CPU1_SB_DQ<23> DQ23_B @S9S_MB_2U_LIB.S9S_MB_2U(SCH_1):M_E_CPU1_SB_DQ(23)
 133 M_E_CPU1_SB_DQ<24> DQ24_B @S9S_MB_2U_LIB.S9S_MB_2U(SCH_1):M_E_CPU1_SB_DQ(24)
 135 M_E_CPU1_SB_DQ<25> DQ25_B @S9S_MB_2U_LIB.S9S_MB_2U(SCH_1):M_E_CPU1_SB_DQ(25)
 278 M_E_CPU1_SB_DQ<26> DQ26_B @S9S_MB_2U_LIB.S9S_MB_2U(SCH_1):M_E_CPU1_SB_DQ(26)
 280 M_E_CPU1_SB_DQ<27> DQ27_B @S9S_MB_2U_LIB.S9S_MB_2U(SCH_1):M_E_CPU1_SB_DQ(27)
 140 M_E_CPU1_SB_DQ<28> DQ28_B @S9S_MB_2U_LIB.S9S_MB_2U(SCH_1):M_E_CPU1_SB_DQ(28)
 142 M_E_CPU1_SB_DQ<29> DQ29_B @S9S_MB_2U_LIB.S9S_MB_2U(SCH_1):M_E_CPU1_SB_DQ(29)
 285 M_E_CPU1_SB_DQ<30> DQ30_B @S9S_MB_2U_LIB.S9S_MB_2U(SCH_1):M_E_CPU1_SB_DQ(30)
 287 M_E_CPU1_SB_DQ<31> DQ31_B @S9S_MB_2U_LIB.S9S_MB_2U(SCH_1):M_E_CPU1_SB_DQ(31)
   7 M_E_CPU1_SA_DQ<0>  DQ0_A @S9S_MB_2U_LIB.S9S_MB_2U(SCH_1):M_E_CPU1_SA_DQ(0)
   9 M_E_CPU1_SA_DQ<1>  DQ1_A @S9S_MB_2U_LIB.S9S_MB_2U(SCH_1):M_E_CPU1_SA_DQ(1)
 152 M_E_CPU1_SA_DQ<2>  DQ2_A @S9S_MB_2U_LIB.S9S_MB_2U(SCH_1):M_E_CPU1_SA_DQ(2)
 154 M_E_CPU1_SA_DQ<3>  DQ3_A @S9S_MB_2U_LIB.S9S_MB_2U(SCH_1):M_E_CPU1_SA_DQ(3)
  14 M_E_CPU1_SA_DQ<4>  DQ4_A @S9S_MB_2U_LIB.S9S_MB_2U(SCH_1):M_E_CPU1_SA_DQ(4)
  16 M_E_CPU1_SA_DQ<5>  DQ5_A @S9S_MB_2U_LIB.S9S_MB_2U(SCH_1):M_E_CPU1_SA_DQ(5)
 159 M_E_CPU1_SA_DQ<6>  DQ6_A @S9S_MB_2U_LIB.S9S_MB_2U(SCH_1):M_E_CPU1_SA_DQ(6)
 161 M_E_CPU1_SA_DQ<7>  DQ7_A @S9S_MB_2U_LIB.S9S_MB_2U(SCH_1):M_E_CPU1_SA_DQ(7)
  18 M_E_CPU1_SA_DQ<8>  DQ8_A @S9S_MB_2U_LIB.S9S_MB_2U(SCH_1):M_E_CPU1_SA_DQ(8)
  20 M_E_CPU1_SA_DQ<9>  DQ9_A @S9S_MB_2U_LIB.S9S_MB_2U(SCH_1):M_E_CPU1_SA_DQ(9)
 163 M_E_CPU1_SA_DQ<10> DQ10_A @S9S_MB_2U_LIB.S9S_MB_2U(SCH_1):M_E_CPU1_SA_DQ(10)
 165 M_E_CPU1_SA_DQ<11> DQ11_A @S9S_MB_2U_LIB.S9S_MB_2U(SCH_1):M_E_CPU1_SA_DQ(11)
  25 M_E_CPU1_SA_DQ<12> DQ12_A @S9S_MB_2U_LIB.S9S_MB_2U(SCH_1):M_E_CPU1_SA_DQ(12)
  27 M_E_CPU1_SA_DQ<13> DQ13_A @S9S_MB_2U_LIB.S9S_MB_2U(SCH_1):M_E_CPU1_SA_DQ(13)
 170 M_E_CPU1_SA_DQ<14> DQ14_A @S9S_MB_2U_LIB.S9S_MB_2U(SCH_1):M_E_CPU1_SA_DQ(14)
 172 M_E_CPU1_SA_DQ<15> DQ15_A @S9S_MB_2U_LIB.S9S_MB_2U(SCH_1):M_E_CPU1_SA_DQ(15)
  29 M_E_CPU1_SA_DQ<16> DQ16_A @S9S_MB_2U_LIB.S9S_MB_2U(SCH_1):M_E_CPU1_SA_DQ(16)
  31 M_E_CPU1_SA_DQ<17> DQ17_A @S9S_MB_2U_LIB.S9S_MB_2U(SCH_1):M_E_CPU1_SA_DQ(17)
 174 M_E_CPU1_SA_DQ<18> DQ18_A @S9S_MB_2U_LIB.S9S_MB_2U(SCH_1):M_E_CPU1_SA_DQ(18)
 176 M_E_CPU1_SA_DQ<19> DQ19_A @S9S_MB_2U_LIB.S9S_MB_2U(SCH_1):M_E_CPU1_SA_DQ(19)
  36 M_E_CPU1_SA_DQ<20> DQ20_A @S9S_MB_2U_LIB.S9S_MB_2U(SCH_1):M_E_CPU1_SA_DQ(20)
  38 M_E_CPU1_SA_DQ<21> DQ21_A @S9S_MB_2U_LIB.S9S_MB_2U(SCH_1):M_E_CPU1_SA_DQ(21)
 181 M_E_CPU1_SA_DQ<22> DQ22_A @S9S_MB_2U_LIB.S9S_MB_2U(SCH_1):M_E_CPU1_SA_DQ(22)
 183 M_E_CPU1_SA_DQ<23> DQ23_A @S9S_MB_2U_LIB.S9S_MB_2U(SCH_1):M_E_CPU1_SA_DQ(23)
  40 M_E_CPU1_SA_DQ<24> DQ24_A @S9S_MB_2U_LIB.S9S_MB_2U(SCH_1):M_E_CPU1_SA_DQ(24)
  42 M_E_CPU1_SA_DQ<25> DQ25_A @S9S_MB_2U_LIB.S9S_MB_2U(SCH_1):M_E_CPU1_SA_DQ(25)
 185 M_E_CPU1_SA_DQ<26> DQ26_A @S9S_MB_2U_LIB.S9S_MB_2U(SCH_1):M_E_CPU1_SA_DQ(26)
 187 M_E_CPU1_SA_DQ<27> DQ27_A @S9S_MB_2U_LIB.S9S_MB_2U(SCH_1):M_E_CPU1_SA_DQ(27)
  47 M_E_CPU1_SA_DQ<28> DQ28_A @S9S_MB_2U_LIB.S9S_MB_2U(SCH_1):M_E_CPU1_SA_DQ(28)
  49 M_E_CPU1_SA_DQ<29> DQ29_A @S9S_MB_2U_LIB.S9S_MB_2U(SCH_1):M_E_CPU1_SA_DQ(29)
 192 M_E_CPU1_SA_DQ<30> DQ30_A @S9S_MB_2U_LIB.S9S_MB_2U(SCH_1):M_E_CPU1_SA_DQ(30)
 229 M_E_CPU1_SB_CS_N<3> CS1_B_N @S9S_MB_2U_LIB.S9S_MB_2U(SCH_1):M_E_CPU1_SB_CS_N(3)
 209 M_E_CPU1_SA_CS_N<3> CS1_A_N @S9S_MB_2U_LIB.S9S_MB_2U(SCH_1):M_E_CPU1_SA_CS_N(3)
  84 M_E_CPU1_SB_CS_N<2> CS0_B_N @S9S_MB_2U_LIB.S9S_MB_2U(SCH_1):M_E_CPU1_SB_CS_N(2)
  64 M_E_CPU1_SA_CS_N<2> CS0_A_N @S9S_MB_2U_LIB.S9S_MB_2U(SCH_1):M_E_CPU1_SA_CS_N(2)
 217 M_E_CPU1_CLK_DP<1>   CK_T @S9S_MB_2U_LIB.S9S_MB_2U(SCH_1):M_E_CPU1_CLK_DP(1)
 218 M_E_CPU1_CLK_DN<1>   CK_C @S9S_MB_2U_LIB.S9S_MB_2U(SCH_1):M_E_CPU1_CLK_DN(1)
  96 M_E_CPU1_SB_CB<0>  CB0_B @S9S_MB_2U_LIB.S9S_MB_2U(SCH_1):M_E_CPU1_SB_CB(0)
  98 M_E_CPU1_SB_CB<1>  CB1_B @S9S_MB_2U_LIB.S9S_MB_2U(SCH_1):M_E_CPU1_SB_CB(1)
 241 M_E_CPU1_SB_CB<2>  CB2_B @S9S_MB_2U_LIB.S9S_MB_2U(SCH_1):M_E_CPU1_SB_CB(2)
 243 M_E_CPU1_SB_CB<3>  CB3_B @S9S_MB_2U_LIB.S9S_MB_2U(SCH_1):M_E_CPU1_SB_CB(3)
  89 M_E_CPU1_SB_CB<4>  CB4_B @S9S_MB_2U_LIB.S9S_MB_2U(SCH_1):M_E_CPU1_SB_CB(4)
  91 M_E_CPU1_SB_CB<5>  CB5_B @S9S_MB_2U_LIB.S9S_MB_2U(SCH_1):M_E_CPU1_SB_CB(5)
 234 M_E_CPU1_SB_CB<6>  CB6_B @S9S_MB_2U_LIB.S9S_MB_2U(SCH_1):M_E_CPU1_SB_CB(6)
  51 M_E_CPU1_SA_CB<0>  CB0_A @S9S_MB_2U_LIB.S9S_MB_2U(SCH_1):M_E_CPU1_SA_CB(0)
 196 M_E_CPU1_SA_CB<2>  CB2_A @S9S_MB_2U_LIB.S9S_MB_2U(SCH_1):M_E_CPU1_SA_CB(2)
 198 M_E_CPU1_SA_CB<3>  CB3_A @S9S_MB_2U_LIB.S9S_MB_2U(SCH_1):M_E_CPU1_SA_CB(3)
  60 M_E_CPU1_SA_CB<5>  CB5_A @S9S_MB_2U_LIB.S9S_MB_2U(SCH_1):M_E_CPU1_SA_CB(5)
 203 M_E_CPU1_SA_CB<6>  CB6_A @S9S_MB_2U_LIB.S9S_MB_2U(SCH_1):M_E_CPU1_SA_CB(6)
  82 M_E_CPU1_SB_CA<6>  CA6_B @S9S_MB_2U_LIB.S9S_MB_2U(SCH_1):M_E_CPU1_SB_CA(6)
  72 M_E_CPU1_SA_CA<6>  CA6_A @S9S_MB_2U_LIB.S9S_MB_2U(SCH_1):M_E_CPU1_SA_CA(6)
 225 M_E_CPU1_SB_CA<5>  CA5_B @S9S_MB_2U_LIB.S9S_MB_2U(SCH_1):M_E_CPU1_SB_CA(5)
 215 M_E_CPU1_SA_CA<5>  CA5_A @S9S_MB_2U_LIB.S9S_MB_2U(SCH_1):M_E_CPU1_SA_CA(5)
  80 M_E_CPU1_SB_CA<4>  CA4_B @S9S_MB_2U_LIB.S9S_MB_2U(SCH_1):M_E_CPU1_SB_CA(4)
  70 M_E_CPU1_SA_CA<4>  CA4_A @S9S_MB_2U_LIB.S9S_MB_2U(SCH_1):M_E_CPU1_SA_CA(4)
 223 M_E_CPU1_SB_CA<3>  CA3_B @S9S_MB_2U_LIB.S9S_MB_2U(SCH_1):M_E_CPU1_SB_CA(3)
 213 M_E_CPU1_SA_CA<3>  CA3_A @S9S_MB_2U_LIB.S9S_MB_2U(SCH_1):M_E_CPU1_SA_CA(3)
  78 M_E_CPU1_SB_CA<2>  CA2_B @S9S_MB_2U_LIB.S9S_MB_2U(SCH_1):M_E_CPU1_SB_CA(2)
  68 M_E_CPU1_SA_CA<2>  CA2_A @S9S_MB_2U_LIB.S9S_MB_2U(SCH_1):M_E_CPU1_SA_CA(2)
 221 M_E_CPU1_SB_CA<1>  CA1_B @S9S_MB_2U_LIB.S9S_MB_2U(SCH_1):M_E_CPU1_SB_CA(1)
 211 M_E_CPU1_SA_CA<1>  CA1_A @S9S_MB_2U_LIB.S9S_MB_2U(SCH_1):M_E_CPU1_SA_CA(1)
  76 M_E_CPU1_SB_CA<0>  CA0_B @S9S_MB_2U_LIB.S9S_MB_2U(SCH_1):M_E_CPU1_SB_CA(0)
  66 M_E_CPU1_SA_CA<0>  CA0_A @S9S_MB_2U_LIB.S9S_MB_2U(SCH_1):M_E_CPU1_SA_CA(0)
  62 M_E_CPU1_ALERT_N ALERT_N @S9S_MB_2U_LIB.S9S_MB_2U(SCH_1):M_E_CPU1_ALERT_N
 236 M_E_CPU1_SB_CB<7>  CB7_B @S9S_MB_2U_LIB.S9S_MB_2U(SCH_1):M_E_CPU1_SB_CB(7)
  53 M_E_CPU1_SA_CB<1>  CB1_A @S9S_MB_2U_LIB.S9S_MB_2U(SCH_1):M_E_CPU1_SA_CB(1)
  58 M_E_CPU1_SA_CB<4>  CB4_A @S9S_MB_2U_LIB.S9S_MB_2U(SCH_1):M_E_CPU1_SA_CB(4)
 205 M_E_CPU1_SA_CB<7>  CB7_A @S9S_MB_2U_LIB.S9S_MB_2U(SCH_1):M_E_CPU1_SA_CB(7)
 194 M_E_CPU1_SA_DQ<31> DQ31_A @S9S_MB_2U_LIB.S9S_MB_2U(SCH_1):M_E_CPU1_SA_DQ(31)

SCONN288_ADR50017P087CC-SCONN2A  I181  J26
  93 M_E_CPU1_SB_DQS_DP<9> DQS9_B_T||TDQS9_B_T||DBI4_B_N @S9S_MB_2U_LIB.S9S_MB_2U(SCH_1):M_E_CPU1_SB_DQS_DP(9)
  94 M_E_CPU1_SB_DQS_DN<9> DQS9_B_C||TDQS9_B_C @S9S_MB_2U_LIB.S9S_MB_2U(SCH_1):M_E_CPU1_SB_DQS_DN(9)
 201 M_E_CPU1_SA_DQS_DP<9> DQS9_A_T||TDQS9_A_T @S9S_MB_2U_LIB.S9S_MB_2U(SCH_1):M_E_CPU1_SA_DQS_DP(9)
 200 M_E_CPU1_SA_DQS_DN<9> DQS9_A_C||TDQS9_A_C @S9S_MB_2U_LIB.S9S_MB_2U(SCH_1):M_E_CPU1_SA_DQS_DN(9)
 190 M_E_CPU1_SA_DQS_DP<8> DQS8_A_T||TDQS8_A_T @S9S_MB_2U_LIB.S9S_MB_2U(SCH_1):M_E_CPU1_SA_DQS_DP(8)
 189 M_E_CPU1_SA_DQS_DN<8> DQS8_A_C||TDQS8_A_C @S9S_MB_2U_LIB.S9S_MB_2U(SCH_1):M_E_CPU1_SA_DQS_DN(8)
 271 M_E_CPU1_SB_DQS_DN<7> DQS7_B_C||TDQS7_B_C @S9S_MB_2U_LIB.S9S_MB_2U(SCH_1):M_E_CPU1_SB_DQS_DN(7)
 179 M_E_CPU1_SA_DQS_DP<7> DQS7_A_T||TDQS7_A_T @S9S_MB_2U_LIB.S9S_MB_2U(SCH_1):M_E_CPU1_SA_DQS_DP(7)
 261 M_E_CPU1_SB_DQS_DP<6> DQS6_B_T||TDQS6_B_T @S9S_MB_2U_LIB.S9S_MB_2U(SCH_1):M_E_CPU1_SB_DQS_DP(6)
 260 M_E_CPU1_SB_DQS_DN<6> DQS6_B_C||TDQS6_B_C @S9S_MB_2U_LIB.S9S_MB_2U(SCH_1):M_E_CPU1_SB_DQS_DN(6)
 167 M_E_CPU1_SA_DQS_DN<6> DQS6_A_C||TDQS6_A_C||DQS6_A_T||TDQS6_A_T @S9S_MB_2U_LIB.S9S_MB_2U(SCH_1):M_E_CPU1_SA_DQS_DN(6)
 250 M_E_CPU1_SB_DQS_DP<5> DQS5_B_T||TDQS5_B_T @S9S_MB_2U_LIB.S9S_MB_2U(SCH_1):M_E_CPU1_SB_DQS_DP(5)
 249 M_E_CPU1_SB_DQS_DN<5> DQS5_B_C||TDQS5_B_C @S9S_MB_2U_LIB.S9S_MB_2U(SCH_1):M_E_CPU1_SB_DQS_DN(5)
 157 M_E_CPU1_SA_DQS_DP<5> DQS5_A_T||TDQS5_A_T @S9S_MB_2U_LIB.S9S_MB_2U(SCH_1):M_E_CPU1_SA_DQS_DP(5)
 156 M_E_CPU1_SA_DQS_DN<5> DQS5_A_C||TDQS5_A_C||DQS5_A_T||TDQS5_A_T @S9S_MB_2U_LIB.S9S_MB_2U(SCH_1):M_E_CPU1_SA_DQS_DN(5)
 239 M_E_CPU1_SB_DQS_DP<4> DQS4_B_T @S9S_MB_2U_LIB.S9S_MB_2U(SCH_1):M_E_CPU1_SB_DQS_DP(4)
 238 M_E_CPU1_SB_DQS_DN<4> DQS4_B_C @S9S_MB_2U_LIB.S9S_MB_2U(SCH_1):M_E_CPU1_SB_DQS_DN(4)
  55 M_E_CPU1_SA_DQS_DP<4> DQS4_A_T @S9S_MB_2U_LIB.S9S_MB_2U(SCH_1):M_E_CPU1_SA_DQS_DP(4)
  56 M_E_CPU1_SA_DQS_DN<4> DQS4_A_C @S9S_MB_2U_LIB.S9S_MB_2U(SCH_1):M_E_CPU1_SA_DQS_DN(4)
 137 M_E_CPU1_SB_DQS_DP<3> DQS3_B_T @S9S_MB_2U_LIB.S9S_MB_2U(SCH_1):M_E_CPU1_SB_DQS_DP(3)
 138 M_E_CPU1_SB_DQS_DN<3> DQS3_B_C @S9S_MB_2U_LIB.S9S_MB_2U(SCH_1):M_E_CPU1_SB_DQS_DN(3)
  44 M_E_CPU1_SA_DQS_DP<3> DQS3_A_T @S9S_MB_2U_LIB.S9S_MB_2U(SCH_1):M_E_CPU1_SA_DQS_DP(3)
  45 M_E_CPU1_SA_DQS_DN<3> DQS3_A_C @S9S_MB_2U_LIB.S9S_MB_2U(SCH_1):M_E_CPU1_SA_DQS_DN(3)
 126 M_E_CPU1_SB_DQS_DP<2> DQS2_B_T @S9S_MB_2U_LIB.S9S_MB_2U(SCH_1):M_E_CPU1_SB_DQS_DP(2)
 127 M_E_CPU1_SB_DQS_DN<2> DQS2_B_C @S9S_MB_2U_LIB.S9S_MB_2U(SCH_1):M_E_CPU1_SB_DQS_DN(2)
  33 M_E_CPU1_SA_DQS_DP<2> DQS2_A_T @S9S_MB_2U_LIB.S9S_MB_2U(SCH_1):M_E_CPU1_SA_DQS_DP(2)
  34 M_E_CPU1_SA_DQS_DN<2> DQS2_A_C @S9S_MB_2U_LIB.S9S_MB_2U(SCH_1):M_E_CPU1_SA_DQS_DN(2)
 115 M_E_CPU1_SB_DQS_DP<1> DQS1_B_T @S9S_MB_2U_LIB.S9S_MB_2U(SCH_1):M_E_CPU1_SB_DQS_DP(1)
 116 M_E_CPU1_SB_DQS_DN<1> DQS1_B_C @S9S_MB_2U_LIB.S9S_MB_2U(SCH_1):M_E_CPU1_SB_DQS_DN(1)
  22 M_E_CPU1_SA_DQS_DP<1> DQS1_A_T @S9S_MB_2U_LIB.S9S_MB_2U(SCH_1):M_E_CPU1_SA_DQS_DP(1)
  23 M_E_CPU1_SA_DQS_DN<1> DQS1_A_C @S9S_MB_2U_LIB.S9S_MB_2U(SCH_1):M_E_CPU1_SA_DQS_DN(1)
 104 M_E_CPU1_SB_DQS_DP<0> DQS0_B_T @S9S_MB_2U_LIB.S9S_MB_2U(SCH_1):M_E_CPU1_SB_DQS_DP(0)
 105 M_E_CPU1_SB_DQS_DN<0> DQS0_B_C @S9S_MB_2U_LIB.S9S_MB_2U(SCH_1):M_E_CPU1_SB_DQS_DN(0)
  11 M_E_CPU1_SA_DQS_DP<0> DQS0_A_T @S9S_MB_2U_LIB.S9S_MB_2U(SCH_1):M_E_CPU1_SA_DQS_DP(0)
  12 M_E_CPU1_SA_DQS_DN<0> DQS0_A_C @S9S_MB_2U_LIB.S9S_MB_2U(SCH_1):M_E_CPU1_SA_DQS_DN(0)
 272 M_E_CPU1_SB_DQS_DP<7> DQS7_B_T||TDQS7_B_T @S9S_MB_2U_LIB.S9S_MB_2U(SCH_1):M_E_CPU1_SB_DQS_DP(7)
 282 M_E_CPU1_SB_DQS_DN<8> DQS8_B_C||TDQS8_B_C @S9S_MB_2U_LIB.S9S_MB_2U(SCH_1):M_E_CPU1_SB_DQS_DN(8)
 283 M_E_CPU1_SB_DQS_DP<8> DQS8_B_T||TDQS8_B_T @S9S_MB_2U_LIB.S9S_MB_2U(SCH_1):M_E_CPU1_SB_DQS_DP(8)
 168 M_E_CPU1_SA_DQS_DP<6> DQS6_A_T||TDQS6_A_T @S9S_MB_2U_LIB.S9S_MB_2U(SCH_1):M_E_CPU1_SA_DQS_DP(6)
 178 M_E_CPU1_SA_DQS_DN<7> DQS7_A_C||TDQS7_A_C @S9S_MB_2U_LIB.S9S_MB_2U(SCH_1):M_E_CPU1_SA_DQS_DN(7)

Q_RES_0402LF-49.9,1%,1/16W,CHIA  I183  R3900
   1 I3C_SPD_DDREFGH_CPU1_LVC1_SCL_1      A @S9S_MB_2U_LIB.S9S_MB_2U(SCH_1):I3C_SPD_DDREFGH_CPU1_LVC1_SCL_R2
   2 I3C_SPD_DDREFGH_CPU1_LVC1_SCL      B @S9S_MB_2U_LIB.S9S_MB_2U(SCH_1):I3C_SPD_DDREFGH_CPU1_LVC1_SCL


DRAWING: @S9S_MB_2U_LIB.S9S_MB_2U(SCH_1):PAGE108 

Q_RES_0402LF-23.2K,1%,1/16W,CHA  I10  R77
   1 PD_CHF_CPU1_DIMM1_SAA      A @S9S_MB_2U_LIB.S9S_MB_2U(SCH_1):PD_CHF_CPU1_DIMM1_SAA
   2    GND      B @S9S_MB_2U_LIB.S9S_MB_2U(SCH_1):GND

Q_CAP_C0402-2.2UF,6.3V,20%,X6SA  I121  C87
   1 P3V3_AUX      A @S9S_MB_2U_LIB.S9S_MB_2U(SCH_1):P3V3_AUX
   2    GND      B @S9S_MB_2U_LIB.S9S_MB_2U(SCH_1):GND

Q_CAP_C0805-10UF,16V,10%,X6S,CA  I123  C88
   1 P12V_S3_AUX_CPU1_NVDIMM      A @S9S_MB_2U_LIB.S9S_MB_2U(SCH_1):P12V_S3_AUX_CPU1_NVDIMM
   2    GND      B @S9S_MB_2U_LIB.S9S_MB_2U(SCH_1):GND

Q_CAP_C0805-10UF,16V,10%,X6S,CA  I160  C89
   1 P12V_S3_AUX_CPU1_NVDIMM      A @S9S_MB_2U_LIB.S9S_MB_2U(SCH_1):P12V_S3_AUX_CPU1_NVDIMM
   2    GND      B @S9S_MB_2U_LIB.S9S_MB_2U(SCH_1):GND

SCONN288_ADR50017P130CC-SCONN2A  I178  J27
   6    GND   VSS0 @S9S_MB_2U_LIB.S9S_MB_2U(SCH_1):GND
   8    GND   VSS1 @S9S_MB_2U_LIB.S9S_MB_2U(SCH_1):GND
  10    GND   VSS2 @S9S_MB_2U_LIB.S9S_MB_2U(SCH_1):GND
  13    GND   VSS3 @S9S_MB_2U_LIB.S9S_MB_2U(SCH_1):GND
  15    GND   VSS4 @S9S_MB_2U_LIB.S9S_MB_2U(SCH_1):GND
  17    GND   VSS5 @S9S_MB_2U_LIB.S9S_MB_2U(SCH_1):GND
  19    GND   VSS6 @S9S_MB_2U_LIB.S9S_MB_2U(SCH_1):GND
  21    GND   VSS7 @S9S_MB_2U_LIB.S9S_MB_2U(SCH_1):GND
  24    GND   VSS8 @S9S_MB_2U_LIB.S9S_MB_2U(SCH_1):GND
  26    GND   VSS9 @S9S_MB_2U_LIB.S9S_MB_2U(SCH_1):GND
  28    GND  VSS10 @S9S_MB_2U_LIB.S9S_MB_2U(SCH_1):GND
  30    GND  VSS11 @S9S_MB_2U_LIB.S9S_MB_2U(SCH_1):GND
  32    GND  VSS12 @S9S_MB_2U_LIB.S9S_MB_2U(SCH_1):GND
  35    GND  VSS13 @S9S_MB_2U_LIB.S9S_MB_2U(SCH_1):GND
  37    GND  VSS14 @S9S_MB_2U_LIB.S9S_MB_2U(SCH_1):GND
  39    GND  VSS15 @S9S_MB_2U_LIB.S9S_MB_2U(SCH_1):GND
  41    GND  VSS16 @S9S_MB_2U_LIB.S9S_MB_2U(SCH_1):GND
  43    GND  VSS17 @S9S_MB_2U_LIB.S9S_MB_2U(SCH_1):GND
  46    GND  VSS18 @S9S_MB_2U_LIB.S9S_MB_2U(SCH_1):GND
  48    GND  VSS19 @S9S_MB_2U_LIB.S9S_MB_2U(SCH_1):GND
  50    GND  VSS20 @S9S_MB_2U_LIB.S9S_MB_2U(SCH_1):GND
  52    GND  VSS21 @S9S_MB_2U_LIB.S9S_MB_2U(SCH_1):GND
  54    GND  VSS22 @S9S_MB_2U_LIB.S9S_MB_2U(SCH_1):GND
  57    GND  VSS23 @S9S_MB_2U_LIB.S9S_MB_2U(SCH_1):GND
  59    GND  VSS24 @S9S_MB_2U_LIB.S9S_MB_2U(SCH_1):GND
  61    GND  VSS25 @S9S_MB_2U_LIB.S9S_MB_2U(SCH_1):GND
  63    GND  VSS26 @S9S_MB_2U_LIB.S9S_MB_2U(SCH_1):GND
  65    GND  VSS27 @S9S_MB_2U_LIB.S9S_MB_2U(SCH_1):GND
  67    GND  VSS28 @S9S_MB_2U_LIB.S9S_MB_2U(SCH_1):GND
  69    GND  VSS29 @S9S_MB_2U_LIB.S9S_MB_2U(SCH_1):GND
  71    GND  VSS30 @S9S_MB_2U_LIB.S9S_MB_2U(SCH_1):GND
  73    GND  VSS31 @S9S_MB_2U_LIB.S9S_MB_2U(SCH_1):GND
  75    GND  VSS32 @S9S_MB_2U_LIB.S9S_MB_2U(SCH_1):GND
  77    GND  VSS33 @S9S_MB_2U_LIB.S9S_MB_2U(SCH_1):GND
  79    GND  VSS34 @S9S_MB_2U_LIB.S9S_MB_2U(SCH_1):GND
  81    GND  VSS35 @S9S_MB_2U_LIB.S9S_MB_2U(SCH_1):GND
  83    GND  VSS36 @S9S_MB_2U_LIB.S9S_MB_2U(SCH_1):GND
  85    GND  VSS37 @S9S_MB_2U_LIB.S9S_MB_2U(SCH_1):GND
  88    GND  VSS38 @S9S_MB_2U_LIB.S9S_MB_2U(SCH_1):GND
  90    GND  VSS39 @S9S_MB_2U_LIB.S9S_MB_2U(SCH_1):GND
  92    GND  VSS40 @S9S_MB_2U_LIB.S9S_MB_2U(SCH_1):GND
  95    GND  VSS41 @S9S_MB_2U_LIB.S9S_MB_2U(SCH_1):GND
  97    GND  VSS42 @S9S_MB_2U_LIB.S9S_MB_2U(SCH_1):GND
  99    GND  VSS43 @S9S_MB_2U_LIB.S9S_MB_2U(SCH_1):GND
 101    GND  VSS44 @S9S_MB_2U_LIB.S9S_MB_2U(SCH_1):GND
 103    GND  VSS45 @S9S_MB_2U_LIB.S9S_MB_2U(SCH_1):GND
 106    GND  VSS46 @S9S_MB_2U_LIB.S9S_MB_2U(SCH_1):GND
 108    GND  VSS47 @S9S_MB_2U_LIB.S9S_MB_2U(SCH_1):GND
 110    GND  VSS48 @S9S_MB_2U_LIB.S9S_MB_2U(SCH_1):GND
 112    GND  VSS49 @S9S_MB_2U_LIB.S9S_MB_2U(SCH_1):GND
 114    GND  VSS50 @S9S_MB_2U_LIB.S9S_MB_2U(SCH_1):GND
 117    GND  VSS51 @S9S_MB_2U_LIB.S9S_MB_2U(SCH_1):GND
 119    GND  VSS52 @S9S_MB_2U_LIB.S9S_MB_2U(SCH_1):GND
 121    GND  VSS53 @S9S_MB_2U_LIB.S9S_MB_2U(SCH_1):GND
 123    GND  VSS54 @S9S_MB_2U_LIB.S9S_MB_2U(SCH_1):GND
 125    GND  VSS55 @S9S_MB_2U_LIB.S9S_MB_2U(SCH_1):GND
 128    GND  VSS56 @S9S_MB_2U_LIB.S9S_MB_2U(SCH_1):GND
 130    GND  VSS57 @S9S_MB_2U_LIB.S9S_MB_2U(SCH_1):GND
 134    GND  VSS59 @S9S_MB_2U_LIB.S9S_MB_2U(SCH_1):GND
 143    GND  VSS63 @S9S_MB_2U_LIB.S9S_MB_2U(SCH_1):GND
 151    GND  VSS64 @S9S_MB_2U_LIB.S9S_MB_2U(SCH_1):GND
 153    GND  VSS65 @S9S_MB_2U_LIB.S9S_MB_2U(SCH_1):GND
 155    GND  VSS66 @S9S_MB_2U_LIB.S9S_MB_2U(SCH_1):GND
 158    GND  VSS67 @S9S_MB_2U_LIB.S9S_MB_2U(SCH_1):GND
 160    GND  VSS68 @S9S_MB_2U_LIB.S9S_MB_2U(SCH_1):GND
 162    GND  VSS69 @S9S_MB_2U_LIB.S9S_MB_2U(SCH_1):GND
 164    GND  VSS70 @S9S_MB_2U_LIB.S9S_MB_2U(SCH_1):GND
 166    GND  VSS71 @S9S_MB_2U_LIB.S9S_MB_2U(SCH_1):GND
 169    GND  VSS72 @S9S_MB_2U_LIB.S9S_MB_2U(SCH_1):GND
 171    GND  VSS73 @S9S_MB_2U_LIB.S9S_MB_2U(SCH_1):GND
 173    GND  VSS74 @S9S_MB_2U_LIB.S9S_MB_2U(SCH_1):GND
 175    GND  VSS75 @S9S_MB_2U_LIB.S9S_MB_2U(SCH_1):GND
 177    GND  VSS76 @S9S_MB_2U_LIB.S9S_MB_2U(SCH_1):GND
 180    GND  VSS77 @S9S_MB_2U_LIB.S9S_MB_2U(SCH_1):GND
 182    GND  VSS78 @S9S_MB_2U_LIB.S9S_MB_2U(SCH_1):GND
 184    GND  VSS79 @S9S_MB_2U_LIB.S9S_MB_2U(SCH_1):GND
 186    GND  VSS80 @S9S_MB_2U_LIB.S9S_MB_2U(SCH_1):GND
 188    GND  VSS81 @S9S_MB_2U_LIB.S9S_MB_2U(SCH_1):GND
 191    GND  VSS82 @S9S_MB_2U_LIB.S9S_MB_2U(SCH_1):GND
 193    GND  VSS83 @S9S_MB_2U_LIB.S9S_MB_2U(SCH_1):GND
 195    GND  VSS84 @S9S_MB_2U_LIB.S9S_MB_2U(SCH_1):GND
 197    GND  VSS85 @S9S_MB_2U_LIB.S9S_MB_2U(SCH_1):GND
 199    GND  VSS86 @S9S_MB_2U_LIB.S9S_MB_2U(SCH_1):GND
 202    GND  VSS87 @S9S_MB_2U_LIB.S9S_MB_2U(SCH_1):GND
 204    GND  VSS88 @S9S_MB_2U_LIB.S9S_MB_2U(SCH_1):GND
 206    GND  VSS89 @S9S_MB_2U_LIB.S9S_MB_2U(SCH_1):GND
 208    GND  VSS90 @S9S_MB_2U_LIB.S9S_MB_2U(SCH_1):GND
 210    GND  VSS91 @S9S_MB_2U_LIB.S9S_MB_2U(SCH_1):GND
 212    GND  VSS92 @S9S_MB_2U_LIB.S9S_MB_2U(SCH_1):GND
 214    GND  VSS93 @S9S_MB_2U_LIB.S9S_MB_2U(SCH_1):GND
 216    GND  VSS94 @S9S_MB_2U_LIB.S9S_MB_2U(SCH_1):GND
 219    GND  VSS95 @S9S_MB_2U_LIB.S9S_MB_2U(SCH_1):GND
 222    GND  VSS96 @S9S_MB_2U_LIB.S9S_MB_2U(SCH_1):GND
 224    GND  VSS97 @S9S_MB_2U_LIB.S9S_MB_2U(SCH_1):GND
 226    GND  VSS98 @S9S_MB_2U_LIB.S9S_MB_2U(SCH_1):GND
 228    GND  VSS99 @S9S_MB_2U_LIB.S9S_MB_2U(SCH_1):GND
 233    GND VSS101 @S9S_MB_2U_LIB.S9S_MB_2U(SCH_1):GND
 237    GND VSS103 @S9S_MB_2U_LIB.S9S_MB_2U(SCH_1):GND
 242    GND VSS105 @S9S_MB_2U_LIB.S9S_MB_2U(SCH_1):GND
 244    GND VSS106 @S9S_MB_2U_LIB.S9S_MB_2U(SCH_1):GND
 246    GND VSS107 @S9S_MB_2U_LIB.S9S_MB_2U(SCH_1):GND
 248    GND VSS108 @S9S_MB_2U_LIB.S9S_MB_2U(SCH_1):GND
 251    GND VSS109 @S9S_MB_2U_LIB.S9S_MB_2U(SCH_1):GND
 253    GND VSS110 @S9S_MB_2U_LIB.S9S_MB_2U(SCH_1):GND
 255    GND VSS111 @S9S_MB_2U_LIB.S9S_MB_2U(SCH_1):GND
 257    GND VSS112 @S9S_MB_2U_LIB.S9S_MB_2U(SCH_1):GND
 259    GND VSS113 @S9S_MB_2U_LIB.S9S_MB_2U(SCH_1):GND
 262    GND VSS114 @S9S_MB_2U_LIB.S9S_MB_2U(SCH_1):GND
 264    GND VSS115 @S9S_MB_2U_LIB.S9S_MB_2U(SCH_1):GND
 266    GND VSS116 @S9S_MB_2U_LIB.S9S_MB_2U(SCH_1):GND
 268    GND VSS117 @S9S_MB_2U_LIB.S9S_MB_2U(SCH_1):GND
 270    GND VSS118 @S9S_MB_2U_LIB.S9S_MB_2U(SCH_1):GND
 273    GND VSS119 @S9S_MB_2U_LIB.S9S_MB_2U(SCH_1):GND
 275    GND VSS120 @S9S_MB_2U_LIB.S9S_MB_2U(SCH_1):GND
 277    GND VSS121 @S9S_MB_2U_LIB.S9S_MB_2U(SCH_1):GND
 279    GND VSS122 @S9S_MB_2U_LIB.S9S_MB_2U(SCH_1):GND
 281    GND VSS123 @S9S_MB_2U_LIB.S9S_MB_2U(SCH_1):GND
 284    GND VSS124 @S9S_MB_2U_LIB.S9S_MB_2U(SCH_1):GND
 286    GND VSS125 @S9S_MB_2U_LIB.S9S_MB_2U(SCH_1):GND
 288    GND VSS126 @S9S_MB_2U_LIB.S9S_MB_2U(SCH_1):GND
   1 P12V_S3_AUX_CPU1_NVDIMM VIN_BULK0 @S9S_MB_2U_LIB.S9S_MB_2U(SCH_1):P12V_S3_AUX_CPU1_NVDIMM
 145 P12V_S3_AUX_CPU1_NVDIMM VIN_BULK1 @S9S_MB_2U_LIB.S9S_MB_2U(SCH_1):P12V_S3_AUX_CPU1_NVDIMM
 146 P12V_S3_AUX_CPU1_NVDIMM VIN_BULK2 @S9S_MB_2U_LIB.S9S_MB_2U(SCH_1):P12V_S3_AUX_CPU1_NVDIMM
 230    GND VSS100 @S9S_MB_2U_LIB.S9S_MB_2U(SCH_1):GND
 235    GND VSS102 @S9S_MB_2U_LIB.S9S_MB_2U(SCH_1):GND
 240    GND VSS104 @S9S_MB_2U_LIB.S9S_MB_2U(SCH_1):GND
 132    GND  VSS58 @S9S_MB_2U_LIB.S9S_MB_2U(SCH_1):GND
 136    GND  VSS60 @S9S_MB_2U_LIB.S9S_MB_2U(SCH_1):GND
 139    GND  VSS61 @S9S_MB_2U_LIB.S9S_MB_2U(SCH_1):GND
 141    GND  VSS62 @S9S_MB_2U_LIB.S9S_MB_2U(SCH_1):GND
  G1    GND     G1 @S9S_MB_2U_LIB.S9S_MB_2U(SCH_1):GND
  G2    GND     G2 @S9S_MB_2U_LIB.S9S_MB_2U(SCH_1):GND
  G3    GND     G3 @S9S_MB_2U_LIB.S9S_MB_2U(SCH_1):GND

SCONN288_ADR50017P130CC-SCONN2A  I179  J27
   3 P3V3_AUX VIN_MGMT @S9S_MB_2U_LIB.S9S_MB_2U(SCH_1):P3V3_AUX
   2 TP_CHF_CPU1_DIMM1_FRU_0   RFU0 @S9S_MB_2U_LIB.S9S_MB_2U(SCH_1):TP_CHF_CPU1_DIMM1_FRU_0
 144 TP_CHF_CPU1_DIMM1_FRU_1   RFU1 @S9S_MB_2U_LIB.S9S_MB_2U(SCH_1):TP_CHF_CPU1_DIMM1_FRU_1
 149 TP_CHF_CPU1_DIMM1_FRU_2   RFU2 @S9S_MB_2U_LIB.S9S_MB_2U(SCH_1):TP_CHF_CPU1_DIMM1_FRU_2
 150 TP_CHF_CPU1_DIMM1_FRU_3   RFU3 @S9S_MB_2U_LIB.S9S_MB_2U(SCH_1):TP_CHF_CPU1_DIMM1_FRU_3
 220 TP_CHF_CPU1_DIMM1_FRU_4   RFU4 @S9S_MB_2U_LIB.S9S_MB_2U(SCH_1):TP_CHF_CPU1_DIMM1_FRU_4
 231 TP_CHF_CPU1_DIMM1_FRU_5   RFU5 @S9S_MB_2U_LIB.S9S_MB_2U(SCH_1):TP_CHF_CPU1_DIMM1_FRU_5
 232 TP_CHF_CPU1_DIMM1_FRU_6   RFU6 @S9S_MB_2U_LIB.S9S_MB_2U(SCH_1):TP_CHF_CPU1_DIMM1_FRU_6
 207 RST_M_EF_CPU1_FPGA_N RESET_N @S9S_MB_2U_LIB.S9S_MB_2U(SCH_1):RST_M_EF_CPU1_FPGA_N
 147 PWRGD_CHF_CPU1_DIMM1 PWR_GOOD||FAIL_N @S9S_MB_2U_LIB.S9S_MB_2U(SCH_1):PWRGD_CHF_CPU1_DIMM1
 227 M_F_CPU1_SB_PAR  PAR_B @S9S_MB_2U_LIB.S9S_MB_2U(SCH_1):M_F_CPU1_SB_PAR
  74 M_F_CPU1_SA_PAR  PAR_A @S9S_MB_2U_LIB.S9S_MB_2U(SCH_1):M_F_CPU1_SA_PAR
  87 M_F_CPU1_SB_RSP<0> LBS||RSP_B_N @S9S_MB_2U_LIB.S9S_MB_2U(SCH_1):M_F_CPU1_SB_RSP(0)
  86 M_F_CPU1_SA_RSP<0> LBD||RSP_A_N @S9S_MB_2U_LIB.S9S_MB_2U(SCH_1):M_F_CPU1_SA_RSP(0)
   5 I3C_SPD_DDREFGH_CPU1_LVC1_SDA   HSDA @S9S_MB_2U_LIB.S9S_MB_2U(SCH_1):I3C_SPD_DDREFGH_CPU1_LVC1_SDA
   4 I3C_SPD_DDREFGH_CPU1_LVC1_SCL_2   HSCL @S9S_MB_2U_LIB.S9S_MB_2U(SCH_1):I3C_SPD_DDREFGH_CPU1_LVC1_SCL_R3
 148 PD_CHF_CPU1_DIMM1_SAA    HSA @S9S_MB_2U_LIB.S9S_MB_2U(SCH_1):PD_CHF_CPU1_DIMM1_SAA
 100 M_F_CPU1_SB_DQ<0>  DQ0_B @S9S_MB_2U_LIB.S9S_MB_2U(SCH_1):M_F_CPU1_SB_DQ(0)
 102 M_F_CPU1_SB_DQ<1>  DQ1_B @S9S_MB_2U_LIB.S9S_MB_2U(SCH_1):M_F_CPU1_SB_DQ(1)
 245 M_F_CPU1_SB_DQ<2>  DQ2_B @S9S_MB_2U_LIB.S9S_MB_2U(SCH_1):M_F_CPU1_SB_DQ(2)
 247 M_F_CPU1_SB_DQ<3>  DQ3_B @S9S_MB_2U_LIB.S9S_MB_2U(SCH_1):M_F_CPU1_SB_DQ(3)
 107 M_F_CPU1_SB_DQ<4>  DQ4_B @S9S_MB_2U_LIB.S9S_MB_2U(SCH_1):M_F_CPU1_SB_DQ(4)
 109 M_F_CPU1_SB_DQ<5>  DQ5_B @S9S_MB_2U_LIB.S9S_MB_2U(SCH_1):M_F_CPU1_SB_DQ(5)
 252 M_F_CPU1_SB_DQ<6>  DQ6_B @S9S_MB_2U_LIB.S9S_MB_2U(SCH_1):M_F_CPU1_SB_DQ(6)
 254 M_F_CPU1_SB_DQ<7>  DQ7_B @S9S_MB_2U_LIB.S9S_MB_2U(SCH_1):M_F_CPU1_SB_DQ(7)
 111 M_F_CPU1_SB_DQ<8>  DQ8_B @S9S_MB_2U_LIB.S9S_MB_2U(SCH_1):M_F_CPU1_SB_DQ(8)
 113 M_F_CPU1_SB_DQ<9>  DQ9_B @S9S_MB_2U_LIB.S9S_MB_2U(SCH_1):M_F_CPU1_SB_DQ(9)
 256 M_F_CPU1_SB_DQ<10> DQ10_B @S9S_MB_2U_LIB.S9S_MB_2U(SCH_1):M_F_CPU1_SB_DQ(10)
 258 M_F_CPU1_SB_DQ<11> DQ11_B @S9S_MB_2U_LIB.S9S_MB_2U(SCH_1):M_F_CPU1_SB_DQ(11)
 118 M_F_CPU1_SB_DQ<12> DQ12_B @S9S_MB_2U_LIB.S9S_MB_2U(SCH_1):M_F_CPU1_SB_DQ(12)
 120 M_F_CPU1_SB_DQ<13> DQ13_B @S9S_MB_2U_LIB.S9S_MB_2U(SCH_1):M_F_CPU1_SB_DQ(13)
 263 M_F_CPU1_SB_DQ<14> DQ14_B @S9S_MB_2U_LIB.S9S_MB_2U(SCH_1):M_F_CPU1_SB_DQ(14)
 265 M_F_CPU1_SB_DQ<15> DQ15_B @S9S_MB_2U_LIB.S9S_MB_2U(SCH_1):M_F_CPU1_SB_DQ(15)
 122 M_F_CPU1_SB_DQ<16> DQ16_B @S9S_MB_2U_LIB.S9S_MB_2U(SCH_1):M_F_CPU1_SB_DQ(16)
 124 M_F_CPU1_SB_DQ<17> DQ17_B @S9S_MB_2U_LIB.S9S_MB_2U(SCH_1):M_F_CPU1_SB_DQ(17)
 267 M_F_CPU1_SB_DQ<18> DQ18_B @S9S_MB_2U_LIB.S9S_MB_2U(SCH_1):M_F_CPU1_SB_DQ(18)
 269 M_F_CPU1_SB_DQ<19> DQ19_B @S9S_MB_2U_LIB.S9S_MB_2U(SCH_1):M_F_CPU1_SB_DQ(19)
 129 M_F_CPU1_SB_DQ<20> DQ20_B @S9S_MB_2U_LIB.S9S_MB_2U(SCH_1):M_F_CPU1_SB_DQ(20)
 131 M_F_CPU1_SB_DQ<21> DQ21_B @S9S_MB_2U_LIB.S9S_MB_2U(SCH_1):M_F_CPU1_SB_DQ(21)
 274 M_F_CPU1_SB_DQ<22> DQ22_B @S9S_MB_2U_LIB.S9S_MB_2U(SCH_1):M_F_CPU1_SB_DQ(22)
 276 M_F_CPU1_SB_DQ<23> DQ23_B @S9S_MB_2U_LIB.S9S_MB_2U(SCH_1):M_F_CPU1_SB_DQ(23)
 133 M_F_CPU1_SB_DQ<24> DQ24_B @S9S_MB_2U_LIB.S9S_MB_2U(SCH_1):M_F_CPU1_SB_DQ(24)
 135 M_F_CPU1_SB_DQ<25> DQ25_B @S9S_MB_2U_LIB.S9S_MB_2U(SCH_1):M_F_CPU1_SB_DQ(25)
 278 M_F_CPU1_SB_DQ<26> DQ26_B @S9S_MB_2U_LIB.S9S_MB_2U(SCH_1):M_F_CPU1_SB_DQ(26)
 280 M_F_CPU1_SB_DQ<27> DQ27_B @S9S_MB_2U_LIB.S9S_MB_2U(SCH_1):M_F_CPU1_SB_DQ(27)
 140 M_F_CPU1_SB_DQ<28> DQ28_B @S9S_MB_2U_LIB.S9S_MB_2U(SCH_1):M_F_CPU1_SB_DQ(28)
 142 M_F_CPU1_SB_DQ<29> DQ29_B @S9S_MB_2U_LIB.S9S_MB_2U(SCH_1):M_F_CPU1_SB_DQ(29)
 285 M_F_CPU1_SB_DQ<30> DQ30_B @S9S_MB_2U_LIB.S9S_MB_2U(SCH_1):M_F_CPU1_SB_DQ(30)
 287 M_F_CPU1_SB_DQ<31> DQ31_B @S9S_MB_2U_LIB.S9S_MB_2U(SCH_1):M_F_CPU1_SB_DQ(31)
   7 M_F_CPU1_SA_DQ<0>  DQ0_A @S9S_MB_2U_LIB.S9S_MB_2U(SCH_1):M_F_CPU1_SA_DQ(0)
   9 M_F_CPU1_SA_DQ<1>  DQ1_A @S9S_MB_2U_LIB.S9S_MB_2U(SCH_1):M_F_CPU1_SA_DQ(1)
 152 M_F_CPU1_SA_DQ<2>  DQ2_A @S9S_MB_2U_LIB.S9S_MB_2U(SCH_1):M_F_CPU1_SA_DQ(2)
 154 M_F_CPU1_SA_DQ<3>  DQ3_A @S9S_MB_2U_LIB.S9S_MB_2U(SCH_1):M_F_CPU1_SA_DQ(3)
  14 M_F_CPU1_SA_DQ<4>  DQ4_A @S9S_MB_2U_LIB.S9S_MB_2U(SCH_1):M_F_CPU1_SA_DQ(4)
  16 M_F_CPU1_SA_DQ<5>  DQ5_A @S9S_MB_2U_LIB.S9S_MB_2U(SCH_1):M_F_CPU1_SA_DQ(5)
 159 M_F_CPU1_SA_DQ<6>  DQ6_A @S9S_MB_2U_LIB.S9S_MB_2U(SCH_1):M_F_CPU1_SA_DQ(6)
 161 M_F_CPU1_SA_DQ<7>  DQ7_A @S9S_MB_2U_LIB.S9S_MB_2U(SCH_1):M_F_CPU1_SA_DQ(7)
  18 M_F_CPU1_SA_DQ<8>  DQ8_A @S9S_MB_2U_LIB.S9S_MB_2U(SCH_1):M_F_CPU1_SA_DQ(8)
  20 M_F_CPU1_SA_DQ<9>  DQ9_A @S9S_MB_2U_LIB.S9S_MB_2U(SCH_1):M_F_CPU1_SA_DQ(9)
 163 M_F_CPU1_SA_DQ<10> DQ10_A @S9S_MB_2U_LIB.S9S_MB_2U(SCH_1):M_F_CPU1_SA_DQ(10)
 165 M_F_CPU1_SA_DQ<11> DQ11_A @S9S_MB_2U_LIB.S9S_MB_2U(SCH_1):M_F_CPU1_SA_DQ(11)
  25 M_F_CPU1_SA_DQ<12> DQ12_A @S9S_MB_2U_LIB.S9S_MB_2U(SCH_1):M_F_CPU1_SA_DQ(12)
  27 M_F_CPU1_SA_DQ<13> DQ13_A @S9S_MB_2U_LIB.S9S_MB_2U(SCH_1):M_F_CPU1_SA_DQ(13)
 170 M_F_CPU1_SA_DQ<14> DQ14_A @S9S_MB_2U_LIB.S9S_MB_2U(SCH_1):M_F_CPU1_SA_DQ(14)
 172 M_F_CPU1_SA_DQ<15> DQ15_A @S9S_MB_2U_LIB.S9S_MB_2U(SCH_1):M_F_CPU1_SA_DQ(15)
  29 M_F_CPU1_SA_DQ<16> DQ16_A @S9S_MB_2U_LIB.S9S_MB_2U(SCH_1):M_F_CPU1_SA_DQ(16)
  31 M_F_CPU1_SA_DQ<17> DQ17_A @S9S_MB_2U_LIB.S9S_MB_2U(SCH_1):M_F_CPU1_SA_DQ(17)
 174 M_F_CPU1_SA_DQ<18> DQ18_A @S9S_MB_2U_LIB.S9S_MB_2U(SCH_1):M_F_CPU1_SA_DQ(18)
 176 M_F_CPU1_SA_DQ<19> DQ19_A @S9S_MB_2U_LIB.S9S_MB_2U(SCH_1):M_F_CPU1_SA_DQ(19)
  36 M_F_CPU1_SA_DQ<20> DQ20_A @S9S_MB_2U_LIB.S9S_MB_2U(SCH_1):M_F_CPU1_SA_DQ(20)
  38 M_F_CPU1_SA_DQ<21> DQ21_A @S9S_MB_2U_LIB.S9S_MB_2U(SCH_1):M_F_CPU1_SA_DQ(21)
 181 M_F_CPU1_SA_DQ<22> DQ22_A @S9S_MB_2U_LIB.S9S_MB_2U(SCH_1):M_F_CPU1_SA_DQ(22)
 183 M_F_CPU1_SA_DQ<23> DQ23_A @S9S_MB_2U_LIB.S9S_MB_2U(SCH_1):M_F_CPU1_SA_DQ(23)
  40 M_F_CPU1_SA_DQ<24> DQ24_A @S9S_MB_2U_LIB.S9S_MB_2U(SCH_1):M_F_CPU1_SA_DQ(24)
  42 M_F_CPU1_SA_DQ<25> DQ25_A @S9S_MB_2U_LIB.S9S_MB_2U(SCH_1):M_F_CPU1_SA_DQ(25)
 185 M_F_CPU1_SA_DQ<26> DQ26_A @S9S_MB_2U_LIB.S9S_MB_2U(SCH_1):M_F_CPU1_SA_DQ(26)
 187 M_F_CPU1_SA_DQ<27> DQ27_A @S9S_MB_2U_LIB.S9S_MB_2U(SCH_1):M_F_CPU1_SA_DQ(27)
  47 M_F_CPU1_SA_DQ<28> DQ28_A @S9S_MB_2U_LIB.S9S_MB_2U(SCH_1):M_F_CPU1_SA_DQ(28)
  49 M_F_CPU1_SA_DQ<29> DQ29_A @S9S_MB_2U_LIB.S9S_MB_2U(SCH_1):M_F_CPU1_SA_DQ(29)
 192 M_F_CPU1_SA_DQ<30> DQ30_A @S9S_MB_2U_LIB.S9S_MB_2U(SCH_1):M_F_CPU1_SA_DQ(30)
 229 M_F_CPU1_SB_CS_N<1> CS1_B_N @S9S_MB_2U_LIB.S9S_MB_2U(SCH_1):M_F_CPU1_SB_CS_N(1)
 209 M_F_CPU1_SA_CS_N<1> CS1_A_N @S9S_MB_2U_LIB.S9S_MB_2U(SCH_1):M_F_CPU1_SA_CS_N(1)
  84 M_F_CPU1_SB_CS_N<0> CS0_B_N @S9S_MB_2U_LIB.S9S_MB_2U(SCH_1):M_F_CPU1_SB_CS_N(0)
  64 M_F_CPU1_SA_CS_N<0> CS0_A_N @S9S_MB_2U_LIB.S9S_MB_2U(SCH_1):M_F_CPU1_SA_CS_N(0)
 217 M_F_CPU1_CLK_DP<0>   CK_T @S9S_MB_2U_LIB.S9S_MB_2U(SCH_1):M_F_CPU1_CLK_DP(0)
 218 M_F_CPU1_CLK_DN<0>   CK_C @S9S_MB_2U_LIB.S9S_MB_2U(SCH_1):M_F_CPU1_CLK_DN(0)
  96 M_F_CPU1_SB_CB<0>  CB0_B @S9S_MB_2U_LIB.S9S_MB_2U(SCH_1):M_F_CPU1_SB_CB(0)
  98 M_F_CPU1_SB_CB<1>  CB1_B @S9S_MB_2U_LIB.S9S_MB_2U(SCH_1):M_F_CPU1_SB_CB(1)
 241 M_F_CPU1_SB_CB<2>  CB2_B @S9S_MB_2U_LIB.S9S_MB_2U(SCH_1):M_F_CPU1_SB_CB(2)
 243 M_F_CPU1_SB_CB<3>  CB3_B @S9S_MB_2U_LIB.S9S_MB_2U(SCH_1):M_F_CPU1_SB_CB(3)
  89 M_F_CPU1_SB_CB<4>  CB4_B @S9S_MB_2U_LIB.S9S_MB_2U(SCH_1):M_F_CPU1_SB_CB(4)
  91 M_F_CPU1_SB_CB<5>  CB5_B @S9S_MB_2U_LIB.S9S_MB_2U(SCH_1):M_F_CPU1_SB_CB(5)
 234 M_F_CPU1_SB_CB<6>  CB6_B @S9S_MB_2U_LIB.S9S_MB_2U(SCH_1):M_F_CPU1_SB_CB(6)
  51 M_F_CPU1_SA_CB<0>  CB0_A @S9S_MB_2U_LIB.S9S_MB_2U(SCH_1):M_F_CPU1_SA_CB(0)
 196 M_F_CPU1_SA_CB<2>  CB2_A @S9S_MB_2U_LIB.S9S_MB_2U(SCH_1):M_F_CPU1_SA_CB(2)
 198 M_F_CPU1_SA_CB<3>  CB3_A @S9S_MB_2U_LIB.S9S_MB_2U(SCH_1):M_F_CPU1_SA_CB(3)
  60 M_F_CPU1_SA_CB<5>  CB5_A @S9S_MB_2U_LIB.S9S_MB_2U(SCH_1):M_F_CPU1_SA_CB(5)
 203 M_F_CPU1_SA_CB<6>  CB6_A @S9S_MB_2U_LIB.S9S_MB_2U(SCH_1):M_F_CPU1_SA_CB(6)
  82 M_F_CPU1_SB_CA<6>  CA6_B @S9S_MB_2U_LIB.S9S_MB_2U(SCH_1):M_F_CPU1_SB_CA(6)
  72 M_F_CPU1_SA_CA<6>  CA6_A @S9S_MB_2U_LIB.S9S_MB_2U(SCH_1):M_F_CPU1_SA_CA(6)
 225 M_F_CPU1_SB_CA<5>  CA5_B @S9S_MB_2U_LIB.S9S_MB_2U(SCH_1):M_F_CPU1_SB_CA(5)
 215 M_F_CPU1_SA_CA<5>  CA5_A @S9S_MB_2U_LIB.S9S_MB_2U(SCH_1):M_F_CPU1_SA_CA(5)
  80 M_F_CPU1_SB_CA<4>  CA4_B @S9S_MB_2U_LIB.S9S_MB_2U(SCH_1):M_F_CPU1_SB_CA(4)
  70 M_F_CPU1_SA_CA<4>  CA4_A @S9S_MB_2U_LIB.S9S_MB_2U(SCH_1):M_F_CPU1_SA_CA(4)
 223 M_F_CPU1_SB_CA<3>  CA3_B @S9S_MB_2U_LIB.S9S_MB_2U(SCH_1):M_F_CPU1_SB_CA(3)
 213 M_F_CPU1_SA_CA<3>  CA3_A @S9S_MB_2U_LIB.S9S_MB_2U(SCH_1):M_F_CPU1_SA_CA(3)
  78 M_F_CPU1_SB_CA<2>  CA2_B @S9S_MB_2U_LIB.S9S_MB_2U(SCH_1):M_F_CPU1_SB_CA(2)
  68 M_F_CPU1_SA_CA<2>  CA2_A @S9S_MB_2U_LIB.S9S_MB_2U(SCH_1):M_F_CPU1_SA_CA(2)
 221 M_F_CPU1_SB_CA<1>  CA1_B @S9S_MB_2U_LIB.S9S_MB_2U(SCH_1):M_F_CPU1_SB_CA(1)
 211 M_F_CPU1_SA_CA<1>  CA1_A @S9S_MB_2U_LIB.S9S_MB_2U(SCH_1):M_F_CPU1_SA_CA(1)
  76 M_F_CPU1_SB_CA<0>  CA0_B @S9S_MB_2U_LIB.S9S_MB_2U(SCH_1):M_F_CPU1_SB_CA(0)
  66 M_F_CPU1_SA_CA<0>  CA0_A @S9S_MB_2U_LIB.S9S_MB_2U(SCH_1):M_F_CPU1_SA_CA(0)
  62 M_F_CPU1_ALERT_N ALERT_N @S9S_MB_2U_LIB.S9S_MB_2U(SCH_1):M_F_CPU1_ALERT_N
 236 M_F_CPU1_SB_CB<7>  CB7_B @S9S_MB_2U_LIB.S9S_MB_2U(SCH_1):M_F_CPU1_SB_CB(7)
  53 M_F_CPU1_SA_CB<1>  CB1_A @S9S_MB_2U_LIB.S9S_MB_2U(SCH_1):M_F_CPU1_SA_CB(1)
  58 M_F_CPU1_SA_CB<4>  CB4_A @S9S_MB_2U_LIB.S9S_MB_2U(SCH_1):M_F_CPU1_SA_CB(4)
 205 M_F_CPU1_SA_CB<7>  CB7_A @S9S_MB_2U_LIB.S9S_MB_2U(SCH_1):M_F_CPU1_SA_CB(7)
 194 M_F_CPU1_SA_DQ<31> DQ31_A @S9S_MB_2U_LIB.S9S_MB_2U(SCH_1):M_F_CPU1_SA_DQ(31)

SCONN288_ADR50017P130CC-SCONN2A  I180  J27
  93 M_F_CPU1_SB_DQS_DP<9> DQS9_B_T||TDQS9_B_T||DBI4_B_N @S9S_MB_2U_LIB.S9S_MB_2U(SCH_1):M_F_CPU1_SB_DQS_DP(9)
  94 M_F_CPU1_SB_DQS_DN<9> DQS9_B_C||TDQS9_B_C @S9S_MB_2U_LIB.S9S_MB_2U(SCH_1):M_F_CPU1_SB_DQS_DN(9)
 201 M_F_CPU1_SA_DQS_DP<9> DQS9_A_T||TDQS9_A_T @S9S_MB_2U_LIB.S9S_MB_2U(SCH_1):M_F_CPU1_SA_DQS_DP(9)
 200 M_F_CPU1_SA_DQS_DN<9> DQS9_A_C||TDQS9_A_C @S9S_MB_2U_LIB.S9S_MB_2U(SCH_1):M_F_CPU1_SA_DQS_DN(9)
 190 M_F_CPU1_SA_DQS_DP<8> DQS8_A_T||TDQS8_A_T @S9S_MB_2U_LIB.S9S_MB_2U(SCH_1):M_F_CPU1_SA_DQS_DP(8)
 189 M_F_CPU1_SA_DQS_DN<8> DQS8_A_C||TDQS8_A_C @S9S_MB_2U_LIB.S9S_MB_2U(SCH_1):M_F_CPU1_SA_DQS_DN(8)
 271 M_F_CPU1_SB_DQS_DN<7> DQS7_B_C||TDQS7_B_C @S9S_MB_2U_LIB.S9S_MB_2U(SCH_1):M_F_CPU1_SB_DQS_DN(7)
 179 M_F_CPU1_SA_DQS_DP<7> DQS7_A_T||TDQS7_A_T @S9S_MB_2U_LIB.S9S_MB_2U(SCH_1):M_F_CPU1_SA_DQS_DP(7)
 261 M_F_CPU1_SB_DQS_DP<6> DQS6_B_T||TDQS6_B_T @S9S_MB_2U_LIB.S9S_MB_2U(SCH_1):M_F_CPU1_SB_DQS_DP(6)
 260 M_F_CPU1_SB_DQS_DN<6> DQS6_B_C||TDQS6_B_C @S9S_MB_2U_LIB.S9S_MB_2U(SCH_1):M_F_CPU1_SB_DQS_DN(6)
 167 M_F_CPU1_SA_DQS_DN<6> DQS6_A_C||TDQS6_A_C||DQS6_A_T||TDQS6_A_T @S9S_MB_2U_LIB.S9S_MB_2U(SCH_1):M_F_CPU1_SA_DQS_DN(6)
 250 M_F_CPU1_SB_DQS_DP<5> DQS5_B_T||TDQS5_B_T @S9S_MB_2U_LIB.S9S_MB_2U(SCH_1):M_F_CPU1_SB_DQS_DP(5)
 249 M_F_CPU1_SB_DQS_DN<5> DQS5_B_C||TDQS5_B_C @S9S_MB_2U_LIB.S9S_MB_2U(SCH_1):M_F_CPU1_SB_DQS_DN(5)
 157 M_F_CPU1_SA_DQS_DP<5> DQS5_A_T||TDQS5_A_T @S9S_MB_2U_LIB.S9S_MB_2U(SCH_1):M_F_CPU1_SA_DQS_DP(5)
 156 M_F_CPU1_SA_DQS_DN<5> DQS5_A_C||TDQS5_A_C||DQS5_A_T||TDQS5_A_T @S9S_MB_2U_LIB.S9S_MB_2U(SCH_1):M_F_CPU1_SA_DQS_DN(5)
 239 M_F_CPU1_SB_DQS_DP<4> DQS4_B_T @S9S_MB_2U_LIB.S9S_MB_2U(SCH_1):M_F_CPU1_SB_DQS_DP(4)
 238 M_F_CPU1_SB_DQS_DN<4> DQS4_B_C @S9S_MB_2U_LIB.S9S_MB_2U(SCH_1):M_F_CPU1_SB_DQS_DN(4)
  55 M_F_CPU1_SA_DQS_DP<4> DQS4_A_T @S9S_MB_2U_LIB.S9S_MB_2U(SCH_1):M_F_CPU1_SA_DQS_DP(4)
  56 M_F_CPU1_SA_DQS_DN<4> DQS4_A_C @S9S_MB_2U_LIB.S9S_MB_2U(SCH_1):M_F_CPU1_SA_DQS_DN(4)
 137 M_F_CPU1_SB_DQS_DP<3> DQS3_B_T @S9S_MB_2U_LIB.S9S_MB_2U(SCH_1):M_F_CPU1_SB_DQS_DP(3)
 138 M_F_CPU1_SB_DQS_DN<3> DQS3_B_C @S9S_MB_2U_LIB.S9S_MB_2U(SCH_1):M_F_CPU1_SB_DQS_DN(3)
  44 M_F_CPU1_SA_DQS_DP<3> DQS3_A_T @S9S_MB_2U_LIB.S9S_MB_2U(SCH_1):M_F_CPU1_SA_DQS_DP(3)
  45 M_F_CPU1_SA_DQS_DN<3> DQS3_A_C @S9S_MB_2U_LIB.S9S_MB_2U(SCH_1):M_F_CPU1_SA_DQS_DN(3)
 126 M_F_CPU1_SB_DQS_DP<2> DQS2_B_T @S9S_MB_2U_LIB.S9S_MB_2U(SCH_1):M_F_CPU1_SB_DQS_DP(2)
 127 M_F_CPU1_SB_DQS_DN<2> DQS2_B_C @S9S_MB_2U_LIB.S9S_MB_2U(SCH_1):M_F_CPU1_SB_DQS_DN(2)
  33 M_F_CPU1_SA_DQS_DP<2> DQS2_A_T @S9S_MB_2U_LIB.S9S_MB_2U(SCH_1):M_F_CPU1_SA_DQS_DP(2)
  34 M_F_CPU1_SA_DQS_DN<2> DQS2_A_C @S9S_MB_2U_LIB.S9S_MB_2U(SCH_1):M_F_CPU1_SA_DQS_DN(2)
 115 M_F_CPU1_SB_DQS_DP<1> DQS1_B_T @S9S_MB_2U_LIB.S9S_MB_2U(SCH_1):M_F_CPU1_SB_DQS_DP(1)
 116 M_F_CPU1_SB_DQS_DN<1> DQS1_B_C @S9S_MB_2U_LIB.S9S_MB_2U(SCH_1):M_F_CPU1_SB_DQS_DN(1)
  22 M_F_CPU1_SA_DQS_DP<1> DQS1_A_T @S9S_MB_2U_LIB.S9S_MB_2U(SCH_1):M_F_CPU1_SA_DQS_DP(1)
  23 M_F_CPU1_SA_DQS_DN<1> DQS1_A_C @S9S_MB_2U_LIB.S9S_MB_2U(SCH_1):M_F_CPU1_SA_DQS_DN(1)
 104 M_F_CPU1_SB_DQS_DP<0> DQS0_B_T @S9S_MB_2U_LIB.S9S_MB_2U(SCH_1):M_F_CPU1_SB_DQS_DP(0)
 105 M_F_CPU1_SB_DQS_DN<0> DQS0_B_C @S9S_MB_2U_LIB.S9S_MB_2U(SCH_1):M_F_CPU1_SB_DQS_DN(0)
  11 M_F_CPU1_SA_DQS_DP<0> DQS0_A_T @S9S_MB_2U_LIB.S9S_MB_2U(SCH_1):M_F_CPU1_SA_DQS_DP(0)
  12 M_F_CPU1_SA_DQS_DN<0> DQS0_A_C @S9S_MB_2U_LIB.S9S_MB_2U(SCH_1):M_F_CPU1_SA_DQS_DN(0)
 272 M_F_CPU1_SB_DQS_DP<7> DQS7_B_T||TDQS7_B_T @S9S_MB_2U_LIB.S9S_MB_2U(SCH_1):M_F_CPU1_SB_DQS_DP(7)
 282 M_F_CPU1_SB_DQS_DN<8> DQS8_B_C||TDQS8_B_C @S9S_MB_2U_LIB.S9S_MB_2U(SCH_1):M_F_CPU1_SB_DQS_DN(8)
 283 M_F_CPU1_SB_DQS_DP<8> DQS8_B_T||TDQS8_B_T @S9S_MB_2U_LIB.S9S_MB_2U(SCH_1):M_F_CPU1_SB_DQS_DP(8)
 168 M_F_CPU1_SA_DQS_DP<6> DQS6_A_T||TDQS6_A_T @S9S_MB_2U_LIB.S9S_MB_2U(SCH_1):M_F_CPU1_SA_DQS_DP(6)
 178 M_F_CPU1_SA_DQS_DN<7> DQS7_A_C||TDQS7_A_C @S9S_MB_2U_LIB.S9S_MB_2U(SCH_1):M_F_CPU1_SA_DQS_DN(7)

Q_RES_0402LF-49.9,1%,1/16W,CHIA  I182  R3901
   1 I3C_SPD_DDREFGH_CPU1_LVC1_SCL_2      A @S9S_MB_2U_LIB.S9S_MB_2U(SCH_1):I3C_SPD_DDREFGH_CPU1_LVC1_SCL_R3
   2 I3C_SPD_DDREFGH_CPU1_LVC1_SCL      B @S9S_MB_2U_LIB.S9S_MB_2U(SCH_1):I3C_SPD_DDREFGH_CPU1_LVC1_SCL


DRAWING: @S9S_MB_2U_LIB.S9S_MB_2U(SCH_1):PAGE109 

Q_RES_0402LF-35.7K,1%,1/16W,CHA  I46  R76
   1 PD_CHF_CPU1_DIMM2_SAA      A @S9S_MB_2U_LIB.S9S_MB_2U(SCH_1):PD_CHF_CPU1_DIMM2_SAA
   2    GND      B @S9S_MB_2U_LIB.S9S_MB_2U(SCH_1):GND

SCONN288_ADR50017P087CC-SCONN2A  I47  J28
   3 P3V3_AUX VIN_MGMT @S9S_MB_2U_LIB.S9S_MB_2U(SCH_1):P3V3_AUX
   2 TP_CHF_CPU1_DIMM2_FRU_0   RFU0 @S9S_MB_2U_LIB.S9S_MB_2U(SCH_1):TP_CHF_CPU1_DIMM2_FRU_0
 144 TP_CHF_CPU1_DIMM2_FRU_1   RFU1 @S9S_MB_2U_LIB.S9S_MB_2U(SCH_1):TP_CHF_CPU1_DIMM2_FRU_1
 149 TP_CHF_CPU1_DIMM2_FRU_2   RFU2 @S9S_MB_2U_LIB.S9S_MB_2U(SCH_1):TP_CHF_CPU1_DIMM2_FRU_2
 150 TP_CHF_CPU1_DIMM2_FRU_3   RFU3 @S9S_MB_2U_LIB.S9S_MB_2U(SCH_1):TP_CHF_CPU1_DIMM2_FRU_3
 220 TP_CHF_CPU1_DIMM2_FRU_4   RFU4 @S9S_MB_2U_LIB.S9S_MB_2U(SCH_1):TP_CHF_CPU1_DIMM2_FRU_4
 231 TP_CHF_CPU1_DIMM2_FRU_5   RFU5 @S9S_MB_2U_LIB.S9S_MB_2U(SCH_1):TP_CHF_CPU1_DIMM2_FRU_5
 232 TP_CHF_CPU1_DIMM2_FRU_6   RFU6 @S9S_MB_2U_LIB.S9S_MB_2U(SCH_1):TP_CHF_CPU1_DIMM2_FRU_6
 207 RST_M_EF_CPU1_FPGA_N RESET_N @S9S_MB_2U_LIB.S9S_MB_2U(SCH_1):RST_M_EF_CPU1_FPGA_N
 147 PWRGD_CHF_CPU1_DIMM2 PWR_GOOD||FAIL_N @S9S_MB_2U_LIB.S9S_MB_2U(SCH_1):PWRGD_CHF_CPU1_DIMM2
 227 M_F_CPU1_SB_PAR  PAR_B @S9S_MB_2U_LIB.S9S_MB_2U(SCH_1):M_F_CPU1_SB_PAR
  74 M_F_CPU1_SA_PAR  PAR_A @S9S_MB_2U_LIB.S9S_MB_2U(SCH_1):M_F_CPU1_SA_PAR
  87 M_F_CPU1_SB_RSP<1> LBS||RSP_B_N @S9S_MB_2U_LIB.S9S_MB_2U(SCH_1):M_F_CPU1_SB_RSP(1)
  86 M_F_CPU1_SA_RSP<1> LBD||RSP_A_N @S9S_MB_2U_LIB.S9S_MB_2U(SCH_1):M_F_CPU1_SA_RSP(1)
   5 I3C_SPD_DDREFGH_CPU1_LVC1_SDA   HSDA @S9S_MB_2U_LIB.S9S_MB_2U(SCH_1):I3C_SPD_DDREFGH_CPU1_LVC1_SDA
   4 I3C_SPD_DDREFGH_CPU1_LVC1_SCL_3   HSCL @S9S_MB_2U_LIB.S9S_MB_2U(SCH_1):I3C_SPD_DDREFGH_CPU1_LVC1_SCL_R4
 148 PD_CHF_CPU1_DIMM2_SAA    HSA @S9S_MB_2U_LIB.S9S_MB_2U(SCH_1):PD_CHF_CPU1_DIMM2_SAA
 100 M_F_CPU1_SB_DQ<0>  DQ0_B @S9S_MB_2U_LIB.S9S_MB_2U(SCH_1):M_F_CPU1_SB_DQ(0)
 102 M_F_CPU1_SB_DQ<1>  DQ1_B @S9S_MB_2U_LIB.S9S_MB_2U(SCH_1):M_F_CPU1_SB_DQ(1)
 245 M_F_CPU1_SB_DQ<2>  DQ2_B @S9S_MB_2U_LIB.S9S_MB_2U(SCH_1):M_F_CPU1_SB_DQ(2)
 247 M_F_CPU1_SB_DQ<3>  DQ3_B @S9S_MB_2U_LIB.S9S_MB_2U(SCH_1):M_F_CPU1_SB_DQ(3)
 107 M_F_CPU1_SB_DQ<4>  DQ4_B @S9S_MB_2U_LIB.S9S_MB_2U(SCH_1):M_F_CPU1_SB_DQ(4)
 109 M_F_CPU1_SB_DQ<5>  DQ5_B @S9S_MB_2U_LIB.S9S_MB_2U(SCH_1):M_F_CPU1_SB_DQ(5)
 252 M_F_CPU1_SB_DQ<6>  DQ6_B @S9S_MB_2U_LIB.S9S_MB_2U(SCH_1):M_F_CPU1_SB_DQ(6)
 254 M_F_CPU1_SB_DQ<7>  DQ7_B @S9S_MB_2U_LIB.S9S_MB_2U(SCH_1):M_F_CPU1_SB_DQ(7)
 111 M_F_CPU1_SB_DQ<8>  DQ8_B @S9S_MB_2U_LIB.S9S_MB_2U(SCH_1):M_F_CPU1_SB_DQ(8)
 113 M_F_CPU1_SB_DQ<9>  DQ9_B @S9S_MB_2U_LIB.S9S_MB_2U(SCH_1):M_F_CPU1_SB_DQ(9)
 256 M_F_CPU1_SB_DQ<10> DQ10_B @S9S_MB_2U_LIB.S9S_MB_2U(SCH_1):M_F_CPU1_SB_DQ(10)
 258 M_F_CPU1_SB_DQ<11> DQ11_B @S9S_MB_2U_LIB.S9S_MB_2U(SCH_1):M_F_CPU1_SB_DQ(11)
 118 M_F_CPU1_SB_DQ<12> DQ12_B @S9S_MB_2U_LIB.S9S_MB_2U(SCH_1):M_F_CPU1_SB_DQ(12)
 120 M_F_CPU1_SB_DQ<13> DQ13_B @S9S_MB_2U_LIB.S9S_MB_2U(SCH_1):M_F_CPU1_SB_DQ(13)
 263 M_F_CPU1_SB_DQ<14> DQ14_B @S9S_MB_2U_LIB.S9S_MB_2U(SCH_1):M_F_CPU1_SB_DQ(14)
 265 M_F_CPU1_SB_DQ<15> DQ15_B @S9S_MB_2U_LIB.S9S_MB_2U(SCH_1):M_F_CPU1_SB_DQ(15)
 122 M_F_CPU1_SB_DQ<16> DQ16_B @S9S_MB_2U_LIB.S9S_MB_2U(SCH_1):M_F_CPU1_SB_DQ(16)
 124 M_F_CPU1_SB_DQ<17> DQ17_B @S9S_MB_2U_LIB.S9S_MB_2U(SCH_1):M_F_CPU1_SB_DQ(17)
 267 M_F_CPU1_SB_DQ<18> DQ18_B @S9S_MB_2U_LIB.S9S_MB_2U(SCH_1):M_F_CPU1_SB_DQ(18)
 269 M_F_CPU1_SB_DQ<19> DQ19_B @S9S_MB_2U_LIB.S9S_MB_2U(SCH_1):M_F_CPU1_SB_DQ(19)
 129 M_F_CPU1_SB_DQ<20> DQ20_B @S9S_MB_2U_LIB.S9S_MB_2U(SCH_1):M_F_CPU1_SB_DQ(20)
 131 M_F_CPU1_SB_DQ<21> DQ21_B @S9S_MB_2U_LIB.S9S_MB_2U(SCH_1):M_F_CPU1_SB_DQ(21)
 274 M_F_CPU1_SB_DQ<22> DQ22_B @S9S_MB_2U_LIB.S9S_MB_2U(SCH_1):M_F_CPU1_SB_DQ(22)
 276 M_F_CPU1_SB_DQ<23> DQ23_B @S9S_MB_2U_LIB.S9S_MB_2U(SCH_1):M_F_CPU1_SB_DQ(23)
 133 M_F_CPU1_SB_DQ<24> DQ24_B @S9S_MB_2U_LIB.S9S_MB_2U(SCH_1):M_F_CPU1_SB_DQ(24)
 135 M_F_CPU1_SB_DQ<25> DQ25_B @S9S_MB_2U_LIB.S9S_MB_2U(SCH_1):M_F_CPU1_SB_DQ(25)
 278 M_F_CPU1_SB_DQ<26> DQ26_B @S9S_MB_2U_LIB.S9S_MB_2U(SCH_1):M_F_CPU1_SB_DQ(26)
 280 M_F_CPU1_SB_DQ<27> DQ27_B @S9S_MB_2U_LIB.S9S_MB_2U(SCH_1):M_F_CPU1_SB_DQ(27)
 140 M_F_CPU1_SB_DQ<28> DQ28_B @S9S_MB_2U_LIB.S9S_MB_2U(SCH_1):M_F_CPU1_SB_DQ(28)
 142 M_F_CPU1_SB_DQ<29> DQ29_B @S9S_MB_2U_LIB.S9S_MB_2U(SCH_1):M_F_CPU1_SB_DQ(29)
 285 M_F_CPU1_SB_DQ<30> DQ30_B @S9S_MB_2U_LIB.S9S_MB_2U(SCH_1):M_F_CPU1_SB_DQ(30)
 287 M_F_CPU1_SB_DQ<31> DQ31_B @S9S_MB_2U_LIB.S9S_MB_2U(SCH_1):M_F_CPU1_SB_DQ(31)
   7 M_F_CPU1_SA_DQ<0>  DQ0_A @S9S_MB_2U_LIB.S9S_MB_2U(SCH_1):M_F_CPU1_SA_DQ(0)
   9 M_F_CPU1_SA_DQ<1>  DQ1_A @S9S_MB_2U_LIB.S9S_MB_2U(SCH_1):M_F_CPU1_SA_DQ(1)
 152 M_F_CPU1_SA_DQ<2>  DQ2_A @S9S_MB_2U_LIB.S9S_MB_2U(SCH_1):M_F_CPU1_SA_DQ(2)
 154 M_F_CPU1_SA_DQ<3>  DQ3_A @S9S_MB_2U_LIB.S9S_MB_2U(SCH_1):M_F_CPU1_SA_DQ(3)
  14 M_F_CPU1_SA_DQ<4>  DQ4_A @S9S_MB_2U_LIB.S9S_MB_2U(SCH_1):M_F_CPU1_SA_DQ(4)
  16 M_F_CPU1_SA_DQ<5>  DQ5_A @S9S_MB_2U_LIB.S9S_MB_2U(SCH_1):M_F_CPU1_SA_DQ(5)
 159 M_F_CPU1_SA_DQ<6>  DQ6_A @S9S_MB_2U_LIB.S9S_MB_2U(SCH_1):M_F_CPU1_SA_DQ(6)
 161 M_F_CPU1_SA_DQ<7>  DQ7_A @S9S_MB_2U_LIB.S9S_MB_2U(SCH_1):M_F_CPU1_SA_DQ(7)
  18 M_F_CPU1_SA_DQ<8>  DQ8_A @S9S_MB_2U_LIB.S9S_MB_2U(SCH_1):M_F_CPU1_SA_DQ(8)
  20 M_F_CPU1_SA_DQ<9>  DQ9_A @S9S_MB_2U_LIB.S9S_MB_2U(SCH_1):M_F_CPU1_SA_DQ(9)
 163 M_F_CPU1_SA_DQ<10> DQ10_A @S9S_MB_2U_LIB.S9S_MB_2U(SCH_1):M_F_CPU1_SA_DQ(10)
 165 M_F_CPU1_SA_DQ<11> DQ11_A @S9S_MB_2U_LIB.S9S_MB_2U(SCH_1):M_F_CPU1_SA_DQ(11)
  25 M_F_CPU1_SA_DQ<12> DQ12_A @S9S_MB_2U_LIB.S9S_MB_2U(SCH_1):M_F_CPU1_SA_DQ(12)
  27 M_F_CPU1_SA_DQ<13> DQ13_A @S9S_MB_2U_LIB.S9S_MB_2U(SCH_1):M_F_CPU1_SA_DQ(13)
 170 M_F_CPU1_SA_DQ<14> DQ14_A @S9S_MB_2U_LIB.S9S_MB_2U(SCH_1):M_F_CPU1_SA_DQ(14)
 172 M_F_CPU1_SA_DQ<15> DQ15_A @S9S_MB_2U_LIB.S9S_MB_2U(SCH_1):M_F_CPU1_SA_DQ(15)
  29 M_F_CPU1_SA_DQ<16> DQ16_A @S9S_MB_2U_LIB.S9S_MB_2U(SCH_1):M_F_CPU1_SA_DQ(16)
  31 M_F_CPU1_SA_DQ<17> DQ17_A @S9S_MB_2U_LIB.S9S_MB_2U(SCH_1):M_F_CPU1_SA_DQ(17)
 174 M_F_CPU1_SA_DQ<18> DQ18_A @S9S_MB_2U_LIB.S9S_MB_2U(SCH_1):M_F_CPU1_SA_DQ(18)
 176 M_F_CPU1_SA_DQ<19> DQ19_A @S9S_MB_2U_LIB.S9S_MB_2U(SCH_1):M_F_CPU1_SA_DQ(19)
  36 M_F_CPU1_SA_DQ<20> DQ20_A @S9S_MB_2U_LIB.S9S_MB_2U(SCH_1):M_F_CPU1_SA_DQ(20)
  38 M_F_CPU1_SA_DQ<21> DQ21_A @S9S_MB_2U_LIB.S9S_MB_2U(SCH_1):M_F_CPU1_SA_DQ(21)
 181 M_F_CPU1_SA_DQ<22> DQ22_A @S9S_MB_2U_LIB.S9S_MB_2U(SCH_1):M_F_CPU1_SA_DQ(22)
 183 M_F_CPU1_SA_DQ<23> DQ23_A @S9S_MB_2U_LIB.S9S_MB_2U(SCH_1):M_F_CPU1_SA_DQ(23)
  40 M_F_CPU1_SA_DQ<24> DQ24_A @S9S_MB_2U_LIB.S9S_MB_2U(SCH_1):M_F_CPU1_SA_DQ(24)
  42 M_F_CPU1_SA_DQ<25> DQ25_A @S9S_MB_2U_LIB.S9S_MB_2U(SCH_1):M_F_CPU1_SA_DQ(25)
 185 M_F_CPU1_SA_DQ<26> DQ26_A @S9S_MB_2U_LIB.S9S_MB_2U(SCH_1):M_F_CPU1_SA_DQ(26)
 187 M_F_CPU1_SA_DQ<27> DQ27_A @S9S_MB_2U_LIB.S9S_MB_2U(SCH_1):M_F_CPU1_SA_DQ(27)
  47 M_F_CPU1_SA_DQ<28> DQ28_A @S9S_MB_2U_LIB.S9S_MB_2U(SCH_1):M_F_CPU1_SA_DQ(28)
  49 M_F_CPU1_SA_DQ<29> DQ29_A @S9S_MB_2U_LIB.S9S_MB_2U(SCH_1):M_F_CPU1_SA_DQ(29)
 192 M_F_CPU1_SA_DQ<30> DQ30_A @S9S_MB_2U_LIB.S9S_MB_2U(SCH_1):M_F_CPU1_SA_DQ(30)
 229 M_F_CPU1_SB_CS_N<3> CS1_B_N @S9S_MB_2U_LIB.S9S_MB_2U(SCH_1):M_F_CPU1_SB_CS_N(3)
 209 M_F_CPU1_SA_CS_N<3> CS1_A_N @S9S_MB_2U_LIB.S9S_MB_2U(SCH_1):M_F_CPU1_SA_CS_N(3)
  84 M_F_CPU1_SB_CS_N<2> CS0_B_N @S9S_MB_2U_LIB.S9S_MB_2U(SCH_1):M_F_CPU1_SB_CS_N(2)
  64 M_F_CPU1_SA_CS_N<2> CS0_A_N @S9S_MB_2U_LIB.S9S_MB_2U(SCH_1):M_F_CPU1_SA_CS_N(2)
 217 M_F_CPU1_CLK_DP<1>   CK_T @S9S_MB_2U_LIB.S9S_MB_2U(SCH_1):M_F_CPU1_CLK_DP(1)
 218 M_F_CPU1_CLK_DN<1>   CK_C @S9S_MB_2U_LIB.S9S_MB_2U(SCH_1):M_F_CPU1_CLK_DN(1)
  96 M_F_CPU1_SB_CB<0>  CB0_B @S9S_MB_2U_LIB.S9S_MB_2U(SCH_1):M_F_CPU1_SB_CB(0)
  98 M_F_CPU1_SB_CB<1>  CB1_B @S9S_MB_2U_LIB.S9S_MB_2U(SCH_1):M_F_CPU1_SB_CB(1)
 241 M_F_CPU1_SB_CB<2>  CB2_B @S9S_MB_2U_LIB.S9S_MB_2U(SCH_1):M_F_CPU1_SB_CB(2)
 243 M_F_CPU1_SB_CB<3>  CB3_B @S9S_MB_2U_LIB.S9S_MB_2U(SCH_1):M_F_CPU1_SB_CB(3)
  89 M_F_CPU1_SB_CB<4>  CB4_B @S9S_MB_2U_LIB.S9S_MB_2U(SCH_1):M_F_CPU1_SB_CB(4)
  91 M_F_CPU1_SB_CB<5>  CB5_B @S9S_MB_2U_LIB.S9S_MB_2U(SCH_1):M_F_CPU1_SB_CB(5)
 234 M_F_CPU1_SB_CB<6>  CB6_B @S9S_MB_2U_LIB.S9S_MB_2U(SCH_1):M_F_CPU1_SB_CB(6)
  51 M_F_CPU1_SA_CB<0>  CB0_A @S9S_MB_2U_LIB.S9S_MB_2U(SCH_1):M_F_CPU1_SA_CB(0)
 196 M_F_CPU1_SA_CB<2>  CB2_A @S9S_MB_2U_LIB.S9S_MB_2U(SCH_1):M_F_CPU1_SA_CB(2)
 198 M_F_CPU1_SA_CB<3>  CB3_A @S9S_MB_2U_LIB.S9S_MB_2U(SCH_1):M_F_CPU1_SA_CB(3)
  60 M_F_CPU1_SA_CB<5>  CB5_A @S9S_MB_2U_LIB.S9S_MB_2U(SCH_1):M_F_CPU1_SA_CB(5)
 203 M_F_CPU1_SA_CB<6>  CB6_A @S9S_MB_2U_LIB.S9S_MB_2U(SCH_1):M_F_CPU1_SA_CB(6)
  82 M_F_CPU1_SB_CA<6>  CA6_B @S9S_MB_2U_LIB.S9S_MB_2U(SCH_1):M_F_CPU1_SB_CA(6)
  72 M_F_CPU1_SA_CA<6>  CA6_A @S9S_MB_2U_LIB.S9S_MB_2U(SCH_1):M_F_CPU1_SA_CA(6)
 225 M_F_CPU1_SB_CA<5>  CA5_B @S9S_MB_2U_LIB.S9S_MB_2U(SCH_1):M_F_CPU1_SB_CA(5)
 215 M_F_CPU1_SA_CA<5>  CA5_A @S9S_MB_2U_LIB.S9S_MB_2U(SCH_1):M_F_CPU1_SA_CA(5)
  80 M_F_CPU1_SB_CA<4>  CA4_B @S9S_MB_2U_LIB.S9S_MB_2U(SCH_1):M_F_CPU1_SB_CA(4)
  70 M_F_CPU1_SA_CA<4>  CA4_A @S9S_MB_2U_LIB.S9S_MB_2U(SCH_1):M_F_CPU1_SA_CA(4)
 223 M_F_CPU1_SB_CA<3>  CA3_B @S9S_MB_2U_LIB.S9S_MB_2U(SCH_1):M_F_CPU1_SB_CA(3)
 213 M_F_CPU1_SA_CA<3>  CA3_A @S9S_MB_2U_LIB.S9S_MB_2U(SCH_1):M_F_CPU1_SA_CA(3)
  78 M_F_CPU1_SB_CA<2>  CA2_B @S9S_MB_2U_LIB.S9S_MB_2U(SCH_1):M_F_CPU1_SB_CA(2)
  68 M_F_CPU1_SA_CA<2>  CA2_A @S9S_MB_2U_LIB.S9S_MB_2U(SCH_1):M_F_CPU1_SA_CA(2)
 221 M_F_CPU1_SB_CA<1>  CA1_B @S9S_MB_2U_LIB.S9S_MB_2U(SCH_1):M_F_CPU1_SB_CA(1)
 211 M_F_CPU1_SA_CA<1>  CA1_A @S9S_MB_2U_LIB.S9S_MB_2U(SCH_1):M_F_CPU1_SA_CA(1)
  76 M_F_CPU1_SB_CA<0>  CA0_B @S9S_MB_2U_LIB.S9S_MB_2U(SCH_1):M_F_CPU1_SB_CA(0)
  66 M_F_CPU1_SA_CA<0>  CA0_A @S9S_MB_2U_LIB.S9S_MB_2U(SCH_1):M_F_CPU1_SA_CA(0)
  62 M_F_CPU1_ALERT_N ALERT_N @S9S_MB_2U_LIB.S9S_MB_2U(SCH_1):M_F_CPU1_ALERT_N
 236 M_F_CPU1_SB_CB<7>  CB7_B @S9S_MB_2U_LIB.S9S_MB_2U(SCH_1):M_F_CPU1_SB_CB(7)
  53 M_F_CPU1_SA_CB<1>  CB1_A @S9S_MB_2U_LIB.S9S_MB_2U(SCH_1):M_F_CPU1_SA_CB(1)
  58 M_F_CPU1_SA_CB<4>  CB4_A @S9S_MB_2U_LIB.S9S_MB_2U(SCH_1):M_F_CPU1_SA_CB(4)
 205 M_F_CPU1_SA_CB<7>  CB7_A @S9S_MB_2U_LIB.S9S_MB_2U(SCH_1):M_F_CPU1_SA_CB(7)
 194 M_F_CPU1_SA_DQ<31> DQ31_A @S9S_MB_2U_LIB.S9S_MB_2U(SCH_1):M_F_CPU1_SA_DQ(31)

Q_CAP_C0402-2.2UF,6.3V,20%,X6SA  I121  C84
   1 P3V3_AUX      A @S9S_MB_2U_LIB.S9S_MB_2U(SCH_1):P3V3_AUX
   2    GND      B @S9S_MB_2U_LIB.S9S_MB_2U(SCH_1):GND

Q_CAP_C0805-10UF,16V,10%,X6S,CA  I125  C85
   1 P12V_S3_AUX_CPU1_NVDIMM      A @S9S_MB_2U_LIB.S9S_MB_2U(SCH_1):P12V_S3_AUX_CPU1_NVDIMM
   2    GND      B @S9S_MB_2U_LIB.S9S_MB_2U(SCH_1):GND

Q_CAP_C0805-10UF,16V,10%,X6S,CA  I128  C86
   1 P12V_S3_AUX_CPU1_NVDIMM      A @S9S_MB_2U_LIB.S9S_MB_2U(SCH_1):P12V_S3_AUX_CPU1_NVDIMM
   2    GND      B @S9S_MB_2U_LIB.S9S_MB_2U(SCH_1):GND

SCONN288_ADR50017P087CC-SCONN2A  I176  J28
   6    GND   VSS0 @S9S_MB_2U_LIB.S9S_MB_2U(SCH_1):GND
   8    GND   VSS1 @S9S_MB_2U_LIB.S9S_MB_2U(SCH_1):GND
  10    GND   VSS2 @S9S_MB_2U_LIB.S9S_MB_2U(SCH_1):GND
  13    GND   VSS3 @S9S_MB_2U_LIB.S9S_MB_2U(SCH_1):GND
  15    GND   VSS4 @S9S_MB_2U_LIB.S9S_MB_2U(SCH_1):GND
  17    GND   VSS5 @S9S_MB_2U_LIB.S9S_MB_2U(SCH_1):GND
  19    GND   VSS6 @S9S_MB_2U_LIB.S9S_MB_2U(SCH_1):GND
  21    GND   VSS7 @S9S_MB_2U_LIB.S9S_MB_2U(SCH_1):GND
  24    GND   VSS8 @S9S_MB_2U_LIB.S9S_MB_2U(SCH_1):GND
  26    GND   VSS9 @S9S_MB_2U_LIB.S9S_MB_2U(SCH_1):GND
  28    GND  VSS10 @S9S_MB_2U_LIB.S9S_MB_2U(SCH_1):GND
  30    GND  VSS11 @S9S_MB_2U_LIB.S9S_MB_2U(SCH_1):GND
  32    GND  VSS12 @S9S_MB_2U_LIB.S9S_MB_2U(SCH_1):GND
  35    GND  VSS13 @S9S_MB_2U_LIB.S9S_MB_2U(SCH_1):GND
  37    GND  VSS14 @S9S_MB_2U_LIB.S9S_MB_2U(SCH_1):GND
  39    GND  VSS15 @S9S_MB_2U_LIB.S9S_MB_2U(SCH_1):GND
  41    GND  VSS16 @S9S_MB_2U_LIB.S9S_MB_2U(SCH_1):GND
  43    GND  VSS17 @S9S_MB_2U_LIB.S9S_MB_2U(SCH_1):GND
  46    GND  VSS18 @S9S_MB_2U_LIB.S9S_MB_2U(SCH_1):GND
  48    GND  VSS19 @S9S_MB_2U_LIB.S9S_MB_2U(SCH_1):GND
  50    GND  VSS20 @S9S_MB_2U_LIB.S9S_MB_2U(SCH_1):GND
  52    GND  VSS21 @S9S_MB_2U_LIB.S9S_MB_2U(SCH_1):GND
  54    GND  VSS22 @S9S_MB_2U_LIB.S9S_MB_2U(SCH_1):GND
  57    GND  VSS23 @S9S_MB_2U_LIB.S9S_MB_2U(SCH_1):GND
  59    GND  VSS24 @S9S_MB_2U_LIB.S9S_MB_2U(SCH_1):GND
  61    GND  VSS25 @S9S_MB_2U_LIB.S9S_MB_2U(SCH_1):GND
  63    GND  VSS26 @S9S_MB_2U_LIB.S9S_MB_2U(SCH_1):GND
  65    GND  VSS27 @S9S_MB_2U_LIB.S9S_MB_2U(SCH_1):GND
  67    GND  VSS28 @S9S_MB_2U_LIB.S9S_MB_2U(SCH_1):GND
  69    GND  VSS29 @S9S_MB_2U_LIB.S9S_MB_2U(SCH_1):GND
  71    GND  VSS30 @S9S_MB_2U_LIB.S9S_MB_2U(SCH_1):GND
  73    GND  VSS31 @S9S_MB_2U_LIB.S9S_MB_2U(SCH_1):GND
  75    GND  VSS32 @S9S_MB_2U_LIB.S9S_MB_2U(SCH_1):GND
  77    GND  VSS33 @S9S_MB_2U_LIB.S9S_MB_2U(SCH_1):GND
  79    GND  VSS34 @S9S_MB_2U_LIB.S9S_MB_2U(SCH_1):GND
  81    GND  VSS35 @S9S_MB_2U_LIB.S9S_MB_2U(SCH_1):GND
  83    GND  VSS36 @S9S_MB_2U_LIB.S9S_MB_2U(SCH_1):GND
  85    GND  VSS37 @S9S_MB_2U_LIB.S9S_MB_2U(SCH_1):GND
  88    GND  VSS38 @S9S_MB_2U_LIB.S9S_MB_2U(SCH_1):GND
  90    GND  VSS39 @S9S_MB_2U_LIB.S9S_MB_2U(SCH_1):GND
  92    GND  VSS40 @S9S_MB_2U_LIB.S9S_MB_2U(SCH_1):GND
  95    GND  VSS41 @S9S_MB_2U_LIB.S9S_MB_2U(SCH_1):GND
  97    GND  VSS42 @S9S_MB_2U_LIB.S9S_MB_2U(SCH_1):GND
  99    GND  VSS43 @S9S_MB_2U_LIB.S9S_MB_2U(SCH_1):GND
 101    GND  VSS44 @S9S_MB_2U_LIB.S9S_MB_2U(SCH_1):GND
 103    GND  VSS45 @S9S_MB_2U_LIB.S9S_MB_2U(SCH_1):GND
 106    GND  VSS46 @S9S_MB_2U_LIB.S9S_MB_2U(SCH_1):GND
 108    GND  VSS47 @S9S_MB_2U_LIB.S9S_MB_2U(SCH_1):GND
 110    GND  VSS48 @S9S_MB_2U_LIB.S9S_MB_2U(SCH_1):GND
 112    GND  VSS49 @S9S_MB_2U_LIB.S9S_MB_2U(SCH_1):GND
 114    GND  VSS50 @S9S_MB_2U_LIB.S9S_MB_2U(SCH_1):GND
 117    GND  VSS51 @S9S_MB_2U_LIB.S9S_MB_2U(SCH_1):GND
 119    GND  VSS52 @S9S_MB_2U_LIB.S9S_MB_2U(SCH_1):GND
 121    GND  VSS53 @S9S_MB_2U_LIB.S9S_MB_2U(SCH_1):GND
 123    GND  VSS54 @S9S_MB_2U_LIB.S9S_MB_2U(SCH_1):GND
 125    GND  VSS55 @S9S_MB_2U_LIB.S9S_MB_2U(SCH_1):GND
 128    GND  VSS56 @S9S_MB_2U_LIB.S9S_MB_2U(SCH_1):GND
 130    GND  VSS57 @S9S_MB_2U_LIB.S9S_MB_2U(SCH_1):GND
 134    GND  VSS59 @S9S_MB_2U_LIB.S9S_MB_2U(SCH_1):GND
 143    GND  VSS63 @S9S_MB_2U_LIB.S9S_MB_2U(SCH_1):GND
 151    GND  VSS64 @S9S_MB_2U_LIB.S9S_MB_2U(SCH_1):GND
 153    GND  VSS65 @S9S_MB_2U_LIB.S9S_MB_2U(SCH_1):GND
 155    GND  VSS66 @S9S_MB_2U_LIB.S9S_MB_2U(SCH_1):GND
 158    GND  VSS67 @S9S_MB_2U_LIB.S9S_MB_2U(SCH_1):GND
 160    GND  VSS68 @S9S_MB_2U_LIB.S9S_MB_2U(SCH_1):GND
 162    GND  VSS69 @S9S_MB_2U_LIB.S9S_MB_2U(SCH_1):GND
 164    GND  VSS70 @S9S_MB_2U_LIB.S9S_MB_2U(SCH_1):GND
 166    GND  VSS71 @S9S_MB_2U_LIB.S9S_MB_2U(SCH_1):GND
 169    GND  VSS72 @S9S_MB_2U_LIB.S9S_MB_2U(SCH_1):GND
 171    GND  VSS73 @S9S_MB_2U_LIB.S9S_MB_2U(SCH_1):GND
 173    GND  VSS74 @S9S_MB_2U_LIB.S9S_MB_2U(SCH_1):GND
 175    GND  VSS75 @S9S_MB_2U_LIB.S9S_MB_2U(SCH_1):GND
 177    GND  VSS76 @S9S_MB_2U_LIB.S9S_MB_2U(SCH_1):GND
 180    GND  VSS77 @S9S_MB_2U_LIB.S9S_MB_2U(SCH_1):GND
 182    GND  VSS78 @S9S_MB_2U_LIB.S9S_MB_2U(SCH_1):GND
 184    GND  VSS79 @S9S_MB_2U_LIB.S9S_MB_2U(SCH_1):GND
 186    GND  VSS80 @S9S_MB_2U_LIB.S9S_MB_2U(SCH_1):GND
 188    GND  VSS81 @S9S_MB_2U_LIB.S9S_MB_2U(SCH_1):GND
 191    GND  VSS82 @S9S_MB_2U_LIB.S9S_MB_2U(SCH_1):GND
 193    GND  VSS83 @S9S_MB_2U_LIB.S9S_MB_2U(SCH_1):GND
 195    GND  VSS84 @S9S_MB_2U_LIB.S9S_MB_2U(SCH_1):GND
 197    GND  VSS85 @S9S_MB_2U_LIB.S9S_MB_2U(SCH_1):GND
 199    GND  VSS86 @S9S_MB_2U_LIB.S9S_MB_2U(SCH_1):GND
 202    GND  VSS87 @S9S_MB_2U_LIB.S9S_MB_2U(SCH_1):GND
 204    GND  VSS88 @S9S_MB_2U_LIB.S9S_MB_2U(SCH_1):GND
 206    GND  VSS89 @S9S_MB_2U_LIB.S9S_MB_2U(SCH_1):GND
 208    GND  VSS90 @S9S_MB_2U_LIB.S9S_MB_2U(SCH_1):GND
 210    GND  VSS91 @S9S_MB_2U_LIB.S9S_MB_2U(SCH_1):GND
 212    GND  VSS92 @S9S_MB_2U_LIB.S9S_MB_2U(SCH_1):GND
 214    GND  VSS93 @S9S_MB_2U_LIB.S9S_MB_2U(SCH_1):GND
 216    GND  VSS94 @S9S_MB_2U_LIB.S9S_MB_2U(SCH_1):GND
 219    GND  VSS95 @S9S_MB_2U_LIB.S9S_MB_2U(SCH_1):GND
 222    GND  VSS96 @S9S_MB_2U_LIB.S9S_MB_2U(SCH_1):GND
 224    GND  VSS97 @S9S_MB_2U_LIB.S9S_MB_2U(SCH_1):GND
 226    GND  VSS98 @S9S_MB_2U_LIB.S9S_MB_2U(SCH_1):GND
 228    GND  VSS99 @S9S_MB_2U_LIB.S9S_MB_2U(SCH_1):GND
 233    GND VSS101 @S9S_MB_2U_LIB.S9S_MB_2U(SCH_1):GND
 237    GND VSS103 @S9S_MB_2U_LIB.S9S_MB_2U(SCH_1):GND
 242    GND VSS105 @S9S_MB_2U_LIB.S9S_MB_2U(SCH_1):GND
 244    GND VSS106 @S9S_MB_2U_LIB.S9S_MB_2U(SCH_1):GND
 246    GND VSS107 @S9S_MB_2U_LIB.S9S_MB_2U(SCH_1):GND
 248    GND VSS108 @S9S_MB_2U_LIB.S9S_MB_2U(SCH_1):GND
 251    GND VSS109 @S9S_MB_2U_LIB.S9S_MB_2U(SCH_1):GND
 253    GND VSS110 @S9S_MB_2U_LIB.S9S_MB_2U(SCH_1):GND
 255    GND VSS111 @S9S_MB_2U_LIB.S9S_MB_2U(SCH_1):GND
 257    GND VSS112 @S9S_MB_2U_LIB.S9S_MB_2U(SCH_1):GND
 259    GND VSS113 @S9S_MB_2U_LIB.S9S_MB_2U(SCH_1):GND
 262    GND VSS114 @S9S_MB_2U_LIB.S9S_MB_2U(SCH_1):GND
 264    GND VSS115 @S9S_MB_2U_LIB.S9S_MB_2U(SCH_1):GND
 266    GND VSS116 @S9S_MB_2U_LIB.S9S_MB_2U(SCH_1):GND
 268    GND VSS117 @S9S_MB_2U_LIB.S9S_MB_2U(SCH_1):GND
 270    GND VSS118 @S9S_MB_2U_LIB.S9S_MB_2U(SCH_1):GND
 273    GND VSS119 @S9S_MB_2U_LIB.S9S_MB_2U(SCH_1):GND
 275    GND VSS120 @S9S_MB_2U_LIB.S9S_MB_2U(SCH_1):GND
 277    GND VSS121 @S9S_MB_2U_LIB.S9S_MB_2U(SCH_1):GND
 279    GND VSS122 @S9S_MB_2U_LIB.S9S_MB_2U(SCH_1):GND
 281    GND VSS123 @S9S_MB_2U_LIB.S9S_MB_2U(SCH_1):GND
 284    GND VSS124 @S9S_MB_2U_LIB.S9S_MB_2U(SCH_1):GND
 286    GND VSS125 @S9S_MB_2U_LIB.S9S_MB_2U(SCH_1):GND
 288    GND VSS126 @S9S_MB_2U_LIB.S9S_MB_2U(SCH_1):GND
   1 P12V_S3_AUX_CPU1_NVDIMM VIN_BULK0 @S9S_MB_2U_LIB.S9S_MB_2U(SCH_1):P12V_S3_AUX_CPU1_NVDIMM
 145 P12V_S3_AUX_CPU1_NVDIMM VIN_BULK1 @S9S_MB_2U_LIB.S9S_MB_2U(SCH_1):P12V_S3_AUX_CPU1_NVDIMM
 146 P12V_S3_AUX_CPU1_NVDIMM VIN_BULK2 @S9S_MB_2U_LIB.S9S_MB_2U(SCH_1):P12V_S3_AUX_CPU1_NVDIMM
 230    GND VSS100 @S9S_MB_2U_LIB.S9S_MB_2U(SCH_1):GND
 235    GND VSS102 @S9S_MB_2U_LIB.S9S_MB_2U(SCH_1):GND
 240    GND VSS104 @S9S_MB_2U_LIB.S9S_MB_2U(SCH_1):GND
 132    GND  VSS58 @S9S_MB_2U_LIB.S9S_MB_2U(SCH_1):GND
 136    GND  VSS60 @S9S_MB_2U_LIB.S9S_MB_2U(SCH_1):GND
 139    GND  VSS61 @S9S_MB_2U_LIB.S9S_MB_2U(SCH_1):GND
 141    GND  VSS62 @S9S_MB_2U_LIB.S9S_MB_2U(SCH_1):GND
  G1    GND     G1 @S9S_MB_2U_LIB.S9S_MB_2U(SCH_1):GND
  G2    GND     G2 @S9S_MB_2U_LIB.S9S_MB_2U(SCH_1):GND
  G3    GND     G3 @S9S_MB_2U_LIB.S9S_MB_2U(SCH_1):GND

SCONN288_ADR50017P087CC-SCONN2A  I178  J28
  93 M_F_CPU1_SB_DQS_DP<9> DQS9_B_T||TDQS9_B_T||DBI4_B_N @S9S_MB_2U_LIB.S9S_MB_2U(SCH_1):M_F_CPU1_SB_DQS_DP(9)
  94 M_F_CPU1_SB_DQS_DN<9> DQS9_B_C||TDQS9_B_C @S9S_MB_2U_LIB.S9S_MB_2U(SCH_1):M_F_CPU1_SB_DQS_DN(9)
 201 M_F_CPU1_SA_DQS_DP<9> DQS9_A_T||TDQS9_A_T @S9S_MB_2U_LIB.S9S_MB_2U(SCH_1):M_F_CPU1_SA_DQS_DP(9)
 200 M_F_CPU1_SA_DQS_DN<9> DQS9_A_C||TDQS9_A_C @S9S_MB_2U_LIB.S9S_MB_2U(SCH_1):M_F_CPU1_SA_DQS_DN(9)
 190 M_F_CPU1_SA_DQS_DP<8> DQS8_A_T||TDQS8_A_T @S9S_MB_2U_LIB.S9S_MB_2U(SCH_1):M_F_CPU1_SA_DQS_DP(8)
 189 M_F_CPU1_SA_DQS_DN<8> DQS8_A_C||TDQS8_A_C @S9S_MB_2U_LIB.S9S_MB_2U(SCH_1):M_F_CPU1_SA_DQS_DN(8)
 271 M_F_CPU1_SB_DQS_DN<7> DQS7_B_C||TDQS7_B_C @S9S_MB_2U_LIB.S9S_MB_2U(SCH_1):M_F_CPU1_SB_DQS_DN(7)
 179 M_F_CPU1_SA_DQS_DP<7> DQS7_A_T||TDQS7_A_T @S9S_MB_2U_LIB.S9S_MB_2U(SCH_1):M_F_CPU1_SA_DQS_DP(7)
 261 M_F_CPU1_SB_DQS_DP<6> DQS6_B_T||TDQS6_B_T @S9S_MB_2U_LIB.S9S_MB_2U(SCH_1):M_F_CPU1_SB_DQS_DP(6)
 260 M_F_CPU1_SB_DQS_DN<6> DQS6_B_C||TDQS6_B_C @S9S_MB_2U_LIB.S9S_MB_2U(SCH_1):M_F_CPU1_SB_DQS_DN(6)
 167 M_F_CPU1_SA_DQS_DN<6> DQS6_A_C||TDQS6_A_C||DQS6_A_T||TDQS6_A_T @S9S_MB_2U_LIB.S9S_MB_2U(SCH_1):M_F_CPU1_SA_DQS_DN(6)
 250 M_F_CPU1_SB_DQS_DP<5> DQS5_B_T||TDQS5_B_T @S9S_MB_2U_LIB.S9S_MB_2U(SCH_1):M_F_CPU1_SB_DQS_DP(5)
 249 M_F_CPU1_SB_DQS_DN<5> DQS5_B_C||TDQS5_B_C @S9S_MB_2U_LIB.S9S_MB_2U(SCH_1):M_F_CPU1_SB_DQS_DN(5)
 157 M_F_CPU1_SA_DQS_DP<5> DQS5_A_T||TDQS5_A_T @S9S_MB_2U_LIB.S9S_MB_2U(SCH_1):M_F_CPU1_SA_DQS_DP(5)
 156 M_F_CPU1_SA_DQS_DN<5> DQS5_A_C||TDQS5_A_C||DQS5_A_T||TDQS5_A_T @S9S_MB_2U_LIB.S9S_MB_2U(SCH_1):M_F_CPU1_SA_DQS_DN(5)
 239 M_F_CPU1_SB_DQS_DP<4> DQS4_B_T @S9S_MB_2U_LIB.S9S_MB_2U(SCH_1):M_F_CPU1_SB_DQS_DP(4)
 238 M_F_CPU1_SB_DQS_DN<4> DQS4_B_C @S9S_MB_2U_LIB.S9S_MB_2U(SCH_1):M_F_CPU1_SB_DQS_DN(4)
  55 M_F_CPU1_SA_DQS_DP<4> DQS4_A_T @S9S_MB_2U_LIB.S9S_MB_2U(SCH_1):M_F_CPU1_SA_DQS_DP(4)
  56 M_F_CPU1_SA_DQS_DN<4> DQS4_A_C @S9S_MB_2U_LIB.S9S_MB_2U(SCH_1):M_F_CPU1_SA_DQS_DN(4)
 137 M_F_CPU1_SB_DQS_DP<3> DQS3_B_T @S9S_MB_2U_LIB.S9S_MB_2U(SCH_1):M_F_CPU1_SB_DQS_DP(3)
 138 M_F_CPU1_SB_DQS_DN<3> DQS3_B_C @S9S_MB_2U_LIB.S9S_MB_2U(SCH_1):M_F_CPU1_SB_DQS_DN(3)
  44 M_F_CPU1_SA_DQS_DP<3> DQS3_A_T @S9S_MB_2U_LIB.S9S_MB_2U(SCH_1):M_F_CPU1_SA_DQS_DP(3)
  45 M_F_CPU1_SA_DQS_DN<3> DQS3_A_C @S9S_MB_2U_LIB.S9S_MB_2U(SCH_1):M_F_CPU1_SA_DQS_DN(3)
 126 M_F_CPU1_SB_DQS_DP<2> DQS2_B_T @S9S_MB_2U_LIB.S9S_MB_2U(SCH_1):M_F_CPU1_SB_DQS_DP(2)
 127 M_F_CPU1_SB_DQS_DN<2> DQS2_B_C @S9S_MB_2U_LIB.S9S_MB_2U(SCH_1):M_F_CPU1_SB_DQS_DN(2)
  33 M_F_CPU1_SA_DQS_DP<2> DQS2_A_T @S9S_MB_2U_LIB.S9S_MB_2U(SCH_1):M_F_CPU1_SA_DQS_DP(2)
  34 M_F_CPU1_SA_DQS_DN<2> DQS2_A_C @S9S_MB_2U_LIB.S9S_MB_2U(SCH_1):M_F_CPU1_SA_DQS_DN(2)
 115 M_F_CPU1_SB_DQS_DP<1> DQS1_B_T @S9S_MB_2U_LIB.S9S_MB_2U(SCH_1):M_F_CPU1_SB_DQS_DP(1)
 116 M_F_CPU1_SB_DQS_DN<1> DQS1_B_C @S9S_MB_2U_LIB.S9S_MB_2U(SCH_1):M_F_CPU1_SB_DQS_DN(1)
  22 M_F_CPU1_SA_DQS_DP<1> DQS1_A_T @S9S_MB_2U_LIB.S9S_MB_2U(SCH_1):M_F_CPU1_SA_DQS_DP(1)
  23 M_F_CPU1_SA_DQS_DN<1> DQS1_A_C @S9S_MB_2U_LIB.S9S_MB_2U(SCH_1):M_F_CPU1_SA_DQS_DN(1)
 104 M_F_CPU1_SB_DQS_DP<0> DQS0_B_T @S9S_MB_2U_LIB.S9S_MB_2U(SCH_1):M_F_CPU1_SB_DQS_DP(0)
 105 M_F_CPU1_SB_DQS_DN<0> DQS0_B_C @S9S_MB_2U_LIB.S9S_MB_2U(SCH_1):M_F_CPU1_SB_DQS_DN(0)
  11 M_F_CPU1_SA_DQS_DP<0> DQS0_A_T @S9S_MB_2U_LIB.S9S_MB_2U(SCH_1):M_F_CPU1_SA_DQS_DP(0)
  12 M_F_CPU1_SA_DQS_DN<0> DQS0_A_C @S9S_MB_2U_LIB.S9S_MB_2U(SCH_1):M_F_CPU1_SA_DQS_DN(0)
 272 M_F_CPU1_SB_DQS_DP<7> DQS7_B_T||TDQS7_B_T @S9S_MB_2U_LIB.S9S_MB_2U(SCH_1):M_F_CPU1_SB_DQS_DP(7)
 282 M_F_CPU1_SB_DQS_DN<8> DQS8_B_C||TDQS8_B_C @S9S_MB_2U_LIB.S9S_MB_2U(SCH_1):M_F_CPU1_SB_DQS_DN(8)
 283 M_F_CPU1_SB_DQS_DP<8> DQS8_B_T||TDQS8_B_T @S9S_MB_2U_LIB.S9S_MB_2U(SCH_1):M_F_CPU1_SB_DQS_DP(8)
 168 M_F_CPU1_SA_DQS_DP<6> DQS6_A_T||TDQS6_A_T @S9S_MB_2U_LIB.S9S_MB_2U(SCH_1):M_F_CPU1_SA_DQS_DP(6)
 178 M_F_CPU1_SA_DQS_DN<7> DQS7_A_C||TDQS7_A_C @S9S_MB_2U_LIB.S9S_MB_2U(SCH_1):M_F_CPU1_SA_DQS_DN(7)

Q_RES_0402LF-49.9,1%,1/16W,CHIA  I180  R3902
   1 I3C_SPD_DDREFGH_CPU1_LVC1_SCL_3      A @S9S_MB_2U_LIB.S9S_MB_2U(SCH_1):I3C_SPD_DDREFGH_CPU1_LVC1_SCL_R4
   2 I3C_SPD_DDREFGH_CPU1_LVC1_SCL      B @S9S_MB_2U_LIB.S9S_MB_2U(SCH_1):I3C_SPD_DDREFGH_CPU1_LVC1_SCL


DRAWING: @S9S_MB_2U_LIB.S9S_MB_2U(SCH_1):PAGE110 

Q_RES_0402LF-54.9K,1%,1/16W,CHA  I47  R75
   1 PD_CHG_CPU1_DIMM1_SAA      A @S9S_MB_2U_LIB.S9S_MB_2U(SCH_1):PD_CHG_CPU1_DIMM1_SAA
   2    GND      B @S9S_MB_2U_LIB.S9S_MB_2U(SCH_1):GND

Q_CAP_C0402-2.2UF,6.3V,20%,X6SA  I120  C81
   1 P3V3_AUX      A @S9S_MB_2U_LIB.S9S_MB_2U(SCH_1):P3V3_AUX
   2    GND      B @S9S_MB_2U_LIB.S9S_MB_2U(SCH_1):GND

Q_CAP_C0805-10UF,16V,10%,X6S,CA  I124  C82
   1 P12V_S3_AUX_CPU1_NVDIMM      A @S9S_MB_2U_LIB.S9S_MB_2U(SCH_1):P12V_S3_AUX_CPU1_NVDIMM
   2    GND      B @S9S_MB_2U_LIB.S9S_MB_2U(SCH_1):GND

Q_CAP_C0805-10UF,16V,10%,X6S,CA  I126  C83
   1 P12V_S3_AUX_CPU1_NVDIMM      A @S9S_MB_2U_LIB.S9S_MB_2U(SCH_1):P12V_S3_AUX_CPU1_NVDIMM
   2    GND      B @S9S_MB_2U_LIB.S9S_MB_2U(SCH_1):GND

SCONN288_ADR50017P130CC-SCONN2A  I178  J29
   6    GND   VSS0 @S9S_MB_2U_LIB.S9S_MB_2U(SCH_1):GND
   8    GND   VSS1 @S9S_MB_2U_LIB.S9S_MB_2U(SCH_1):GND
  10    GND   VSS2 @S9S_MB_2U_LIB.S9S_MB_2U(SCH_1):GND
  13    GND   VSS3 @S9S_MB_2U_LIB.S9S_MB_2U(SCH_1):GND
  15    GND   VSS4 @S9S_MB_2U_LIB.S9S_MB_2U(SCH_1):GND
  17    GND   VSS5 @S9S_MB_2U_LIB.S9S_MB_2U(SCH_1):GND
  19    GND   VSS6 @S9S_MB_2U_LIB.S9S_MB_2U(SCH_1):GND
  21    GND   VSS7 @S9S_MB_2U_LIB.S9S_MB_2U(SCH_1):GND
  24    GND   VSS8 @S9S_MB_2U_LIB.S9S_MB_2U(SCH_1):GND
  26    GND   VSS9 @S9S_MB_2U_LIB.S9S_MB_2U(SCH_1):GND
  28    GND  VSS10 @S9S_MB_2U_LIB.S9S_MB_2U(SCH_1):GND
  30    GND  VSS11 @S9S_MB_2U_LIB.S9S_MB_2U(SCH_1):GND
  32    GND  VSS12 @S9S_MB_2U_LIB.S9S_MB_2U(SCH_1):GND
  35    GND  VSS13 @S9S_MB_2U_LIB.S9S_MB_2U(SCH_1):GND
  37    GND  VSS14 @S9S_MB_2U_LIB.S9S_MB_2U(SCH_1):GND
  39    GND  VSS15 @S9S_MB_2U_LIB.S9S_MB_2U(SCH_1):GND
  41    GND  VSS16 @S9S_MB_2U_LIB.S9S_MB_2U(SCH_1):GND
  43    GND  VSS17 @S9S_MB_2U_LIB.S9S_MB_2U(SCH_1):GND
  46    GND  VSS18 @S9S_MB_2U_LIB.S9S_MB_2U(SCH_1):GND
  48    GND  VSS19 @S9S_MB_2U_LIB.S9S_MB_2U(SCH_1):GND
  50    GND  VSS20 @S9S_MB_2U_LIB.S9S_MB_2U(SCH_1):GND
  52    GND  VSS21 @S9S_MB_2U_LIB.S9S_MB_2U(SCH_1):GND
  54    GND  VSS22 @S9S_MB_2U_LIB.S9S_MB_2U(SCH_1):GND
  57    GND  VSS23 @S9S_MB_2U_LIB.S9S_MB_2U(SCH_1):GND
  59    GND  VSS24 @S9S_MB_2U_LIB.S9S_MB_2U(SCH_1):GND
  61    GND  VSS25 @S9S_MB_2U_LIB.S9S_MB_2U(SCH_1):GND
  63    GND  VSS26 @S9S_MB_2U_LIB.S9S_MB_2U(SCH_1):GND
  65    GND  VSS27 @S9S_MB_2U_LIB.S9S_MB_2U(SCH_1):GND
  67    GND  VSS28 @S9S_MB_2U_LIB.S9S_MB_2U(SCH_1):GND
  69    GND  VSS29 @S9S_MB_2U_LIB.S9S_MB_2U(SCH_1):GND
  71    GND  VSS30 @S9S_MB_2U_LIB.S9S_MB_2U(SCH_1):GND
  73    GND  VSS31 @S9S_MB_2U_LIB.S9S_MB_2U(SCH_1):GND
  75    GND  VSS32 @S9S_MB_2U_LIB.S9S_MB_2U(SCH_1):GND
  77    GND  VSS33 @S9S_MB_2U_LIB.S9S_MB_2U(SCH_1):GND
  79    GND  VSS34 @S9S_MB_2U_LIB.S9S_MB_2U(SCH_1):GND
  81    GND  VSS35 @S9S_MB_2U_LIB.S9S_MB_2U(SCH_1):GND
  83    GND  VSS36 @S9S_MB_2U_LIB.S9S_MB_2U(SCH_1):GND
  85    GND  VSS37 @S9S_MB_2U_LIB.S9S_MB_2U(SCH_1):GND
  88    GND  VSS38 @S9S_MB_2U_LIB.S9S_MB_2U(SCH_1):GND
  90    GND  VSS39 @S9S_MB_2U_LIB.S9S_MB_2U(SCH_1):GND
  92    GND  VSS40 @S9S_MB_2U_LIB.S9S_MB_2U(SCH_1):GND
  95    GND  VSS41 @S9S_MB_2U_LIB.S9S_MB_2U(SCH_1):GND
  97    GND  VSS42 @S9S_MB_2U_LIB.S9S_MB_2U(SCH_1):GND
  99    GND  VSS43 @S9S_MB_2U_LIB.S9S_MB_2U(SCH_1):GND
 101    GND  VSS44 @S9S_MB_2U_LIB.S9S_MB_2U(SCH_1):GND
 103    GND  VSS45 @S9S_MB_2U_LIB.S9S_MB_2U(SCH_1):GND
 106    GND  VSS46 @S9S_MB_2U_LIB.S9S_MB_2U(SCH_1):GND
 108    GND  VSS47 @S9S_MB_2U_LIB.S9S_MB_2U(SCH_1):GND
 110    GND  VSS48 @S9S_MB_2U_LIB.S9S_MB_2U(SCH_1):GND
 112    GND  VSS49 @S9S_MB_2U_LIB.S9S_MB_2U(SCH_1):GND
 114    GND  VSS50 @S9S_MB_2U_LIB.S9S_MB_2U(SCH_1):GND
 117    GND  VSS51 @S9S_MB_2U_LIB.S9S_MB_2U(SCH_1):GND
 119    GND  VSS52 @S9S_MB_2U_LIB.S9S_MB_2U(SCH_1):GND
 121    GND  VSS53 @S9S_MB_2U_LIB.S9S_MB_2U(SCH_1):GND
 123    GND  VSS54 @S9S_MB_2U_LIB.S9S_MB_2U(SCH_1):GND
 125    GND  VSS55 @S9S_MB_2U_LIB.S9S_MB_2U(SCH_1):GND
 128    GND  VSS56 @S9S_MB_2U_LIB.S9S_MB_2U(SCH_1):GND
 130    GND  VSS57 @S9S_MB_2U_LIB.S9S_MB_2U(SCH_1):GND
 134    GND  VSS59 @S9S_MB_2U_LIB.S9S_MB_2U(SCH_1):GND
 143    GND  VSS63 @S9S_MB_2U_LIB.S9S_MB_2U(SCH_1):GND
 151    GND  VSS64 @S9S_MB_2U_LIB.S9S_MB_2U(SCH_1):GND
 153    GND  VSS65 @S9S_MB_2U_LIB.S9S_MB_2U(SCH_1):GND
 155    GND  VSS66 @S9S_MB_2U_LIB.S9S_MB_2U(SCH_1):GND
 158    GND  VSS67 @S9S_MB_2U_LIB.S9S_MB_2U(SCH_1):GND
 160    GND  VSS68 @S9S_MB_2U_LIB.S9S_MB_2U(SCH_1):GND
 162    GND  VSS69 @S9S_MB_2U_LIB.S9S_MB_2U(SCH_1):GND
 164    GND  VSS70 @S9S_MB_2U_LIB.S9S_MB_2U(SCH_1):GND
 166    GND  VSS71 @S9S_MB_2U_LIB.S9S_MB_2U(SCH_1):GND
 169    GND  VSS72 @S9S_MB_2U_LIB.S9S_MB_2U(SCH_1):GND
 171    GND  VSS73 @S9S_MB_2U_LIB.S9S_MB_2U(SCH_1):GND
 173    GND  VSS74 @S9S_MB_2U_LIB.S9S_MB_2U(SCH_1):GND
 175    GND  VSS75 @S9S_MB_2U_LIB.S9S_MB_2U(SCH_1):GND
 177    GND  VSS76 @S9S_MB_2U_LIB.S9S_MB_2U(SCH_1):GND
 180    GND  VSS77 @S9S_MB_2U_LIB.S9S_MB_2U(SCH_1):GND
 182    GND  VSS78 @S9S_MB_2U_LIB.S9S_MB_2U(SCH_1):GND
 184    GND  VSS79 @S9S_MB_2U_LIB.S9S_MB_2U(SCH_1):GND
 186    GND  VSS80 @S9S_MB_2U_LIB.S9S_MB_2U(SCH_1):GND
 188    GND  VSS81 @S9S_MB_2U_LIB.S9S_MB_2U(SCH_1):GND
 191    GND  VSS82 @S9S_MB_2U_LIB.S9S_MB_2U(SCH_1):GND
 193    GND  VSS83 @S9S_MB_2U_LIB.S9S_MB_2U(SCH_1):GND
 195    GND  VSS84 @S9S_MB_2U_LIB.S9S_MB_2U(SCH_1):GND
 197    GND  VSS85 @S9S_MB_2U_LIB.S9S_MB_2U(SCH_1):GND
 199    GND  VSS86 @S9S_MB_2U_LIB.S9S_MB_2U(SCH_1):GND
 202    GND  VSS87 @S9S_MB_2U_LIB.S9S_MB_2U(SCH_1):GND
 204    GND  VSS88 @S9S_MB_2U_LIB.S9S_MB_2U(SCH_1):GND
 206    GND  VSS89 @S9S_MB_2U_LIB.S9S_MB_2U(SCH_1):GND
 208    GND  VSS90 @S9S_MB_2U_LIB.S9S_MB_2U(SCH_1):GND
 210    GND  VSS91 @S9S_MB_2U_LIB.S9S_MB_2U(SCH_1):GND
 212    GND  VSS92 @S9S_MB_2U_LIB.S9S_MB_2U(SCH_1):GND
 214    GND  VSS93 @S9S_MB_2U_LIB.S9S_MB_2U(SCH_1):GND
 216    GND  VSS94 @S9S_MB_2U_LIB.S9S_MB_2U(SCH_1):GND
 219    GND  VSS95 @S9S_MB_2U_LIB.S9S_MB_2U(SCH_1):GND
 222    GND  VSS96 @S9S_MB_2U_LIB.S9S_MB_2U(SCH_1):GND
 224    GND  VSS97 @S9S_MB_2U_LIB.S9S_MB_2U(SCH_1):GND
 226    GND  VSS98 @S9S_MB_2U_LIB.S9S_MB_2U(SCH_1):GND
 228    GND  VSS99 @S9S_MB_2U_LIB.S9S_MB_2U(SCH_1):GND
 233    GND VSS101 @S9S_MB_2U_LIB.S9S_MB_2U(SCH_1):GND
 237    GND VSS103 @S9S_MB_2U_LIB.S9S_MB_2U(SCH_1):GND
 242    GND VSS105 @S9S_MB_2U_LIB.S9S_MB_2U(SCH_1):GND
 244    GND VSS106 @S9S_MB_2U_LIB.S9S_MB_2U(SCH_1):GND
 246    GND VSS107 @S9S_MB_2U_LIB.S9S_MB_2U(SCH_1):GND
 248    GND VSS108 @S9S_MB_2U_LIB.S9S_MB_2U(SCH_1):GND
 251    GND VSS109 @S9S_MB_2U_LIB.S9S_MB_2U(SCH_1):GND
 253    GND VSS110 @S9S_MB_2U_LIB.S9S_MB_2U(SCH_1):GND
 255    GND VSS111 @S9S_MB_2U_LIB.S9S_MB_2U(SCH_1):GND
 257    GND VSS112 @S9S_MB_2U_LIB.S9S_MB_2U(SCH_1):GND
 259    GND VSS113 @S9S_MB_2U_LIB.S9S_MB_2U(SCH_1):GND
 262    GND VSS114 @S9S_MB_2U_LIB.S9S_MB_2U(SCH_1):GND
 264    GND VSS115 @S9S_MB_2U_LIB.S9S_MB_2U(SCH_1):GND
 266    GND VSS116 @S9S_MB_2U_LIB.S9S_MB_2U(SCH_1):GND
 268    GND VSS117 @S9S_MB_2U_LIB.S9S_MB_2U(SCH_1):GND
 270    GND VSS118 @S9S_MB_2U_LIB.S9S_MB_2U(SCH_1):GND
 273    GND VSS119 @S9S_MB_2U_LIB.S9S_MB_2U(SCH_1):GND
 275    GND VSS120 @S9S_MB_2U_LIB.S9S_MB_2U(SCH_1):GND
 277    GND VSS121 @S9S_MB_2U_LIB.S9S_MB_2U(SCH_1):GND
 279    GND VSS122 @S9S_MB_2U_LIB.S9S_MB_2U(SCH_1):GND
 281    GND VSS123 @S9S_MB_2U_LIB.S9S_MB_2U(SCH_1):GND
 284    GND VSS124 @S9S_MB_2U_LIB.S9S_MB_2U(SCH_1):GND
 286    GND VSS125 @S9S_MB_2U_LIB.S9S_MB_2U(SCH_1):GND
 288    GND VSS126 @S9S_MB_2U_LIB.S9S_MB_2U(SCH_1):GND
   1 P12V_S3_AUX_CPU1_NVDIMM VIN_BULK0 @S9S_MB_2U_LIB.S9S_MB_2U(SCH_1):P12V_S3_AUX_CPU1_NVDIMM
 145 P12V_S3_AUX_CPU1_NVDIMM VIN_BULK1 @S9S_MB_2U_LIB.S9S_MB_2U(SCH_1):P12V_S3_AUX_CPU1_NVDIMM
 146 P12V_S3_AUX_CPU1_NVDIMM VIN_BULK2 @S9S_MB_2U_LIB.S9S_MB_2U(SCH_1):P12V_S3_AUX_CPU1_NVDIMM
 230    GND VSS100 @S9S_MB_2U_LIB.S9S_MB_2U(SCH_1):GND
 235    GND VSS102 @S9S_MB_2U_LIB.S9S_MB_2U(SCH_1):GND
 240    GND VSS104 @S9S_MB_2U_LIB.S9S_MB_2U(SCH_1):GND
 132    GND  VSS58 @S9S_MB_2U_LIB.S9S_MB_2U(SCH_1):GND
 136    GND  VSS60 @S9S_MB_2U_LIB.S9S_MB_2U(SCH_1):GND
 139    GND  VSS61 @S9S_MB_2U_LIB.S9S_MB_2U(SCH_1):GND
 141    GND  VSS62 @S9S_MB_2U_LIB.S9S_MB_2U(SCH_1):GND
  G1    GND     G1 @S9S_MB_2U_LIB.S9S_MB_2U(SCH_1):GND
  G2    GND     G2 @S9S_MB_2U_LIB.S9S_MB_2U(SCH_1):GND
  G3    GND     G3 @S9S_MB_2U_LIB.S9S_MB_2U(SCH_1):GND

SCONN288_ADR50017P130CC-SCONN2A  I179  J29
   3 P3V3_AUX VIN_MGMT @S9S_MB_2U_LIB.S9S_MB_2U(SCH_1):P3V3_AUX
   2 TP_CHG_CPU1_DIMM1_FRU_0   RFU0 @S9S_MB_2U_LIB.S9S_MB_2U(SCH_1):TP_CHG_CPU1_DIMM1_FRU_0
 144 TP_CHG_CPU1_DIMM1_FRU_1   RFU1 @S9S_MB_2U_LIB.S9S_MB_2U(SCH_1):TP_CHG_CPU1_DIMM1_FRU_1
 149 TP_CHG_CPU1_DIMM1_FRU_2   RFU2 @S9S_MB_2U_LIB.S9S_MB_2U(SCH_1):TP_CHG_CPU1_DIMM1_FRU_2
 150 TP_CHG_CPU1_DIMM1_FRU_3   RFU3 @S9S_MB_2U_LIB.S9S_MB_2U(SCH_1):TP_CHG_CPU1_DIMM1_FRU_3
 220 TP_CHG_CPU1_DIMM1_FRU_4   RFU4 @S9S_MB_2U_LIB.S9S_MB_2U(SCH_1):TP_CHG_CPU1_DIMM1_FRU_4
 231 TP_CHG_CPU1_DIMM1_FRU_5   RFU5 @S9S_MB_2U_LIB.S9S_MB_2U(SCH_1):TP_CHG_CPU1_DIMM1_FRU_5
 232 TP_CHG_CPU1_DIMM1_FRU_6   RFU6 @S9S_MB_2U_LIB.S9S_MB_2U(SCH_1):TP_CHG_CPU1_DIMM1_FRU_6
 207 RST_M_GH_CPU1_FPGA_N RESET_N @S9S_MB_2U_LIB.S9S_MB_2U(SCH_1):RST_M_GH_CPU1_FPGA_N
 147 PWRGD_CHG_CPU1_DIMM1 PWR_GOOD||FAIL_N @S9S_MB_2U_LIB.S9S_MB_2U(SCH_1):PWRGD_CHG_CPU1_DIMM1
 227 M_G_CPU1_SB_PAR  PAR_B @S9S_MB_2U_LIB.S9S_MB_2U(SCH_1):M_G_CPU1_SB_PAR
  74 M_G_CPU1_SA_PAR  PAR_A @S9S_MB_2U_LIB.S9S_MB_2U(SCH_1):M_G_CPU1_SA_PAR
  87 M_G_CPU1_SB_RSP<0> LBS||RSP_B_N @S9S_MB_2U_LIB.S9S_MB_2U(SCH_1):M_G_CPU1_SB_RSP(0)
  86 M_G_CPU1_SA_RSP<0> LBD||RSP_A_N @S9S_MB_2U_LIB.S9S_MB_2U(SCH_1):M_G_CPU1_SA_RSP(0)
   5 I3C_SPD_DDREFGH_CPU1_LVC1_SDA   HSDA @S9S_MB_2U_LIB.S9S_MB_2U(SCH_1):I3C_SPD_DDREFGH_CPU1_LVC1_SDA
   4 I3C_SPD_DDREFGH_CPU1_LVC1_SCL_4   HSCL @S9S_MB_2U_LIB.S9S_MB_2U(SCH_1):I3C_SPD_DDREFGH_CPU1_LVC1_SCL_R5
 148 PD_CHG_CPU1_DIMM1_SAA    HSA @S9S_MB_2U_LIB.S9S_MB_2U(SCH_1):PD_CHG_CPU1_DIMM1_SAA
 100 M_G_CPU1_SB_DQ<0>  DQ0_B @S9S_MB_2U_LIB.S9S_MB_2U(SCH_1):M_G_CPU1_SB_DQ(0)
 102 M_G_CPU1_SB_DQ<1>  DQ1_B @S9S_MB_2U_LIB.S9S_MB_2U(SCH_1):M_G_CPU1_SB_DQ(1)
 245 M_G_CPU1_SB_DQ<2>  DQ2_B @S9S_MB_2U_LIB.S9S_MB_2U(SCH_1):M_G_CPU1_SB_DQ(2)
 247 M_G_CPU1_SB_DQ<3>  DQ3_B @S9S_MB_2U_LIB.S9S_MB_2U(SCH_1):M_G_CPU1_SB_DQ(3)
 107 M_G_CPU1_SB_DQ<4>  DQ4_B @S9S_MB_2U_LIB.S9S_MB_2U(SCH_1):M_G_CPU1_SB_DQ(4)
 109 M_G_CPU1_SB_DQ<5>  DQ5_B @S9S_MB_2U_LIB.S9S_MB_2U(SCH_1):M_G_CPU1_SB_DQ(5)
 252 M_G_CPU1_SB_DQ<6>  DQ6_B @S9S_MB_2U_LIB.S9S_MB_2U(SCH_1):M_G_CPU1_SB_DQ(6)
 254 M_G_CPU1_SB_DQ<7>  DQ7_B @S9S_MB_2U_LIB.S9S_MB_2U(SCH_1):M_G_CPU1_SB_DQ(7)
 111 M_G_CPU1_SB_DQ<8>  DQ8_B @S9S_MB_2U_LIB.S9S_MB_2U(SCH_1):M_G_CPU1_SB_DQ(8)
 113 M_G_CPU1_SB_DQ<9>  DQ9_B @S9S_MB_2U_LIB.S9S_MB_2U(SCH_1):M_G_CPU1_SB_DQ(9)
 256 M_G_CPU1_SB_DQ<10> DQ10_B @S9S_MB_2U_LIB.S9S_MB_2U(SCH_1):M_G_CPU1_SB_DQ(10)
 258 M_G_CPU1_SB_DQ<11> DQ11_B @S9S_MB_2U_LIB.S9S_MB_2U(SCH_1):M_G_CPU1_SB_DQ(11)
 118 M_G_CPU1_SB_DQ<12> DQ12_B @S9S_MB_2U_LIB.S9S_MB_2U(SCH_1):M_G_CPU1_SB_DQ(12)
 120 M_G_CPU1_SB_DQ<13> DQ13_B @S9S_MB_2U_LIB.S9S_MB_2U(SCH_1):M_G_CPU1_SB_DQ(13)
 263 M_G_CPU1_SB_DQ<14> DQ14_B @S9S_MB_2U_LIB.S9S_MB_2U(SCH_1):M_G_CPU1_SB_DQ(14)
 265 M_G_CPU1_SB_DQ<15> DQ15_B @S9S_MB_2U_LIB.S9S_MB_2U(SCH_1):M_G_CPU1_SB_DQ(15)
 122 M_G_CPU1_SB_DQ<16> DQ16_B @S9S_MB_2U_LIB.S9S_MB_2U(SCH_1):M_G_CPU1_SB_DQ(16)
 124 M_G_CPU1_SB_DQ<17> DQ17_B @S9S_MB_2U_LIB.S9S_MB_2U(SCH_1):M_G_CPU1_SB_DQ(17)
 267 M_G_CPU1_SB_DQ<18> DQ18_B @S9S_MB_2U_LIB.S9S_MB_2U(SCH_1):M_G_CPU1_SB_DQ(18)
 269 M_G_CPU1_SB_DQ<19> DQ19_B @S9S_MB_2U_LIB.S9S_MB_2U(SCH_1):M_G_CPU1_SB_DQ(19)
 129 M_G_CPU1_SB_DQ<20> DQ20_B @S9S_MB_2U_LIB.S9S_MB_2U(SCH_1):M_G_CPU1_SB_DQ(20)
 131 M_G_CPU1_SB_DQ<21> DQ21_B @S9S_MB_2U_LIB.S9S_MB_2U(SCH_1):M_G_CPU1_SB_DQ(21)
 274 M_G_CPU1_SB_DQ<22> DQ22_B @S9S_MB_2U_LIB.S9S_MB_2U(SCH_1):M_G_CPU1_SB_DQ(22)
 276 M_G_CPU1_SB_DQ<23> DQ23_B @S9S_MB_2U_LIB.S9S_MB_2U(SCH_1):M_G_CPU1_SB_DQ(23)
 133 M_G_CPU1_SB_DQ<24> DQ24_B @S9S_MB_2U_LIB.S9S_MB_2U(SCH_1):M_G_CPU1_SB_DQ(24)
 135 M_G_CPU1_SB_DQ<25> DQ25_B @S9S_MB_2U_LIB.S9S_MB_2U(SCH_1):M_G_CPU1_SB_DQ(25)
 278 M_G_CPU1_SB_DQ<26> DQ26_B @S9S_MB_2U_LIB.S9S_MB_2U(SCH_1):M_G_CPU1_SB_DQ(26)
 280 M_G_CPU1_SB_DQ<27> DQ27_B @S9S_MB_2U_LIB.S9S_MB_2U(SCH_1):M_G_CPU1_SB_DQ(27)
 140 M_G_CPU1_SB_DQ<28> DQ28_B @S9S_MB_2U_LIB.S9S_MB_2U(SCH_1):M_G_CPU1_SB_DQ(28)
 142 M_G_CPU1_SB_DQ<29> DQ29_B @S9S_MB_2U_LIB.S9S_MB_2U(SCH_1):M_G_CPU1_SB_DQ(29)
 285 M_G_CPU1_SB_DQ<30> DQ30_B @S9S_MB_2U_LIB.S9S_MB_2U(SCH_1):M_G_CPU1_SB_DQ(30)
 287 M_G_CPU1_SB_DQ<31> DQ31_B @S9S_MB_2U_LIB.S9S_MB_2U(SCH_1):M_G_CPU1_SB_DQ(31)
   7 M_G_CPU1_SA_DQ<0>  DQ0_A @S9S_MB_2U_LIB.S9S_MB_2U(SCH_1):M_G_CPU1_SA_DQ(0)
   9 M_G_CPU1_SA_DQ<1>  DQ1_A @S9S_MB_2U_LIB.S9S_MB_2U(SCH_1):M_G_CPU1_SA_DQ(1)
 152 M_G_CPU1_SA_DQ<2>  DQ2_A @S9S_MB_2U_LIB.S9S_MB_2U(SCH_1):M_G_CPU1_SA_DQ(2)
 154 M_G_CPU1_SA_DQ<3>  DQ3_A @S9S_MB_2U_LIB.S9S_MB_2U(SCH_1):M_G_CPU1_SA_DQ(3)
  14 M_G_CPU1_SA_DQ<4>  DQ4_A @S9S_MB_2U_LIB.S9S_MB_2U(SCH_1):M_G_CPU1_SA_DQ(4)
  16 M_G_CPU1_SA_DQ<5>  DQ5_A @S9S_MB_2U_LIB.S9S_MB_2U(SCH_1):M_G_CPU1_SA_DQ(5)
 159 M_G_CPU1_SA_DQ<6>  DQ6_A @S9S_MB_2U_LIB.S9S_MB_2U(SCH_1):M_G_CPU1_SA_DQ(6)
 161 M_G_CPU1_SA_DQ<7>  DQ7_A @S9S_MB_2U_LIB.S9S_MB_2U(SCH_1):M_G_CPU1_SA_DQ(7)
  18 M_G_CPU1_SA_DQ<8>  DQ8_A @S9S_MB_2U_LIB.S9S_MB_2U(SCH_1):M_G_CPU1_SA_DQ(8)
  20 M_G_CPU1_SA_DQ<9>  DQ9_A @S9S_MB_2U_LIB.S9S_MB_2U(SCH_1):M_G_CPU1_SA_DQ(9)
 163 M_G_CPU1_SA_DQ<10> DQ10_A @S9S_MB_2U_LIB.S9S_MB_2U(SCH_1):M_G_CPU1_SA_DQ(10)
 165 M_G_CPU1_SA_DQ<11> DQ11_A @S9S_MB_2U_LIB.S9S_MB_2U(SCH_1):M_G_CPU1_SA_DQ(11)
  25 M_G_CPU1_SA_DQ<12> DQ12_A @S9S_MB_2U_LIB.S9S_MB_2U(SCH_1):M_G_CPU1_SA_DQ(12)
  27 M_G_CPU1_SA_DQ<13> DQ13_A @S9S_MB_2U_LIB.S9S_MB_2U(SCH_1):M_G_CPU1_SA_DQ(13)
 170 M_G_CPU1_SA_DQ<14> DQ14_A @S9S_MB_2U_LIB.S9S_MB_2U(SCH_1):M_G_CPU1_SA_DQ(14)
 172 M_G_CPU1_SA_DQ<15> DQ15_A @S9S_MB_2U_LIB.S9S_MB_2U(SCH_1):M_G_CPU1_SA_DQ(15)
  29 M_G_CPU1_SA_DQ<16> DQ16_A @S9S_MB_2U_LIB.S9S_MB_2U(SCH_1):M_G_CPU1_SA_DQ(16)
  31 M_G_CPU1_SA_DQ<17> DQ17_A @S9S_MB_2U_LIB.S9S_MB_2U(SCH_1):M_G_CPU1_SA_DQ(17)
 174 M_G_CPU1_SA_DQ<18> DQ18_A @S9S_MB_2U_LIB.S9S_MB_2U(SCH_1):M_G_CPU1_SA_DQ(18)
 176 M_G_CPU1_SA_DQ<19> DQ19_A @S9S_MB_2U_LIB.S9S_MB_2U(SCH_1):M_G_CPU1_SA_DQ(19)
  36 M_G_CPU1_SA_DQ<20> DQ20_A @S9S_MB_2U_LIB.S9S_MB_2U(SCH_1):M_G_CPU1_SA_DQ(20)
  38 M_G_CPU1_SA_DQ<21> DQ21_A @S9S_MB_2U_LIB.S9S_MB_2U(SCH_1):M_G_CPU1_SA_DQ(21)
 181 M_G_CPU1_SA_DQ<22> DQ22_A @S9S_MB_2U_LIB.S9S_MB_2U(SCH_1):M_G_CPU1_SA_DQ(22)
 183 M_G_CPU1_SA_DQ<23> DQ23_A @S9S_MB_2U_LIB.S9S_MB_2U(SCH_1):M_G_CPU1_SA_DQ(23)
  40 M_G_CPU1_SA_DQ<24> DQ24_A @S9S_MB_2U_LIB.S9S_MB_2U(SCH_1):M_G_CPU1_SA_DQ(24)
  42 M_G_CPU1_SA_DQ<25> DQ25_A @S9S_MB_2U_LIB.S9S_MB_2U(SCH_1):M_G_CPU1_SA_DQ(25)
 185 M_G_CPU1_SA_DQ<26> DQ26_A @S9S_MB_2U_LIB.S9S_MB_2U(SCH_1):M_G_CPU1_SA_DQ(26)
 187 M_G_CPU1_SA_DQ<27> DQ27_A @S9S_MB_2U_LIB.S9S_MB_2U(SCH_1):M_G_CPU1_SA_DQ(27)
  47 M_G_CPU1_SA_DQ<28> DQ28_A @S9S_MB_2U_LIB.S9S_MB_2U(SCH_1):M_G_CPU1_SA_DQ(28)
  49 M_G_CPU1_SA_DQ<29> DQ29_A @S9S_MB_2U_LIB.S9S_MB_2U(SCH_1):M_G_CPU1_SA_DQ(29)
 192 M_G_CPU1_SA_DQ<30> DQ30_A @S9S_MB_2U_LIB.S9S_MB_2U(SCH_1):M_G_CPU1_SA_DQ(30)
 229 M_G_CPU1_SB_CS_N<1> CS1_B_N @S9S_MB_2U_LIB.S9S_MB_2U(SCH_1):M_G_CPU1_SB_CS_N(1)
 209 M_G_CPU1_SA_CS_N<1> CS1_A_N @S9S_MB_2U_LIB.S9S_MB_2U(SCH_1):M_G_CPU1_SA_CS_N(1)
  84 M_G_CPU1_SB_CS_N<0> CS0_B_N @S9S_MB_2U_LIB.S9S_MB_2U(SCH_1):M_G_CPU1_SB_CS_N(0)
  64 M_G_CPU1_SA_CS_N<0> CS0_A_N @S9S_MB_2U_LIB.S9S_MB_2U(SCH_1):M_G_CPU1_SA_CS_N(0)
 217 M_G_CPU1_CLK_DP<0>   CK_T @S9S_MB_2U_LIB.S9S_MB_2U(SCH_1):M_G_CPU1_CLK_DP(0)
 218 M_G_CPU1_CLK_DN<0>   CK_C @S9S_MB_2U_LIB.S9S_MB_2U(SCH_1):M_G_CPU1_CLK_DN(0)
  96 M_G_CPU1_SB_CB<0>  CB0_B @S9S_MB_2U_LIB.S9S_MB_2U(SCH_1):M_G_CPU1_SB_CB(0)
  98 M_G_CPU1_SB_CB<1>  CB1_B @S9S_MB_2U_LIB.S9S_MB_2U(SCH_1):M_G_CPU1_SB_CB(1)
 241 M_G_CPU1_SB_CB<2>  CB2_B @S9S_MB_2U_LIB.S9S_MB_2U(SCH_1):M_G_CPU1_SB_CB(2)
 243 M_G_CPU1_SB_CB<3>  CB3_B @S9S_MB_2U_LIB.S9S_MB_2U(SCH_1):M_G_CPU1_SB_CB(3)
  89 M_G_CPU1_SB_CB<4>  CB4_B @S9S_MB_2U_LIB.S9S_MB_2U(SCH_1):M_G_CPU1_SB_CB(4)
  91 M_G_CPU1_SB_CB<5>  CB5_B @S9S_MB_2U_LIB.S9S_MB_2U(SCH_1):M_G_CPU1_SB_CB(5)
 234 M_G_CPU1_SB_CB<6>  CB6_B @S9S_MB_2U_LIB.S9S_MB_2U(SCH_1):M_G_CPU1_SB_CB(6)
  51 M_G_CPU1_SA_CB<0>  CB0_A @S9S_MB_2U_LIB.S9S_MB_2U(SCH_1):M_G_CPU1_SA_CB(0)
 196 M_G_CPU1_SA_CB<2>  CB2_A @S9S_MB_2U_LIB.S9S_MB_2U(SCH_1):M_G_CPU1_SA_CB(2)
 198 M_G_CPU1_SA_CB<3>  CB3_A @S9S_MB_2U_LIB.S9S_MB_2U(SCH_1):M_G_CPU1_SA_CB(3)
  60 M_G_CPU1_SA_CB<5>  CB5_A @S9S_MB_2U_LIB.S9S_MB_2U(SCH_1):M_G_CPU1_SA_CB(5)
 203 M_G_CPU1_SA_CB<6>  CB6_A @S9S_MB_2U_LIB.S9S_MB_2U(SCH_1):M_G_CPU1_SA_CB(6)
  82 M_G_CPU1_SB_CA<6>  CA6_B @S9S_MB_2U_LIB.S9S_MB_2U(SCH_1):M_G_CPU1_SB_CA(6)
  72 M_G_CPU1_SA_CA<6>  CA6_A @S9S_MB_2U_LIB.S9S_MB_2U(SCH_1):M_G_CPU1_SA_CA(6)
 225 M_G_CPU1_SB_CA<5>  CA5_B @S9S_MB_2U_LIB.S9S_MB_2U(SCH_1):M_G_CPU1_SB_CA(5)
 215 M_G_CPU1_SA_CA<5>  CA5_A @S9S_MB_2U_LIB.S9S_MB_2U(SCH_1):M_G_CPU1_SA_CA(5)
  80 M_G_CPU1_SB_CA<4>  CA4_B @S9S_MB_2U_LIB.S9S_MB_2U(SCH_1):M_G_CPU1_SB_CA(4)
  70 M_G_CPU1_SA_CA<4>  CA4_A @S9S_MB_2U_LIB.S9S_MB_2U(SCH_1):M_G_CPU1_SA_CA(4)
 223 M_G_CPU1_SB_CA<3>  CA3_B @S9S_MB_2U_LIB.S9S_MB_2U(SCH_1):M_G_CPU1_SB_CA(3)
 213 M_G_CPU1_SA_CA<3>  CA3_A @S9S_MB_2U_LIB.S9S_MB_2U(SCH_1):M_G_CPU1_SA_CA(3)
  78 M_G_CPU1_SB_CA<2>  CA2_B @S9S_MB_2U_LIB.S9S_MB_2U(SCH_1):M_G_CPU1_SB_CA(2)
  68 M_G_CPU1_SA_CA<2>  CA2_A @S9S_MB_2U_LIB.S9S_MB_2U(SCH_1):M_G_CPU1_SA_CA(2)
 221 M_G_CPU1_SB_CA<1>  CA1_B @S9S_MB_2U_LIB.S9S_MB_2U(SCH_1):M_G_CPU1_SB_CA(1)
 211 M_G_CPU1_SA_CA<1>  CA1_A @S9S_MB_2U_LIB.S9S_MB_2U(SCH_1):M_G_CPU1_SA_CA(1)
  76 M_G_CPU1_SB_CA<0>  CA0_B @S9S_MB_2U_LIB.S9S_MB_2U(SCH_1):M_G_CPU1_SB_CA(0)
  66 M_G_CPU1_SA_CA<0>  CA0_A @S9S_MB_2U_LIB.S9S_MB_2U(SCH_1):M_G_CPU1_SA_CA(0)
  62 M_G_CPU1_ALERT_N ALERT_N @S9S_MB_2U_LIB.S9S_MB_2U(SCH_1):M_G_CPU1_ALERT_N
 236 M_G_CPU1_SB_CB<7>  CB7_B @S9S_MB_2U_LIB.S9S_MB_2U(SCH_1):M_G_CPU1_SB_CB(7)
  53 M_G_CPU1_SA_CB<1>  CB1_A @S9S_MB_2U_LIB.S9S_MB_2U(SCH_1):M_G_CPU1_SA_CB(1)
  58 M_G_CPU1_SA_CB<4>  CB4_A @S9S_MB_2U_LIB.S9S_MB_2U(SCH_1):M_G_CPU1_SA_CB(4)
 205 M_G_CPU1_SA_CB<7>  CB7_A @S9S_MB_2U_LIB.S9S_MB_2U(SCH_1):M_G_CPU1_SA_CB(7)
 194 M_G_CPU1_SA_DQ<31> DQ31_A @S9S_MB_2U_LIB.S9S_MB_2U(SCH_1):M_G_CPU1_SA_DQ(31)

SCONN288_ADR50017P130CC-SCONN2A  I180  J29
  93 M_G_CPU1_SB_DQS_DP<9> DQS9_B_T||TDQS9_B_T||DBI4_B_N @S9S_MB_2U_LIB.S9S_MB_2U(SCH_1):M_G_CPU1_SB_DQS_DP(9)
  94 M_G_CPU1_SB_DQS_DN<9> DQS9_B_C||TDQS9_B_C @S9S_MB_2U_LIB.S9S_MB_2U(SCH_1):M_G_CPU1_SB_DQS_DN(9)
 201 M_G_CPU1_SA_DQS_DP<9> DQS9_A_T||TDQS9_A_T @S9S_MB_2U_LIB.S9S_MB_2U(SCH_1):M_G_CPU1_SA_DQS_DP(9)
 200 M_G_CPU1_SA_DQS_DN<9> DQS9_A_C||TDQS9_A_C @S9S_MB_2U_LIB.S9S_MB_2U(SCH_1):M_G_CPU1_SA_DQS_DN(9)
 190 M_G_CPU1_SA_DQS_DP<8> DQS8_A_T||TDQS8_A_T @S9S_MB_2U_LIB.S9S_MB_2U(SCH_1):M_G_CPU1_SA_DQS_DP(8)
 189 M_G_CPU1_SA_DQS_DN<8> DQS8_A_C||TDQS8_A_C @S9S_MB_2U_LIB.S9S_MB_2U(SCH_1):M_G_CPU1_SA_DQS_DN(8)
 271 M_G_CPU1_SB_DQS_DN<7> DQS7_B_C||TDQS7_B_C @S9S_MB_2U_LIB.S9S_MB_2U(SCH_1):M_G_CPU1_SB_DQS_DN(7)
 179 M_G_CPU1_SA_DQS_DP<7> DQS7_A_T||TDQS7_A_T @S9S_MB_2U_LIB.S9S_MB_2U(SCH_1):M_G_CPU1_SA_DQS_DP(7)
 261 M_G_CPU1_SB_DQS_DP<6> DQS6_B_T||TDQS6_B_T @S9S_MB_2U_LIB.S9S_MB_2U(SCH_1):M_G_CPU1_SB_DQS_DP(6)
 260 M_G_CPU1_SB_DQS_DN<6> DQS6_B_C||TDQS6_B_C @S9S_MB_2U_LIB.S9S_MB_2U(SCH_1):M_G_CPU1_SB_DQS_DN(6)
 167 M_G_CPU1_SA_DQS_DN<6> DQS6_A_C||TDQS6_A_C||DQS6_A_T||TDQS6_A_T @S9S_MB_2U_LIB.S9S_MB_2U(SCH_1):M_G_CPU1_SA_DQS_DN(6)
 250 M_G_CPU1_SB_DQS_DP<5> DQS5_B_T||TDQS5_B_T @S9S_MB_2U_LIB.S9S_MB_2U(SCH_1):M_G_CPU1_SB_DQS_DP(5)
 249 M_G_CPU1_SB_DQS_DN<5> DQS5_B_C||TDQS5_B_C @S9S_MB_2U_LIB.S9S_MB_2U(SCH_1):M_G_CPU1_SB_DQS_DN(5)
 157 M_G_CPU1_SA_DQS_DP<5> DQS5_A_T||TDQS5_A_T @S9S_MB_2U_LIB.S9S_MB_2U(SCH_1):M_G_CPU1_SA_DQS_DP(5)
 156 M_G_CPU1_SA_DQS_DN<5> DQS5_A_C||TDQS5_A_C||DQS5_A_T||TDQS5_A_T @S9S_MB_2U_LIB.S9S_MB_2U(SCH_1):M_G_CPU1_SA_DQS_DN(5)
 239 M_G_CPU1_SB_DQS_DP<4> DQS4_B_T @S9S_MB_2U_LIB.S9S_MB_2U(SCH_1):M_G_CPU1_SB_DQS_DP(4)
 238 M_G_CPU1_SB_DQS_DN<4> DQS4_B_C @S9S_MB_2U_LIB.S9S_MB_2U(SCH_1):M_G_CPU1_SB_DQS_DN(4)
  55 M_G_CPU1_SA_DQS_DP<4> DQS4_A_T @S9S_MB_2U_LIB.S9S_MB_2U(SCH_1):M_G_CPU1_SA_DQS_DP(4)
  56 M_G_CPU1_SA_DQS_DN<4> DQS4_A_C @S9S_MB_2U_LIB.S9S_MB_2U(SCH_1):M_G_CPU1_SA_DQS_DN(4)
 137 M_G_CPU1_SB_DQS_DP<3> DQS3_B_T @S9S_MB_2U_LIB.S9S_MB_2U(SCH_1):M_G_CPU1_SB_DQS_DP(3)
 138 M_G_CPU1_SB_DQS_DN<3> DQS3_B_C @S9S_MB_2U_LIB.S9S_MB_2U(SCH_1):M_G_CPU1_SB_DQS_DN(3)
  44 M_G_CPU1_SA_DQS_DP<3> DQS3_A_T @S9S_MB_2U_LIB.S9S_MB_2U(SCH_1):M_G_CPU1_SA_DQS_DP(3)
  45 M_G_CPU1_SA_DQS_DN<3> DQS3_A_C @S9S_MB_2U_LIB.S9S_MB_2U(SCH_1):M_G_CPU1_SA_DQS_DN(3)
 126 M_G_CPU1_SB_DQS_DP<2> DQS2_B_T @S9S_MB_2U_LIB.S9S_MB_2U(SCH_1):M_G_CPU1_SB_DQS_DP(2)
 127 M_G_CPU1_SB_DQS_DN<2> DQS2_B_C @S9S_MB_2U_LIB.S9S_MB_2U(SCH_1):M_G_CPU1_SB_DQS_DN(2)
  33 M_G_CPU1_SA_DQS_DP<2> DQS2_A_T @S9S_MB_2U_LIB.S9S_MB_2U(SCH_1):M_G_CPU1_SA_DQS_DP(2)
  34 M_G_CPU1_SA_DQS_DN<2> DQS2_A_C @S9S_MB_2U_LIB.S9S_MB_2U(SCH_1):M_G_CPU1_SA_DQS_DN(2)
 115 M_G_CPU1_SB_DQS_DP<1> DQS1_B_T @S9S_MB_2U_LIB.S9S_MB_2U(SCH_1):M_G_CPU1_SB_DQS_DP(1)
 116 M_G_CPU1_SB_DQS_DN<1> DQS1_B_C @S9S_MB_2U_LIB.S9S_MB_2U(SCH_1):M_G_CPU1_SB_DQS_DN(1)
  22 M_G_CPU1_SA_DQS_DP<1> DQS1_A_T @S9S_MB_2U_LIB.S9S_MB_2U(SCH_1):M_G_CPU1_SA_DQS_DP(1)
  23 M_G_CPU1_SA_DQS_DN<1> DQS1_A_C @S9S_MB_2U_LIB.S9S_MB_2U(SCH_1):M_G_CPU1_SA_DQS_DN(1)
 104 M_G_CPU1_SB_DQS_DP<0> DQS0_B_T @S9S_MB_2U_LIB.S9S_MB_2U(SCH_1):M_G_CPU1_SB_DQS_DP(0)
 105 M_G_CPU1_SB_DQS_DN<0> DQS0_B_C @S9S_MB_2U_LIB.S9S_MB_2U(SCH_1):M_G_CPU1_SB_DQS_DN(0)
  11 M_G_CPU1_SA_DQS_DP<0> DQS0_A_T @S9S_MB_2U_LIB.S9S_MB_2U(SCH_1):M_G_CPU1_SA_DQS_DP(0)
  12 M_G_CPU1_SA_DQS_DN<0> DQS0_A_C @S9S_MB_2U_LIB.S9S_MB_2U(SCH_1):M_G_CPU1_SA_DQS_DN(0)
 272 M_G_CPU1_SB_DQS_DP<7> DQS7_B_T||TDQS7_B_T @S9S_MB_2U_LIB.S9S_MB_2U(SCH_1):M_G_CPU1_SB_DQS_DP(7)
 282 M_G_CPU1_SB_DQS_DN<8> DQS8_B_C||TDQS8_B_C @S9S_MB_2U_LIB.S9S_MB_2U(SCH_1):M_G_CPU1_SB_DQS_DN(8)
 283 M_G_CPU1_SB_DQS_DP<8> DQS8_B_T||TDQS8_B_T @S9S_MB_2U_LIB.S9S_MB_2U(SCH_1):M_G_CPU1_SB_DQS_DP(8)
 168 M_G_CPU1_SA_DQS_DP<6> DQS6_A_T||TDQS6_A_T @S9S_MB_2U_LIB.S9S_MB_2U(SCH_1):M_G_CPU1_SA_DQS_DP(6)
 178 M_G_CPU1_SA_DQS_DN<7> DQS7_A_C||TDQS7_A_C @S9S_MB_2U_LIB.S9S_MB_2U(SCH_1):M_G_CPU1_SA_DQS_DN(7)

Q_RES_0402LF-49.9,1%,1/16W,CHIA  I182  R3903
   1 I3C_SPD_DDREFGH_CPU1_LVC1_SCL_4      A @S9S_MB_2U_LIB.S9S_MB_2U(SCH_1):I3C_SPD_DDREFGH_CPU1_LVC1_SCL_R5
   2 I3C_SPD_DDREFGH_CPU1_LVC1_SCL      B @S9S_MB_2U_LIB.S9S_MB_2U(SCH_1):I3C_SPD_DDREFGH_CPU1_LVC1_SCL


DRAWING: @S9S_MB_2U_LIB.S9S_MB_2U(SCH_1):PAGE111 

Q_RES_0402LF-84.5K,1%,1/16W,CHA  I5  R74
   1 PD_CHG_CPU1_DIMM2_SAA      A @S9S_MB_2U_LIB.S9S_MB_2U(SCH_1):PD_CHG_CPU1_DIMM2_SAA
   2    GND      B @S9S_MB_2U_LIB.S9S_MB_2U(SCH_1):GND

Q_CAP_C0402-2.2UF,6.3V,20%,X6SA  I54  C78
   1 P3V3_AUX      A @S9S_MB_2U_LIB.S9S_MB_2U(SCH_1):P3V3_AUX
   2    GND      B @S9S_MB_2U_LIB.S9S_MB_2U(SCH_1):GND

Q_CAP_C0805-10UF,16V,10%,X6S,CA  I56  C79
   1 P12V_S3_AUX_CPU1_NVDIMM      A @S9S_MB_2U_LIB.S9S_MB_2U(SCH_1):P12V_S3_AUX_CPU1_NVDIMM
   2    GND      B @S9S_MB_2U_LIB.S9S_MB_2U(SCH_1):GND

Q_CAP_C0805-10UF,16V,10%,X6S,CA  I59  C80
   1 P12V_S3_AUX_CPU1_NVDIMM      A @S9S_MB_2U_LIB.S9S_MB_2U(SCH_1):P12V_S3_AUX_CPU1_NVDIMM
   2    GND      B @S9S_MB_2U_LIB.S9S_MB_2U(SCH_1):GND

SCONN288_ADR50017P087CC-SCONN2A  I178  J30
   6    GND   VSS0 @S9S_MB_2U_LIB.S9S_MB_2U(SCH_1):GND
   8    GND   VSS1 @S9S_MB_2U_LIB.S9S_MB_2U(SCH_1):GND
  10    GND   VSS2 @S9S_MB_2U_LIB.S9S_MB_2U(SCH_1):GND
  13    GND   VSS3 @S9S_MB_2U_LIB.S9S_MB_2U(SCH_1):GND
  15    GND   VSS4 @S9S_MB_2U_LIB.S9S_MB_2U(SCH_1):GND
  17    GND   VSS5 @S9S_MB_2U_LIB.S9S_MB_2U(SCH_1):GND
  19    GND   VSS6 @S9S_MB_2U_LIB.S9S_MB_2U(SCH_1):GND
  21    GND   VSS7 @S9S_MB_2U_LIB.S9S_MB_2U(SCH_1):GND
  24    GND   VSS8 @S9S_MB_2U_LIB.S9S_MB_2U(SCH_1):GND
  26    GND   VSS9 @S9S_MB_2U_LIB.S9S_MB_2U(SCH_1):GND
  28    GND  VSS10 @S9S_MB_2U_LIB.S9S_MB_2U(SCH_1):GND
  30    GND  VSS11 @S9S_MB_2U_LIB.S9S_MB_2U(SCH_1):GND
  32    GND  VSS12 @S9S_MB_2U_LIB.S9S_MB_2U(SCH_1):GND
  35    GND  VSS13 @S9S_MB_2U_LIB.S9S_MB_2U(SCH_1):GND
  37    GND  VSS14 @S9S_MB_2U_LIB.S9S_MB_2U(SCH_1):GND
  39    GND  VSS15 @S9S_MB_2U_LIB.S9S_MB_2U(SCH_1):GND
  41    GND  VSS16 @S9S_MB_2U_LIB.S9S_MB_2U(SCH_1):GND
  43    GND  VSS17 @S9S_MB_2U_LIB.S9S_MB_2U(SCH_1):GND
  46    GND  VSS18 @S9S_MB_2U_LIB.S9S_MB_2U(SCH_1):GND
  48    GND  VSS19 @S9S_MB_2U_LIB.S9S_MB_2U(SCH_1):GND
  50    GND  VSS20 @S9S_MB_2U_LIB.S9S_MB_2U(SCH_1):GND
  52    GND  VSS21 @S9S_MB_2U_LIB.S9S_MB_2U(SCH_1):GND
  54    GND  VSS22 @S9S_MB_2U_LIB.S9S_MB_2U(SCH_1):GND
  57    GND  VSS23 @S9S_MB_2U_LIB.S9S_MB_2U(SCH_1):GND
  59    GND  VSS24 @S9S_MB_2U_LIB.S9S_MB_2U(SCH_1):GND
  61    GND  VSS25 @S9S_MB_2U_LIB.S9S_MB_2U(SCH_1):GND
  63    GND  VSS26 @S9S_MB_2U_LIB.S9S_MB_2U(SCH_1):GND
  65    GND  VSS27 @S9S_MB_2U_LIB.S9S_MB_2U(SCH_1):GND
  67    GND  VSS28 @S9S_MB_2U_LIB.S9S_MB_2U(SCH_1):GND
  69    GND  VSS29 @S9S_MB_2U_LIB.S9S_MB_2U(SCH_1):GND
  71    GND  VSS30 @S9S_MB_2U_LIB.S9S_MB_2U(SCH_1):GND
  73    GND  VSS31 @S9S_MB_2U_LIB.S9S_MB_2U(SCH_1):GND
  75    GND  VSS32 @S9S_MB_2U_LIB.S9S_MB_2U(SCH_1):GND
  77    GND  VSS33 @S9S_MB_2U_LIB.S9S_MB_2U(SCH_1):GND
  79    GND  VSS34 @S9S_MB_2U_LIB.S9S_MB_2U(SCH_1):GND
  81    GND  VSS35 @S9S_MB_2U_LIB.S9S_MB_2U(SCH_1):GND
  83    GND  VSS36 @S9S_MB_2U_LIB.S9S_MB_2U(SCH_1):GND
  85    GND  VSS37 @S9S_MB_2U_LIB.S9S_MB_2U(SCH_1):GND
  88    GND  VSS38 @S9S_MB_2U_LIB.S9S_MB_2U(SCH_1):GND
  90    GND  VSS39 @S9S_MB_2U_LIB.S9S_MB_2U(SCH_1):GND
  92    GND  VSS40 @S9S_MB_2U_LIB.S9S_MB_2U(SCH_1):GND
  95    GND  VSS41 @S9S_MB_2U_LIB.S9S_MB_2U(SCH_1):GND
  97    GND  VSS42 @S9S_MB_2U_LIB.S9S_MB_2U(SCH_1):GND
  99    GND  VSS43 @S9S_MB_2U_LIB.S9S_MB_2U(SCH_1):GND
 101    GND  VSS44 @S9S_MB_2U_LIB.S9S_MB_2U(SCH_1):GND
 103    GND  VSS45 @S9S_MB_2U_LIB.S9S_MB_2U(SCH_1):GND
 106    GND  VSS46 @S9S_MB_2U_LIB.S9S_MB_2U(SCH_1):GND
 108    GND  VSS47 @S9S_MB_2U_LIB.S9S_MB_2U(SCH_1):GND
 110    GND  VSS48 @S9S_MB_2U_LIB.S9S_MB_2U(SCH_1):GND
 112    GND  VSS49 @S9S_MB_2U_LIB.S9S_MB_2U(SCH_1):GND
 114    GND  VSS50 @S9S_MB_2U_LIB.S9S_MB_2U(SCH_1):GND
 117    GND  VSS51 @S9S_MB_2U_LIB.S9S_MB_2U(SCH_1):GND
 119    GND  VSS52 @S9S_MB_2U_LIB.S9S_MB_2U(SCH_1):GND
 121    GND  VSS53 @S9S_MB_2U_LIB.S9S_MB_2U(SCH_1):GND
 123    GND  VSS54 @S9S_MB_2U_LIB.S9S_MB_2U(SCH_1):GND
 125    GND  VSS55 @S9S_MB_2U_LIB.S9S_MB_2U(SCH_1):GND
 128    GND  VSS56 @S9S_MB_2U_LIB.S9S_MB_2U(SCH_1):GND
 130    GND  VSS57 @S9S_MB_2U_LIB.S9S_MB_2U(SCH_1):GND
 134    GND  VSS59 @S9S_MB_2U_LIB.S9S_MB_2U(SCH_1):GND
 143    GND  VSS63 @S9S_MB_2U_LIB.S9S_MB_2U(SCH_1):GND
 151    GND  VSS64 @S9S_MB_2U_LIB.S9S_MB_2U(SCH_1):GND
 153    GND  VSS65 @S9S_MB_2U_LIB.S9S_MB_2U(SCH_1):GND
 155    GND  VSS66 @S9S_MB_2U_LIB.S9S_MB_2U(SCH_1):GND
 158    GND  VSS67 @S9S_MB_2U_LIB.S9S_MB_2U(SCH_1):GND
 160    GND  VSS68 @S9S_MB_2U_LIB.S9S_MB_2U(SCH_1):GND
 162    GND  VSS69 @S9S_MB_2U_LIB.S9S_MB_2U(SCH_1):GND
 164    GND  VSS70 @S9S_MB_2U_LIB.S9S_MB_2U(SCH_1):GND
 166    GND  VSS71 @S9S_MB_2U_LIB.S9S_MB_2U(SCH_1):GND
 169    GND  VSS72 @S9S_MB_2U_LIB.S9S_MB_2U(SCH_1):GND
 171    GND  VSS73 @S9S_MB_2U_LIB.S9S_MB_2U(SCH_1):GND
 173    GND  VSS74 @S9S_MB_2U_LIB.S9S_MB_2U(SCH_1):GND
 175    GND  VSS75 @S9S_MB_2U_LIB.S9S_MB_2U(SCH_1):GND
 177    GND  VSS76 @S9S_MB_2U_LIB.S9S_MB_2U(SCH_1):GND
 180    GND  VSS77 @S9S_MB_2U_LIB.S9S_MB_2U(SCH_1):GND
 182    GND  VSS78 @S9S_MB_2U_LIB.S9S_MB_2U(SCH_1):GND
 184    GND  VSS79 @S9S_MB_2U_LIB.S9S_MB_2U(SCH_1):GND
 186    GND  VSS80 @S9S_MB_2U_LIB.S9S_MB_2U(SCH_1):GND
 188    GND  VSS81 @S9S_MB_2U_LIB.S9S_MB_2U(SCH_1):GND
 191    GND  VSS82 @S9S_MB_2U_LIB.S9S_MB_2U(SCH_1):GND
 193    GND  VSS83 @S9S_MB_2U_LIB.S9S_MB_2U(SCH_1):GND
 195    GND  VSS84 @S9S_MB_2U_LIB.S9S_MB_2U(SCH_1):GND
 197    GND  VSS85 @S9S_MB_2U_LIB.S9S_MB_2U(SCH_1):GND
 199    GND  VSS86 @S9S_MB_2U_LIB.S9S_MB_2U(SCH_1):GND
 202    GND  VSS87 @S9S_MB_2U_LIB.S9S_MB_2U(SCH_1):GND
 204    GND  VSS88 @S9S_MB_2U_LIB.S9S_MB_2U(SCH_1):GND
 206    GND  VSS89 @S9S_MB_2U_LIB.S9S_MB_2U(SCH_1):GND
 208    GND  VSS90 @S9S_MB_2U_LIB.S9S_MB_2U(SCH_1):GND
 210    GND  VSS91 @S9S_MB_2U_LIB.S9S_MB_2U(SCH_1):GND
 212    GND  VSS92 @S9S_MB_2U_LIB.S9S_MB_2U(SCH_1):GND
 214    GND  VSS93 @S9S_MB_2U_LIB.S9S_MB_2U(SCH_1):GND
 216    GND  VSS94 @S9S_MB_2U_LIB.S9S_MB_2U(SCH_1):GND
 219    GND  VSS95 @S9S_MB_2U_LIB.S9S_MB_2U(SCH_1):GND
 222    GND  VSS96 @S9S_MB_2U_LIB.S9S_MB_2U(SCH_1):GND
 224    GND  VSS97 @S9S_MB_2U_LIB.S9S_MB_2U(SCH_1):GND
 226    GND  VSS98 @S9S_MB_2U_LIB.S9S_MB_2U(SCH_1):GND
 228    GND  VSS99 @S9S_MB_2U_LIB.S9S_MB_2U(SCH_1):GND
 233    GND VSS101 @S9S_MB_2U_LIB.S9S_MB_2U(SCH_1):GND
 237    GND VSS103 @S9S_MB_2U_LIB.S9S_MB_2U(SCH_1):GND
 242    GND VSS105 @S9S_MB_2U_LIB.S9S_MB_2U(SCH_1):GND
 244    GND VSS106 @S9S_MB_2U_LIB.S9S_MB_2U(SCH_1):GND
 246    GND VSS107 @S9S_MB_2U_LIB.S9S_MB_2U(SCH_1):GND
 248    GND VSS108 @S9S_MB_2U_LIB.S9S_MB_2U(SCH_1):GND
 251    GND VSS109 @S9S_MB_2U_LIB.S9S_MB_2U(SCH_1):GND
 253    GND VSS110 @S9S_MB_2U_LIB.S9S_MB_2U(SCH_1):GND
 255    GND VSS111 @S9S_MB_2U_LIB.S9S_MB_2U(SCH_1):GND
 257    GND VSS112 @S9S_MB_2U_LIB.S9S_MB_2U(SCH_1):GND
 259    GND VSS113 @S9S_MB_2U_LIB.S9S_MB_2U(SCH_1):GND
 262    GND VSS114 @S9S_MB_2U_LIB.S9S_MB_2U(SCH_1):GND
 264    GND VSS115 @S9S_MB_2U_LIB.S9S_MB_2U(SCH_1):GND
 266    GND VSS116 @S9S_MB_2U_LIB.S9S_MB_2U(SCH_1):GND
 268    GND VSS117 @S9S_MB_2U_LIB.S9S_MB_2U(SCH_1):GND
 270    GND VSS118 @S9S_MB_2U_LIB.S9S_MB_2U(SCH_1):GND
 273    GND VSS119 @S9S_MB_2U_LIB.S9S_MB_2U(SCH_1):GND
 275    GND VSS120 @S9S_MB_2U_LIB.S9S_MB_2U(SCH_1):GND
 277    GND VSS121 @S9S_MB_2U_LIB.S9S_MB_2U(SCH_1):GND
 279    GND VSS122 @S9S_MB_2U_LIB.S9S_MB_2U(SCH_1):GND
 281    GND VSS123 @S9S_MB_2U_LIB.S9S_MB_2U(SCH_1):GND
 284    GND VSS124 @S9S_MB_2U_LIB.S9S_MB_2U(SCH_1):GND
 286    GND VSS125 @S9S_MB_2U_LIB.S9S_MB_2U(SCH_1):GND
 288    GND VSS126 @S9S_MB_2U_LIB.S9S_MB_2U(SCH_1):GND
   1 P12V_S3_AUX_CPU1_NVDIMM VIN_BULK0 @S9S_MB_2U_LIB.S9S_MB_2U(SCH_1):P12V_S3_AUX_CPU1_NVDIMM
 145 P12V_S3_AUX_CPU1_NVDIMM VIN_BULK1 @S9S_MB_2U_LIB.S9S_MB_2U(SCH_1):P12V_S3_AUX_CPU1_NVDIMM
 146 P12V_S3_AUX_CPU1_NVDIMM VIN_BULK2 @S9S_MB_2U_LIB.S9S_MB_2U(SCH_1):P12V_S3_AUX_CPU1_NVDIMM
 230    GND VSS100 @S9S_MB_2U_LIB.S9S_MB_2U(SCH_1):GND
 235    GND VSS102 @S9S_MB_2U_LIB.S9S_MB_2U(SCH_1):GND
 240    GND VSS104 @S9S_MB_2U_LIB.S9S_MB_2U(SCH_1):GND
 132    GND  VSS58 @S9S_MB_2U_LIB.S9S_MB_2U(SCH_1):GND
 136    GND  VSS60 @S9S_MB_2U_LIB.S9S_MB_2U(SCH_1):GND
 139    GND  VSS61 @S9S_MB_2U_LIB.S9S_MB_2U(SCH_1):GND
 141    GND  VSS62 @S9S_MB_2U_LIB.S9S_MB_2U(SCH_1):GND
  G1    GND     G1 @S9S_MB_2U_LIB.S9S_MB_2U(SCH_1):GND
  G2    GND     G2 @S9S_MB_2U_LIB.S9S_MB_2U(SCH_1):GND
  G3    GND     G3 @S9S_MB_2U_LIB.S9S_MB_2U(SCH_1):GND

SCONN288_ADR50017P087CC-SCONN2A  I179  J30
   3 P3V3_AUX VIN_MGMT @S9S_MB_2U_LIB.S9S_MB_2U(SCH_1):P3V3_AUX
   2 TP_CHG_CPU1_DIMM2_FRU_0   RFU0 @S9S_MB_2U_LIB.S9S_MB_2U(SCH_1):TP_CHG_CPU1_DIMM2_FRU_0
 144 TP_CHG_CPU1_DIMM2_FRU_1   RFU1 @S9S_MB_2U_LIB.S9S_MB_2U(SCH_1):TP_CHG_CPU1_DIMM2_FRU_1
 149 TP_CHG_CPU1_DIMM2_FRU_2   RFU2 @S9S_MB_2U_LIB.S9S_MB_2U(SCH_1):TP_CHG_CPU1_DIMM2_FRU_2
 150 TP_CHG_CPU1_DIMM2_FRU_3   RFU3 @S9S_MB_2U_LIB.S9S_MB_2U(SCH_1):TP_CHG_CPU1_DIMM2_FRU_3
 220 TP_CHG_CPU1_DIMM2_FRU_4   RFU4 @S9S_MB_2U_LIB.S9S_MB_2U(SCH_1):TP_CHG_CPU1_DIMM2_FRU_4
 231 TP_CHG_CPU1_DIMM2_FRU_5   RFU5 @S9S_MB_2U_LIB.S9S_MB_2U(SCH_1):TP_CHG_CPU1_DIMM2_FRU_5
 232 TP_CHG_CPU1_DIMM2_FRU_6   RFU6 @S9S_MB_2U_LIB.S9S_MB_2U(SCH_1):TP_CHG_CPU1_DIMM2_FRU_6
 207 RST_M_GH_CPU1_FPGA_N RESET_N @S9S_MB_2U_LIB.S9S_MB_2U(SCH_1):RST_M_GH_CPU1_FPGA_N
 147 PWRGD_CHG_CPU1_DIMM2 PWR_GOOD||FAIL_N @S9S_MB_2U_LIB.S9S_MB_2U(SCH_1):PWRGD_CHG_CPU1_DIMM2
 227 M_G_CPU1_SB_PAR  PAR_B @S9S_MB_2U_LIB.S9S_MB_2U(SCH_1):M_G_CPU1_SB_PAR
  74 M_G_CPU1_SA_PAR  PAR_A @S9S_MB_2U_LIB.S9S_MB_2U(SCH_1):M_G_CPU1_SA_PAR
  87 M_G_CPU1_SB_RSP<1> LBS||RSP_B_N @S9S_MB_2U_LIB.S9S_MB_2U(SCH_1):M_G_CPU1_SB_RSP(1)
  86 M_G_CPU1_SA_RSP<1> LBD||RSP_A_N @S9S_MB_2U_LIB.S9S_MB_2U(SCH_1):M_G_CPU1_SA_RSP(1)
   5 I3C_SPD_DDREFGH_CPU1_LVC1_SDA   HSDA @S9S_MB_2U_LIB.S9S_MB_2U(SCH_1):I3C_SPD_DDREFGH_CPU1_LVC1_SDA
   4 I3C_SPD_DDREFGH_CPU1_LVC1_SCL_5   HSCL @S9S_MB_2U_LIB.S9S_MB_2U(SCH_1):I3C_SPD_DDREFGH_CPU1_LVC1_SCL_R6
 148 PD_CHG_CPU1_DIMM2_SAA    HSA @S9S_MB_2U_LIB.S9S_MB_2U(SCH_1):PD_CHG_CPU1_DIMM2_SAA
 100 M_G_CPU1_SB_DQ<0>  DQ0_B @S9S_MB_2U_LIB.S9S_MB_2U(SCH_1):M_G_CPU1_SB_DQ(0)
 102 M_G_CPU1_SB_DQ<1>  DQ1_B @S9S_MB_2U_LIB.S9S_MB_2U(SCH_1):M_G_CPU1_SB_DQ(1)
 245 M_G_CPU1_SB_DQ<2>  DQ2_B @S9S_MB_2U_LIB.S9S_MB_2U(SCH_1):M_G_CPU1_SB_DQ(2)
 247 M_G_CPU1_SB_DQ<3>  DQ3_B @S9S_MB_2U_LIB.S9S_MB_2U(SCH_1):M_G_CPU1_SB_DQ(3)
 107 M_G_CPU1_SB_DQ<4>  DQ4_B @S9S_MB_2U_LIB.S9S_MB_2U(SCH_1):M_G_CPU1_SB_DQ(4)
 109 M_G_CPU1_SB_DQ<5>  DQ5_B @S9S_MB_2U_LIB.S9S_MB_2U(SCH_1):M_G_CPU1_SB_DQ(5)
 252 M_G_CPU1_SB_DQ<6>  DQ6_B @S9S_MB_2U_LIB.S9S_MB_2U(SCH_1):M_G_CPU1_SB_DQ(6)
 254 M_G_CPU1_SB_DQ<7>  DQ7_B @S9S_MB_2U_LIB.S9S_MB_2U(SCH_1):M_G_CPU1_SB_DQ(7)
 111 M_G_CPU1_SB_DQ<8>  DQ8_B @S9S_MB_2U_LIB.S9S_MB_2U(SCH_1):M_G_CPU1_SB_DQ(8)
 113 M_G_CPU1_SB_DQ<9>  DQ9_B @S9S_MB_2U_LIB.S9S_MB_2U(SCH_1):M_G_CPU1_SB_DQ(9)
 256 M_G_CPU1_SB_DQ<10> DQ10_B @S9S_MB_2U_LIB.S9S_MB_2U(SCH_1):M_G_CPU1_SB_DQ(10)
 258 M_G_CPU1_SB_DQ<11> DQ11_B @S9S_MB_2U_LIB.S9S_MB_2U(SCH_1):M_G_CPU1_SB_DQ(11)
 118 M_G_CPU1_SB_DQ<12> DQ12_B @S9S_MB_2U_LIB.S9S_MB_2U(SCH_1):M_G_CPU1_SB_DQ(12)
 120 M_G_CPU1_SB_DQ<13> DQ13_B @S9S_MB_2U_LIB.S9S_MB_2U(SCH_1):M_G_CPU1_SB_DQ(13)
 263 M_G_CPU1_SB_DQ<14> DQ14_B @S9S_MB_2U_LIB.S9S_MB_2U(SCH_1):M_G_CPU1_SB_DQ(14)
 265 M_G_CPU1_SB_DQ<15> DQ15_B @S9S_MB_2U_LIB.S9S_MB_2U(SCH_1):M_G_CPU1_SB_DQ(15)
 122 M_G_CPU1_SB_DQ<16> DQ16_B @S9S_MB_2U_LIB.S9S_MB_2U(SCH_1):M_G_CPU1_SB_DQ(16)
 124 M_G_CPU1_SB_DQ<17> DQ17_B @S9S_MB_2U_LIB.S9S_MB_2U(SCH_1):M_G_CPU1_SB_DQ(17)
 267 M_G_CPU1_SB_DQ<18> DQ18_B @S9S_MB_2U_LIB.S9S_MB_2U(SCH_1):M_G_CPU1_SB_DQ(18)
 269 M_G_CPU1_SB_DQ<19> DQ19_B @S9S_MB_2U_LIB.S9S_MB_2U(SCH_1):M_G_CPU1_SB_DQ(19)
 129 M_G_CPU1_SB_DQ<20> DQ20_B @S9S_MB_2U_LIB.S9S_MB_2U(SCH_1):M_G_CPU1_SB_DQ(20)
 131 M_G_CPU1_SB_DQ<21> DQ21_B @S9S_MB_2U_LIB.S9S_MB_2U(SCH_1):M_G_CPU1_SB_DQ(21)
 274 M_G_CPU1_SB_DQ<22> DQ22_B @S9S_MB_2U_LIB.S9S_MB_2U(SCH_1):M_G_CPU1_SB_DQ(22)
 276 M_G_CPU1_SB_DQ<23> DQ23_B @S9S_MB_2U_LIB.S9S_MB_2U(SCH_1):M_G_CPU1_SB_DQ(23)
 133 M_G_CPU1_SB_DQ<24> DQ24_B @S9S_MB_2U_LIB.S9S_MB_2U(SCH_1):M_G_CPU1_SB_DQ(24)
 135 M_G_CPU1_SB_DQ<25> DQ25_B @S9S_MB_2U_LIB.S9S_MB_2U(SCH_1):M_G_CPU1_SB_DQ(25)
 278 M_G_CPU1_SB_DQ<26> DQ26_B @S9S_MB_2U_LIB.S9S_MB_2U(SCH_1):M_G_CPU1_SB_DQ(26)
 280 M_G_CPU1_SB_DQ<27> DQ27_B @S9S_MB_2U_LIB.S9S_MB_2U(SCH_1):M_G_CPU1_SB_DQ(27)
 140 M_G_CPU1_SB_DQ<28> DQ28_B @S9S_MB_2U_LIB.S9S_MB_2U(SCH_1):M_G_CPU1_SB_DQ(28)
 142 M_G_CPU1_SB_DQ<29> DQ29_B @S9S_MB_2U_LIB.S9S_MB_2U(SCH_1):M_G_CPU1_SB_DQ(29)
 285 M_G_CPU1_SB_DQ<30> DQ30_B @S9S_MB_2U_LIB.S9S_MB_2U(SCH_1):M_G_CPU1_SB_DQ(30)
 287 M_G_CPU1_SB_DQ<31> DQ31_B @S9S_MB_2U_LIB.S9S_MB_2U(SCH_1):M_G_CPU1_SB_DQ(31)
   7 M_G_CPU1_SA_DQ<0>  DQ0_A @S9S_MB_2U_LIB.S9S_MB_2U(SCH_1):M_G_CPU1_SA_DQ(0)
   9 M_G_CPU1_SA_DQ<1>  DQ1_A @S9S_MB_2U_LIB.S9S_MB_2U(SCH_1):M_G_CPU1_SA_DQ(1)
 152 M_G_CPU1_SA_DQ<2>  DQ2_A @S9S_MB_2U_LIB.S9S_MB_2U(SCH_1):M_G_CPU1_SA_DQ(2)
 154 M_G_CPU1_SA_DQ<3>  DQ3_A @S9S_MB_2U_LIB.S9S_MB_2U(SCH_1):M_G_CPU1_SA_DQ(3)
  14 M_G_CPU1_SA_DQ<4>  DQ4_A @S9S_MB_2U_LIB.S9S_MB_2U(SCH_1):M_G_CPU1_SA_DQ(4)
  16 M_G_CPU1_SA_DQ<5>  DQ5_A @S9S_MB_2U_LIB.S9S_MB_2U(SCH_1):M_G_CPU1_SA_DQ(5)
 159 M_G_CPU1_SA_DQ<6>  DQ6_A @S9S_MB_2U_LIB.S9S_MB_2U(SCH_1):M_G_CPU1_SA_DQ(6)
 161 M_G_CPU1_SA_DQ<7>  DQ7_A @S9S_MB_2U_LIB.S9S_MB_2U(SCH_1):M_G_CPU1_SA_DQ(7)
  18 M_G_CPU1_SA_DQ<8>  DQ8_A @S9S_MB_2U_LIB.S9S_MB_2U(SCH_1):M_G_CPU1_SA_DQ(8)
  20 M_G_CPU1_SA_DQ<9>  DQ9_A @S9S_MB_2U_LIB.S9S_MB_2U(SCH_1):M_G_CPU1_SA_DQ(9)
 163 M_G_CPU1_SA_DQ<10> DQ10_A @S9S_MB_2U_LIB.S9S_MB_2U(SCH_1):M_G_CPU1_SA_DQ(10)
 165 M_G_CPU1_SA_DQ<11> DQ11_A @S9S_MB_2U_LIB.S9S_MB_2U(SCH_1):M_G_CPU1_SA_DQ(11)
  25 M_G_CPU1_SA_DQ<12> DQ12_A @S9S_MB_2U_LIB.S9S_MB_2U(SCH_1):M_G_CPU1_SA_DQ(12)
  27 M_G_CPU1_SA_DQ<13> DQ13_A @S9S_MB_2U_LIB.S9S_MB_2U(SCH_1):M_G_CPU1_SA_DQ(13)
 170 M_G_CPU1_SA_DQ<14> DQ14_A @S9S_MB_2U_LIB.S9S_MB_2U(SCH_1):M_G_CPU1_SA_DQ(14)
 172 M_G_CPU1_SA_DQ<15> DQ15_A @S9S_MB_2U_LIB.S9S_MB_2U(SCH_1):M_G_CPU1_SA_DQ(15)
  29 M_G_CPU1_SA_DQ<16> DQ16_A @S9S_MB_2U_LIB.S9S_MB_2U(SCH_1):M_G_CPU1_SA_DQ(16)
  31 M_G_CPU1_SA_DQ<17> DQ17_A @S9S_MB_2U_LIB.S9S_MB_2U(SCH_1):M_G_CPU1_SA_DQ(17)
 174 M_G_CPU1_SA_DQ<18> DQ18_A @S9S_MB_2U_LIB.S9S_MB_2U(SCH_1):M_G_CPU1_SA_DQ(18)
 176 M_G_CPU1_SA_DQ<19> DQ19_A @S9S_MB_2U_LIB.S9S_MB_2U(SCH_1):M_G_CPU1_SA_DQ(19)
  36 M_G_CPU1_SA_DQ<20> DQ20_A @S9S_MB_2U_LIB.S9S_MB_2U(SCH_1):M_G_CPU1_SA_DQ(20)
  38 M_G_CPU1_SA_DQ<21> DQ21_A @S9S_MB_2U_LIB.S9S_MB_2U(SCH_1):M_G_CPU1_SA_DQ(21)
 181 M_G_CPU1_SA_DQ<22> DQ22_A @S9S_MB_2U_LIB.S9S_MB_2U(SCH_1):M_G_CPU1_SA_DQ(22)
 183 M_G_CPU1_SA_DQ<23> DQ23_A @S9S_MB_2U_LIB.S9S_MB_2U(SCH_1):M_G_CPU1_SA_DQ(23)
  40 M_G_CPU1_SA_DQ<24> DQ24_A @S9S_MB_2U_LIB.S9S_MB_2U(SCH_1):M_G_CPU1_SA_DQ(24)
  42 M_G_CPU1_SA_DQ<25> DQ25_A @S9S_MB_2U_LIB.S9S_MB_2U(SCH_1):M_G_CPU1_SA_DQ(25)
 185 M_G_CPU1_SA_DQ<26> DQ26_A @S9S_MB_2U_LIB.S9S_MB_2U(SCH_1):M_G_CPU1_SA_DQ(26)
 187 M_G_CPU1_SA_DQ<27> DQ27_A @S9S_MB_2U_LIB.S9S_MB_2U(SCH_1):M_G_CPU1_SA_DQ(27)
  47 M_G_CPU1_SA_DQ<28> DQ28_A @S9S_MB_2U_LIB.S9S_MB_2U(SCH_1):M_G_CPU1_SA_DQ(28)
  49 M_G_CPU1_SA_DQ<29> DQ29_A @S9S_MB_2U_LIB.S9S_MB_2U(SCH_1):M_G_CPU1_SA_DQ(29)
 192 M_G_CPU1_SA_DQ<30> DQ30_A @S9S_MB_2U_LIB.S9S_MB_2U(SCH_1):M_G_CPU1_SA_DQ(30)
 229 M_G_CPU1_SB_CS_N<3> CS1_B_N @S9S_MB_2U_LIB.S9S_MB_2U(SCH_1):M_G_CPU1_SB_CS_N(3)
 209 M_G_CPU1_SA_CS_N<3> CS1_A_N @S9S_MB_2U_LIB.S9S_MB_2U(SCH_1):M_G_CPU1_SA_CS_N(3)
  84 M_G_CPU1_SB_CS_N<2> CS0_B_N @S9S_MB_2U_LIB.S9S_MB_2U(SCH_1):M_G_CPU1_SB_CS_N(2)
  64 M_G_CPU1_SA_CS_N<2> CS0_A_N @S9S_MB_2U_LIB.S9S_MB_2U(SCH_1):M_G_CPU1_SA_CS_N(2)
 217 M_G_CPU1_CLK_DP<1>   CK_T @S9S_MB_2U_LIB.S9S_MB_2U(SCH_1):M_G_CPU1_CLK_DP(1)
 218 M_G_CPU1_CLK_DN<1>   CK_C @S9S_MB_2U_LIB.S9S_MB_2U(SCH_1):M_G_CPU1_CLK_DN(1)
  96 M_G_CPU1_SB_CB<0>  CB0_B @S9S_MB_2U_LIB.S9S_MB_2U(SCH_1):M_G_CPU1_SB_CB(0)
  98 M_G_CPU1_SB_CB<1>  CB1_B @S9S_MB_2U_LIB.S9S_MB_2U(SCH_1):M_G_CPU1_SB_CB(1)
 241 M_G_CPU1_SB_CB<2>  CB2_B @S9S_MB_2U_LIB.S9S_MB_2U(SCH_1):M_G_CPU1_SB_CB(2)
 243 M_G_CPU1_SB_CB<3>  CB3_B @S9S_MB_2U_LIB.S9S_MB_2U(SCH_1):M_G_CPU1_SB_CB(3)
  89 M_G_CPU1_SB_CB<4>  CB4_B @S9S_MB_2U_LIB.S9S_MB_2U(SCH_1):M_G_CPU1_SB_CB(4)
  91 M_G_CPU1_SB_CB<5>  CB5_B @S9S_MB_2U_LIB.S9S_MB_2U(SCH_1):M_G_CPU1_SB_CB(5)
 234 M_G_CPU1_SB_CB<6>  CB6_B @S9S_MB_2U_LIB.S9S_MB_2U(SCH_1):M_G_CPU1_SB_CB(6)
  51 M_G_CPU1_SA_CB<0>  CB0_A @S9S_MB_2U_LIB.S9S_MB_2U(SCH_1):M_G_CPU1_SA_CB(0)
 196 M_G_CPU1_SA_CB<2>  CB2_A @S9S_MB_2U_LIB.S9S_MB_2U(SCH_1):M_G_CPU1_SA_CB(2)
 198 M_G_CPU1_SA_CB<3>  CB3_A @S9S_MB_2U_LIB.S9S_MB_2U(SCH_1):M_G_CPU1_SA_CB(3)
  60 M_G_CPU1_SA_CB<5>  CB5_A @S9S_MB_2U_LIB.S9S_MB_2U(SCH_1):M_G_CPU1_SA_CB(5)
 203 M_G_CPU1_SA_CB<6>  CB6_A @S9S_MB_2U_LIB.S9S_MB_2U(SCH_1):M_G_CPU1_SA_CB(6)
  82 M_G_CPU1_SB_CA<6>  CA6_B @S9S_MB_2U_LIB.S9S_MB_2U(SCH_1):M_G_CPU1_SB_CA(6)
  72 M_G_CPU1_SA_CA<6>  CA6_A @S9S_MB_2U_LIB.S9S_MB_2U(SCH_1):M_G_CPU1_SA_CA(6)
 225 M_G_CPU1_SB_CA<5>  CA5_B @S9S_MB_2U_LIB.S9S_MB_2U(SCH_1):M_G_CPU1_SB_CA(5)
 215 M_G_CPU1_SA_CA<5>  CA5_A @S9S_MB_2U_LIB.S9S_MB_2U(SCH_1):M_G_CPU1_SA_CA(5)
  80 M_G_CPU1_SB_CA<4>  CA4_B @S9S_MB_2U_LIB.S9S_MB_2U(SCH_1):M_G_CPU1_SB_CA(4)
  70 M_G_CPU1_SA_CA<4>  CA4_A @S9S_MB_2U_LIB.S9S_MB_2U(SCH_1):M_G_CPU1_SA_CA(4)
 223 M_G_CPU1_SB_CA<3>  CA3_B @S9S_MB_2U_LIB.S9S_MB_2U(SCH_1):M_G_CPU1_SB_CA(3)
 213 M_G_CPU1_SA_CA<3>  CA3_A @S9S_MB_2U_LIB.S9S_MB_2U(SCH_1):M_G_CPU1_SA_CA(3)
  78 M_G_CPU1_SB_CA<2>  CA2_B @S9S_MB_2U_LIB.S9S_MB_2U(SCH_1):M_G_CPU1_SB_CA(2)
  68 M_G_CPU1_SA_CA<2>  CA2_A @S9S_MB_2U_LIB.S9S_MB_2U(SCH_1):M_G_CPU1_SA_CA(2)
 221 M_G_CPU1_SB_CA<1>  CA1_B @S9S_MB_2U_LIB.S9S_MB_2U(SCH_1):M_G_CPU1_SB_CA(1)
 211 M_G_CPU1_SA_CA<1>  CA1_A @S9S_MB_2U_LIB.S9S_MB_2U(SCH_1):M_G_CPU1_SA_CA(1)
  76 M_G_CPU1_SB_CA<0>  CA0_B @S9S_MB_2U_LIB.S9S_MB_2U(SCH_1):M_G_CPU1_SB_CA(0)
  66 M_G_CPU1_SA_CA<0>  CA0_A @S9S_MB_2U_LIB.S9S_MB_2U(SCH_1):M_G_CPU1_SA_CA(0)
  62 M_G_CPU1_ALERT_N ALERT_N @S9S_MB_2U_LIB.S9S_MB_2U(SCH_1):M_G_CPU1_ALERT_N
 236 M_G_CPU1_SB_CB<7>  CB7_B @S9S_MB_2U_LIB.S9S_MB_2U(SCH_1):M_G_CPU1_SB_CB(7)
  53 M_G_CPU1_SA_CB<1>  CB1_A @S9S_MB_2U_LIB.S9S_MB_2U(SCH_1):M_G_CPU1_SA_CB(1)
  58 M_G_CPU1_SA_CB<4>  CB4_A @S9S_MB_2U_LIB.S9S_MB_2U(SCH_1):M_G_CPU1_SA_CB(4)
 205 M_G_CPU1_SA_CB<7>  CB7_A @S9S_MB_2U_LIB.S9S_MB_2U(SCH_1):M_G_CPU1_SA_CB(7)
 194 M_G_CPU1_SA_DQ<31> DQ31_A @S9S_MB_2U_LIB.S9S_MB_2U(SCH_1):M_G_CPU1_SA_DQ(31)

SCONN288_ADR50017P087CC-SCONN2A  I180  J30
  93 M_G_CPU1_SB_DQS_DP<9> DQS9_B_T||TDQS9_B_T||DBI4_B_N @S9S_MB_2U_LIB.S9S_MB_2U(SCH_1):M_G_CPU1_SB_DQS_DP(9)
  94 M_G_CPU1_SB_DQS_DN<9> DQS9_B_C||TDQS9_B_C @S9S_MB_2U_LIB.S9S_MB_2U(SCH_1):M_G_CPU1_SB_DQS_DN(9)
 201 M_G_CPU1_SA_DQS_DP<9> DQS9_A_T||TDQS9_A_T @S9S_MB_2U_LIB.S9S_MB_2U(SCH_1):M_G_CPU1_SA_DQS_DP(9)
 200 M_G_CPU1_SA_DQS_DN<9> DQS9_A_C||TDQS9_A_C @S9S_MB_2U_LIB.S9S_MB_2U(SCH_1):M_G_CPU1_SA_DQS_DN(9)
 190 M_G_CPU1_SA_DQS_DP<8> DQS8_A_T||TDQS8_A_T @S9S_MB_2U_LIB.S9S_MB_2U(SCH_1):M_G_CPU1_SA_DQS_DP(8)
 189 M_G_CPU1_SA_DQS_DN<8> DQS8_A_C||TDQS8_A_C @S9S_MB_2U_LIB.S9S_MB_2U(SCH_1):M_G_CPU1_SA_DQS_DN(8)
 271 M_G_CPU1_SB_DQS_DN<7> DQS7_B_C||TDQS7_B_C @S9S_MB_2U_LIB.S9S_MB_2U(SCH_1):M_G_CPU1_SB_DQS_DN(7)
 179 M_G_CPU1_SA_DQS_DP<7> DQS7_A_T||TDQS7_A_T @S9S_MB_2U_LIB.S9S_MB_2U(SCH_1):M_G_CPU1_SA_DQS_DP(7)
 261 M_G_CPU1_SB_DQS_DP<6> DQS6_B_T||TDQS6_B_T @S9S_MB_2U_LIB.S9S_MB_2U(SCH_1):M_G_CPU1_SB_DQS_DP(6)
 260 M_G_CPU1_SB_DQS_DN<6> DQS6_B_C||TDQS6_B_C @S9S_MB_2U_LIB.S9S_MB_2U(SCH_1):M_G_CPU1_SB_DQS_DN(6)
 167 M_G_CPU1_SA_DQS_DN<6> DQS6_A_C||TDQS6_A_C||DQS6_A_T||TDQS6_A_T @S9S_MB_2U_LIB.S9S_MB_2U(SCH_1):M_G_CPU1_SA_DQS_DN(6)
 250 M_G_CPU1_SB_DQS_DP<5> DQS5_B_T||TDQS5_B_T @S9S_MB_2U_LIB.S9S_MB_2U(SCH_1):M_G_CPU1_SB_DQS_DP(5)
 249 M_G_CPU1_SB_DQS_DN<5> DQS5_B_C||TDQS5_B_C @S9S_MB_2U_LIB.S9S_MB_2U(SCH_1):M_G_CPU1_SB_DQS_DN(5)
 157 M_G_CPU1_SA_DQS_DP<5> DQS5_A_T||TDQS5_A_T @S9S_MB_2U_LIB.S9S_MB_2U(SCH_1):M_G_CPU1_SA_DQS_DP(5)
 156 M_G_CPU1_SA_DQS_DN<5> DQS5_A_C||TDQS5_A_C||DQS5_A_T||TDQS5_A_T @S9S_MB_2U_LIB.S9S_MB_2U(SCH_1):M_G_CPU1_SA_DQS_DN(5)
 239 M_G_CPU1_SB_DQS_DP<4> DQS4_B_T @S9S_MB_2U_LIB.S9S_MB_2U(SCH_1):M_G_CPU1_SB_DQS_DP(4)
 238 M_G_CPU1_SB_DQS_DN<4> DQS4_B_C @S9S_MB_2U_LIB.S9S_MB_2U(SCH_1):M_G_CPU1_SB_DQS_DN(4)
  55 M_G_CPU1_SA_DQS_DP<4> DQS4_A_T @S9S_MB_2U_LIB.S9S_MB_2U(SCH_1):M_G_CPU1_SA_DQS_DP(4)
  56 M_G_CPU1_SA_DQS_DN<4> DQS4_A_C @S9S_MB_2U_LIB.S9S_MB_2U(SCH_1):M_G_CPU1_SA_DQS_DN(4)
 137 M_G_CPU1_SB_DQS_DP<3> DQS3_B_T @S9S_MB_2U_LIB.S9S_MB_2U(SCH_1):M_G_CPU1_SB_DQS_DP(3)
 138 M_G_CPU1_SB_DQS_DN<3> DQS3_B_C @S9S_MB_2U_LIB.S9S_MB_2U(SCH_1):M_G_CPU1_SB_DQS_DN(3)
  44 M_G_CPU1_SA_DQS_DP<3> DQS3_A_T @S9S_MB_2U_LIB.S9S_MB_2U(SCH_1):M_G_CPU1_SA_DQS_DP(3)
  45 M_G_CPU1_SA_DQS_DN<3> DQS3_A_C @S9S_MB_2U_LIB.S9S_MB_2U(SCH_1):M_G_CPU1_SA_DQS_DN(3)
 126 M_G_CPU1_SB_DQS_DP<2> DQS2_B_T @S9S_MB_2U_LIB.S9S_MB_2U(SCH_1):M_G_CPU1_SB_DQS_DP(2)
 127 M_G_CPU1_SB_DQS_DN<2> DQS2_B_C @S9S_MB_2U_LIB.S9S_MB_2U(SCH_1):M_G_CPU1_SB_DQS_DN(2)
  33 M_G_CPU1_SA_DQS_DP<2> DQS2_A_T @S9S_MB_2U_LIB.S9S_MB_2U(SCH_1):M_G_CPU1_SA_DQS_DP(2)
  34 M_G_CPU1_SA_DQS_DN<2> DQS2_A_C @S9S_MB_2U_LIB.S9S_MB_2U(SCH_1):M_G_CPU1_SA_DQS_DN(2)
 115 M_G_CPU1_SB_DQS_DP<1> DQS1_B_T @S9S_MB_2U_LIB.S9S_MB_2U(SCH_1):M_G_CPU1_SB_DQS_DP(1)
 116 M_G_CPU1_SB_DQS_DN<1> DQS1_B_C @S9S_MB_2U_LIB.S9S_MB_2U(SCH_1):M_G_CPU1_SB_DQS_DN(1)
  22 M_G_CPU1_SA_DQS_DP<1> DQS1_A_T @S9S_MB_2U_LIB.S9S_MB_2U(SCH_1):M_G_CPU1_SA_DQS_DP(1)
  23 M_G_CPU1_SA_DQS_DN<1> DQS1_A_C @S9S_MB_2U_LIB.S9S_MB_2U(SCH_1):M_G_CPU1_SA_DQS_DN(1)
 104 M_G_CPU1_SB_DQS_DP<0> DQS0_B_T @S9S_MB_2U_LIB.S9S_MB_2U(SCH_1):M_G_CPU1_SB_DQS_DP(0)
 105 M_G_CPU1_SB_DQS_DN<0> DQS0_B_C @S9S_MB_2U_LIB.S9S_MB_2U(SCH_1):M_G_CPU1_SB_DQS_DN(0)
  11 M_G_CPU1_SA_DQS_DP<0> DQS0_A_T @S9S_MB_2U_LIB.S9S_MB_2U(SCH_1):M_G_CPU1_SA_DQS_DP(0)
  12 M_G_CPU1_SA_DQS_DN<0> DQS0_A_C @S9S_MB_2U_LIB.S9S_MB_2U(SCH_1):M_G_CPU1_SA_DQS_DN(0)
 272 M_G_CPU1_SB_DQS_DP<7> DQS7_B_T||TDQS7_B_T @S9S_MB_2U_LIB.S9S_MB_2U(SCH_1):M_G_CPU1_SB_DQS_DP(7)
 282 M_G_CPU1_SB_DQS_DN<8> DQS8_B_C||TDQS8_B_C @S9S_MB_2U_LIB.S9S_MB_2U(SCH_1):M_G_CPU1_SB_DQS_DN(8)
 283 M_G_CPU1_SB_DQS_DP<8> DQS8_B_T||TDQS8_B_T @S9S_MB_2U_LIB.S9S_MB_2U(SCH_1):M_G_CPU1_SB_DQS_DP(8)
 168 M_G_CPU1_SA_DQS_DP<6> DQS6_A_T||TDQS6_A_T @S9S_MB_2U_LIB.S9S_MB_2U(SCH_1):M_G_CPU1_SA_DQS_DP(6)
 178 M_G_CPU1_SA_DQS_DN<7> DQS7_A_C||TDQS7_A_C @S9S_MB_2U_LIB.S9S_MB_2U(SCH_1):M_G_CPU1_SA_DQS_DN(7)

Q_RES_0402LF-49.9,1%,1/16W,CHIA  I182  R3904
   1 I3C_SPD_DDREFGH_CPU1_LVC1_SCL_5      A @S9S_MB_2U_LIB.S9S_MB_2U(SCH_1):I3C_SPD_DDREFGH_CPU1_LVC1_SCL_R6
   2 I3C_SPD_DDREFGH_CPU1_LVC1_SCL      B @S9S_MB_2U_LIB.S9S_MB_2U(SCH_1):I3C_SPD_DDREFGH_CPU1_LVC1_SCL


DRAWING: @S9S_MB_2U_LIB.S9S_MB_2U(SCH_1):PAGE112 

Q_RES_0402LF-127K,1%,1/16W,CHIA  I3  R73
   1 PD_CHH_CPU1_DIMM1_SAA      A @S9S_MB_2U_LIB.S9S_MB_2U(SCH_1):PD_CHH_CPU1_DIMM1_SAA
   2    GND      B @S9S_MB_2U_LIB.S9S_MB_2U(SCH_1):GND

Q_CAP_C0402-2.2UF,6.3V,20%,X6SA  I124  C75
   1 P3V3_AUX      A @S9S_MB_2U_LIB.S9S_MB_2U(SCH_1):P3V3_AUX
   2    GND      B @S9S_MB_2U_LIB.S9S_MB_2U(SCH_1):GND

Q_CAP_C0805-10UF,16V,10%,X6S,CA  I125  C76
   1 P12V_S3_AUX_CPU1_NVDIMM      A @S9S_MB_2U_LIB.S9S_MB_2U(SCH_1):P12V_S3_AUX_CPU1_NVDIMM
   2    GND      B @S9S_MB_2U_LIB.S9S_MB_2U(SCH_1):GND

Q_CAP_C0805-10UF,16V,10%,X6S,CA  I126  C77
   1 P12V_S3_AUX_CPU1_NVDIMM      A @S9S_MB_2U_LIB.S9S_MB_2U(SCH_1):P12V_S3_AUX_CPU1_NVDIMM
   2    GND      B @S9S_MB_2U_LIB.S9S_MB_2U(SCH_1):GND

SCONN288_ADR50017P130CC-SCONN2A  I178  J31
   6    GND   VSS0 @S9S_MB_2U_LIB.S9S_MB_2U(SCH_1):GND
   8    GND   VSS1 @S9S_MB_2U_LIB.S9S_MB_2U(SCH_1):GND
  10    GND   VSS2 @S9S_MB_2U_LIB.S9S_MB_2U(SCH_1):GND
  13    GND   VSS3 @S9S_MB_2U_LIB.S9S_MB_2U(SCH_1):GND
  15    GND   VSS4 @S9S_MB_2U_LIB.S9S_MB_2U(SCH_1):GND
  17    GND   VSS5 @S9S_MB_2U_LIB.S9S_MB_2U(SCH_1):GND
  19    GND   VSS6 @S9S_MB_2U_LIB.S9S_MB_2U(SCH_1):GND
  21    GND   VSS7 @S9S_MB_2U_LIB.S9S_MB_2U(SCH_1):GND
  24    GND   VSS8 @S9S_MB_2U_LIB.S9S_MB_2U(SCH_1):GND
  26    GND   VSS9 @S9S_MB_2U_LIB.S9S_MB_2U(SCH_1):GND
  28    GND  VSS10 @S9S_MB_2U_LIB.S9S_MB_2U(SCH_1):GND
  30    GND  VSS11 @S9S_MB_2U_LIB.S9S_MB_2U(SCH_1):GND
  32    GND  VSS12 @S9S_MB_2U_LIB.S9S_MB_2U(SCH_1):GND
  35    GND  VSS13 @S9S_MB_2U_LIB.S9S_MB_2U(SCH_1):GND
  37    GND  VSS14 @S9S_MB_2U_LIB.S9S_MB_2U(SCH_1):GND
  39    GND  VSS15 @S9S_MB_2U_LIB.S9S_MB_2U(SCH_1):GND
  41    GND  VSS16 @S9S_MB_2U_LIB.S9S_MB_2U(SCH_1):GND
  43    GND  VSS17 @S9S_MB_2U_LIB.S9S_MB_2U(SCH_1):GND
  46    GND  VSS18 @S9S_MB_2U_LIB.S9S_MB_2U(SCH_1):GND
  48    GND  VSS19 @S9S_MB_2U_LIB.S9S_MB_2U(SCH_1):GND
  50    GND  VSS20 @S9S_MB_2U_LIB.S9S_MB_2U(SCH_1):GND
  52    GND  VSS21 @S9S_MB_2U_LIB.S9S_MB_2U(SCH_1):GND
  54    GND  VSS22 @S9S_MB_2U_LIB.S9S_MB_2U(SCH_1):GND
  57    GND  VSS23 @S9S_MB_2U_LIB.S9S_MB_2U(SCH_1):GND
  59    GND  VSS24 @S9S_MB_2U_LIB.S9S_MB_2U(SCH_1):GND
  61    GND  VSS25 @S9S_MB_2U_LIB.S9S_MB_2U(SCH_1):GND
  63    GND  VSS26 @S9S_MB_2U_LIB.S9S_MB_2U(SCH_1):GND
  65    GND  VSS27 @S9S_MB_2U_LIB.S9S_MB_2U(SCH_1):GND
  67    GND  VSS28 @S9S_MB_2U_LIB.S9S_MB_2U(SCH_1):GND
  69    GND  VSS29 @S9S_MB_2U_LIB.S9S_MB_2U(SCH_1):GND
  71    GND  VSS30 @S9S_MB_2U_LIB.S9S_MB_2U(SCH_1):GND
  73    GND  VSS31 @S9S_MB_2U_LIB.S9S_MB_2U(SCH_1):GND
  75    GND  VSS32 @S9S_MB_2U_LIB.S9S_MB_2U(SCH_1):GND
  77    GND  VSS33 @S9S_MB_2U_LIB.S9S_MB_2U(SCH_1):GND
  79    GND  VSS34 @S9S_MB_2U_LIB.S9S_MB_2U(SCH_1):GND
  81    GND  VSS35 @S9S_MB_2U_LIB.S9S_MB_2U(SCH_1):GND
  83    GND  VSS36 @S9S_MB_2U_LIB.S9S_MB_2U(SCH_1):GND
  85    GND  VSS37 @S9S_MB_2U_LIB.S9S_MB_2U(SCH_1):GND
  88    GND  VSS38 @S9S_MB_2U_LIB.S9S_MB_2U(SCH_1):GND
  90    GND  VSS39 @S9S_MB_2U_LIB.S9S_MB_2U(SCH_1):GND
  92    GND  VSS40 @S9S_MB_2U_LIB.S9S_MB_2U(SCH_1):GND
  95    GND  VSS41 @S9S_MB_2U_LIB.S9S_MB_2U(SCH_1):GND
  97    GND  VSS42 @S9S_MB_2U_LIB.S9S_MB_2U(SCH_1):GND
  99    GND  VSS43 @S9S_MB_2U_LIB.S9S_MB_2U(SCH_1):GND
 101    GND  VSS44 @S9S_MB_2U_LIB.S9S_MB_2U(SCH_1):GND
 103    GND  VSS45 @S9S_MB_2U_LIB.S9S_MB_2U(SCH_1):GND
 106    GND  VSS46 @S9S_MB_2U_LIB.S9S_MB_2U(SCH_1):GND
 108    GND  VSS47 @S9S_MB_2U_LIB.S9S_MB_2U(SCH_1):GND
 110    GND  VSS48 @S9S_MB_2U_LIB.S9S_MB_2U(SCH_1):GND
 112    GND  VSS49 @S9S_MB_2U_LIB.S9S_MB_2U(SCH_1):GND
 114    GND  VSS50 @S9S_MB_2U_LIB.S9S_MB_2U(SCH_1):GND
 117    GND  VSS51 @S9S_MB_2U_LIB.S9S_MB_2U(SCH_1):GND
 119    GND  VSS52 @S9S_MB_2U_LIB.S9S_MB_2U(SCH_1):GND
 121    GND  VSS53 @S9S_MB_2U_LIB.S9S_MB_2U(SCH_1):GND
 123    GND  VSS54 @S9S_MB_2U_LIB.S9S_MB_2U(SCH_1):GND
 125    GND  VSS55 @S9S_MB_2U_LIB.S9S_MB_2U(SCH_1):GND
 128    GND  VSS56 @S9S_MB_2U_LIB.S9S_MB_2U(SCH_1):GND
 130    GND  VSS57 @S9S_MB_2U_LIB.S9S_MB_2U(SCH_1):GND
 134    GND  VSS59 @S9S_MB_2U_LIB.S9S_MB_2U(SCH_1):GND
 143    GND  VSS63 @S9S_MB_2U_LIB.S9S_MB_2U(SCH_1):GND
 151    GND  VSS64 @S9S_MB_2U_LIB.S9S_MB_2U(SCH_1):GND
 153    GND  VSS65 @S9S_MB_2U_LIB.S9S_MB_2U(SCH_1):GND
 155    GND  VSS66 @S9S_MB_2U_LIB.S9S_MB_2U(SCH_1):GND
 158    GND  VSS67 @S9S_MB_2U_LIB.S9S_MB_2U(SCH_1):GND
 160    GND  VSS68 @S9S_MB_2U_LIB.S9S_MB_2U(SCH_1):GND
 162    GND  VSS69 @S9S_MB_2U_LIB.S9S_MB_2U(SCH_1):GND
 164    GND  VSS70 @S9S_MB_2U_LIB.S9S_MB_2U(SCH_1):GND
 166    GND  VSS71 @S9S_MB_2U_LIB.S9S_MB_2U(SCH_1):GND
 169    GND  VSS72 @S9S_MB_2U_LIB.S9S_MB_2U(SCH_1):GND
 171    GND  VSS73 @S9S_MB_2U_LIB.S9S_MB_2U(SCH_1):GND
 173    GND  VSS74 @S9S_MB_2U_LIB.S9S_MB_2U(SCH_1):GND
 175    GND  VSS75 @S9S_MB_2U_LIB.S9S_MB_2U(SCH_1):GND
 177    GND  VSS76 @S9S_MB_2U_LIB.S9S_MB_2U(SCH_1):GND
 180    GND  VSS77 @S9S_MB_2U_LIB.S9S_MB_2U(SCH_1):GND
 182    GND  VSS78 @S9S_MB_2U_LIB.S9S_MB_2U(SCH_1):GND
 184    GND  VSS79 @S9S_MB_2U_LIB.S9S_MB_2U(SCH_1):GND
 186    GND  VSS80 @S9S_MB_2U_LIB.S9S_MB_2U(SCH_1):GND
 188    GND  VSS81 @S9S_MB_2U_LIB.S9S_MB_2U(SCH_1):GND
 191    GND  VSS82 @S9S_MB_2U_LIB.S9S_MB_2U(SCH_1):GND
 193    GND  VSS83 @S9S_MB_2U_LIB.S9S_MB_2U(SCH_1):GND
 195    GND  VSS84 @S9S_MB_2U_LIB.S9S_MB_2U(SCH_1):GND
 197    GND  VSS85 @S9S_MB_2U_LIB.S9S_MB_2U(SCH_1):GND
 199    GND  VSS86 @S9S_MB_2U_LIB.S9S_MB_2U(SCH_1):GND
 202    GND  VSS87 @S9S_MB_2U_LIB.S9S_MB_2U(SCH_1):GND
 204    GND  VSS88 @S9S_MB_2U_LIB.S9S_MB_2U(SCH_1):GND
 206    GND  VSS89 @S9S_MB_2U_LIB.S9S_MB_2U(SCH_1):GND
 208    GND  VSS90 @S9S_MB_2U_LIB.S9S_MB_2U(SCH_1):GND
 210    GND  VSS91 @S9S_MB_2U_LIB.S9S_MB_2U(SCH_1):GND
 212    GND  VSS92 @S9S_MB_2U_LIB.S9S_MB_2U(SCH_1):GND
 214    GND  VSS93 @S9S_MB_2U_LIB.S9S_MB_2U(SCH_1):GND
 216    GND  VSS94 @S9S_MB_2U_LIB.S9S_MB_2U(SCH_1):GND
 219    GND  VSS95 @S9S_MB_2U_LIB.S9S_MB_2U(SCH_1):GND
 222    GND  VSS96 @S9S_MB_2U_LIB.S9S_MB_2U(SCH_1):GND
 224    GND  VSS97 @S9S_MB_2U_LIB.S9S_MB_2U(SCH_1):GND
 226    GND  VSS98 @S9S_MB_2U_LIB.S9S_MB_2U(SCH_1):GND
 228    GND  VSS99 @S9S_MB_2U_LIB.S9S_MB_2U(SCH_1):GND
 233    GND VSS101 @S9S_MB_2U_LIB.S9S_MB_2U(SCH_1):GND
 237    GND VSS103 @S9S_MB_2U_LIB.S9S_MB_2U(SCH_1):GND
 242    GND VSS105 @S9S_MB_2U_LIB.S9S_MB_2U(SCH_1):GND
 244    GND VSS106 @S9S_MB_2U_LIB.S9S_MB_2U(SCH_1):GND
 246    GND VSS107 @S9S_MB_2U_LIB.S9S_MB_2U(SCH_1):GND
 248    GND VSS108 @S9S_MB_2U_LIB.S9S_MB_2U(SCH_1):GND
 251    GND VSS109 @S9S_MB_2U_LIB.S9S_MB_2U(SCH_1):GND
 253    GND VSS110 @S9S_MB_2U_LIB.S9S_MB_2U(SCH_1):GND
 255    GND VSS111 @S9S_MB_2U_LIB.S9S_MB_2U(SCH_1):GND
 257    GND VSS112 @S9S_MB_2U_LIB.S9S_MB_2U(SCH_1):GND
 259    GND VSS113 @S9S_MB_2U_LIB.S9S_MB_2U(SCH_1):GND
 262    GND VSS114 @S9S_MB_2U_LIB.S9S_MB_2U(SCH_1):GND
 264    GND VSS115 @S9S_MB_2U_LIB.S9S_MB_2U(SCH_1):GND
 266    GND VSS116 @S9S_MB_2U_LIB.S9S_MB_2U(SCH_1):GND
 268    GND VSS117 @S9S_MB_2U_LIB.S9S_MB_2U(SCH_1):GND
 270    GND VSS118 @S9S_MB_2U_LIB.S9S_MB_2U(SCH_1):GND
 273    GND VSS119 @S9S_MB_2U_LIB.S9S_MB_2U(SCH_1):GND
 275    GND VSS120 @S9S_MB_2U_LIB.S9S_MB_2U(SCH_1):GND
 277    GND VSS121 @S9S_MB_2U_LIB.S9S_MB_2U(SCH_1):GND
 279    GND VSS122 @S9S_MB_2U_LIB.S9S_MB_2U(SCH_1):GND
 281    GND VSS123 @S9S_MB_2U_LIB.S9S_MB_2U(SCH_1):GND
 284    GND VSS124 @S9S_MB_2U_LIB.S9S_MB_2U(SCH_1):GND
 286    GND VSS125 @S9S_MB_2U_LIB.S9S_MB_2U(SCH_1):GND
 288    GND VSS126 @S9S_MB_2U_LIB.S9S_MB_2U(SCH_1):GND
   1 P12V_S3_AUX_CPU1_NVDIMM VIN_BULK0 @S9S_MB_2U_LIB.S9S_MB_2U(SCH_1):P12V_S3_AUX_CPU1_NVDIMM
 145 P12V_S3_AUX_CPU1_NVDIMM VIN_BULK1 @S9S_MB_2U_LIB.S9S_MB_2U(SCH_1):P12V_S3_AUX_CPU1_NVDIMM
 146 P12V_S3_AUX_CPU1_NVDIMM VIN_BULK2 @S9S_MB_2U_LIB.S9S_MB_2U(SCH_1):P12V_S3_AUX_CPU1_NVDIMM
 230    GND VSS100 @S9S_MB_2U_LIB.S9S_MB_2U(SCH_1):GND
 235    GND VSS102 @S9S_MB_2U_LIB.S9S_MB_2U(SCH_1):GND
 240    GND VSS104 @S9S_MB_2U_LIB.S9S_MB_2U(SCH_1):GND
 132    GND  VSS58 @S9S_MB_2U_LIB.S9S_MB_2U(SCH_1):GND
 136    GND  VSS60 @S9S_MB_2U_LIB.S9S_MB_2U(SCH_1):GND
 139    GND  VSS61 @S9S_MB_2U_LIB.S9S_MB_2U(SCH_1):GND
 141    GND  VSS62 @S9S_MB_2U_LIB.S9S_MB_2U(SCH_1):GND
  G1    GND     G1 @S9S_MB_2U_LIB.S9S_MB_2U(SCH_1):GND
  G2    GND     G2 @S9S_MB_2U_LIB.S9S_MB_2U(SCH_1):GND
  G3    GND     G3 @S9S_MB_2U_LIB.S9S_MB_2U(SCH_1):GND

SCONN288_ADR50017P130CC-SCONN2A  I180  J31
   3 P3V3_AUX VIN_MGMT @S9S_MB_2U_LIB.S9S_MB_2U(SCH_1):P3V3_AUX
   2 TP_CHH_CPU1_DIMM1_FRU_0   RFU0 @S9S_MB_2U_LIB.S9S_MB_2U(SCH_1):TP_CHH_CPU1_DIMM1_FRU_0
 144 TP_CHH_CPU1_DIMM1_FRU_1   RFU1 @S9S_MB_2U_LIB.S9S_MB_2U(SCH_1):TP_CHH_CPU1_DIMM1_FRU_1
 149 TP_CHH_CPU1_DIMM1_FRU_2   RFU2 @S9S_MB_2U_LIB.S9S_MB_2U(SCH_1):TP_CHH_CPU1_DIMM1_FRU_2
 150 TP_CHH_CPU1_DIMM1_FRU_3   RFU3 @S9S_MB_2U_LIB.S9S_MB_2U(SCH_1):TP_CHH_CPU1_DIMM1_FRU_3
 220 TP_CHH_CPU1_DIMM1_FRU_4   RFU4 @S9S_MB_2U_LIB.S9S_MB_2U(SCH_1):TP_CHH_CPU1_DIMM1_FRU_4
 231 TP_CHH_CPU1_DIMM1_FRU_5   RFU5 @S9S_MB_2U_LIB.S9S_MB_2U(SCH_1):TP_CHH_CPU1_DIMM1_FRU_5
 232 TP_CHH_CPU1_DIMM1_FRU_6   RFU6 @S9S_MB_2U_LIB.S9S_MB_2U(SCH_1):TP_CHH_CPU1_DIMM1_FRU_6
 207 RST_M_GH_CPU1_FPGA_N RESET_N @S9S_MB_2U_LIB.S9S_MB_2U(SCH_1):RST_M_GH_CPU1_FPGA_N
 147 PWRGD_CHH_CPU1_DIMM1 PWR_GOOD||FAIL_N @S9S_MB_2U_LIB.S9S_MB_2U(SCH_1):PWRGD_CHH_CPU1_DIMM1
 227 M_H_CPU1_SB_PAR  PAR_B @S9S_MB_2U_LIB.S9S_MB_2U(SCH_1):M_H_CPU1_SB_PAR
  74 M_H_CPU1_SA_PAR  PAR_A @S9S_MB_2U_LIB.S9S_MB_2U(SCH_1):M_H_CPU1_SA_PAR
  87 M_H_CPU1_SB_RSP<0> LBS||RSP_B_N @S9S_MB_2U_LIB.S9S_MB_2U(SCH_1):M_H_CPU1_SB_RSP(0)
  86 M_H_CPU1_SA_RSP<0> LBD||RSP_A_N @S9S_MB_2U_LIB.S9S_MB_2U(SCH_1):M_H_CPU1_SA_RSP(0)
   5 I3C_SPD_DDREFGH_CPU1_LVC1_SDA   HSDA @S9S_MB_2U_LIB.S9S_MB_2U(SCH_1):I3C_SPD_DDREFGH_CPU1_LVC1_SDA
   4 I3C_SPD_DDREFGH_CPU1_LVC1_SCL_6   HSCL @S9S_MB_2U_LIB.S9S_MB_2U(SCH_1):I3C_SPD_DDREFGH_CPU1_LVC1_SCL_R7
 148 PD_CHH_CPU1_DIMM1_SAA    HSA @S9S_MB_2U_LIB.S9S_MB_2U(SCH_1):PD_CHH_CPU1_DIMM1_SAA
 100 M_H_CPU1_SB_DQ<0>  DQ0_B @S9S_MB_2U_LIB.S9S_MB_2U(SCH_1):M_H_CPU1_SB_DQ(0)
 102 M_H_CPU1_SB_DQ<1>  DQ1_B @S9S_MB_2U_LIB.S9S_MB_2U(SCH_1):M_H_CPU1_SB_DQ(1)
 245 M_H_CPU1_SB_DQ<2>  DQ2_B @S9S_MB_2U_LIB.S9S_MB_2U(SCH_1):M_H_CPU1_SB_DQ(2)
 247 M_H_CPU1_SB_DQ<3>  DQ3_B @S9S_MB_2U_LIB.S9S_MB_2U(SCH_1):M_H_CPU1_SB_DQ(3)
 107 M_H_CPU1_SB_DQ<4>  DQ4_B @S9S_MB_2U_LIB.S9S_MB_2U(SCH_1):M_H_CPU1_SB_DQ(4)
 109 M_H_CPU1_SB_DQ<5>  DQ5_B @S9S_MB_2U_LIB.S9S_MB_2U(SCH_1):M_H_CPU1_SB_DQ(5)
 252 M_H_CPU1_SB_DQ<6>  DQ6_B @S9S_MB_2U_LIB.S9S_MB_2U(SCH_1):M_H_CPU1_SB_DQ(6)
 254 M_H_CPU1_SB_DQ<7>  DQ7_B @S9S_MB_2U_LIB.S9S_MB_2U(SCH_1):M_H_CPU1_SB_DQ(7)
 111 M_H_CPU1_SB_DQ<8>  DQ8_B @S9S_MB_2U_LIB.S9S_MB_2U(SCH_1):M_H_CPU1_SB_DQ(8)
 113 M_H_CPU1_SB_DQ<9>  DQ9_B @S9S_MB_2U_LIB.S9S_MB_2U(SCH_1):M_H_CPU1_SB_DQ(9)
 256 M_H_CPU1_SB_DQ<10> DQ10_B @S9S_MB_2U_LIB.S9S_MB_2U(SCH_1):M_H_CPU1_SB_DQ(10)
 258 M_H_CPU1_SB_DQ<11> DQ11_B @S9S_MB_2U_LIB.S9S_MB_2U(SCH_1):M_H_CPU1_SB_DQ(11)
 118 M_H_CPU1_SB_DQ<12> DQ12_B @S9S_MB_2U_LIB.S9S_MB_2U(SCH_1):M_H_CPU1_SB_DQ(12)
 120 M_H_CPU1_SB_DQ<13> DQ13_B @S9S_MB_2U_LIB.S9S_MB_2U(SCH_1):M_H_CPU1_SB_DQ(13)
 263 M_H_CPU1_SB_DQ<14> DQ14_B @S9S_MB_2U_LIB.S9S_MB_2U(SCH_1):M_H_CPU1_SB_DQ(14)
 265 M_H_CPU1_SB_DQ<15> DQ15_B @S9S_MB_2U_LIB.S9S_MB_2U(SCH_1):M_H_CPU1_SB_DQ(15)
 122 M_H_CPU1_SB_DQ<16> DQ16_B @S9S_MB_2U_LIB.S9S_MB_2U(SCH_1):M_H_CPU1_SB_DQ(16)
 124 M_H_CPU1_SB_DQ<17> DQ17_B @S9S_MB_2U_LIB.S9S_MB_2U(SCH_1):M_H_CPU1_SB_DQ(17)
 267 M_H_CPU1_SB_DQ<18> DQ18_B @S9S_MB_2U_LIB.S9S_MB_2U(SCH_1):M_H_CPU1_SB_DQ(18)
 269 M_H_CPU1_SB_DQ<19> DQ19_B @S9S_MB_2U_LIB.S9S_MB_2U(SCH_1):M_H_CPU1_SB_DQ(19)
 129 M_H_CPU1_SB_DQ<20> DQ20_B @S9S_MB_2U_LIB.S9S_MB_2U(SCH_1):M_H_CPU1_SB_DQ(20)
 131 M_H_CPU1_SB_DQ<21> DQ21_B @S9S_MB_2U_LIB.S9S_MB_2U(SCH_1):M_H_CPU1_SB_DQ(21)
 274 M_H_CPU1_SB_DQ<22> DQ22_B @S9S_MB_2U_LIB.S9S_MB_2U(SCH_1):M_H_CPU1_SB_DQ(22)
 276 M_H_CPU1_SB_DQ<23> DQ23_B @S9S_MB_2U_LIB.S9S_MB_2U(SCH_1):M_H_CPU1_SB_DQ(23)
 133 M_H_CPU1_SB_DQ<24> DQ24_B @S9S_MB_2U_LIB.S9S_MB_2U(SCH_1):M_H_CPU1_SB_DQ(24)
 135 M_H_CPU1_SB_DQ<25> DQ25_B @S9S_MB_2U_LIB.S9S_MB_2U(SCH_1):M_H_CPU1_SB_DQ(25)
 278 M_H_CPU1_SB_DQ<26> DQ26_B @S9S_MB_2U_LIB.S9S_MB_2U(SCH_1):M_H_CPU1_SB_DQ(26)
 280 M_H_CPU1_SB_DQ<27> DQ27_B @S9S_MB_2U_LIB.S9S_MB_2U(SCH_1):M_H_CPU1_SB_DQ(27)
 140 M_H_CPU1_SB_DQ<28> DQ28_B @S9S_MB_2U_LIB.S9S_MB_2U(SCH_1):M_H_CPU1_SB_DQ(28)
 142 M_H_CPU1_SB_DQ<29> DQ29_B @S9S_MB_2U_LIB.S9S_MB_2U(SCH_1):M_H_CPU1_SB_DQ(29)
 285 M_H_CPU1_SB_DQ<30> DQ30_B @S9S_MB_2U_LIB.S9S_MB_2U(SCH_1):M_H_CPU1_SB_DQ(30)
 287 M_H_CPU1_SB_DQ<31> DQ31_B @S9S_MB_2U_LIB.S9S_MB_2U(SCH_1):M_H_CPU1_SB_DQ(31)
   7 M_H_CPU1_SA_DQ<0>  DQ0_A @S9S_MB_2U_LIB.S9S_MB_2U(SCH_1):M_H_CPU1_SA_DQ(0)
   9 M_H_CPU1_SA_DQ<1>  DQ1_A @S9S_MB_2U_LIB.S9S_MB_2U(SCH_1):M_H_CPU1_SA_DQ(1)
 152 M_H_CPU1_SA_DQ<2>  DQ2_A @S9S_MB_2U_LIB.S9S_MB_2U(SCH_1):M_H_CPU1_SA_DQ(2)
 154 M_H_CPU1_SA_DQ<3>  DQ3_A @S9S_MB_2U_LIB.S9S_MB_2U(SCH_1):M_H_CPU1_SA_DQ(3)
  14 M_H_CPU1_SA_DQ<4>  DQ4_A @S9S_MB_2U_LIB.S9S_MB_2U(SCH_1):M_H_CPU1_SA_DQ(4)
  16 M_H_CPU1_SA_DQ<5>  DQ5_A @S9S_MB_2U_LIB.S9S_MB_2U(SCH_1):M_H_CPU1_SA_DQ(5)
 159 M_H_CPU1_SA_DQ<6>  DQ6_A @S9S_MB_2U_LIB.S9S_MB_2U(SCH_1):M_H_CPU1_SA_DQ(6)
 161 M_H_CPU1_SA_DQ<7>  DQ7_A @S9S_MB_2U_LIB.S9S_MB_2U(SCH_1):M_H_CPU1_SA_DQ(7)
  18 M_H_CPU1_SA_DQ<8>  DQ8_A @S9S_MB_2U_LIB.S9S_MB_2U(SCH_1):M_H_CPU1_SA_DQ(8)
  20 M_H_CPU1_SA_DQ<9>  DQ9_A @S9S_MB_2U_LIB.S9S_MB_2U(SCH_1):M_H_CPU1_SA_DQ(9)
 163 M_H_CPU1_SA_DQ<10> DQ10_A @S9S_MB_2U_LIB.S9S_MB_2U(SCH_1):M_H_CPU1_SA_DQ(10)
 165 M_H_CPU1_SA_DQ<11> DQ11_A @S9S_MB_2U_LIB.S9S_MB_2U(SCH_1):M_H_CPU1_SA_DQ(11)
  25 M_H_CPU1_SA_DQ<12> DQ12_A @S9S_MB_2U_LIB.S9S_MB_2U(SCH_1):M_H_CPU1_SA_DQ(12)
  27 M_H_CPU1_SA_DQ<13> DQ13_A @S9S_MB_2U_LIB.S9S_MB_2U(SCH_1):M_H_CPU1_SA_DQ(13)
 170 M_H_CPU1_SA_DQ<14> DQ14_A @S9S_MB_2U_LIB.S9S_MB_2U(SCH_1):M_H_CPU1_SA_DQ(14)
 172 M_H_CPU1_SA_DQ<15> DQ15_A @S9S_MB_2U_LIB.S9S_MB_2U(SCH_1):M_H_CPU1_SA_DQ(15)
  29 M_H_CPU1_SA_DQ<16> DQ16_A @S9S_MB_2U_LIB.S9S_MB_2U(SCH_1):M_H_CPU1_SA_DQ(16)
  31 M_H_CPU1_SA_DQ<17> DQ17_A @S9S_MB_2U_LIB.S9S_MB_2U(SCH_1):M_H_CPU1_SA_DQ(17)
 174 M_H_CPU1_SA_DQ<18> DQ18_A @S9S_MB_2U_LIB.S9S_MB_2U(SCH_1):M_H_CPU1_SA_DQ(18)
 176 M_H_CPU1_SA_DQ<19> DQ19_A @S9S_MB_2U_LIB.S9S_MB_2U(SCH_1):M_H_CPU1_SA_DQ(19)
  36 M_H_CPU1_SA_DQ<20> DQ20_A @S9S_MB_2U_LIB.S9S_MB_2U(SCH_1):M_H_CPU1_SA_DQ(20)
  38 M_H_CPU1_SA_DQ<21> DQ21_A @S9S_MB_2U_LIB.S9S_MB_2U(SCH_1):M_H_CPU1_SA_DQ(21)
 181 M_H_CPU1_SA_DQ<22> DQ22_A @S9S_MB_2U_LIB.S9S_MB_2U(SCH_1):M_H_CPU1_SA_DQ(22)
 183 M_H_CPU1_SA_DQ<23> DQ23_A @S9S_MB_2U_LIB.S9S_MB_2U(SCH_1):M_H_CPU1_SA_DQ(23)
  40 M_H_CPU1_SA_DQ<24> DQ24_A @S9S_MB_2U_LIB.S9S_MB_2U(SCH_1):M_H_CPU1_SA_DQ(24)
  42 M_H_CPU1_SA_DQ<25> DQ25_A @S9S_MB_2U_LIB.S9S_MB_2U(SCH_1):M_H_CPU1_SA_DQ(25)
 185 M_H_CPU1_SA_DQ<26> DQ26_A @S9S_MB_2U_LIB.S9S_MB_2U(SCH_1):M_H_CPU1_SA_DQ(26)
 187 M_H_CPU1_SA_DQ<27> DQ27_A @S9S_MB_2U_LIB.S9S_MB_2U(SCH_1):M_H_CPU1_SA_DQ(27)
  47 M_H_CPU1_SA_DQ<28> DQ28_A @S9S_MB_2U_LIB.S9S_MB_2U(SCH_1):M_H_CPU1_SA_DQ(28)
  49 M_H_CPU1_SA_DQ<29> DQ29_A @S9S_MB_2U_LIB.S9S_MB_2U(SCH_1):M_H_CPU1_SA_DQ(29)
 192 M_H_CPU1_SA_DQ<30> DQ30_A @S9S_MB_2U_LIB.S9S_MB_2U(SCH_1):M_H_CPU1_SA_DQ(30)
 229 M_H_CPU1_SB_CS_N<1> CS1_B_N @S9S_MB_2U_LIB.S9S_MB_2U(SCH_1):M_H_CPU1_SB_CS_N(1)
 209 M_H_CPU1_SA_CS_N<1> CS1_A_N @S9S_MB_2U_LIB.S9S_MB_2U(SCH_1):M_H_CPU1_SA_CS_N(1)
  84 M_H_CPU1_SB_CS_N<0> CS0_B_N @S9S_MB_2U_LIB.S9S_MB_2U(SCH_1):M_H_CPU1_SB_CS_N(0)
  64 M_H_CPU1_SA_CS_N<0> CS0_A_N @S9S_MB_2U_LIB.S9S_MB_2U(SCH_1):M_H_CPU1_SA_CS_N(0)
 217 M_H_CPU1_CLK_DP<0>   CK_T @S9S_MB_2U_LIB.S9S_MB_2U(SCH_1):M_H_CPU1_CLK_DP(0)
 218 M_H_CPU1_CLK_DN<0>   CK_C @S9S_MB_2U_LIB.S9S_MB_2U(SCH_1):M_H_CPU1_CLK_DN(0)
  96 M_H_CPU1_SB_CB<0>  CB0_B @S9S_MB_2U_LIB.S9S_MB_2U(SCH_1):M_H_CPU1_SB_CB(0)
  98 M_H_CPU1_SB_CB<1>  CB1_B @S9S_MB_2U_LIB.S9S_MB_2U(SCH_1):M_H_CPU1_SB_CB(1)
 241 M_H_CPU1_SB_CB<2>  CB2_B @S9S_MB_2U_LIB.S9S_MB_2U(SCH_1):M_H_CPU1_SB_CB(2)
 243 M_H_CPU1_SB_CB<3>  CB3_B @S9S_MB_2U_LIB.S9S_MB_2U(SCH_1):M_H_CPU1_SB_CB(3)
  89 M_H_CPU1_SB_CB<4>  CB4_B @S9S_MB_2U_LIB.S9S_MB_2U(SCH_1):M_H_CPU1_SB_CB(4)
  91 M_H_CPU1_SB_CB<5>  CB5_B @S9S_MB_2U_LIB.S9S_MB_2U(SCH_1):M_H_CPU1_SB_CB(5)
 234 M_H_CPU1_SB_CB<6>  CB6_B @S9S_MB_2U_LIB.S9S_MB_2U(SCH_1):M_H_CPU1_SB_CB(6)
  51 M_H_CPU1_SA_CB<0>  CB0_A @S9S_MB_2U_LIB.S9S_MB_2U(SCH_1):M_H_CPU1_SA_CB(0)
 196 M_H_CPU1_SA_CB<2>  CB2_A @S9S_MB_2U_LIB.S9S_MB_2U(SCH_1):M_H_CPU1_SA_CB(2)
 198 M_H_CPU1_SA_CB<3>  CB3_A @S9S_MB_2U_LIB.S9S_MB_2U(SCH_1):M_H_CPU1_SA_CB(3)
  60 M_H_CPU1_SA_CB<5>  CB5_A @S9S_MB_2U_LIB.S9S_MB_2U(SCH_1):M_H_CPU1_SA_CB(5)
 203 M_H_CPU1_SA_CB<6>  CB6_A @S9S_MB_2U_LIB.S9S_MB_2U(SCH_1):M_H_CPU1_SA_CB(6)
  82 M_H_CPU1_SB_CA<6>  CA6_B @S9S_MB_2U_LIB.S9S_MB_2U(SCH_1):M_H_CPU1_SB_CA(6)
  72 M_H_CPU1_SA_CA<6>  CA6_A @S9S_MB_2U_LIB.S9S_MB_2U(SCH_1):M_H_CPU1_SA_CA(6)
 225 M_H_CPU1_SB_CA<5>  CA5_B @S9S_MB_2U_LIB.S9S_MB_2U(SCH_1):M_H_CPU1_SB_CA(5)
 215 M_H_CPU1_SA_CA<5>  CA5_A @S9S_MB_2U_LIB.S9S_MB_2U(SCH_1):M_H_CPU1_SA_CA(5)
  80 M_H_CPU1_SB_CA<4>  CA4_B @S9S_MB_2U_LIB.S9S_MB_2U(SCH_1):M_H_CPU1_SB_CA(4)
  70 M_H_CPU1_SA_CA<4>  CA4_A @S9S_MB_2U_LIB.S9S_MB_2U(SCH_1):M_H_CPU1_SA_CA(4)
 223 M_H_CPU1_SB_CA<3>  CA3_B @S9S_MB_2U_LIB.S9S_MB_2U(SCH_1):M_H_CPU1_SB_CA(3)
 213 M_H_CPU1_SA_CA<3>  CA3_A @S9S_MB_2U_LIB.S9S_MB_2U(SCH_1):M_H_CPU1_SA_CA(3)
  78 M_H_CPU1_SB_CA<2>  CA2_B @S9S_MB_2U_LIB.S9S_MB_2U(SCH_1):M_H_CPU1_SB_CA(2)
  68 M_H_CPU1_SA_CA<2>  CA2_A @S9S_MB_2U_LIB.S9S_MB_2U(SCH_1):M_H_CPU1_SA_CA(2)
 221 M_H_CPU1_SB_CA<1>  CA1_B @S9S_MB_2U_LIB.S9S_MB_2U(SCH_1):M_H_CPU1_SB_CA(1)
 211 M_H_CPU1_SA_CA<1>  CA1_A @S9S_MB_2U_LIB.S9S_MB_2U(SCH_1):M_H_CPU1_SA_CA(1)
  76 M_H_CPU1_SB_CA<0>  CA0_B @S9S_MB_2U_LIB.S9S_MB_2U(SCH_1):M_H_CPU1_SB_CA(0)
  66 M_H_CPU1_SA_CA<0>  CA0_A @S9S_MB_2U_LIB.S9S_MB_2U(SCH_1):M_H_CPU1_SA_CA(0)
  62 M_H_CPU1_ALERT_N ALERT_N @S9S_MB_2U_LIB.S9S_MB_2U(SCH_1):M_H_CPU1_ALERT_N
 236 M_H_CPU1_SB_CB<7>  CB7_B @S9S_MB_2U_LIB.S9S_MB_2U(SCH_1):M_H_CPU1_SB_CB(7)
  53 M_H_CPU1_SA_CB<1>  CB1_A @S9S_MB_2U_LIB.S9S_MB_2U(SCH_1):M_H_CPU1_SA_CB(1)
  58 M_H_CPU1_SA_CB<4>  CB4_A @S9S_MB_2U_LIB.S9S_MB_2U(SCH_1):M_H_CPU1_SA_CB(4)
 205 M_H_CPU1_SA_CB<7>  CB7_A @S9S_MB_2U_LIB.S9S_MB_2U(SCH_1):M_H_CPU1_SA_CB(7)
 194 M_H_CPU1_SA_DQ<31> DQ31_A @S9S_MB_2U_LIB.S9S_MB_2U(SCH_1):M_H_CPU1_SA_DQ(31)

SCONN288_ADR50017P130CC-SCONN2A  I181  J31
  93 M_H_CPU1_SB_DQS_DP<9> DQS9_B_T||TDQS9_B_T||DBI4_B_N @S9S_MB_2U_LIB.S9S_MB_2U(SCH_1):M_H_CPU1_SB_DQS_DP(9)
  94 M_H_CPU1_SB_DQS_DN<9> DQS9_B_C||TDQS9_B_C @S9S_MB_2U_LIB.S9S_MB_2U(SCH_1):M_H_CPU1_SB_DQS_DN(9)
 201 M_H_CPU1_SA_DQS_DP<9> DQS9_A_T||TDQS9_A_T @S9S_MB_2U_LIB.S9S_MB_2U(SCH_1):M_H_CPU1_SA_DQS_DP(9)
 200 M_H_CPU1_SA_DQS_DN<9> DQS9_A_C||TDQS9_A_C @S9S_MB_2U_LIB.S9S_MB_2U(SCH_1):M_H_CPU1_SA_DQS_DN(9)
 190 M_H_CPU1_SA_DQS_DP<8> DQS8_A_T||TDQS8_A_T @S9S_MB_2U_LIB.S9S_MB_2U(SCH_1):M_H_CPU1_SA_DQS_DP(8)
 189 M_H_CPU1_SA_DQS_DN<8> DQS8_A_C||TDQS8_A_C @S9S_MB_2U_LIB.S9S_MB_2U(SCH_1):M_H_CPU1_SA_DQS_DN(8)
 271 M_H_CPU1_SB_DQS_DN<7> DQS7_B_C||TDQS7_B_C @S9S_MB_2U_LIB.S9S_MB_2U(SCH_1):M_H_CPU1_SB_DQS_DN(7)
 179 M_H_CPU1_SA_DQS_DP<7> DQS7_A_T||TDQS7_A_T @S9S_MB_2U_LIB.S9S_MB_2U(SCH_1):M_H_CPU1_SA_DQS_DP(7)
 261 M_H_CPU1_SB_DQS_DP<6> DQS6_B_T||TDQS6_B_T @S9S_MB_2U_LIB.S9S_MB_2U(SCH_1):M_H_CPU1_SB_DQS_DP(6)
 260 M_H_CPU1_SB_DQS_DN<6> DQS6_B_C||TDQS6_B_C @S9S_MB_2U_LIB.S9S_MB_2U(SCH_1):M_H_CPU1_SB_DQS_DN(6)
 167 M_H_CPU1_SA_DQS_DN<6> DQS6_A_C||TDQS6_A_C||DQS6_A_T||TDQS6_A_T @S9S_MB_2U_LIB.S9S_MB_2U(SCH_1):M_H_CPU1_SA_DQS_DN(6)
 250 M_H_CPU1_SB_DQS_DP<5> DQS5_B_T||TDQS5_B_T @S9S_MB_2U_LIB.S9S_MB_2U(SCH_1):M_H_CPU1_SB_DQS_DP(5)
 249 M_H_CPU1_SB_DQS_DN<5> DQS5_B_C||TDQS5_B_C @S9S_MB_2U_LIB.S9S_MB_2U(SCH_1):M_H_CPU1_SB_DQS_DN(5)
 157 M_H_CPU1_SA_DQS_DP<5> DQS5_A_T||TDQS5_A_T @S9S_MB_2U_LIB.S9S_MB_2U(SCH_1):M_H_CPU1_SA_DQS_DP(5)
 156 M_H_CPU1_SA_DQS_DN<5> DQS5_A_C||TDQS5_A_C||DQS5_A_T||TDQS5_A_T @S9S_MB_2U_LIB.S9S_MB_2U(SCH_1):M_H_CPU1_SA_DQS_DN(5)
 239 M_H_CPU1_SB_DQS_DP<4> DQS4_B_T @S9S_MB_2U_LIB.S9S_MB_2U(SCH_1):M_H_CPU1_SB_DQS_DP(4)
 238 M_H_CPU1_SB_DQS_DN<4> DQS4_B_C @S9S_MB_2U_LIB.S9S_MB_2U(SCH_1):M_H_CPU1_SB_DQS_DN(4)
  55 M_H_CPU1_SA_DQS_DP<4> DQS4_A_T @S9S_MB_2U_LIB.S9S_MB_2U(SCH_1):M_H_CPU1_SA_DQS_DP(4)
  56 M_H_CPU1_SA_DQS_DN<4> DQS4_A_C @S9S_MB_2U_LIB.S9S_MB_2U(SCH_1):M_H_CPU1_SA_DQS_DN(4)
 137 M_H_CPU1_SB_DQS_DP<3> DQS3_B_T @S9S_MB_2U_LIB.S9S_MB_2U(SCH_1):M_H_CPU1_SB_DQS_DP(3)
 138 M_H_CPU1_SB_DQS_DN<3> DQS3_B_C @S9S_MB_2U_LIB.S9S_MB_2U(SCH_1):M_H_CPU1_SB_DQS_DN(3)
  44 M_H_CPU1_SA_DQS_DP<3> DQS3_A_T @S9S_MB_2U_LIB.S9S_MB_2U(SCH_1):M_H_CPU1_SA_DQS_DP(3)
  45 M_H_CPU1_SA_DQS_DN<3> DQS3_A_C @S9S_MB_2U_LIB.S9S_MB_2U(SCH_1):M_H_CPU1_SA_DQS_DN(3)
 126 M_H_CPU1_SB_DQS_DP<2> DQS2_B_T @S9S_MB_2U_LIB.S9S_MB_2U(SCH_1):M_H_CPU1_SB_DQS_DP(2)
 127 M_H_CPU1_SB_DQS_DN<2> DQS2_B_C @S9S_MB_2U_LIB.S9S_MB_2U(SCH_1):M_H_CPU1_SB_DQS_DN(2)
  33 M_H_CPU1_SA_DQS_DP<2> DQS2_A_T @S9S_MB_2U_LIB.S9S_MB_2U(SCH_1):M_H_CPU1_SA_DQS_DP(2)
  34 M_H_CPU1_SA_DQS_DN<2> DQS2_A_C @S9S_MB_2U_LIB.S9S_MB_2U(SCH_1):M_H_CPU1_SA_DQS_DN(2)
 115 M_H_CPU1_SB_DQS_DP<1> DQS1_B_T @S9S_MB_2U_LIB.S9S_MB_2U(SCH_1):M_H_CPU1_SB_DQS_DP(1)
 116 M_H_CPU1_SB_DQS_DN<1> DQS1_B_C @S9S_MB_2U_LIB.S9S_MB_2U(SCH_1):M_H_CPU1_SB_DQS_DN(1)
  22 M_H_CPU1_SA_DQS_DP<1> DQS1_A_T @S9S_MB_2U_LIB.S9S_MB_2U(SCH_1):M_H_CPU1_SA_DQS_DP(1)
  23 M_H_CPU1_SA_DQS_DN<1> DQS1_A_C @S9S_MB_2U_LIB.S9S_MB_2U(SCH_1):M_H_CPU1_SA_DQS_DN(1)
 104 M_H_CPU1_SB_DQS_DP<0> DQS0_B_T @S9S_MB_2U_LIB.S9S_MB_2U(SCH_1):M_H_CPU1_SB_DQS_DP(0)
 105 M_H_CPU1_SB_DQS_DN<0> DQS0_B_C @S9S_MB_2U_LIB.S9S_MB_2U(SCH_1):M_H_CPU1_SB_DQS_DN(0)
  11 M_H_CPU1_SA_DQS_DP<0> DQS0_A_T @S9S_MB_2U_LIB.S9S_MB_2U(SCH_1):M_H_CPU1_SA_DQS_DP(0)
  12 M_H_CPU1_SA_DQS_DN<0> DQS0_A_C @S9S_MB_2U_LIB.S9S_MB_2U(SCH_1):M_H_CPU1_SA_DQS_DN(0)
 272 M_H_CPU1_SB_DQS_DP<7> DQS7_B_T||TDQS7_B_T @S9S_MB_2U_LIB.S9S_MB_2U(SCH_1):M_H_CPU1_SB_DQS_DP(7)
 282 M_H_CPU1_SB_DQS_DN<8> DQS8_B_C||TDQS8_B_C @S9S_MB_2U_LIB.S9S_MB_2U(SCH_1):M_H_CPU1_SB_DQS_DN(8)
 283 M_H_CPU1_SB_DQS_DP<8> DQS8_B_T||TDQS8_B_T @S9S_MB_2U_LIB.S9S_MB_2U(SCH_1):M_H_CPU1_SB_DQS_DP(8)
 168 M_H_CPU1_SA_DQS_DP<6> DQS6_A_T||TDQS6_A_T @S9S_MB_2U_LIB.S9S_MB_2U(SCH_1):M_H_CPU1_SA_DQS_DP(6)
 178 M_H_CPU1_SA_DQS_DN<7> DQS7_A_C||TDQS7_A_C @S9S_MB_2U_LIB.S9S_MB_2U(SCH_1):M_H_CPU1_SA_DQS_DN(7)

Q_RES_0402LF-49.9,1%,1/16W,CHIA  I183  R3905
   1 I3C_SPD_DDREFGH_CPU1_LVC1_SCL_6      A @S9S_MB_2U_LIB.S9S_MB_2U(SCH_1):I3C_SPD_DDREFGH_CPU1_LVC1_SCL_R7
   2 I3C_SPD_DDREFGH_CPU1_LVC1_SCL      B @S9S_MB_2U_LIB.S9S_MB_2U(SCH_1):I3C_SPD_DDREFGH_CPU1_LVC1_SCL


DRAWING: @S9S_MB_2U_LIB.S9S_MB_2U(SCH_1):PAGE113 

Q_RES_0402LF-196K,1%,1/16W,CHIA  I2  R72
   1 PD_CHH_CPU1_DIMM2_SAA      A @S9S_MB_2U_LIB.S9S_MB_2U(SCH_1):PD_CHH_CPU1_DIMM2_SAA
   2    GND      B @S9S_MB_2U_LIB.S9S_MB_2U(SCH_1):GND

Q_CAP_C0402-2.2UF,6.3V,20%,X6SA  I116  C72
   1 P3V3_AUX      A @S9S_MB_2U_LIB.S9S_MB_2U(SCH_1):P3V3_AUX
   2    GND      B @S9S_MB_2U_LIB.S9S_MB_2U(SCH_1):GND

Q_CAP_C0805-10UF,16V,10%,X6S,CA  I120  C73
   1 P12V_S3_AUX_CPU1_NVDIMM      A @S9S_MB_2U_LIB.S9S_MB_2U(SCH_1):P12V_S3_AUX_CPU1_NVDIMM
   2    GND      B @S9S_MB_2U_LIB.S9S_MB_2U(SCH_1):GND

Q_CAP_C0805-10UF,16V,10%,X6S,CA  I122  C74
   1 P12V_S3_AUX_CPU1_NVDIMM      A @S9S_MB_2U_LIB.S9S_MB_2U(SCH_1):P12V_S3_AUX_CPU1_NVDIMM
   2    GND      B @S9S_MB_2U_LIB.S9S_MB_2U(SCH_1):GND

SCONN288_ADR50017P087CC-SCONN2A  I177  J32
   6    GND   VSS0 @S9S_MB_2U_LIB.S9S_MB_2U(SCH_1):GND
   8    GND   VSS1 @S9S_MB_2U_LIB.S9S_MB_2U(SCH_1):GND
  10    GND   VSS2 @S9S_MB_2U_LIB.S9S_MB_2U(SCH_1):GND
  13    GND   VSS3 @S9S_MB_2U_LIB.S9S_MB_2U(SCH_1):GND
  15    GND   VSS4 @S9S_MB_2U_LIB.S9S_MB_2U(SCH_1):GND
  17    GND   VSS5 @S9S_MB_2U_LIB.S9S_MB_2U(SCH_1):GND
  19    GND   VSS6 @S9S_MB_2U_LIB.S9S_MB_2U(SCH_1):GND
  21    GND   VSS7 @S9S_MB_2U_LIB.S9S_MB_2U(SCH_1):GND
  24    GND   VSS8 @S9S_MB_2U_LIB.S9S_MB_2U(SCH_1):GND
  26    GND   VSS9 @S9S_MB_2U_LIB.S9S_MB_2U(SCH_1):GND
  28    GND  VSS10 @S9S_MB_2U_LIB.S9S_MB_2U(SCH_1):GND
  30    GND  VSS11 @S9S_MB_2U_LIB.S9S_MB_2U(SCH_1):GND
  32    GND  VSS12 @S9S_MB_2U_LIB.S9S_MB_2U(SCH_1):GND
  35    GND  VSS13 @S9S_MB_2U_LIB.S9S_MB_2U(SCH_1):GND
  37    GND  VSS14 @S9S_MB_2U_LIB.S9S_MB_2U(SCH_1):GND
  39    GND  VSS15 @S9S_MB_2U_LIB.S9S_MB_2U(SCH_1):GND
  41    GND  VSS16 @S9S_MB_2U_LIB.S9S_MB_2U(SCH_1):GND
  43    GND  VSS17 @S9S_MB_2U_LIB.S9S_MB_2U(SCH_1):GND
  46    GND  VSS18 @S9S_MB_2U_LIB.S9S_MB_2U(SCH_1):GND
  48    GND  VSS19 @S9S_MB_2U_LIB.S9S_MB_2U(SCH_1):GND
  50    GND  VSS20 @S9S_MB_2U_LIB.S9S_MB_2U(SCH_1):GND
  52    GND  VSS21 @S9S_MB_2U_LIB.S9S_MB_2U(SCH_1):GND
  54    GND  VSS22 @S9S_MB_2U_LIB.S9S_MB_2U(SCH_1):GND
  57    GND  VSS23 @S9S_MB_2U_LIB.S9S_MB_2U(SCH_1):GND
  59    GND  VSS24 @S9S_MB_2U_LIB.S9S_MB_2U(SCH_1):GND
  61    GND  VSS25 @S9S_MB_2U_LIB.S9S_MB_2U(SCH_1):GND
  63    GND  VSS26 @S9S_MB_2U_LIB.S9S_MB_2U(SCH_1):GND
  65    GND  VSS27 @S9S_MB_2U_LIB.S9S_MB_2U(SCH_1):GND
  67    GND  VSS28 @S9S_MB_2U_LIB.S9S_MB_2U(SCH_1):GND
  69    GND  VSS29 @S9S_MB_2U_LIB.S9S_MB_2U(SCH_1):GND
  71    GND  VSS30 @S9S_MB_2U_LIB.S9S_MB_2U(SCH_1):GND
  73    GND  VSS31 @S9S_MB_2U_LIB.S9S_MB_2U(SCH_1):GND
  75    GND  VSS32 @S9S_MB_2U_LIB.S9S_MB_2U(SCH_1):GND
  77    GND  VSS33 @S9S_MB_2U_LIB.S9S_MB_2U(SCH_1):GND
  79    GND  VSS34 @S9S_MB_2U_LIB.S9S_MB_2U(SCH_1):GND
  81    GND  VSS35 @S9S_MB_2U_LIB.S9S_MB_2U(SCH_1):GND
  83    GND  VSS36 @S9S_MB_2U_LIB.S9S_MB_2U(SCH_1):GND
  85    GND  VSS37 @S9S_MB_2U_LIB.S9S_MB_2U(SCH_1):GND
  88    GND  VSS38 @S9S_MB_2U_LIB.S9S_MB_2U(SCH_1):GND
  90    GND  VSS39 @S9S_MB_2U_LIB.S9S_MB_2U(SCH_1):GND
  92    GND  VSS40 @S9S_MB_2U_LIB.S9S_MB_2U(SCH_1):GND
  95    GND  VSS41 @S9S_MB_2U_LIB.S9S_MB_2U(SCH_1):GND
  97    GND  VSS42 @S9S_MB_2U_LIB.S9S_MB_2U(SCH_1):GND
  99    GND  VSS43 @S9S_MB_2U_LIB.S9S_MB_2U(SCH_1):GND
 101    GND  VSS44 @S9S_MB_2U_LIB.S9S_MB_2U(SCH_1):GND
 103    GND  VSS45 @S9S_MB_2U_LIB.S9S_MB_2U(SCH_1):GND
 106    GND  VSS46 @S9S_MB_2U_LIB.S9S_MB_2U(SCH_1):GND
 108    GND  VSS47 @S9S_MB_2U_LIB.S9S_MB_2U(SCH_1):GND
 110    GND  VSS48 @S9S_MB_2U_LIB.S9S_MB_2U(SCH_1):GND
 112    GND  VSS49 @S9S_MB_2U_LIB.S9S_MB_2U(SCH_1):GND
 114    GND  VSS50 @S9S_MB_2U_LIB.S9S_MB_2U(SCH_1):GND
 117    GND  VSS51 @S9S_MB_2U_LIB.S9S_MB_2U(SCH_1):GND
 119    GND  VSS52 @S9S_MB_2U_LIB.S9S_MB_2U(SCH_1):GND
 121    GND  VSS53 @S9S_MB_2U_LIB.S9S_MB_2U(SCH_1):GND
 123    GND  VSS54 @S9S_MB_2U_LIB.S9S_MB_2U(SCH_1):GND
 125    GND  VSS55 @S9S_MB_2U_LIB.S9S_MB_2U(SCH_1):GND
 128    GND  VSS56 @S9S_MB_2U_LIB.S9S_MB_2U(SCH_1):GND
 130    GND  VSS57 @S9S_MB_2U_LIB.S9S_MB_2U(SCH_1):GND
 134    GND  VSS59 @S9S_MB_2U_LIB.S9S_MB_2U(SCH_1):GND
 143    GND  VSS63 @S9S_MB_2U_LIB.S9S_MB_2U(SCH_1):GND
 151    GND  VSS64 @S9S_MB_2U_LIB.S9S_MB_2U(SCH_1):GND
 153    GND  VSS65 @S9S_MB_2U_LIB.S9S_MB_2U(SCH_1):GND
 155    GND  VSS66 @S9S_MB_2U_LIB.S9S_MB_2U(SCH_1):GND
 158    GND  VSS67 @S9S_MB_2U_LIB.S9S_MB_2U(SCH_1):GND
 160    GND  VSS68 @S9S_MB_2U_LIB.S9S_MB_2U(SCH_1):GND
 162    GND  VSS69 @S9S_MB_2U_LIB.S9S_MB_2U(SCH_1):GND
 164    GND  VSS70 @S9S_MB_2U_LIB.S9S_MB_2U(SCH_1):GND
 166    GND  VSS71 @S9S_MB_2U_LIB.S9S_MB_2U(SCH_1):GND
 169    GND  VSS72 @S9S_MB_2U_LIB.S9S_MB_2U(SCH_1):GND
 171    GND  VSS73 @S9S_MB_2U_LIB.S9S_MB_2U(SCH_1):GND
 173    GND  VSS74 @S9S_MB_2U_LIB.S9S_MB_2U(SCH_1):GND
 175    GND  VSS75 @S9S_MB_2U_LIB.S9S_MB_2U(SCH_1):GND
 177    GND  VSS76 @S9S_MB_2U_LIB.S9S_MB_2U(SCH_1):GND
 180    GND  VSS77 @S9S_MB_2U_LIB.S9S_MB_2U(SCH_1):GND
 182    GND  VSS78 @S9S_MB_2U_LIB.S9S_MB_2U(SCH_1):GND
 184    GND  VSS79 @S9S_MB_2U_LIB.S9S_MB_2U(SCH_1):GND
 186    GND  VSS80 @S9S_MB_2U_LIB.S9S_MB_2U(SCH_1):GND
 188    GND  VSS81 @S9S_MB_2U_LIB.S9S_MB_2U(SCH_1):GND
 191    GND  VSS82 @S9S_MB_2U_LIB.S9S_MB_2U(SCH_1):GND
 193    GND  VSS83 @S9S_MB_2U_LIB.S9S_MB_2U(SCH_1):GND
 195    GND  VSS84 @S9S_MB_2U_LIB.S9S_MB_2U(SCH_1):GND
 197    GND  VSS85 @S9S_MB_2U_LIB.S9S_MB_2U(SCH_1):GND
 199    GND  VSS86 @S9S_MB_2U_LIB.S9S_MB_2U(SCH_1):GND
 202    GND  VSS87 @S9S_MB_2U_LIB.S9S_MB_2U(SCH_1):GND
 204    GND  VSS88 @S9S_MB_2U_LIB.S9S_MB_2U(SCH_1):GND
 206    GND  VSS89 @S9S_MB_2U_LIB.S9S_MB_2U(SCH_1):GND
 208    GND  VSS90 @S9S_MB_2U_LIB.S9S_MB_2U(SCH_1):GND
 210    GND  VSS91 @S9S_MB_2U_LIB.S9S_MB_2U(SCH_1):GND
 212    GND  VSS92 @S9S_MB_2U_LIB.S9S_MB_2U(SCH_1):GND
 214    GND  VSS93 @S9S_MB_2U_LIB.S9S_MB_2U(SCH_1):GND
 216    GND  VSS94 @S9S_MB_2U_LIB.S9S_MB_2U(SCH_1):GND
 219    GND  VSS95 @S9S_MB_2U_LIB.S9S_MB_2U(SCH_1):GND
 222    GND  VSS96 @S9S_MB_2U_LIB.S9S_MB_2U(SCH_1):GND
 224    GND  VSS97 @S9S_MB_2U_LIB.S9S_MB_2U(SCH_1):GND
 226    GND  VSS98 @S9S_MB_2U_LIB.S9S_MB_2U(SCH_1):GND
 228    GND  VSS99 @S9S_MB_2U_LIB.S9S_MB_2U(SCH_1):GND
 233    GND VSS101 @S9S_MB_2U_LIB.S9S_MB_2U(SCH_1):GND
 237    GND VSS103 @S9S_MB_2U_LIB.S9S_MB_2U(SCH_1):GND
 242    GND VSS105 @S9S_MB_2U_LIB.S9S_MB_2U(SCH_1):GND
 244    GND VSS106 @S9S_MB_2U_LIB.S9S_MB_2U(SCH_1):GND
 246    GND VSS107 @S9S_MB_2U_LIB.S9S_MB_2U(SCH_1):GND
 248    GND VSS108 @S9S_MB_2U_LIB.S9S_MB_2U(SCH_1):GND
 251    GND VSS109 @S9S_MB_2U_LIB.S9S_MB_2U(SCH_1):GND
 253    GND VSS110 @S9S_MB_2U_LIB.S9S_MB_2U(SCH_1):GND
 255    GND VSS111 @S9S_MB_2U_LIB.S9S_MB_2U(SCH_1):GND
 257    GND VSS112 @S9S_MB_2U_LIB.S9S_MB_2U(SCH_1):GND
 259    GND VSS113 @S9S_MB_2U_LIB.S9S_MB_2U(SCH_1):GND
 262    GND VSS114 @S9S_MB_2U_LIB.S9S_MB_2U(SCH_1):GND
 264    GND VSS115 @S9S_MB_2U_LIB.S9S_MB_2U(SCH_1):GND
 266    GND VSS116 @S9S_MB_2U_LIB.S9S_MB_2U(SCH_1):GND
 268    GND VSS117 @S9S_MB_2U_LIB.S9S_MB_2U(SCH_1):GND
 270    GND VSS118 @S9S_MB_2U_LIB.S9S_MB_2U(SCH_1):GND
 273    GND VSS119 @S9S_MB_2U_LIB.S9S_MB_2U(SCH_1):GND
 275    GND VSS120 @S9S_MB_2U_LIB.S9S_MB_2U(SCH_1):GND
 277    GND VSS121 @S9S_MB_2U_LIB.S9S_MB_2U(SCH_1):GND
 279    GND VSS122 @S9S_MB_2U_LIB.S9S_MB_2U(SCH_1):GND
 281    GND VSS123 @S9S_MB_2U_LIB.S9S_MB_2U(SCH_1):GND
 284    GND VSS124 @S9S_MB_2U_LIB.S9S_MB_2U(SCH_1):GND
 286    GND VSS125 @S9S_MB_2U_LIB.S9S_MB_2U(SCH_1):GND
 288    GND VSS126 @S9S_MB_2U_LIB.S9S_MB_2U(SCH_1):GND
   1 P12V_S3_AUX_CPU1_NVDIMM VIN_BULK0 @S9S_MB_2U_LIB.S9S_MB_2U(SCH_1):P12V_S3_AUX_CPU1_NVDIMM
 145 P12V_S3_AUX_CPU1_NVDIMM VIN_BULK1 @S9S_MB_2U_LIB.S9S_MB_2U(SCH_1):P12V_S3_AUX_CPU1_NVDIMM
 146 P12V_S3_AUX_CPU1_NVDIMM VIN_BULK2 @S9S_MB_2U_LIB.S9S_MB_2U(SCH_1):P12V_S3_AUX_CPU1_NVDIMM
 230    GND VSS100 @S9S_MB_2U_LIB.S9S_MB_2U(SCH_1):GND
 235    GND VSS102 @S9S_MB_2U_LIB.S9S_MB_2U(SCH_1):GND
 240    GND VSS104 @S9S_MB_2U_LIB.S9S_MB_2U(SCH_1):GND
 132    GND  VSS58 @S9S_MB_2U_LIB.S9S_MB_2U(SCH_1):GND
 136    GND  VSS60 @S9S_MB_2U_LIB.S9S_MB_2U(SCH_1):GND
 139    GND  VSS61 @S9S_MB_2U_LIB.S9S_MB_2U(SCH_1):GND
 141    GND  VSS62 @S9S_MB_2U_LIB.S9S_MB_2U(SCH_1):GND
  G1    GND     G1 @S9S_MB_2U_LIB.S9S_MB_2U(SCH_1):GND
  G2    GND     G2 @S9S_MB_2U_LIB.S9S_MB_2U(SCH_1):GND
  G3    GND     G3 @S9S_MB_2U_LIB.S9S_MB_2U(SCH_1):GND

SCONN288_ADR50017P087CC-SCONN2A  I179  J32
   3 P3V3_AUX VIN_MGMT @S9S_MB_2U_LIB.S9S_MB_2U(SCH_1):P3V3_AUX
   2 TP_CHH_CPU1_DIMM2_FRU_0   RFU0 @S9S_MB_2U_LIB.S9S_MB_2U(SCH_1):TP_CHH_CPU1_DIMM2_FRU_0
 144 TP_CHH_CPU1_DIMM2_FRU_1   RFU1 @S9S_MB_2U_LIB.S9S_MB_2U(SCH_1):TP_CHH_CPU1_DIMM2_FRU_1
 149 TP_CHH_CPU1_DIMM2_FRU_2   RFU2 @S9S_MB_2U_LIB.S9S_MB_2U(SCH_1):TP_CHH_CPU1_DIMM2_FRU_2
 150 TP_CHH_CPU1_DIMM2_FRU_3   RFU3 @S9S_MB_2U_LIB.S9S_MB_2U(SCH_1):TP_CHH_CPU1_DIMM2_FRU_3
 220 TP_CHH_CPU1_DIMM2_FRU_4   RFU4 @S9S_MB_2U_LIB.S9S_MB_2U(SCH_1):TP_CHH_CPU1_DIMM2_FRU_4
 231 TP_CHH_CPU1_DIMM2_FRU_5   RFU5 @S9S_MB_2U_LIB.S9S_MB_2U(SCH_1):TP_CHH_CPU1_DIMM2_FRU_5
 232 TP_CHH_CPU1_DIMM2_FRU_6   RFU6 @S9S_MB_2U_LIB.S9S_MB_2U(SCH_1):TP_CHH_CPU1_DIMM2_FRU_6
 207 RST_M_GH_CPU1_FPGA_N RESET_N @S9S_MB_2U_LIB.S9S_MB_2U(SCH_1):RST_M_GH_CPU1_FPGA_N
 147 PWRGD_CHH_CPU1_DIMM2 PWR_GOOD||FAIL_N @S9S_MB_2U_LIB.S9S_MB_2U(SCH_1):PWRGD_CHH_CPU1_DIMM2
 227 M_H_CPU1_SB_PAR  PAR_B @S9S_MB_2U_LIB.S9S_MB_2U(SCH_1):M_H_CPU1_SB_PAR
  74 M_H_CPU1_SA_PAR  PAR_A @S9S_MB_2U_LIB.S9S_MB_2U(SCH_1):M_H_CPU1_SA_PAR
  87 M_H_CPU1_SB_RSP<1> LBS||RSP_B_N @S9S_MB_2U_LIB.S9S_MB_2U(SCH_1):M_H_CPU1_SB_RSP(1)
  86 M_H_CPU1_SA_RSP<1> LBD||RSP_A_N @S9S_MB_2U_LIB.S9S_MB_2U(SCH_1):M_H_CPU1_SA_RSP(1)
   5 I3C_SPD_DDREFGH_CPU1_LVC1_SDA   HSDA @S9S_MB_2U_LIB.S9S_MB_2U(SCH_1):I3C_SPD_DDREFGH_CPU1_LVC1_SDA
   4 I3C_SPD_DDREFGH_CPU1_LVC1_SCL_7   HSCL @S9S_MB_2U_LIB.S9S_MB_2U(SCH_1):I3C_SPD_DDREFGH_CPU1_LVC1_SCL_R8
 148 PD_CHH_CPU1_DIMM2_SAA    HSA @S9S_MB_2U_LIB.S9S_MB_2U(SCH_1):PD_CHH_CPU1_DIMM2_SAA
 100 M_H_CPU1_SB_DQ<0>  DQ0_B @S9S_MB_2U_LIB.S9S_MB_2U(SCH_1):M_H_CPU1_SB_DQ(0)
 102 M_H_CPU1_SB_DQ<1>  DQ1_B @S9S_MB_2U_LIB.S9S_MB_2U(SCH_1):M_H_CPU1_SB_DQ(1)
 245 M_H_CPU1_SB_DQ<2>  DQ2_B @S9S_MB_2U_LIB.S9S_MB_2U(SCH_1):M_H_CPU1_SB_DQ(2)
 247 M_H_CPU1_SB_DQ<3>  DQ3_B @S9S_MB_2U_LIB.S9S_MB_2U(SCH_1):M_H_CPU1_SB_DQ(3)
 107 M_H_CPU1_SB_DQ<4>  DQ4_B @S9S_MB_2U_LIB.S9S_MB_2U(SCH_1):M_H_CPU1_SB_DQ(4)
 109 M_H_CPU1_SB_DQ<5>  DQ5_B @S9S_MB_2U_LIB.S9S_MB_2U(SCH_1):M_H_CPU1_SB_DQ(5)
 252 M_H_CPU1_SB_DQ<6>  DQ6_B @S9S_MB_2U_LIB.S9S_MB_2U(SCH_1):M_H_CPU1_SB_DQ(6)
 254 M_H_CPU1_SB_DQ<7>  DQ7_B @S9S_MB_2U_LIB.S9S_MB_2U(SCH_1):M_H_CPU1_SB_DQ(7)
 111 M_H_CPU1_SB_DQ<8>  DQ8_B @S9S_MB_2U_LIB.S9S_MB_2U(SCH_1):M_H_CPU1_SB_DQ(8)
 113 M_H_CPU1_SB_DQ<9>  DQ9_B @S9S_MB_2U_LIB.S9S_MB_2U(SCH_1):M_H_CPU1_SB_DQ(9)
 256 M_H_CPU1_SB_DQ<10> DQ10_B @S9S_MB_2U_LIB.S9S_MB_2U(SCH_1):M_H_CPU1_SB_DQ(10)
 258 M_H_CPU1_SB_DQ<11> DQ11_B @S9S_MB_2U_LIB.S9S_MB_2U(SCH_1):M_H_CPU1_SB_DQ(11)
 118 M_H_CPU1_SB_DQ<12> DQ12_B @S9S_MB_2U_LIB.S9S_MB_2U(SCH_1):M_H_CPU1_SB_DQ(12)
 120 M_H_CPU1_SB_DQ<13> DQ13_B @S9S_MB_2U_LIB.S9S_MB_2U(SCH_1):M_H_CPU1_SB_DQ(13)
 263 M_H_CPU1_SB_DQ<14> DQ14_B @S9S_MB_2U_LIB.S9S_MB_2U(SCH_1):M_H_CPU1_SB_DQ(14)
 265 M_H_CPU1_SB_DQ<15> DQ15_B @S9S_MB_2U_LIB.S9S_MB_2U(SCH_1):M_H_CPU1_SB_DQ(15)
 122 M_H_CPU1_SB_DQ<16> DQ16_B @S9S_MB_2U_LIB.S9S_MB_2U(SCH_1):M_H_CPU1_SB_DQ(16)
 124 M_H_CPU1_SB_DQ<17> DQ17_B @S9S_MB_2U_LIB.S9S_MB_2U(SCH_1):M_H_CPU1_SB_DQ(17)
 267 M_H_CPU1_SB_DQ<18> DQ18_B @S9S_MB_2U_LIB.S9S_MB_2U(SCH_1):M_H_CPU1_SB_DQ(18)
 269 M_H_CPU1_SB_DQ<19> DQ19_B @S9S_MB_2U_LIB.S9S_MB_2U(SCH_1):M_H_CPU1_SB_DQ(19)
 129 M_H_CPU1_SB_DQ<20> DQ20_B @S9S_MB_2U_LIB.S9S_MB_2U(SCH_1):M_H_CPU1_SB_DQ(20)
 131 M_H_CPU1_SB_DQ<21> DQ21_B @S9S_MB_2U_LIB.S9S_MB_2U(SCH_1):M_H_CPU1_SB_DQ(21)
 274 M_H_CPU1_SB_DQ<22> DQ22_B @S9S_MB_2U_LIB.S9S_MB_2U(SCH_1):M_H_CPU1_SB_DQ(22)
 276 M_H_CPU1_SB_DQ<23> DQ23_B @S9S_MB_2U_LIB.S9S_MB_2U(SCH_1):M_H_CPU1_SB_DQ(23)
 133 M_H_CPU1_SB_DQ<24> DQ24_B @S9S_MB_2U_LIB.S9S_MB_2U(SCH_1):M_H_CPU1_SB_DQ(24)
 135 M_H_CPU1_SB_DQ<25> DQ25_B @S9S_MB_2U_LIB.S9S_MB_2U(SCH_1):M_H_CPU1_SB_DQ(25)
 278 M_H_CPU1_SB_DQ<26> DQ26_B @S9S_MB_2U_LIB.S9S_MB_2U(SCH_1):M_H_CPU1_SB_DQ(26)
 280 M_H_CPU1_SB_DQ<27> DQ27_B @S9S_MB_2U_LIB.S9S_MB_2U(SCH_1):M_H_CPU1_SB_DQ(27)
 140 M_H_CPU1_SB_DQ<28> DQ28_B @S9S_MB_2U_LIB.S9S_MB_2U(SCH_1):M_H_CPU1_SB_DQ(28)
 142 M_H_CPU1_SB_DQ<29> DQ29_B @S9S_MB_2U_LIB.S9S_MB_2U(SCH_1):M_H_CPU1_SB_DQ(29)
 285 M_H_CPU1_SB_DQ<30> DQ30_B @S9S_MB_2U_LIB.S9S_MB_2U(SCH_1):M_H_CPU1_SB_DQ(30)
 287 M_H_CPU1_SB_DQ<31> DQ31_B @S9S_MB_2U_LIB.S9S_MB_2U(SCH_1):M_H_CPU1_SB_DQ(31)
   7 M_H_CPU1_SA_DQ<0>  DQ0_A @S9S_MB_2U_LIB.S9S_MB_2U(SCH_1):M_H_CPU1_SA_DQ(0)
   9 M_H_CPU1_SA_DQ<1>  DQ1_A @S9S_MB_2U_LIB.S9S_MB_2U(SCH_1):M_H_CPU1_SA_DQ(1)
 152 M_H_CPU1_SA_DQ<2>  DQ2_A @S9S_MB_2U_LIB.S9S_MB_2U(SCH_1):M_H_CPU1_SA_DQ(2)
 154 M_H_CPU1_SA_DQ<3>  DQ3_A @S9S_MB_2U_LIB.S9S_MB_2U(SCH_1):M_H_CPU1_SA_DQ(3)
  14 M_H_CPU1_SA_DQ<4>  DQ4_A @S9S_MB_2U_LIB.S9S_MB_2U(SCH_1):M_H_CPU1_SA_DQ(4)
  16 M_H_CPU1_SA_DQ<5>  DQ5_A @S9S_MB_2U_LIB.S9S_MB_2U(SCH_1):M_H_CPU1_SA_DQ(5)
 159 M_H_CPU1_SA_DQ<6>  DQ6_A @S9S_MB_2U_LIB.S9S_MB_2U(SCH_1):M_H_CPU1_SA_DQ(6)
 161 M_H_CPU1_SA_DQ<7>  DQ7_A @S9S_MB_2U_LIB.S9S_MB_2U(SCH_1):M_H_CPU1_SA_DQ(7)
  18 M_H_CPU1_SA_DQ<8>  DQ8_A @S9S_MB_2U_LIB.S9S_MB_2U(SCH_1):M_H_CPU1_SA_DQ(8)
  20 M_H_CPU1_SA_DQ<9>  DQ9_A @S9S_MB_2U_LIB.S9S_MB_2U(SCH_1):M_H_CPU1_SA_DQ(9)
 163 M_H_CPU1_SA_DQ<10> DQ10_A @S9S_MB_2U_LIB.S9S_MB_2U(SCH_1):M_H_CPU1_SA_DQ(10)
 165 M_H_CPU1_SA_DQ<11> DQ11_A @S9S_MB_2U_LIB.S9S_MB_2U(SCH_1):M_H_CPU1_SA_DQ(11)
  25 M_H_CPU1_SA_DQ<12> DQ12_A @S9S_MB_2U_LIB.S9S_MB_2U(SCH_1):M_H_CPU1_SA_DQ(12)
  27 M_H_CPU1_SA_DQ<13> DQ13_A @S9S_MB_2U_LIB.S9S_MB_2U(SCH_1):M_H_CPU1_SA_DQ(13)
 170 M_H_CPU1_SA_DQ<14> DQ14_A @S9S_MB_2U_LIB.S9S_MB_2U(SCH_1):M_H_CPU1_SA_DQ(14)
 172 M_H_CPU1_SA_DQ<15> DQ15_A @S9S_MB_2U_LIB.S9S_MB_2U(SCH_1):M_H_CPU1_SA_DQ(15)
  29 M_H_CPU1_SA_DQ<16> DQ16_A @S9S_MB_2U_LIB.S9S_MB_2U(SCH_1):M_H_CPU1_SA_DQ(16)
  31 M_H_CPU1_SA_DQ<17> DQ17_A @S9S_MB_2U_LIB.S9S_MB_2U(SCH_1):M_H_CPU1_SA_DQ(17)
 174 M_H_CPU1_SA_DQ<18> DQ18_A @S9S_MB_2U_LIB.S9S_MB_2U(SCH_1):M_H_CPU1_SA_DQ(18)
 176 M_H_CPU1_SA_DQ<19> DQ19_A @S9S_MB_2U_LIB.S9S_MB_2U(SCH_1):M_H_CPU1_SA_DQ(19)
  36 M_H_CPU1_SA_DQ<20> DQ20_A @S9S_MB_2U_LIB.S9S_MB_2U(SCH_1):M_H_CPU1_SA_DQ(20)
  38 M_H_CPU1_SA_DQ<21> DQ21_A @S9S_MB_2U_LIB.S9S_MB_2U(SCH_1):M_H_CPU1_SA_DQ(21)
 181 M_H_CPU1_SA_DQ<22> DQ22_A @S9S_MB_2U_LIB.S9S_MB_2U(SCH_1):M_H_CPU1_SA_DQ(22)
 183 M_H_CPU1_SA_DQ<23> DQ23_A @S9S_MB_2U_LIB.S9S_MB_2U(SCH_1):M_H_CPU1_SA_DQ(23)
  40 M_H_CPU1_SA_DQ<24> DQ24_A @S9S_MB_2U_LIB.S9S_MB_2U(SCH_1):M_H_CPU1_SA_DQ(24)
  42 M_H_CPU1_SA_DQ<25> DQ25_A @S9S_MB_2U_LIB.S9S_MB_2U(SCH_1):M_H_CPU1_SA_DQ(25)
 185 M_H_CPU1_SA_DQ<26> DQ26_A @S9S_MB_2U_LIB.S9S_MB_2U(SCH_1):M_H_CPU1_SA_DQ(26)
 187 M_H_CPU1_SA_DQ<27> DQ27_A @S9S_MB_2U_LIB.S9S_MB_2U(SCH_1):M_H_CPU1_SA_DQ(27)
  47 M_H_CPU1_SA_DQ<28> DQ28_A @S9S_MB_2U_LIB.S9S_MB_2U(SCH_1):M_H_CPU1_SA_DQ(28)
  49 M_H_CPU1_SA_DQ<29> DQ29_A @S9S_MB_2U_LIB.S9S_MB_2U(SCH_1):M_H_CPU1_SA_DQ(29)
 192 M_H_CPU1_SA_DQ<30> DQ30_A @S9S_MB_2U_LIB.S9S_MB_2U(SCH_1):M_H_CPU1_SA_DQ(30)
 229 M_H_CPU1_SB_CS_N<3> CS1_B_N @S9S_MB_2U_LIB.S9S_MB_2U(SCH_1):M_H_CPU1_SB_CS_N(3)
 209 M_H_CPU1_SA_CS_N<3> CS1_A_N @S9S_MB_2U_LIB.S9S_MB_2U(SCH_1):M_H_CPU1_SA_CS_N(3)
  84 M_H_CPU1_SB_CS_N<2> CS0_B_N @S9S_MB_2U_LIB.S9S_MB_2U(SCH_1):M_H_CPU1_SB_CS_N(2)
  64 M_H_CPU1_SA_CS_N<2> CS0_A_N @S9S_MB_2U_LIB.S9S_MB_2U(SCH_1):M_H_CPU1_SA_CS_N(2)
 217 M_H_CPU1_CLK_DP<1>   CK_T @S9S_MB_2U_LIB.S9S_MB_2U(SCH_1):M_H_CPU1_CLK_DP(1)
 218 M_H_CPU1_CLK_DN<1>   CK_C @S9S_MB_2U_LIB.S9S_MB_2U(SCH_1):M_H_CPU1_CLK_DN(1)
  96 M_H_CPU1_SB_CB<0>  CB0_B @S9S_MB_2U_LIB.S9S_MB_2U(SCH_1):M_H_CPU1_SB_CB(0)
  98 M_H_CPU1_SB_CB<1>  CB1_B @S9S_MB_2U_LIB.S9S_MB_2U(SCH_1):M_H_CPU1_SB_CB(1)
 241 M_H_CPU1_SB_CB<2>  CB2_B @S9S_MB_2U_LIB.S9S_MB_2U(SCH_1):M_H_CPU1_SB_CB(2)
 243 M_H_CPU1_SB_CB<3>  CB3_B @S9S_MB_2U_LIB.S9S_MB_2U(SCH_1):M_H_CPU1_SB_CB(3)
  89 M_H_CPU1_SB_CB<4>  CB4_B @S9S_MB_2U_LIB.S9S_MB_2U(SCH_1):M_H_CPU1_SB_CB(4)
  91 M_H_CPU1_SB_CB<5>  CB5_B @S9S_MB_2U_LIB.S9S_MB_2U(SCH_1):M_H_CPU1_SB_CB(5)
 234 M_H_CPU1_SB_CB<6>  CB6_B @S9S_MB_2U_LIB.S9S_MB_2U(SCH_1):M_H_CPU1_SB_CB(6)
  51 M_H_CPU1_SA_CB<0>  CB0_A @S9S_MB_2U_LIB.S9S_MB_2U(SCH_1):M_H_CPU1_SA_CB(0)
 196 M_H_CPU1_SA_CB<2>  CB2_A @S9S_MB_2U_LIB.S9S_MB_2U(SCH_1):M_H_CPU1_SA_CB(2)
 198 M_H_CPU1_SA_CB<3>  CB3_A @S9S_MB_2U_LIB.S9S_MB_2U(SCH_1):M_H_CPU1_SA_CB(3)
  60 M_H_CPU1_SA_CB<5>  CB5_A @S9S_MB_2U_LIB.S9S_MB_2U(SCH_1):M_H_CPU1_SA_CB(5)
 203 M_H_CPU1_SA_CB<6>  CB6_A @S9S_MB_2U_LIB.S9S_MB_2U(SCH_1):M_H_CPU1_SA_CB(6)
  82 M_H_CPU1_SB_CA<6>  CA6_B @S9S_MB_2U_LIB.S9S_MB_2U(SCH_1):M_H_CPU1_SB_CA(6)
  72 M_H_CPU1_SA_CA<6>  CA6_A @S9S_MB_2U_LIB.S9S_MB_2U(SCH_1):M_H_CPU1_SA_CA(6)
 225 M_H_CPU1_SB_CA<5>  CA5_B @S9S_MB_2U_LIB.S9S_MB_2U(SCH_1):M_H_CPU1_SB_CA(5)
 215 M_H_CPU1_SA_CA<5>  CA5_A @S9S_MB_2U_LIB.S9S_MB_2U(SCH_1):M_H_CPU1_SA_CA(5)
  80 M_H_CPU1_SB_CA<4>  CA4_B @S9S_MB_2U_LIB.S9S_MB_2U(SCH_1):M_H_CPU1_SB_CA(4)
  70 M_H_CPU1_SA_CA<4>  CA4_A @S9S_MB_2U_LIB.S9S_MB_2U(SCH_1):M_H_CPU1_SA_CA(4)
 223 M_H_CPU1_SB_CA<3>  CA3_B @S9S_MB_2U_LIB.S9S_MB_2U(SCH_1):M_H_CPU1_SB_CA(3)
 213 M_H_CPU1_SA_CA<3>  CA3_A @S9S_MB_2U_LIB.S9S_MB_2U(SCH_1):M_H_CPU1_SA_CA(3)
  78 M_H_CPU1_SB_CA<2>  CA2_B @S9S_MB_2U_LIB.S9S_MB_2U(SCH_1):M_H_CPU1_SB_CA(2)
  68 M_H_CPU1_SA_CA<2>  CA2_A @S9S_MB_2U_LIB.S9S_MB_2U(SCH_1):M_H_CPU1_SA_CA(2)
 221 M_H_CPU1_SB_CA<1>  CA1_B @S9S_MB_2U_LIB.S9S_MB_2U(SCH_1):M_H_CPU1_SB_CA(1)
 211 M_H_CPU1_SA_CA<1>  CA1_A @S9S_MB_2U_LIB.S9S_MB_2U(SCH_1):M_H_CPU1_SA_CA(1)
  76 M_H_CPU1_SB_CA<0>  CA0_B @S9S_MB_2U_LIB.S9S_MB_2U(SCH_1):M_H_CPU1_SB_CA(0)
  66 M_H_CPU1_SA_CA<0>  CA0_A @S9S_MB_2U_LIB.S9S_MB_2U(SCH_1):M_H_CPU1_SA_CA(0)
  62 M_H_CPU1_ALERT_N ALERT_N @S9S_MB_2U_LIB.S9S_MB_2U(SCH_1):M_H_CPU1_ALERT_N
 236 M_H_CPU1_SB_CB<7>  CB7_B @S9S_MB_2U_LIB.S9S_MB_2U(SCH_1):M_H_CPU1_SB_CB(7)
  53 M_H_CPU1_SA_CB<1>  CB1_A @S9S_MB_2U_LIB.S9S_MB_2U(SCH_1):M_H_CPU1_SA_CB(1)
  58 M_H_CPU1_SA_CB<4>  CB4_A @S9S_MB_2U_LIB.S9S_MB_2U(SCH_1):M_H_CPU1_SA_CB(4)
 205 M_H_CPU1_SA_CB<7>  CB7_A @S9S_MB_2U_LIB.S9S_MB_2U(SCH_1):M_H_CPU1_SA_CB(7)
 194 M_H_CPU1_SA_DQ<31> DQ31_A @S9S_MB_2U_LIB.S9S_MB_2U(SCH_1):M_H_CPU1_SA_DQ(31)

SCONN288_ADR50017P087CC-SCONN2A  I180  J32
  93 M_H_CPU1_SB_DQS_DP<9> DQS9_B_T||TDQS9_B_T||DBI4_B_N @S9S_MB_2U_LIB.S9S_MB_2U(SCH_1):M_H_CPU1_SB_DQS_DP(9)
  94 M_H_CPU1_SB_DQS_DN<9> DQS9_B_C||TDQS9_B_C @S9S_MB_2U_LIB.S9S_MB_2U(SCH_1):M_H_CPU1_SB_DQS_DN(9)
 201 M_H_CPU1_SA_DQS_DP<9> DQS9_A_T||TDQS9_A_T @S9S_MB_2U_LIB.S9S_MB_2U(SCH_1):M_H_CPU1_SA_DQS_DP(9)
 200 M_H_CPU1_SA_DQS_DN<9> DQS9_A_C||TDQS9_A_C @S9S_MB_2U_LIB.S9S_MB_2U(SCH_1):M_H_CPU1_SA_DQS_DN(9)
 190 M_H_CPU1_SA_DQS_DP<8> DQS8_A_T||TDQS8_A_T @S9S_MB_2U_LIB.S9S_MB_2U(SCH_1):M_H_CPU1_SA_DQS_DP(8)
 189 M_H_CPU1_SA_DQS_DN<8> DQS8_A_C||TDQS8_A_C @S9S_MB_2U_LIB.S9S_MB_2U(SCH_1):M_H_CPU1_SA_DQS_DN(8)
 271 M_H_CPU1_SB_DQS_DN<7> DQS7_B_C||TDQS7_B_C @S9S_MB_2U_LIB.S9S_MB_2U(SCH_1):M_H_CPU1_SB_DQS_DN(7)
 179 M_H_CPU1_SA_DQS_DP<7> DQS7_A_T||TDQS7_A_T @S9S_MB_2U_LIB.S9S_MB_2U(SCH_1):M_H_CPU1_SA_DQS_DP(7)
 261 M_H_CPU1_SB_DQS_DP<6> DQS6_B_T||TDQS6_B_T @S9S_MB_2U_LIB.S9S_MB_2U(SCH_1):M_H_CPU1_SB_DQS_DP(6)
 260 M_H_CPU1_SB_DQS_DN<6> DQS6_B_C||TDQS6_B_C @S9S_MB_2U_LIB.S9S_MB_2U(SCH_1):M_H_CPU1_SB_DQS_DN(6)
 167 M_H_CPU1_SA_DQS_DN<6> DQS6_A_C||TDQS6_A_C||DQS6_A_T||TDQS6_A_T @S9S_MB_2U_LIB.S9S_MB_2U(SCH_1):M_H_CPU1_SA_DQS_DN(6)
 250 M_H_CPU1_SB_DQS_DP<5> DQS5_B_T||TDQS5_B_T @S9S_MB_2U_LIB.S9S_MB_2U(SCH_1):M_H_CPU1_SB_DQS_DP(5)
 249 M_H_CPU1_SB_DQS_DN<5> DQS5_B_C||TDQS5_B_C @S9S_MB_2U_LIB.S9S_MB_2U(SCH_1):M_H_CPU1_SB_DQS_DN(5)
 157 M_H_CPU1_SA_DQS_DP<5> DQS5_A_T||TDQS5_A_T @S9S_MB_2U_LIB.S9S_MB_2U(SCH_1):M_H_CPU1_SA_DQS_DP(5)
 156 M_H_CPU1_SA_DQS_DN<5> DQS5_A_C||TDQS5_A_C||DQS5_A_T||TDQS5_A_T @S9S_MB_2U_LIB.S9S_MB_2U(SCH_1):M_H_CPU1_SA_DQS_DN(5)
 239 M_H_CPU1_SB_DQS_DP<4> DQS4_B_T @S9S_MB_2U_LIB.S9S_MB_2U(SCH_1):M_H_CPU1_SB_DQS_DP(4)
 238 M_H_CPU1_SB_DQS_DN<4> DQS4_B_C @S9S_MB_2U_LIB.S9S_MB_2U(SCH_1):M_H_CPU1_SB_DQS_DN(4)
  55 M_H_CPU1_SA_DQS_DP<4> DQS4_A_T @S9S_MB_2U_LIB.S9S_MB_2U(SCH_1):M_H_CPU1_SA_DQS_DP(4)
  56 M_H_CPU1_SA_DQS_DN<4> DQS4_A_C @S9S_MB_2U_LIB.S9S_MB_2U(SCH_1):M_H_CPU1_SA_DQS_DN(4)
 137 M_H_CPU1_SB_DQS_DP<3> DQS3_B_T @S9S_MB_2U_LIB.S9S_MB_2U(SCH_1):M_H_CPU1_SB_DQS_DP(3)
 138 M_H_CPU1_SB_DQS_DN<3> DQS3_B_C @S9S_MB_2U_LIB.S9S_MB_2U(SCH_1):M_H_CPU1_SB_DQS_DN(3)
  44 M_H_CPU1_SA_DQS_DP<3> DQS3_A_T @S9S_MB_2U_LIB.S9S_MB_2U(SCH_1):M_H_CPU1_SA_DQS_DP(3)
  45 M_H_CPU1_SA_DQS_DN<3> DQS3_A_C @S9S_MB_2U_LIB.S9S_MB_2U(SCH_1):M_H_CPU1_SA_DQS_DN(3)
 126 M_H_CPU1_SB_DQS_DP<2> DQS2_B_T @S9S_MB_2U_LIB.S9S_MB_2U(SCH_1):M_H_CPU1_SB_DQS_DP(2)
 127 M_H_CPU1_SB_DQS_DN<2> DQS2_B_C @S9S_MB_2U_LIB.S9S_MB_2U(SCH_1):M_H_CPU1_SB_DQS_DN(2)
  33 M_H_CPU1_SA_DQS_DP<2> DQS2_A_T @S9S_MB_2U_LIB.S9S_MB_2U(SCH_1):M_H_CPU1_SA_DQS_DP(2)
  34 M_H_CPU1_SA_DQS_DN<2> DQS2_A_C @S9S_MB_2U_LIB.S9S_MB_2U(SCH_1):M_H_CPU1_SA_DQS_DN(2)
 115 M_H_CPU1_SB_DQS_DP<1> DQS1_B_T @S9S_MB_2U_LIB.S9S_MB_2U(SCH_1):M_H_CPU1_SB_DQS_DP(1)
 116 M_H_CPU1_SB_DQS_DN<1> DQS1_B_C @S9S_MB_2U_LIB.S9S_MB_2U(SCH_1):M_H_CPU1_SB_DQS_DN(1)
  22 M_H_CPU1_SA_DQS_DP<1> DQS1_A_T @S9S_MB_2U_LIB.S9S_MB_2U(SCH_1):M_H_CPU1_SA_DQS_DP(1)
  23 M_H_CPU1_SA_DQS_DN<1> DQS1_A_C @S9S_MB_2U_LIB.S9S_MB_2U(SCH_1):M_H_CPU1_SA_DQS_DN(1)
 104 M_H_CPU1_SB_DQS_DP<0> DQS0_B_T @S9S_MB_2U_LIB.S9S_MB_2U(SCH_1):M_H_CPU1_SB_DQS_DP(0)
 105 M_H_CPU1_SB_DQS_DN<0> DQS0_B_C @S9S_MB_2U_LIB.S9S_MB_2U(SCH_1):M_H_CPU1_SB_DQS_DN(0)
  11 M_H_CPU1_SA_DQS_DP<0> DQS0_A_T @S9S_MB_2U_LIB.S9S_MB_2U(SCH_1):M_H_CPU1_SA_DQS_DP(0)
  12 M_H_CPU1_SA_DQS_DN<0> DQS0_A_C @S9S_MB_2U_LIB.S9S_MB_2U(SCH_1):M_H_CPU1_SA_DQS_DN(0)
 272 M_H_CPU1_SB_DQS_DP<7> DQS7_B_T||TDQS7_B_T @S9S_MB_2U_LIB.S9S_MB_2U(SCH_1):M_H_CPU1_SB_DQS_DP(7)
 282 M_H_CPU1_SB_DQS_DN<8> DQS8_B_C||TDQS8_B_C @S9S_MB_2U_LIB.S9S_MB_2U(SCH_1):M_H_CPU1_SB_DQS_DN(8)
 283 M_H_CPU1_SB_DQS_DP<8> DQS8_B_T||TDQS8_B_T @S9S_MB_2U_LIB.S9S_MB_2U(SCH_1):M_H_CPU1_SB_DQS_DP(8)
 168 M_H_CPU1_SA_DQS_DP<6> DQS6_A_T||TDQS6_A_T @S9S_MB_2U_LIB.S9S_MB_2U(SCH_1):M_H_CPU1_SA_DQS_DP(6)
 178 M_H_CPU1_SA_DQS_DN<7> DQS7_A_C||TDQS7_A_C @S9S_MB_2U_LIB.S9S_MB_2U(SCH_1):M_H_CPU1_SA_DQS_DN(7)

Q_RES_0402LF-49.9,1%,1/16W,CHIA  I182  R3906
   1 I3C_SPD_DDREFGH_CPU1_LVC1_SCL_7      A @S9S_MB_2U_LIB.S9S_MB_2U(SCH_1):I3C_SPD_DDREFGH_CPU1_LVC1_SCL_R8
   2 I3C_SPD_DDREFGH_CPU1_LVC1_SCL      B @S9S_MB_2U_LIB.S9S_MB_2U(SCH_1):I3C_SPD_DDREFGH_CPU1_LVC1_SCL


DRAWING: @S9S_MB_2U_LIB.S9S_MB_2U(SCH_1):PAGE114 

Q_RES_0402LF-33.2,1%,1/16W,CHIA  I59  R906
   1 PWRGD_CHG_CPU1_DIMM2      A @S9S_MB_2U_LIB.S9S_MB_2U(SCH_1):PWRGD_CHG_CPU1_DIMM2
   2 PWRGD_FAIL_CPU1_GH      B @S9S_MB_2U_LIB.S9S_MB_2U(SCH_1):PWRGD_FAIL_CPU1_GH

Q_RES_0402LF-33.2,1%,1/16W,CHIA  I61  R2736
   1 PWRGD_CHF_CPU1_DIMM2      A @S9S_MB_2U_LIB.S9S_MB_2U(SCH_1):PWRGD_CHF_CPU1_DIMM2
   2 PWRGD_FAIL_CPU1_EF      B @S9S_MB_2U_LIB.S9S_MB_2U(SCH_1):PWRGD_FAIL_CPU1_EF

Q_RES_0402LF-33.2,1%,1/16W,CHIA  I63  R902
   1 PWRGD_CHE_CPU1_DIMM2      A @S9S_MB_2U_LIB.S9S_MB_2U(SCH_1):PWRGD_CHE_CPU1_DIMM2
   2 PWRGD_FAIL_CPU1_EF      B @S9S_MB_2U_LIB.S9S_MB_2U(SCH_1):PWRGD_FAIL_CPU1_EF

Q_RES_0402LF-33.2,1%,1/16W,CHIA  I17  R2735
   1 PWRGD_CHH_CPU0_DIMM2      A @S9S_MB_2U_LIB.S9S_MB_2U(SCH_1):PWRGD_CHH_CPU0_DIMM2
   2 PWRGD_FAIL_CPU0_GH      B @S9S_MB_2U_LIB.S9S_MB_2U(SCH_1):PWRGD_FAIL_CPU0_GH

Q_RES_0402LF-33.2,1%,1/16W,CHIA  I18  R2734
   1 PWRGD_CHH_CPU0_DIMM1      A @S9S_MB_2U_LIB.S9S_MB_2U(SCH_1):PWRGD_CHH_CPU0_DIMM1
   2 PWRGD_FAIL_CPU0_GH      B @S9S_MB_2U_LIB.S9S_MB_2U(SCH_1):PWRGD_FAIL_CPU0_GH

Q_RES_0402LF-33.2,1%,1/16W,CHIA  I19  R890
   1 PWRGD_CHG_CPU0_DIMM2      A @S9S_MB_2U_LIB.S9S_MB_2U(SCH_1):PWRGD_CHG_CPU0_DIMM2
   2 PWRGD_FAIL_CPU0_GH      B @S9S_MB_2U_LIB.S9S_MB_2U(SCH_1):PWRGD_FAIL_CPU0_GH

Q_RES_0402LF-33.2,1%,1/16W,CHIA  I20  R889
   1 PWRGD_CHG_CPU0_DIMM1      A @S9S_MB_2U_LIB.S9S_MB_2U(SCH_1):PWRGD_CHG_CPU0_DIMM1
   2 PWRGD_FAIL_CPU0_GH      B @S9S_MB_2U_LIB.S9S_MB_2U(SCH_1):PWRGD_FAIL_CPU0_GH

Q_RES_0402LF-33.2,1%,1/16W,CHIA  I21  R2733
   1 PWRGD_CHF_CPU0_DIMM2      A @S9S_MB_2U_LIB.S9S_MB_2U(SCH_1):PWRGD_CHF_CPU0_DIMM2
   2 PWRGD_FAIL_CPU0_EF      B @S9S_MB_2U_LIB.S9S_MB_2U(SCH_1):PWRGD_FAIL_CPU0_EF

Q_RES_0402LF-33.2,1%,1/16W,CHIA  I23  R886
   1 PWRGD_CHE_CPU0_DIMM2      A @S9S_MB_2U_LIB.S9S_MB_2U(SCH_1):PWRGD_CHE_CPU0_DIMM2
   2 PWRGD_FAIL_CPU0_EF      B @S9S_MB_2U_LIB.S9S_MB_2U(SCH_1):PWRGD_FAIL_CPU0_EF

Q_RES_0402LF-33.2,1%,1/16W,CHIA  I24  R885
   1 PWRGD_CHE_CPU0_DIMM1      A @S9S_MB_2U_LIB.S9S_MB_2U(SCH_1):PWRGD_CHE_CPU0_DIMM1
   2 PWRGD_FAIL_CPU0_EF      B @S9S_MB_2U_LIB.S9S_MB_2U(SCH_1):PWRGD_FAIL_CPU0_EF

Q_RES_0402LF-33.2,1%,1/16W,CHIA  I26  R884
   1 PWRGD_CHD_CPU0_DIMM2      A @S9S_MB_2U_LIB.S9S_MB_2U(SCH_1):PWRGD_CHD_CPU0_DIMM2
   2 PWRGD_FAIL_CPU0_CD      B @S9S_MB_2U_LIB.S9S_MB_2U(SCH_1):PWRGD_FAIL_CPU0_CD

Q_RES_0402LF-33.2,1%,1/16W,CHIA  I28  R2729
   1 PWRGD_CHC_CPU0_DIMM1      A @S9S_MB_2U_LIB.S9S_MB_2U(SCH_1):PWRGD_CHC_CPU0_DIMM1
   2 PWRGD_FAIL_CPU0_CD      B @S9S_MB_2U_LIB.S9S_MB_2U(SCH_1):PWRGD_FAIL_CPU0_CD

Q_RES_0402LF-33.2,1%,1/16W,CHIA  I29  R880
   1 PWRGD_CHB_CPU0_DIMM2      A @S9S_MB_2U_LIB.S9S_MB_2U(SCH_1):PWRGD_CHB_CPU0_DIMM2
   2 PWRGD_FAIL_CPU0_AB      B @S9S_MB_2U_LIB.S9S_MB_2U(SCH_1):PWRGD_FAIL_CPU0_AB

Q_RES_0402LF-33.2,1%,1/16W,CHIA  I57  R908
   1 PWRGD_CHH_CPU1_DIMM2      A @S9S_MB_2U_LIB.S9S_MB_2U(SCH_1):PWRGD_CHH_CPU1_DIMM2
   2 PWRGD_FAIL_CPU1_GH      B @S9S_MB_2U_LIB.S9S_MB_2U(SCH_1):PWRGD_FAIL_CPU1_GH

Q_RES_0402LF-33.2,1%,1/16W,CHIA  I58  R907
   1 PWRGD_CHH_CPU1_DIMM1      A @S9S_MB_2U_LIB.S9S_MB_2U(SCH_1):PWRGD_CHH_CPU1_DIMM1
   2 PWRGD_FAIL_CPU1_GH      B @S9S_MB_2U_LIB.S9S_MB_2U(SCH_1):PWRGD_FAIL_CPU1_GH

Q_RES_0402LF-33.2,1%,1/16W,CHIA  I60  R905
   1 PWRGD_CHG_CPU1_DIMM1      A @S9S_MB_2U_LIB.S9S_MB_2U(SCH_1):PWRGD_CHG_CPU1_DIMM1
   2 PWRGD_FAIL_CPU1_GH      B @S9S_MB_2U_LIB.S9S_MB_2U(SCH_1):PWRGD_FAIL_CPU1_GH

Q_RES_0402LF-33.2,1%,1/16W,CHIA  I62  R903
   1 PWRGD_CHF_CPU1_DIMM1      A @S9S_MB_2U_LIB.S9S_MB_2U(SCH_1):PWRGD_CHF_CPU1_DIMM1
   2 PWRGD_FAIL_CPU1_EF      B @S9S_MB_2U_LIB.S9S_MB_2U(SCH_1):PWRGD_FAIL_CPU1_EF

Q_RES_0402LF-33.2,1%,1/16W,CHIA  I64  R901
   1 PWRGD_CHE_CPU1_DIMM1      A @S9S_MB_2U_LIB.S9S_MB_2U(SCH_1):PWRGD_CHE_CPU1_DIMM1
   2 PWRGD_FAIL_CPU1_EF      B @S9S_MB_2U_LIB.S9S_MB_2U(SCH_1):PWRGD_FAIL_CPU1_EF

Q_RES_0402LF-33.2,1%,1/16W,CHIA  I66  R900
   1 PWRGD_CHD_CPU1_DIMM2      A @S9S_MB_2U_LIB.S9S_MB_2U(SCH_1):PWRGD_CHD_CPU1_DIMM2
   2 PWRGD_FAIL_CPU1_CD      B @S9S_MB_2U_LIB.S9S_MB_2U(SCH_1):PWRGD_FAIL_CPU1_CD

Q_RES_0402LF-33.2,1%,1/16W,CHIA  I67  R897
   1 PWRGD_CHC_CPU1_DIMM1      A @S9S_MB_2U_LIB.S9S_MB_2U(SCH_1):PWRGD_CHC_CPU1_DIMM1
   2 PWRGD_FAIL_CPU1_CD      B @S9S_MB_2U_LIB.S9S_MB_2U(SCH_1):PWRGD_FAIL_CPU1_CD

Q_RES_0402LF-33.2,1%,1/16W,CHIA  I69  R896
   1 PWRGD_CHB_CPU1_DIMM2      A @S9S_MB_2U_LIB.S9S_MB_2U(SCH_1):PWRGD_CHB_CPU1_DIMM2
   2 PWRGD_FAIL_CPU1_AB      B @S9S_MB_2U_LIB.S9S_MB_2U(SCH_1):PWRGD_FAIL_CPU1_AB

Q_RES_0402LF-33.2,1%,1/16W,CHIA  I22  R2732
   1 PWRGD_CHF_CPU0_DIMM1      A @S9S_MB_2U_LIB.S9S_MB_2U(SCH_1):PWRGD_CHF_CPU0_DIMM1
   2 PWRGD_FAIL_CPU0_EF      B @S9S_MB_2U_LIB.S9S_MB_2U(SCH_1):PWRGD_FAIL_CPU0_EF

Q_RES_0402LF-33.2,1%,1/16W,CHIA  I25  R2731
   1 PWRGD_CHD_CPU0_DIMM1      A @S9S_MB_2U_LIB.S9S_MB_2U(SCH_1):PWRGD_CHD_CPU0_DIMM1
   2 PWRGD_FAIL_CPU0_CD      B @S9S_MB_2U_LIB.S9S_MB_2U(SCH_1):PWRGD_FAIL_CPU0_CD

Q_RES_0402LF-33.2,1%,1/16W,CHIA  I27  R2730
   1 PWRGD_CHC_CPU0_DIMM2      A @S9S_MB_2U_LIB.S9S_MB_2U(SCH_1):PWRGD_CHC_CPU0_DIMM2
   2 PWRGD_FAIL_CPU0_CD      B @S9S_MB_2U_LIB.S9S_MB_2U(SCH_1):PWRGD_FAIL_CPU0_CD

Q_RES_0402LF-33.2,1%,1/16W,CHIA  I30  R2728
   1 PWRGD_CHB_CPU0_DIMM1      A @S9S_MB_2U_LIB.S9S_MB_2U(SCH_1):PWRGD_CHB_CPU0_DIMM1
   2 PWRGD_FAIL_CPU0_AB      B @S9S_MB_2U_LIB.S9S_MB_2U(SCH_1):PWRGD_FAIL_CPU0_AB

Q_RES_0402LF-33.2,1%,1/16W,CHIA  I31  R2727
   1 PWRGD_CHA_CPU0_DIMM2      A @S9S_MB_2U_LIB.S9S_MB_2U(SCH_1):PWRGD_CHA_CPU0_DIMM2
   2 PWRGD_FAIL_CPU0_AB      B @S9S_MB_2U_LIB.S9S_MB_2U(SCH_1):PWRGD_FAIL_CPU0_AB

Q_RES_0402LF-33.2,1%,1/16W,CHIA  I32  R2726
   1 PWRGD_CHA_CPU0_DIMM1      A @S9S_MB_2U_LIB.S9S_MB_2U(SCH_1):PWRGD_CHA_CPU0_DIMM1
   2 PWRGD_FAIL_CPU0_AB      B @S9S_MB_2U_LIB.S9S_MB_2U(SCH_1):PWRGD_FAIL_CPU0_AB

Q_RES_0402LF-33.2,1%,1/16W,CHIA  I65  R899
   1 PWRGD_CHD_CPU1_DIMM1      A @S9S_MB_2U_LIB.S9S_MB_2U(SCH_1):PWRGD_CHD_CPU1_DIMM1
   2 PWRGD_FAIL_CPU1_CD      B @S9S_MB_2U_LIB.S9S_MB_2U(SCH_1):PWRGD_FAIL_CPU1_CD

Q_RES_0402LF-33.2,1%,1/16W,CHIA  I68  R898
   1 PWRGD_CHC_CPU1_DIMM2      A @S9S_MB_2U_LIB.S9S_MB_2U(SCH_1):PWRGD_CHC_CPU1_DIMM2
   2 PWRGD_FAIL_CPU1_CD      B @S9S_MB_2U_LIB.S9S_MB_2U(SCH_1):PWRGD_FAIL_CPU1_CD

Q_RES_0402LF-33.2,1%,1/16W,CHIA  I77  R895
   1 PWRGD_CHB_CPU1_DIMM1      A @S9S_MB_2U_LIB.S9S_MB_2U(SCH_1):PWRGD_CHB_CPU1_DIMM1
   2 PWRGD_FAIL_CPU1_AB      B @S9S_MB_2U_LIB.S9S_MB_2U(SCH_1):PWRGD_FAIL_CPU1_AB

Q_RES_0402LF-33.2,1%,1/16W,CHIA  I78  R894
   1 PWRGD_CHA_CPU1_DIMM2      A @S9S_MB_2U_LIB.S9S_MB_2U(SCH_1):PWRGD_CHA_CPU1_DIMM2
   2 PWRGD_FAIL_CPU1_AB      B @S9S_MB_2U_LIB.S9S_MB_2U(SCH_1):PWRGD_FAIL_CPU1_AB

Q_RES_0402LF-33.2,1%,1/16W,CHIA  I79  R893
   1 PWRGD_CHA_CPU1_DIMM1      A @S9S_MB_2U_LIB.S9S_MB_2U(SCH_1):PWRGD_CHA_CPU1_DIMM1
   2 PWRGD_FAIL_CPU1_AB      B @S9S_MB_2U_LIB.S9S_MB_2U(SCH_1):PWRGD_FAIL_CPU1_AB


DRAWING: @S9S_MB_2U_LIB.S9S_MB_2U(SCH_1):PAGE115 

Q_RES_0402LF-1K,1%,1/16W,CHIP,A  I46  R2490
   1 PWRGD_FAIL_CPU0_AB      A @S9S_MB_2U_LIB.S9S_MB_2U(SCH_1):PWRGD_FAIL_CPU0_AB
   2 PWRGD_FAIL_CPU0_AB_R1      B @S9S_MB_2U_LIB.S9S_MB_2U(SCH_1):PWRGD_FAIL_CPU0_AB_R1

Q_RES_0402LF-1K,1%,1/16W,CHIP,A  I9  R2497
   1 PWRGD_FAIL_CPU1_GH      A @S9S_MB_2U_LIB.S9S_MB_2U(SCH_1):PWRGD_FAIL_CPU1_GH
   2 PWRGD_FAIL_CPU1_GH_R1      B @S9S_MB_2U_LIB.S9S_MB_2U(SCH_1):PWRGD_FAIL_CPU1_GH_R1

Q_RES_0402LF-10K,1%,1/16W,CHIPA  I11  R947
   1 P3V3_AUX      A @S9S_MB_2U_LIB.S9S_MB_2U(SCH_1):P3V3_AUX
   2 PWRGD_FAIL_CPU1_GH_R1      B @S9S_MB_2U_LIB.S9S_MB_2U(SCH_1):PWRGD_FAIL_CPU1_GH_R1

Q_RES_0402LF-1K,1%,1/16W,CHIP,A  I12  R2496
   1 PWRGD_FAIL_CPU1_EF      A @S9S_MB_2U_LIB.S9S_MB_2U(SCH_1):PWRGD_FAIL_CPU1_EF
   2 PWRGD_FAIL_CPU1_EF_R1      B @S9S_MB_2U_LIB.S9S_MB_2U(SCH_1):PWRGD_FAIL_CPU1_EF_R1

Q_RES_0402LF-10K,1%,1/16W,CHIPA  I14  R946
   1 P3V3_AUX      A @S9S_MB_2U_LIB.S9S_MB_2U(SCH_1):P3V3_AUX
   2 PWRGD_FAIL_CPU1_EF_R1      B @S9S_MB_2U_LIB.S9S_MB_2U(SCH_1):PWRGD_FAIL_CPU1_EF_R1

Q_RES_0402LF-10K,1%,1/16W,CHIPA  I16  R945
   1 P3V3_AUX      A @S9S_MB_2U_LIB.S9S_MB_2U(SCH_1):P3V3_AUX
   2 PWRGD_FAIL_CPU1_CD_R1      B @S9S_MB_2U_LIB.S9S_MB_2U(SCH_1):PWRGD_FAIL_CPU1_CD_R1

Q_RES_0402LF-1K,1%,1/16W,CHIP,A  I17  R2495
   1 PWRGD_FAIL_CPU1_CD      A @S9S_MB_2U_LIB.S9S_MB_2U(SCH_1):PWRGD_FAIL_CPU1_CD
   2 PWRGD_FAIL_CPU1_CD_R1      B @S9S_MB_2U_LIB.S9S_MB_2U(SCH_1):PWRGD_FAIL_CPU1_CD_R1

Q_RES_0402LF-10K,1%,1/16W,CHIPA  I19  R944
   1 P3V3_AUX      A @S9S_MB_2U_LIB.S9S_MB_2U(SCH_1):P3V3_AUX
   2 PWRGD_FAIL_CPU1_AB_R1      B @S9S_MB_2U_LIB.S9S_MB_2U(SCH_1):PWRGD_FAIL_CPU1_AB_R1

SCHOTTKY_12-B0530WS7F,SMLF,IC,A  I22  D49
   1 PWRGD_FAIL_CPU1_GH_R1      A @S9S_MB_2U_LIB.S9S_MB_2U(SCH_1):PWRGD_FAIL_CPU1_GH_R1
   2 P3V3_AUX      C @S9S_MB_2U_LIB.S9S_MB_2U(SCH_1):P3V3_AUX

SCHOTTKY_12-B0530WS7F,SMLF,IC,A  I25  D48
   1 PWRGD_FAIL_CPU1_EF_R1      A @S9S_MB_2U_LIB.S9S_MB_2U(SCH_1):PWRGD_FAIL_CPU1_EF_R1
   2 P3V3_AUX      C @S9S_MB_2U_LIB.S9S_MB_2U(SCH_1):P3V3_AUX

SCHOTTKY_12-B0530WS7F,SMLF,IC,A  I27  D47
   1 PWRGD_FAIL_CPU1_CD_R1      A @S9S_MB_2U_LIB.S9S_MB_2U(SCH_1):PWRGD_FAIL_CPU1_CD_R1
   2 P3V3_AUX      C @S9S_MB_2U_LIB.S9S_MB_2U(SCH_1):P3V3_AUX

Q_RES_0402LF-1K,1%,1/16W,CHIP,A  I38  R2493
   1 PWRGD_FAIL_CPU0_GH      A @S9S_MB_2U_LIB.S9S_MB_2U(SCH_1):PWRGD_FAIL_CPU0_GH
   2 PWRGD_FAIL_CPU0_GH_R1      B @S9S_MB_2U_LIB.S9S_MB_2U(SCH_1):PWRGD_FAIL_CPU0_GH_R1

Q_RES_0402LF-1K,1%,1/16W,CHIP,A  I42  R2491
   1 PWRGD_FAIL_CPU0_CD      A @S9S_MB_2U_LIB.S9S_MB_2U(SCH_1):PWRGD_FAIL_CPU0_CD
   2 PWRGD_FAIL_CPU0_CD_R1      B @S9S_MB_2U_LIB.S9S_MB_2U(SCH_1):PWRGD_FAIL_CPU0_CD_R1

Q_RES_0402LF-10K,1%,1/16W,CHIPA  I45  R941
   1 P3V3_AUX      A @S9S_MB_2U_LIB.S9S_MB_2U(SCH_1):P3V3_AUX
   2 PWRGD_FAIL_CPU0_CD_R1      B @S9S_MB_2U_LIB.S9S_MB_2U(SCH_1):PWRGD_FAIL_CPU0_CD_R1

Q_RES_0402LF-10K,1%,1/16W,CHIPA  I48  R940
   1 P3V3_AUX      A @S9S_MB_2U_LIB.S9S_MB_2U(SCH_1):P3V3_AUX
   2 PWRGD_FAIL_CPU0_AB_R1      B @S9S_MB_2U_LIB.S9S_MB_2U(SCH_1):PWRGD_FAIL_CPU0_AB_R1

SCHOTTKY_12-B0530WS7F,SMLF,IC,A  I54  D43
   1 PWRGD_FAIL_CPU0_CD_R1      A @S9S_MB_2U_LIB.S9S_MB_2U(SCH_1):PWRGD_FAIL_CPU0_CD_R1
   2 P3V3_AUX      C @S9S_MB_2U_LIB.S9S_MB_2U(SCH_1):P3V3_AUX

SCHOTTKY_12-B0530WS7F,SMLF,IC,A  I59  D42
   1 PWRGD_FAIL_CPU0_AB_R1      A @S9S_MB_2U_LIB.S9S_MB_2U(SCH_1):PWRGD_FAIL_CPU0_AB_R1
   2 P3V3_AUX      C @S9S_MB_2U_LIB.S9S_MB_2U(SCH_1):P3V3_AUX

Q_RES_0402LF-1K,1%,1/16W,CHIP,A  I18  R2494
   1 PWRGD_FAIL_CPU1_AB      A @S9S_MB_2U_LIB.S9S_MB_2U(SCH_1):PWRGD_FAIL_CPU1_AB
   2 PWRGD_FAIL_CPU1_AB_R1      B @S9S_MB_2U_LIB.S9S_MB_2U(SCH_1):PWRGD_FAIL_CPU1_AB_R1

SCHOTTKY_12-B0530WS7F,SMLF,IC,A  I29  D46
   1 PWRGD_FAIL_CPU1_AB_R1      A @S9S_MB_2U_LIB.S9S_MB_2U(SCH_1):PWRGD_FAIL_CPU1_AB_R1
   2 P3V3_AUX      C @S9S_MB_2U_LIB.S9S_MB_2U(SCH_1):P3V3_AUX

Q_RES_0402LF-10K,1%,1/16W,CHIPA  I37  R943
   1 P3V3_AUX      A @S9S_MB_2U_LIB.S9S_MB_2U(SCH_1):P3V3_AUX
   2 PWRGD_FAIL_CPU0_GH_R1      B @S9S_MB_2U_LIB.S9S_MB_2U(SCH_1):PWRGD_FAIL_CPU0_GH_R1

Q_RES_0402LF-10K,1%,1/16W,CHIPA  I40  R942
   1 P3V3_AUX      A @S9S_MB_2U_LIB.S9S_MB_2U(SCH_1):P3V3_AUX
   2 PWRGD_FAIL_CPU0_EF_R1      B @S9S_MB_2U_LIB.S9S_MB_2U(SCH_1):PWRGD_FAIL_CPU0_EF_R1

Q_RES_0402LF-1K,1%,1/16W,CHIP,A  I41  R2492
   1 PWRGD_FAIL_CPU0_EF      A @S9S_MB_2U_LIB.S9S_MB_2U(SCH_1):PWRGD_FAIL_CPU0_EF
   2 PWRGD_FAIL_CPU0_EF_R1      B @S9S_MB_2U_LIB.S9S_MB_2U(SCH_1):PWRGD_FAIL_CPU0_EF_R1

SCHOTTKY_12-B0530WS7F,SMLF,IC,A  I50  D45
   1 PWRGD_FAIL_CPU0_GH_R1      A @S9S_MB_2U_LIB.S9S_MB_2U(SCH_1):PWRGD_FAIL_CPU0_GH_R1
   2 P3V3_AUX      C @S9S_MB_2U_LIB.S9S_MB_2U(SCH_1):P3V3_AUX

SCHOTTKY_12-B0530WS7F,SMLF,IC,A  I52  D44
   1 PWRGD_FAIL_CPU0_EF_R1      A @S9S_MB_2U_LIB.S9S_MB_2U(SCH_1):PWRGD_FAIL_CPU0_EF_R1
   2 P3V3_AUX      C @S9S_MB_2U_LIB.S9S_MB_2U(SCH_1):P3V3_AUX

Q_RES_0402LF-33.2,1%,1/16W,CHIA  I65  R2505
   1 PWRGD_FAIL_CPU1_GH_R1      A @S9S_MB_2U_LIB.S9S_MB_2U(SCH_1):PWRGD_FAIL_CPU1_GH_R1
   2 PWRGD_FAIL_CPU1_GH_R      B @S9S_MB_2U_LIB.S9S_MB_2U(SCH_1):PWRGD_FAIL_CPU1_GH_R

Q_RES_0402LF-33.2,1%,1/16W,CHIA  I66  R2504
   1 PWRGD_FAIL_CPU1_EF_R1      A @S9S_MB_2U_LIB.S9S_MB_2U(SCH_1):PWRGD_FAIL_CPU1_EF_R1
   2 PWRGD_FAIL_CPU1_EF_R      B @S9S_MB_2U_LIB.S9S_MB_2U(SCH_1):PWRGD_FAIL_CPU1_EF_R

Q_RES_0402LF-33.2,1%,1/16W,CHIA  I67  R2503
   1 PWRGD_FAIL_CPU1_CD_R1      A @S9S_MB_2U_LIB.S9S_MB_2U(SCH_1):PWRGD_FAIL_CPU1_CD_R1
   2 PWRGD_FAIL_CPU1_CD_R      B @S9S_MB_2U_LIB.S9S_MB_2U(SCH_1):PWRGD_FAIL_CPU1_CD_R

Q_RES_0402LF-33.2,1%,1/16W,CHIA  I68  R2502
   1 PWRGD_FAIL_CPU1_AB_R1      A @S9S_MB_2U_LIB.S9S_MB_2U(SCH_1):PWRGD_FAIL_CPU1_AB_R1
   2 PWRGD_FAIL_CPU1_AB_R      B @S9S_MB_2U_LIB.S9S_MB_2U(SCH_1):PWRGD_FAIL_CPU1_AB_R

Q_RES_0402LF-33.2,1%,1/16W,CHIA  I69  R2501
   1 PWRGD_FAIL_CPU0_GH_R1      A @S9S_MB_2U_LIB.S9S_MB_2U(SCH_1):PWRGD_FAIL_CPU0_GH_R1
   2 PWRGD_FAIL_CPU0_GH_R      B @S9S_MB_2U_LIB.S9S_MB_2U(SCH_1):PWRGD_FAIL_CPU0_GH_R

Q_RES_0402LF-33.2,1%,1/16W,CHIA  I70  R2500
   1 PWRGD_FAIL_CPU0_EF_R1      A @S9S_MB_2U_LIB.S9S_MB_2U(SCH_1):PWRGD_FAIL_CPU0_EF_R1
   2 PWRGD_FAIL_CPU0_EF_R      B @S9S_MB_2U_LIB.S9S_MB_2U(SCH_1):PWRGD_FAIL_CPU0_EF_R

Q_RES_0402LF-33.2,1%,1/16W,CHIA  I71  R2499
   1 PWRGD_FAIL_CPU0_CD_R1      A @S9S_MB_2U_LIB.S9S_MB_2U(SCH_1):PWRGD_FAIL_CPU0_CD_R1
   2 PWRGD_FAIL_CPU0_CD_R      B @S9S_MB_2U_LIB.S9S_MB_2U(SCH_1):PWRGD_FAIL_CPU0_CD_R

Q_RES_0402LF-33.2,1%,1/16W,CHIA  I72  R2498
   1 PWRGD_FAIL_CPU0_AB_R1      A @S9S_MB_2U_LIB.S9S_MB_2U(SCH_1):PWRGD_FAIL_CPU0_AB_R1
   2 PWRGD_FAIL_CPU0_AB_R      B @S9S_MB_2U_LIB.S9S_MB_2U(SCH_1):PWRGD_FAIL_CPU0_AB_R


DRAWING: @S9S_MB_2U_LIB.S9S_MB_2U(SCH_1):PAGE117 

Q_RES_0402LF-0,5%,1/16W,CHIP,CA  I9  R1240
   1 H_CPU0_PM_FAST_WAKE_N      A @S9S_MB_2U_LIB.S9S_MB_2U(SCH_1):H_CPU0_PM_FAST_WAKE_N
   2 H_CPU_PM_FAST_WAKE_N      B @S9S_MB_2U_LIB.S9S_MB_2U(SCH_1):H_CPU_PM_FAST_WAKE_N

Q_RES_0402LF-0,5%,1/16W,CHIP,CA  I10  R3023
   1 H_CPU_PM_FAST_WAKE_N      A @S9S_MB_2U_LIB.S9S_MB_2U(SCH_1):H_CPU_PM_FAST_WAKE_N
   2 H_CPU1_PM_FAST_WAKE_N      B @S9S_MB_2U_LIB.S9S_MB_2U(SCH_1):H_CPU1_PM_FAST_WAKE_N

Q_RES_0402LF-301,1%,1/16W,CHIPA  I13  R1242
   1 PVNN_TERM_CPU0      A @S9S_MB_2U_LIB.S9S_MB_2U(SCH_1):PVNN_TERM_CPU0
   2 H_CPU_PM_FAST_WAKE_N      B @S9S_MB_2U_LIB.S9S_MB_2U(SCH_1):H_CPU_PM_FAST_WAKE_N

Q_RES_0402LF-301,1%,1/16W,CHIPA  I16  R1244
   1 PVNN_TERM_CPU1      A @S9S_MB_2U_LIB.S9S_MB_2U(SCH_1):PVNN_TERM_CPU1
   2 H_CPU_PM_FAST_WAKE_N      B @S9S_MB_2U_LIB.S9S_MB_2U(SCH_1):H_CPU_PM_FAST_WAKE_N

Q_RES_0402LF-249,1%,1/16W,CHIPA  I17  R1241
   1 H_PMAX_TRIGGER_IO_CPU0      A @S9S_MB_2U_LIB.S9S_MB_2U(SCH_1):H_PMAX_TRIGGER_IO_CPU0
   2    GND      B @S9S_MB_2U_LIB.S9S_MB_2U(SCH_1):GND

Q_RES_0402LF-249,1%,1/16W,CHIPA  I19  R1243
   1 H_PMAX_TRIGGER_IO_CPU1      A @S9S_MB_2U_LIB.S9S_MB_2U(SCH_1):H_PMAX_TRIGGER_IO_CPU1
   2    GND      B @S9S_MB_2U_LIB.S9S_MB_2U(SCH_1):GND


DRAWING: @S9S_MB_2U_LIB.S9S_MB_2U(SCH_1):PAGE118 

Q_RES_0402LF-0,5%,1/16W,CHIP,CA  I23  R297
   1 H_CPU0_CATERR_LVC1_R_N      A @S9S_MB_2U_LIB.S9S_MB_2U(SCH_1):H_CPU0_CATERR_LVC1_R_N
   2 H_CPU_CATERR_LVC1_R_N      B @S9S_MB_2U_LIB.S9S_MB_2U(SCH_1):H_CPU_CATERR_LVC1_R_N

Q_RES_0402LF-0,5%,1/16W,CHIP,CA  I63  R299
   1 H_CPU1_CATERR_LVC1_R_N      A @S9S_MB_2U_LIB.S9S_MB_2U(SCH_1):H_CPU1_CATERR_LVC1_R_N
   2 H_CPU_CATERR_LVC1_R_N      B @S9S_MB_2U_LIB.S9S_MB_2U(SCH_1):H_CPU_CATERR_LVC1_R_N

Q_RES_0402LF-301,1%,1/16W,CHIPA  I65  R296
   1 PVNN_TERM_CPU0      A @S9S_MB_2U_LIB.S9S_MB_2U(SCH_1):PVNN_TERM_CPU0
   2 H_CPU_CATERR_LVC1_R_N      B @S9S_MB_2U_LIB.S9S_MB_2U(SCH_1):H_CPU_CATERR_LVC1_R_N

Q_RES_0402LF-301,1%,1/16W,CHIPA  I67  R298
   1 PVNN_TERM_CPU1      A @S9S_MB_2U_LIB.S9S_MB_2U(SCH_1):PVNN_TERM_CPU1
   2 H_CPU_CATERR_LVC1_R_N      B @S9S_MB_2U_LIB.S9S_MB_2U(SCH_1):H_CPU_CATERR_LVC1_R_N

Q_RES_0402LF-301,1%,1/16W,CHIPA  I73  R301
   1 PVNN_TERM_CPU0      A @S9S_MB_2U_LIB.S9S_MB_2U(SCH_1):PVNN_TERM_CPU0
   2 H_CPU_RMCA_LVC1_R_N      B @S9S_MB_2U_LIB.S9S_MB_2U(SCH_1):H_CPU_RMCA_LVC1_R_N

Q_RES_0402LF-301,1%,1/16W,CHIPA  I76  R303
   1 PVNN_TERM_CPU1      A @S9S_MB_2U_LIB.S9S_MB_2U(SCH_1):PVNN_TERM_CPU1
   2 H_CPU_RMCA_LVC1_R_N      B @S9S_MB_2U_LIB.S9S_MB_2U(SCH_1):H_CPU_RMCA_LVC1_R_N

Q_RES_0402LF-33.2,1%,1/16W,CHIA  I92  R315
   1 PWRGD_CPUPWRGD_GTL      A @S9S_MB_2U_LIB.S9S_MB_2U(SCH_1):PWRGD_CPUPWRGD_GTL
   2 PWRGD_CPUPWRGD_LVC1_R      B @S9S_MB_2U_LIB.S9S_MB_2U(SCH_1):PWRGD_CPUPWRGD_LVC1_R

Q_RES_0402LF-0,5%,1/16W,CHIP,CA  I101  R302
   1 H_CPU0_RMCA_LVC1_R_N      A @S9S_MB_2U_LIB.S9S_MB_2U(SCH_1):H_CPU0_RMCA_LVC1_R_N
   2 H_CPU_RMCA_LVC1_R_N      B @S9S_MB_2U_LIB.S9S_MB_2U(SCH_1):H_CPU_RMCA_LVC1_R_N

Q_RES_0402LF-0,5%,1/16W,CHIP,CA  I102  R304
   1 H_CPU1_RMCA_LVC1_R_N      A @S9S_MB_2U_LIB.S9S_MB_2U(SCH_1):H_CPU1_RMCA_LVC1_R_N
   2 H_CPU_RMCA_LVC1_R_N      B @S9S_MB_2U_LIB.S9S_MB_2U(SCH_1):H_CPU_RMCA_LVC1_R_N


DRAWING: @S9S_MB_2U_LIB.S9S_MB_2U(SCH_1):PAGE119 

Q_RES_0402LF-240,1%,1/16W,CHIPA  I53  R282
   1 PVNN_TERM_CPU0      A @S9S_MB_2U_LIB.S9S_MB_2U(SCH_1):PVNN_TERM_CPU0
   2 PU_CPU0_LEGACY_SKT      B @S9S_MB_2U_LIB.S9S_MB_2U(SCH_1):PU_CPU0_LEGACY_SKT

Q_RES_0402LF-240,1%,1/16W,EMPTA  I54  R279
   1 PVNN_TERM_CPU0      A @S9S_MB_2U_LIB.S9S_MB_2U(SCH_1):PVNN_TERM_CPU0
   2 PU_CPU0_SOCKET_ID0      B @S9S_MB_2U_LIB.S9S_MB_2U(SCH_1):PU_CPU0_SOCKET_ID0

Q_RES_0402LF-240,1%,1/16W,EMPTA  I57  R280
   1 PVNN_TERM_CPU0      A @S9S_MB_2U_LIB.S9S_MB_2U(SCH_1):PVNN_TERM_CPU0
   2 PU_CPU0_SOCKET_ID1      B @S9S_MB_2U_LIB.S9S_MB_2U(SCH_1):PU_CPU0_SOCKET_ID1

Q_RES_0402LF-240,1%,1/16W,EMPTA  I58  R281
   1 PVNN_TERM_CPU0      A @S9S_MB_2U_LIB.S9S_MB_2U(SCH_1):PVNN_TERM_CPU0
   2 PU_CPU0_SOCKET_ID2      B @S9S_MB_2U_LIB.S9S_MB_2U(SCH_1):PU_CPU0_SOCKET_ID2

Q_RES_0402LF-240,1%,1/16W,EMPTA  I61  R278
   1 PVNN_TERM_CPU0      A @S9S_MB_2U_LIB.S9S_MB_2U(SCH_1):PVNN_TERM_CPU0
   2 H_CPU0_BMCINIT_LVC1      B @S9S_MB_2U_LIB.S9S_MB_2U(SCH_1):H_CPU0_BMCINIT_LVC1

Q_RES_0402LF-240,1%,1/16W,CHIPA  I62  R277
   1 PVNN_TERM_CPU0      A @S9S_MB_2U_LIB.S9S_MB_2U(SCH_1):PVNN_TERM_CPU0
   2 PU_CPU0_FRMAGENT      B @S9S_MB_2U_LIB.S9S_MB_2U(SCH_1):PU_CPU0_FRMAGENT

Q_RES_0402LF-240,1%,1/16W,EMPTA  I66  R276
   1 PVNN_TERM_CPU0      A @S9S_MB_2U_LIB.S9S_MB_2U(SCH_1):PVNN_TERM_CPU0
   2 PU_CPU0_SAFE_MODE_BOOT      B @S9S_MB_2U_LIB.S9S_MB_2U(SCH_1):PU_CPU0_SAFE_MODE_BOOT

Q_RES_0402LF-240,1%,1/16W,CHIPA  I68  R275
   1 PVNN_TERM_CPU0      A @S9S_MB_2U_LIB.S9S_MB_2U(SCH_1):PVNN_TERM_CPU0
   2 PU_CPU0_TXT_AGENT      B @S9S_MB_2U_LIB.S9S_MB_2U(SCH_1):PU_CPU0_TXT_AGENT

Q_RES_0402LF-240,1%,1/16W,EMPTA  I71  R294
   1    GND      A @S9S_MB_2U_LIB.S9S_MB_2U(SCH_1):GND
   2 PD_CPU0_DMIMODE_OVERRIDE      B @S9S_MB_2U_LIB.S9S_MB_2U(SCH_1):PD_CPU0_DMIMODE_OVERRIDE

Q_RES_0402LF-240,1%,1/16W,EMPTA  I72  R295
   1    GND      A @S9S_MB_2U_LIB.S9S_MB_2U(SCH_1):GND
   2 PD_CPU0_ENH_MCECC_DIS      B @S9S_MB_2U_LIB.S9S_MB_2U(SCH_1):PD_CPU0_ENH_MCECC_DIS

Q_RES_0402LF-10K,1%,1/16W,CHIPA  I88  R274
   1 P3V3_AUX      A @S9S_MB_2U_LIB.S9S_MB_2U(SCH_1):P3V3_AUX
   2 FM_CPU1_PROC_ID1      B @S9S_MB_2U_LIB.S9S_MB_2U(SCH_1):FM_CPU1_PROC_ID1

Q_RES_0402LF-10K,1%,1/16W,CHIPA  I89  R273
   1 P3V3_AUX      A @S9S_MB_2U_LIB.S9S_MB_2U(SCH_1):P3V3_AUX
   2 FM_CPU1_PROC_ID0      B @S9S_MB_2U_LIB.S9S_MB_2U(SCH_1):FM_CPU1_PROC_ID0

Q_RES_0402LF-10K,1%,1/16W,CHIPA  I90  R272
   1 P3V3_AUX      A @S9S_MB_2U_LIB.S9S_MB_2U(SCH_1):P3V3_AUX
   2 FM_CPU1_PKGID2      B @S9S_MB_2U_LIB.S9S_MB_2U(SCH_1):FM_CPU1_PKGID2

Q_RES_0402LF-10K,1%,1/16W,CHIPA  I92  R271
   1 P3V3_AUX      A @S9S_MB_2U_LIB.S9S_MB_2U(SCH_1):P3V3_AUX
   2 FM_CPU1_PKGID1      B @S9S_MB_2U_LIB.S9S_MB_2U(SCH_1):FM_CPU1_PKGID1

Q_RES_0402LF-10K,1%,1/16W,CHIPA  I93  R270
   1 P3V3_AUX      A @S9S_MB_2U_LIB.S9S_MB_2U(SCH_1):P3V3_AUX
   2 FM_CPU1_PKGID0      B @S9S_MB_2U_LIB.S9S_MB_2U(SCH_1):FM_CPU1_PKGID0

Q_RES_0402LF-240,1%,1/16W,EMPTA  I94  R268
   1 PVNN_TERM_CPU1      A @S9S_MB_2U_LIB.S9S_MB_2U(SCH_1):PVNN_TERM_CPU1
   2 PU_CPU1_LEGACY_SKT      B @S9S_MB_2U_LIB.S9S_MB_2U(SCH_1):PU_CPU1_LEGACY_SKT

Q_RES_0402LF-240,1%,1/16W,EMPTA  I95  R267
   1 PVNN_TERM_CPU1      A @S9S_MB_2U_LIB.S9S_MB_2U(SCH_1):PVNN_TERM_CPU1
   2 PU_CPU1_SOCKET_ID2      B @S9S_MB_2U_LIB.S9S_MB_2U(SCH_1):PU_CPU1_SOCKET_ID2

Q_RES_0402LF-240,1%,1/16W,EMPTA  I96  R266
   1 PVNN_TERM_CPU1      A @S9S_MB_2U_LIB.S9S_MB_2U(SCH_1):PVNN_TERM_CPU1
   2 PU_CPU1_SOCKET_ID1      B @S9S_MB_2U_LIB.S9S_MB_2U(SCH_1):PU_CPU1_SOCKET_ID1

Q_RES_0402LF-240,1%,1/16W,CHIPA  I97  R265
   1 PVNN_TERM_CPU1      A @S9S_MB_2U_LIB.S9S_MB_2U(SCH_1):PVNN_TERM_CPU1
   2 PU_CPU1_SOCKET_ID0      B @S9S_MB_2U_LIB.S9S_MB_2U(SCH_1):PU_CPU1_SOCKET_ID0

Q_RES_0402LF-240,1%,1/16W,EMPTA  I98  R264
   1 PVNN_TERM_CPU1      A @S9S_MB_2U_LIB.S9S_MB_2U(SCH_1):PVNN_TERM_CPU1
   2 H_CPU1_BMCINIT_LVC1      B @S9S_MB_2U_LIB.S9S_MB_2U(SCH_1):H_CPU1_BMCINIT_LVC1

Q_RES_0402LF-240,1%,1/16W,EMPTA  I100  R262
   1 PVNN_TERM_CPU1      A @S9S_MB_2U_LIB.S9S_MB_2U(SCH_1):PVNN_TERM_CPU1
   2 PU_CPU1_SAFE_MODE_BOOT      B @S9S_MB_2U_LIB.S9S_MB_2U(SCH_1):PU_CPU1_SAFE_MODE_BOOT

Q_RES_0402LF-240,1%,1/16W,EMPTA  I101  R261
   1 PVNN_TERM_CPU1      A @S9S_MB_2U_LIB.S9S_MB_2U(SCH_1):PVNN_TERM_CPU1
   2 PU_CPU1_TXT_AGENT      B @S9S_MB_2U_LIB.S9S_MB_2U(SCH_1):PU_CPU1_TXT_AGENT

Q_RES_0402LF-240,1%,1/16W,EMPTA  I116  R291
   1    GND      A @S9S_MB_2U_LIB.S9S_MB_2U(SCH_1):GND
   2 PD_CPU1_ENH_MCECC_DIS      B @S9S_MB_2U_LIB.S9S_MB_2U(SCH_1):PD_CPU1_ENH_MCECC_DIS

Q_RES_0402LF-240,1%,1/16W,EMPTA  I125  R263
   1 PVNN_TERM_CPU1      A @S9S_MB_2U_LIB.S9S_MB_2U(SCH_1):PVNN_TERM_CPU1
   2 PU_CPU1_FRMAGENT      B @S9S_MB_2U_LIB.S9S_MB_2U(SCH_1):PU_CPU1_FRMAGENT

Q_RES_0402LF-240,1%,1/16W,CHIPA  I135  R290
   1    GND      A @S9S_MB_2U_LIB.S9S_MB_2U(SCH_1):GND
   2 PD_CPU1_DMIMODE_OVERRIDE      B @S9S_MB_2U_LIB.S9S_MB_2U(SCH_1):PD_CPU1_DMIMODE_OVERRIDE

Q_RES_0402LF-1K,1%,1/16W,EMPTYA  I136  R1009
   1 PVNN_TERM_CPU0      A @S9S_MB_2U_LIB.S9S_MB_2U(SCH_1):PVNN_TERM_CPU0
   2 PU_TAP_ODT_CPU0_EN      B @S9S_MB_2U_LIB.S9S_MB_2U(SCH_1):PU_TAP_ODT_CPU0_EN

Q_RES_0402LF-1K,1%,1/16W,EMPTYA  I139  R1008
   1 PVNN_TERM_CPU1      A @S9S_MB_2U_LIB.S9S_MB_2U(SCH_1):PVNN_TERM_CPU1
   2 PU_TAP_ODT_CPU1_EN      B @S9S_MB_2U_LIB.S9S_MB_2U(SCH_1):PU_TAP_ODT_CPU1_EN

Q_RES_0402LF-10K,1%,1/16W,CHIPA  I147  R283
   1 P3V3_AUX      A @S9S_MB_2U_LIB.S9S_MB_2U(SCH_1):P3V3_AUX
   2 FM_CPU0_PKGID0      B @S9S_MB_2U_LIB.S9S_MB_2U(SCH_1):FM_CPU0_PKGID0

Q_RES_0402LF-10K,1%,1/16W,CHIPA  I148  R284
   1 P3V3_AUX      A @S9S_MB_2U_LIB.S9S_MB_2U(SCH_1):P3V3_AUX
   2 FM_CPU0_PKGID1      B @S9S_MB_2U_LIB.S9S_MB_2U(SCH_1):FM_CPU0_PKGID1

Q_RES_0402LF-10K,1%,1/16W,CHIPA  I150  R285
   1 P3V3_AUX      A @S9S_MB_2U_LIB.S9S_MB_2U(SCH_1):P3V3_AUX
   2 FM_CPU0_PKGID2      B @S9S_MB_2U_LIB.S9S_MB_2U(SCH_1):FM_CPU0_PKGID2

Q_RES_0402LF-10K,1%,1/16W,CHIPA  I151  R286
   1 P3V3_AUX      A @S9S_MB_2U_LIB.S9S_MB_2U(SCH_1):P3V3_AUX
   2 FM_CPU0_PROC_ID0      B @S9S_MB_2U_LIB.S9S_MB_2U(SCH_1):FM_CPU0_PROC_ID0

Q_RES_0402LF-10K,1%,1/16W,CHIPA  I152  R287
   1 P3V3_AUX      A @S9S_MB_2U_LIB.S9S_MB_2U(SCH_1):P3V3_AUX
   2 FM_CPU0_PROC_ID1      B @S9S_MB_2U_LIB.S9S_MB_2U(SCH_1):FM_CPU0_PROC_ID1

Q_RES_0402LF-240,1%,1/16W,EMPTA  I156  R1232
   1 PVNN_TERM_CPU0      A @S9S_MB_2U_LIB.S9S_MB_2U(SCH_1):PVNN_TERM_CPU0
   2 PUD_XTAL_CPU0_MODE0      B @S9S_MB_2U_LIB.S9S_MB_2U(SCH_1):PUD_XTAL_CPU0_MODE0

Q_RES_0402LF-240,1%,1/16W,EMPTA  I158  R1233
   1 PVNN_TERM_CPU0      A @S9S_MB_2U_LIB.S9S_MB_2U(SCH_1):PVNN_TERM_CPU0
   2 PUD_XTAL_CPU0_MODE1      B @S9S_MB_2U_LIB.S9S_MB_2U(SCH_1):PUD_XTAL_CPU0_MODE1

Q_RES_0402LF-240,1%,1/16W,EMPTA  I160  R1237
   1    GND      A @S9S_MB_2U_LIB.S9S_MB_2U(SCH_1):GND
   2 PD_EXT_CLK_SEL_CPU0      B @S9S_MB_2U_LIB.S9S_MB_2U(SCH_1):PD_EXT_CLK_SEL_CPU0

Q_RES_0402LF-240,1%,1/16W,EMPTA  I161  R1238
   1    GND      A @S9S_MB_2U_LIB.S9S_MB_2U(SCH_1):GND
   2 PUD_XTAL_CPU0_MODE0      B @S9S_MB_2U_LIB.S9S_MB_2U(SCH_1):PUD_XTAL_CPU0_MODE0

Q_RES_0402LF-240,1%,1/16W,EMPTA  I163  R1239
   1    GND      A @S9S_MB_2U_LIB.S9S_MB_2U(SCH_1):GND
   2 PUD_XTAL_CPU0_MODE1      B @S9S_MB_2U_LIB.S9S_MB_2U(SCH_1):PUD_XTAL_CPU0_MODE1

Q_RES_0402LF-240,1%,1/16W,EMPTA  I169  R1229
   1 PVNN_TERM_CPU1      A @S9S_MB_2U_LIB.S9S_MB_2U(SCH_1):PVNN_TERM_CPU1
   2 PUD_XTAL_CPU1_MODE0      B @S9S_MB_2U_LIB.S9S_MB_2U(SCH_1):PUD_XTAL_CPU1_MODE0

Q_RES_0402LF-240,1%,1/16W,EMPTA  I170  R1230
   1 PVNN_TERM_CPU1      A @S9S_MB_2U_LIB.S9S_MB_2U(SCH_1):PVNN_TERM_CPU1
   2 PUD_XTAL_CPU1_MODE1      B @S9S_MB_2U_LIB.S9S_MB_2U(SCH_1):PUD_XTAL_CPU1_MODE1

Q_RES_0402LF-240,1%,1/16W,EMPTA  I172  R3024
   1    GND      A @S9S_MB_2U_LIB.S9S_MB_2U(SCH_1):GND
   2 PD_EXT_CLK_SEL_CPU1      B @S9S_MB_2U_LIB.S9S_MB_2U(SCH_1):PD_EXT_CLK_SEL_CPU1

Q_RES_0402LF-240,1%,1/16W,EMPTA  I176  R1235
   1    GND      A @S9S_MB_2U_LIB.S9S_MB_2U(SCH_1):GND
   2 PUD_XTAL_CPU1_MODE0      B @S9S_MB_2U_LIB.S9S_MB_2U(SCH_1):PUD_XTAL_CPU1_MODE0

Q_RES_0402LF-240,1%,1/16W,EMPTA  I177  R1236
   1    GND      A @S9S_MB_2U_LIB.S9S_MB_2U(SCH_1):GND
   2 PUD_XTAL_CPU1_MODE1      B @S9S_MB_2U_LIB.S9S_MB_2U(SCH_1):PUD_XTAL_CPU1_MODE1

Q_RES_0402LF-240,1%,1/16W,EMPTA  I196  R292
   1 PVNN_TERM_CPU0      A @S9S_MB_2U_LIB.S9S_MB_2U(SCH_1):PVNN_TERM_CPU0
   2 PD_CPU0_TXT_PLTEN      B @S9S_MB_2U_LIB.S9S_MB_2U(SCH_1):PD_CPU0_TXT_PLTEN

Q_RES_0402LF-240,1%,1/16W,EMPTA  I211  R293
   1 PD_CPU0_TXT_PLTEN      A @S9S_MB_2U_LIB.S9S_MB_2U(SCH_1):PD_CPU0_TXT_PLTEN
   2    GND      B @S9S_MB_2U_LIB.S9S_MB_2U(SCH_1):GND

Q_RES_0402LF-240,1%,1/16W,EMPTA  I215  R4262
   1 PVNN_TERM_CPU0      A @S9S_MB_2U_LIB.S9S_MB_2U(SCH_1):PVNN_TERM_CPU0
   2 PD_CPU0_BIST_ENABLE      B @S9S_MB_2U_LIB.S9S_MB_2U(SCH_1):PD_CPU0_BIST_ENABLE

Q_RES_0402LF-240,1%,1/16W,EMPTA  I216  R4263
   1 PD_CPU0_BIST_ENABLE      A @S9S_MB_2U_LIB.S9S_MB_2U(SCH_1):PD_CPU0_BIST_ENABLE
   2    GND      B @S9S_MB_2U_LIB.S9S_MB_2U(SCH_1):GND

Q_RES_0402LF-240,1%,1/16W,EMPTA  I219  R4260
   1 PVNN_TERM_CPU0      A @S9S_MB_2U_LIB.S9S_MB_2U(SCH_1):PVNN_TERM_CPU0
   2 PD_CPU1_BIST_ENABLE      B @S9S_MB_2U_LIB.S9S_MB_2U(SCH_1):PD_CPU1_BIST_ENABLE

Q_RES_0402LF-240,1%,1/16W,EMPTA  I220  R4261
   1 PD_CPU1_BIST_ENABLE      A @S9S_MB_2U_LIB.S9S_MB_2U(SCH_1):PD_CPU1_BIST_ENABLE
   2    GND      B @S9S_MB_2U_LIB.S9S_MB_2U(SCH_1):GND

Q_RES_0402LF-240,1%,1/16W,EMPTA  I224  R288
   1 PVNN_TERM_CPU0      A @S9S_MB_2U_LIB.S9S_MB_2U(SCH_1):PVNN_TERM_CPU0
   2 PD_CPU1_TXT_PLTEN      B @S9S_MB_2U_LIB.S9S_MB_2U(SCH_1):PD_CPU1_TXT_PLTEN

Q_RES_0402LF-240,1%,1/16W,EMPTA  I225  R289
   1 PD_CPU1_TXT_PLTEN      A @S9S_MB_2U_LIB.S9S_MB_2U(SCH_1):PD_CPU1_TXT_PLTEN
   2    GND      B @S9S_MB_2U_LIB.S9S_MB_2U(SCH_1):GND


DRAWING: @S9S_MB_2U_LIB.S9S_MB_2U(SCH_1):PAGE120 

Q_RES_0402LF-240,1%,1/16W,EMPTA  I27  R249
   1 PVNN_TERM_CPU0      A @S9S_MB_2U_LIB.S9S_MB_2U(SCH_1):PVNN_TERM_CPU0
   2 FM_S3M_CPU0_LVC1_GPIO_0      B @S9S_MB_2U_LIB.S9S_MB_2U(SCH_1):FM_S3M_CPU0_LVC1_GPIO_0

Q_RES_0402LF-240,1%,1/16W,EMPTA  I28  R251
   1 PVNN_TERM_CPU0      A @S9S_MB_2U_LIB.S9S_MB_2U(SCH_1):PVNN_TERM_CPU0
   2 FM_S3M_CPU0_LVC1_GPIO_4      B @S9S_MB_2U_LIB.S9S_MB_2U(SCH_1):FM_S3M_CPU0_LVC1_GPIO_4

Q_RES_0402LF-240,1%,1/16W,EMPTA  I29  R250
   1 PVNN_TERM_CPU0      A @S9S_MB_2U_LIB.S9S_MB_2U(SCH_1):PVNN_TERM_CPU0
   2 FM_S3M_CPU0_LVC1_GPIO_1      B @S9S_MB_2U_LIB.S9S_MB_2U(SCH_1):FM_S3M_CPU0_LVC1_GPIO_1

Q_RES_0402LF-240,1%,1/16W,CHIPA  I30  R252
   1 PVNN_TERM_CPU0      A @S9S_MB_2U_LIB.S9S_MB_2U(SCH_1):PVNN_TERM_CPU0
   2 PUD_PCH_BOOT_MODE_CPU0      B @S9S_MB_2U_LIB.S9S_MB_2U(SCH_1):PUD_PCH_BOOT_MODE_CPU0

Q_RES_0402LF-240,1%,1/16W,CHIPA  I31  R253
   1 PVNN_TERM_CPU0      A @S9S_MB_2U_LIB.S9S_MB_2U(SCH_1):PVNN_TERM_CPU0
   2 FM_S3M_CPU0_LVC1_GPIO_2      B @S9S_MB_2U_LIB.S9S_MB_2U(SCH_1):FM_S3M_CPU0_LVC1_GPIO_2

Q_RES_0402LF-240,1%,1/16W,CHIPA  I32  R254
   1 PVNN_TERM_CPU0      A @S9S_MB_2U_LIB.S9S_MB_2U(SCH_1):PVNN_TERM_CPU0
   2 FM_S3M_CPU0_LVC1_GPIO_3      B @S9S_MB_2U_LIB.S9S_MB_2U(SCH_1):FM_S3M_CPU0_LVC1_GPIO_3

Q_RES_0402LF-240,1%,1/16W,EMPTA  I42  R255
   1 PVNN_TERM_CPU1      A @S9S_MB_2U_LIB.S9S_MB_2U(SCH_1):PVNN_TERM_CPU1
   2 FM_S3M_CPU1_LVC1_GPIO_0      B @S9S_MB_2U_LIB.S9S_MB_2U(SCH_1):FM_S3M_CPU1_LVC1_GPIO_0

Q_RES_0402LF-240,1%,1/16W,EMPTA  I43  R257
   1 PVNN_TERM_CPU1      A @S9S_MB_2U_LIB.S9S_MB_2U(SCH_1):PVNN_TERM_CPU1
   2 FM_S3M_CPU1_LVC1_GPIO_4      B @S9S_MB_2U_LIB.S9S_MB_2U(SCH_1):FM_S3M_CPU1_LVC1_GPIO_4

Q_RES_0402LF-240,1%,1/16W,CHIPA  I44  R258
   1 PVNN_TERM_CPU1      A @S9S_MB_2U_LIB.S9S_MB_2U(SCH_1):PVNN_TERM_CPU1
   2 PUD_PCH_BOOT_MODE_CPU1      B @S9S_MB_2U_LIB.S9S_MB_2U(SCH_1):PUD_PCH_BOOT_MODE_CPU1

Q_RES_0402LF-240,1%,1/16W,CHIPA  I45  R259
   1 PVNN_TERM_CPU1      A @S9S_MB_2U_LIB.S9S_MB_2U(SCH_1):PVNN_TERM_CPU1
   2 FM_S3M_CPU1_LVC1_GPIO_2      B @S9S_MB_2U_LIB.S9S_MB_2U(SCH_1):FM_S3M_CPU1_LVC1_GPIO_2

Q_RES_0402LF-240,1%,1/16W,CHIPA  I46  R260
   1 PVNN_TERM_CPU1      A @S9S_MB_2U_LIB.S9S_MB_2U(SCH_1):PVNN_TERM_CPU1
   2 FM_S3M_CPU1_LVC1_GPIO_3      B @S9S_MB_2U_LIB.S9S_MB_2U(SCH_1):FM_S3M_CPU1_LVC1_GPIO_3

Q_RES_0402LF-240,1%,1/16W,EMPTA  I48  R256
   1 PVNN_TERM_CPU1      A @S9S_MB_2U_LIB.S9S_MB_2U(SCH_1):PVNN_TERM_CPU1
   2 FM_S3M_CPU1_LVC1_GPIO_1      B @S9S_MB_2U_LIB.S9S_MB_2U(SCH_1):FM_S3M_CPU1_LVC1_GPIO_1

Q_RES_0402LF-240,1%,1/16W,EMPTA  I61  R1391
   1    GND      A @S9S_MB_2U_LIB.S9S_MB_2U(SCH_1):GND
   2 FM_S3M_CPU0_LVC1_GPIO_2      B @S9S_MB_2U_LIB.S9S_MB_2U(SCH_1):FM_S3M_CPU0_LVC1_GPIO_2

Q_RES_0402LF-240,1%,1/16W,EMPTA  I62  R1392
   1    GND      A @S9S_MB_2U_LIB.S9S_MB_2U(SCH_1):GND
   2 FM_S3M_CPU0_LVC1_GPIO_3      B @S9S_MB_2U_LIB.S9S_MB_2U(SCH_1):FM_S3M_CPU0_LVC1_GPIO_3

Q_RES_0402LF-240,1%,1/16W,EMPTA  I66  R1393
   1    GND      A @S9S_MB_2U_LIB.S9S_MB_2U(SCH_1):GND
   2 FM_S3M_CPU1_LVC1_GPIO_2      B @S9S_MB_2U_LIB.S9S_MB_2U(SCH_1):FM_S3M_CPU1_LVC1_GPIO_2

Q_RES_0402LF-240,1%,1/16W,EMPTA  I67  R1394
   1    GND      A @S9S_MB_2U_LIB.S9S_MB_2U(SCH_1):GND
   2 FM_S3M_CPU1_LVC1_GPIO_3      B @S9S_MB_2U_LIB.S9S_MB_2U(SCH_1):FM_S3M_CPU1_LVC1_GPIO_3


DRAWING: @S9S_MB_2U_LIB.S9S_MB_2U(SCH_1):PAGE123 

Q_RES_0402LF-1.5K,1%,1/16W,CHIA  I8  R206
   1 H_CPU1_MEMTRIP_LVC1_R_N      A @S9S_MB_2U_LIB.S9S_MB_2U(SCH_1):H_CPU1_MEMTRIP_LVC1_R_N
   2 H_CPU1_MEMTRIP_OUT_VT_R_N      B @S9S_MB_2U_LIB.S9S_MB_2U(SCH_1):H_CPU1_MEMTRIP_OUT_VT_R_N

Q_RES_0402LF-0,5%,1/16W,CHIP,CA  I4  R188
   1 H_CPU_NMI_LVC1_R_N      A @S9S_MB_2U_LIB.S9S_MB_2U(SCH_1):H_CPU_NMI_LVC1_R_N
   2 H_CPU_NMI_LVC1_N      B @S9S_MB_2U_LIB.S9S_MB_2U(SCH_1):H_CPU_NMI_LVC1_N

Q_RES_0402LF-49.9,1%,1/16W,CHIA  I5  R196
   1 H_CPU_NMI_LVC1_N      A @S9S_MB_2U_LIB.S9S_MB_2U(SCH_1):H_CPU_NMI_LVC1_N
   2 H_CPU1_NMI_LVC1_N      B @S9S_MB_2U_LIB.S9S_MB_2U(SCH_1):H_CPU1_NMI_LVC1_N

Q_RES_0402LF-49.9,1%,1/16W,CHIA  I6  R195
   1 H_CPU_NMI_LVC1_N      A @S9S_MB_2U_LIB.S9S_MB_2U(SCH_1):H_CPU_NMI_LVC1_N
   2 H_CPU0_NMI_LVC1_N      B @S9S_MB_2U_LIB.S9S_MB_2U(SCH_1):H_CPU0_NMI_LVC1_N

Q_RES_0402LF-100,1%,1/16W,CHIPA  I7  R202
   1 PVNN_TERM_CPU1      A @S9S_MB_2U_LIB.S9S_MB_2U(SCH_1):PVNN_TERM_CPU1
   2 H_CPU1_MEMTRIP_LVC1_R_N      B @S9S_MB_2U_LIB.S9S_MB_2U(SCH_1):H_CPU1_MEMTRIP_LVC1_R_N

Q_RES_0402LF-1.5K,1%,1/16W,CHIA  I10  R205
   1 H_CPU0_MEMTRIP_LVC1_R_N      A @S9S_MB_2U_LIB.S9S_MB_2U(SCH_1):H_CPU0_MEMTRIP_LVC1_R_N
   2 H_CPU0_MEMTRIP_OUT_VT_R_N      B @S9S_MB_2U_LIB.S9S_MB_2U(SCH_1):H_CPU0_MEMTRIP_OUT_VT_R_N

BC847BPN-BC847BPN,SMLF,IC,BA00A  I11  Q140
   5 H_CPU1_MEMTRIP_OUT_VT_R_N     B2 @S9S_MB_2U_LIB.S9S_MB_2U(SCH_1):H_CPU1_MEMTRIP_OUT_VT_R_N
   3 H_CPU1_MEMTRIP     C2 @S9S_MB_2U_LIB.S9S_MB_2U(SCH_1):H_CPU1_MEMTRIP
   4 PVNN_TERM_CPU1     E2 @S9S_MB_2U_LIB.S9S_MB_2U(SCH_1):PVNN_TERM_CPU1

BC847BPN-BC847BPN,SMLF,IC,BA00A  I12  Q141
   5 H_CPU0_MEMTRIP_OUT_VT_R_N     B2 @S9S_MB_2U_LIB.S9S_MB_2U(SCH_1):H_CPU0_MEMTRIP_OUT_VT_R_N
   3 H_CPU0_MEMTRIP     C2 @S9S_MB_2U_LIB.S9S_MB_2U(SCH_1):H_CPU0_MEMTRIP
   4 PVNN_TERM_CPU0     E2 @S9S_MB_2U_LIB.S9S_MB_2U(SCH_1):PVNN_TERM_CPU0

Q_RES_0402LF-1.5K,1%,1/16W,CHIA  I14  R4410
   1 H_CPU1_MEMTRIP      A @S9S_MB_2U_LIB.S9S_MB_2U(SCH_1):H_CPU1_MEMTRIP
   2 H_CPU1_MEMTRIP_R      B @S9S_MB_2U_LIB.S9S_MB_2U(SCH_1):H_CPU1_MEMTRIP_R

Q_RES_0402LF-1.5K,1%,1/16W,CHIA  I15  R4409
   1 H_CPU0_MEMTRIP      A @S9S_MB_2U_LIB.S9S_MB_2U(SCH_1):H_CPU0_MEMTRIP
   2 H_CPU0_MEMTRIP_R      B @S9S_MB_2U_LIB.S9S_MB_2U(SCH_1):H_CPU0_MEMTRIP_R

BC847BPN-BC847BPN,SMLF,IC,BA00A  I16  Q140
   2 H_CPU1_MEMTRIP_R     B1 @S9S_MB_2U_LIB.S9S_MB_2U(SCH_1):H_CPU1_MEMTRIP_R
   6 H_CPU1_MEMTRIP_VT_N     C1 @S9S_MB_2U_LIB.S9S_MB_2U(SCH_1):H_CPU1_MEMTRIP_VT_N
   1    GND     E1 @S9S_MB_2U_LIB.S9S_MB_2U(SCH_1):GND

BC847BPN-BC847BPN,SMLF,IC,BA00A  I18  Q141
   2 H_CPU0_MEMTRIP_R     B1 @S9S_MB_2U_LIB.S9S_MB_2U(SCH_1):H_CPU0_MEMTRIP_R
   6 H_CPU0_MEMTRIP_VT_N     C1 @S9S_MB_2U_LIB.S9S_MB_2U(SCH_1):H_CPU0_MEMTRIP_VT_N
   1    GND     E1 @S9S_MB_2U_LIB.S9S_MB_2U(SCH_1):GND

Q_RES_0402LF-100,1%,1/16W,CHIPA  I19  R200
   1 PVNN_TERM_CPU0      A @S9S_MB_2U_LIB.S9S_MB_2U(SCH_1):PVNN_TERM_CPU0
   2 H_CPU0_MEMTRIP_LVC1_R_N      B @S9S_MB_2U_LIB.S9S_MB_2U(SCH_1):H_CPU0_MEMTRIP_LVC1_R_N

Q_RES_0402LF-301,1%,1/16W,CHIPA  I23  R198
   1 PVNN_TERM_CPU1      A @S9S_MB_2U_LIB.S9S_MB_2U(SCH_1):PVNN_TERM_CPU1
   2 H_CPU1_NMI_LVC1_N      B @S9S_MB_2U_LIB.S9S_MB_2U(SCH_1):H_CPU1_NMI_LVC1_N

Q_RES_0402LF-301,1%,1/16W,CHIPA  I27  R197
   1 PVNN_TERM_CPU0      A @S9S_MB_2U_LIB.S9S_MB_2U(SCH_1):PVNN_TERM_CPU0
   2 H_CPU0_NMI_LVC1_N      B @S9S_MB_2U_LIB.S9S_MB_2U(SCH_1):H_CPU0_NMI_LVC1_N

Q_RES_0402LF-4.75K,1%,1/16W,CHA  I29  R4412
   1   P3V3      A @S9S_MB_2U_LIB.S9S_MB_2U(SCH_1):P3V3
   2 H_CPU1_MEMTRIP_VT_N      B @S9S_MB_2U_LIB.S9S_MB_2U(SCH_1):H_CPU1_MEMTRIP_VT_N

Q_RES_0402LF-33.2,1%,1/16W,CHIA  I31  R4414
   1 H_CPU1_MEMTRIP_VT_N      A @S9S_MB_2U_LIB.S9S_MB_2U(SCH_1):H_CPU1_MEMTRIP_VT_N
   2 H_CPU1_MEMTRIP_LVC1_N      B @S9S_MB_2U_LIB.S9S_MB_2U(SCH_1):H_CPU1_MEMTRIP_LVC1_N

Q_RES_0402LF-4.75K,1%,1/16W,CHA  I32  R4411
   1   P3V3      A @S9S_MB_2U_LIB.S9S_MB_2U(SCH_1):P3V3
   2 H_CPU0_MEMTRIP_VT_N      B @S9S_MB_2U_LIB.S9S_MB_2U(SCH_1):H_CPU0_MEMTRIP_VT_N

Q_RES_0402LF-33.2,1%,1/16W,CHIA  I33  R4413
   1 H_CPU0_MEMTRIP_VT_N      A @S9S_MB_2U_LIB.S9S_MB_2U(SCH_1):H_CPU0_MEMTRIP_VT_N
   2 H_CPU0_MEMTRIP_LVC1_N      B @S9S_MB_2U_LIB.S9S_MB_2U(SCH_1):H_CPU0_MEMTRIP_LVC1_N


DRAWING: @S9S_MB_2U_LIB.S9S_MB_2U(SCH_1):PAGE124 

Q_RES_0402LF-0,5%,1/16W,CHIP,CA  I17  R160
   1 PWRGD_DRAMPWRGD_CPU0_AB_R_LVC1      A @S9S_MB_2U_LIB.S9S_MB_2U(SCH_1):PWRGD_DRAMPWRGD_CPU0_AB_R_LVC1
   2 PWRGD_DRAMPWRGD_CPU0_AB_LVC1_R2      B @S9S_MB_2U_LIB.S9S_MB_2U(SCH_1):PWRGD_DRAMPWRGD_CPU0_AB_LVC1_R2

Q_RES_0402LF-0,5%,1/16W,CHIP,CA  I19  R162
   1 PWRGD_DRAMPWRGD_CPU0_CD_R_LVC1      A @S9S_MB_2U_LIB.S9S_MB_2U(SCH_1):PWRGD_DRAMPWRGD_CPU0_CD_R_LVC1
   2 PWRGD_DRAMPWRGD_CPU0_CD_LVC1_R2      B @S9S_MB_2U_LIB.S9S_MB_2U(SCH_1):PWRGD_DRAMPWRGD_CPU0_CD_LVC1_R2

Q_RES_0402LF-0,5%,1/16W,CHIP,CA  I26  R164
   1 PWRGD_DRAMPWRGD_CPU0_EF_R_LVC1      A @S9S_MB_2U_LIB.S9S_MB_2U(SCH_1):PWRGD_DRAMPWRGD_CPU0_EF_R_LVC1
   2 PWRGD_DRAMPWRGD_CPU0_EF_LVC1_R2      B @S9S_MB_2U_LIB.S9S_MB_2U(SCH_1):PWRGD_DRAMPWRGD_CPU0_EF_LVC1_R2

Q_RES_0402LF-0,5%,1/16W,CHIP,CA  I33  R166
   1 PWRGD_DRAMPWRGD_CPU0_GH_R_LVC1      A @S9S_MB_2U_LIB.S9S_MB_2U(SCH_1):PWRGD_DRAMPWRGD_CPU0_GH_R_LVC1
   2 PWRGD_DRAMPWRGD_CPU0_GH_LVC1_R2      B @S9S_MB_2U_LIB.S9S_MB_2U(SCH_1):PWRGD_DRAMPWRGD_CPU0_GH_LVC1_R2

Q_RES_0402LF-0,5%,1/16W,CHIP,CA  I43  R168
   1 PWRGD_CPU0_LVC1_R      A @S9S_MB_2U_LIB.S9S_MB_2U(SCH_1):PWRGD_CPU0_LVC1_R
   2 PWRGD_CPU0_BUF_R      B @S9S_MB_2U_LIB.S9S_MB_2U(SCH_1):PWRGD_CPU0_BUF_R

Q_RES_0402LF-0,5%,1/16W,CHIP,CA  I52  R171
   1 RST_CPU0_LVC1_R_N      A @S9S_MB_2U_LIB.S9S_MB_2U(SCH_1):RST_CPU0_LVC1_R_N
   2 RST_CPU0_BUF_R_N      B @S9S_MB_2U_LIB.S9S_MB_2U(SCH_1):RST_CPU0_BUF_R_N

Q_RES_0402LF-100,1%,1/16W,CHIPA  I60  R185
   1 RST_CPU0_BUF_R_N      A @S9S_MB_2U_LIB.S9S_MB_2U(SCH_1):RST_CPU0_BUF_R_N
   2 PVNN_TERM_CPU0      B @S9S_MB_2U_LIB.S9S_MB_2U(SCH_1):PVNN_TERM_CPU0

Q_RES_0402LF-100,1%,1/16W,CHIPA  I62  R183
   1 PWRGD_CPU0_BUF_R      A @S9S_MB_2U_LIB.S9S_MB_2U(SCH_1):PWRGD_CPU0_BUF_R
   2 PVNN_TERM_CPU0      B @S9S_MB_2U_LIB.S9S_MB_2U(SCH_1):PVNN_TERM_CPU0

Q_RES_0402LF-100,1%,1/16W,CHIPA  I68  R181
   1 PWRGD_DRAMPWRGD_CPU0_GH_LVC1_R2      A @S9S_MB_2U_LIB.S9S_MB_2U(SCH_1):PWRGD_DRAMPWRGD_CPU0_GH_LVC1_R2
   2 PVCCD_HV_CPU0      B @S9S_MB_2U_LIB.S9S_MB_2U(SCH_1):PVCCD_HV_CPU0

Q_RES_0402LF-100,1%,1/16W,CHIPA  I70  R179
   1 PWRGD_DRAMPWRGD_CPU0_EF_LVC1_R2      A @S9S_MB_2U_LIB.S9S_MB_2U(SCH_1):PWRGD_DRAMPWRGD_CPU0_EF_LVC1_R2
   2 PVCCD_HV_CPU0      B @S9S_MB_2U_LIB.S9S_MB_2U(SCH_1):PVCCD_HV_CPU0

Q_RES_0402LF-100,1%,1/16W,CHIPA  I72  R177
   1 PWRGD_DRAMPWRGD_CPU0_CD_LVC1_R2      A @S9S_MB_2U_LIB.S9S_MB_2U(SCH_1):PWRGD_DRAMPWRGD_CPU0_CD_LVC1_R2
   2 PVCCD_HV_CPU0      B @S9S_MB_2U_LIB.S9S_MB_2U(SCH_1):PVCCD_HV_CPU0

Q_RES_0402LF-100,1%,1/16W,CHIPA  I76  R175
   1 PWRGD_DRAMPWRGD_CPU0_AB_LVC1_R2      A @S9S_MB_2U_LIB.S9S_MB_2U(SCH_1):PWRGD_DRAMPWRGD_CPU0_AB_LVC1_R2
   2 PVCCD_HV_CPU0      B @S9S_MB_2U_LIB.S9S_MB_2U(SCH_1):PVCCD_HV_CPU0

Q_RES_0402LF-100,1%,1/16W,CHIPA  I77  R184
   1 PWRGD_CPU0_BUF_R      A @S9S_MB_2U_LIB.S9S_MB_2U(SCH_1):PWRGD_CPU0_BUF_R
   2 PWRGD_CPU0_LVC1      B @S9S_MB_2U_LIB.S9S_MB_2U(SCH_1):PWRGD_CPU0_LVC1

Q_RES_0402LF-100,1%,1/16W,CHIPA  I78  R186
   1 RST_CPU0_BUF_R_N      A @S9S_MB_2U_LIB.S9S_MB_2U(SCH_1):RST_CPU0_BUF_R_N
   2 RST_CPU0_LVC1_N      B @S9S_MB_2U_LIB.S9S_MB_2U(SCH_1):RST_CPU0_LVC1_N

Q_RES_0402LF-100,1%,1/16W,CHIPA  I79  R4298
   1 PWRGD_DRAMPWRGD_CPU0_GH_LVC1_R2      A @S9S_MB_2U_LIB.S9S_MB_2U(SCH_1):PWRGD_DRAMPWRGD_CPU0_GH_LVC1_R2
   2 PWRGD_DRAMPWRGD_CPU0_GH_LVC1_R      B @S9S_MB_2U_LIB.S9S_MB_2U(SCH_1):PWRGD_DRAMPWRGD_CPU0_GH_LVC1_R

Q_RES_0402LF-100,1%,1/16W,CHIPA  I82  R4297
   1 PWRGD_DRAMPWRGD_CPU0_EF_LVC1_R2      A @S9S_MB_2U_LIB.S9S_MB_2U(SCH_1):PWRGD_DRAMPWRGD_CPU0_EF_LVC1_R2
   2 PWRGD_DRAMPWRGD_CPU0_EF_LVC1_R      B @S9S_MB_2U_LIB.S9S_MB_2U(SCH_1):PWRGD_DRAMPWRGD_CPU0_EF_LVC1_R

Q_RES_0402LF-100,1%,1/16W,CHIPA  I85  R4296
   1 PWRGD_DRAMPWRGD_CPU0_CD_LVC1_R2      A @S9S_MB_2U_LIB.S9S_MB_2U(SCH_1):PWRGD_DRAMPWRGD_CPU0_CD_LVC1_R2
   2 PWRGD_DRAMPWRGD_CPU0_CD_LVC1_R      B @S9S_MB_2U_LIB.S9S_MB_2U(SCH_1):PWRGD_DRAMPWRGD_CPU0_CD_LVC1_R

Q_RES_0402LF-100,1%,1/16W,CHIPA  I87  R4295
   1 PWRGD_DRAMPWRGD_CPU0_AB_LVC1_R2      A @S9S_MB_2U_LIB.S9S_MB_2U(SCH_1):PWRGD_DRAMPWRGD_CPU0_AB_LVC1_R2
   2 PWRGD_DRAMPWRGD_CPU0_AB_LVC1_R      B @S9S_MB_2U_LIB.S9S_MB_2U(SCH_1):PWRGD_DRAMPWRGD_CPU0_AB_LVC1_R


DRAWING: @S9S_MB_2U_LIB.S9S_MB_2U(SCH_1):PAGE125 

Q_RES_0402LF-0,5%,1/16W,CHIP,CA  I3  R132
   1 RST_CPU1_LVC1_R_N      A @S9S_MB_2U_LIB.S9S_MB_2U(SCH_1):RST_CPU1_LVC1_R_N
   2 RST_CPU1_BUF_R_N      B @S9S_MB_2U_LIB.S9S_MB_2U(SCH_1):RST_CPU1_BUF_R_N

Q_RES_0402LF-0,5%,1/16W,CHIP,CA  I5  R130
   1 PWRGD_CPU1_LVC1_R      A @S9S_MB_2U_LIB.S9S_MB_2U(SCH_1):PWRGD_CPU1_LVC1_R
   2 PWRGD_CPU1_BUF_R      B @S9S_MB_2U_LIB.S9S_MB_2U(SCH_1):PWRGD_CPU1_BUF_R

Q_RES_0402LF-0,5%,1/16W,CHIP,CA  I7  R128
   1 PWRGD_DRAMPWRGD_CPU1_GH_R_LVC1      A @S9S_MB_2U_LIB.S9S_MB_2U(SCH_1):PWRGD_DRAMPWRGD_CPU1_GH_R_LVC1
   2 PWRGD_DRAMPWRGD_CPU1_GH_LVC1_R2      B @S9S_MB_2U_LIB.S9S_MB_2U(SCH_1):PWRGD_DRAMPWRGD_CPU1_GH_LVC1_R2

Q_RES_0402LF-0,5%,1/16W,CHIP,CA  I13  R126
   1 PWRGD_DRAMPWRGD_CPU1_EF_R_LVC1      A @S9S_MB_2U_LIB.S9S_MB_2U(SCH_1):PWRGD_DRAMPWRGD_CPU1_EF_R_LVC1
   2 PWRGD_DRAMPWRGD_CPU1_EF_LVC1_R2      B @S9S_MB_2U_LIB.S9S_MB_2U(SCH_1):PWRGD_DRAMPWRGD_CPU1_EF_LVC1_R2

Q_RES_0402LF-0,5%,1/16W,CHIP,CA  I15  R124
   1 PWRGD_DRAMPWRGD_CPU1_CD_R_LVC1      A @S9S_MB_2U_LIB.S9S_MB_2U(SCH_1):PWRGD_DRAMPWRGD_CPU1_CD_R_LVC1
   2 PWRGD_DRAMPWRGD_CPU1_CD_LVC1_R2      B @S9S_MB_2U_LIB.S9S_MB_2U(SCH_1):PWRGD_DRAMPWRGD_CPU1_CD_LVC1_R2

Q_RES_0402LF-0,5%,1/16W,CHIP,CA  I17  R122
   1 PWRGD_DRAMPWRGD_CPU1_AB_R_LVC1      A @S9S_MB_2U_LIB.S9S_MB_2U(SCH_1):PWRGD_DRAMPWRGD_CPU1_AB_R_LVC1
   2 PWRGD_DRAMPWRGD_CPU1_AB_LVC1_R2      B @S9S_MB_2U_LIB.S9S_MB_2U(SCH_1):PWRGD_DRAMPWRGD_CPU1_AB_LVC1_R2

Q_RES_0402LF-100,1%,1/16W,CHIPA  I24  R157
   1 RST_CPU1_BUF_R_N      A @S9S_MB_2U_LIB.S9S_MB_2U(SCH_1):RST_CPU1_BUF_R_N
   2 PVNN_TERM_CPU1      B @S9S_MB_2U_LIB.S9S_MB_2U(SCH_1):PVNN_TERM_CPU1

Q_RES_0402LF-100,1%,1/16W,CHIPA  I26  R155
   1 PWRGD_CPU1_BUF_R      A @S9S_MB_2U_LIB.S9S_MB_2U(SCH_1):PWRGD_CPU1_BUF_R
   2 PVNN_TERM_CPU1      B @S9S_MB_2U_LIB.S9S_MB_2U(SCH_1):PVNN_TERM_CPU1

Q_RES_0402LF-100,1%,1/16W,CHIPA  I56  R153
   1 PWRGD_DRAMPWRGD_CPU1_GH_LVC1_R2      A @S9S_MB_2U_LIB.S9S_MB_2U(SCH_1):PWRGD_DRAMPWRGD_CPU1_GH_LVC1_R2
   2 PVCCD_HV_CPU1      B @S9S_MB_2U_LIB.S9S_MB_2U(SCH_1):PVCCD_HV_CPU1

Q_RES_0402LF-100,1%,1/16W,CHIPA  I58  R151
   1 PWRGD_DRAMPWRGD_CPU1_EF_LVC1_R2      A @S9S_MB_2U_LIB.S9S_MB_2U(SCH_1):PWRGD_DRAMPWRGD_CPU1_EF_LVC1_R2
   2 PVCCD_HV_CPU1      B @S9S_MB_2U_LIB.S9S_MB_2U(SCH_1):PVCCD_HV_CPU1

Q_RES_0402LF-100,1%,1/16W,CHIPA  I60  R137
   1 PWRGD_DRAMPWRGD_CPU1_CD_LVC1_R2      A @S9S_MB_2U_LIB.S9S_MB_2U(SCH_1):PWRGD_DRAMPWRGD_CPU1_CD_LVC1_R2
   2 PVCCD_HV_CPU1      B @S9S_MB_2U_LIB.S9S_MB_2U(SCH_1):PVCCD_HV_CPU1

Q_RES_0402LF-100,1%,1/16W,CHIPA  I62  R135
   1 PWRGD_DRAMPWRGD_CPU1_AB_LVC1_R2      A @S9S_MB_2U_LIB.S9S_MB_2U(SCH_1):PWRGD_DRAMPWRGD_CPU1_AB_LVC1_R2
   2 PVCCD_HV_CPU1      B @S9S_MB_2U_LIB.S9S_MB_2U(SCH_1):PVCCD_HV_CPU1

Q_RES_0402LF-100,1%,1/16W,CHIPA  I64  R156
   1 PWRGD_CPU1_BUF_R      A @S9S_MB_2U_LIB.S9S_MB_2U(SCH_1):PWRGD_CPU1_BUF_R
   2 PWRGD_CPU1_LVC1      B @S9S_MB_2U_LIB.S9S_MB_2U(SCH_1):PWRGD_CPU1_LVC1

Q_RES_0402LF-100,1%,1/16W,CHIPA  I65  R158
   1 RST_CPU1_BUF_R_N      A @S9S_MB_2U_LIB.S9S_MB_2U(SCH_1):RST_CPU1_BUF_R_N
   2 RST_CPU1_LVC1_N      B @S9S_MB_2U_LIB.S9S_MB_2U(SCH_1):RST_CPU1_LVC1_N

Q_RES_0402LF-100,1%,1/16W,CHIPA  I66  R4302
   1 PWRGD_DRAMPWRGD_CPU1_GH_LVC1_R2      A @S9S_MB_2U_LIB.S9S_MB_2U(SCH_1):PWRGD_DRAMPWRGD_CPU1_GH_LVC1_R2
   2 PWRGD_DRAMPWRGD_CPU1_GH_LVC1_R      B @S9S_MB_2U_LIB.S9S_MB_2U(SCH_1):PWRGD_DRAMPWRGD_CPU1_GH_LVC1_R

Q_RES_0402LF-100,1%,1/16W,CHIPA  I68  R4301
   1 PWRGD_DRAMPWRGD_CPU1_EF_LVC1_R2      A @S9S_MB_2U_LIB.S9S_MB_2U(SCH_1):PWRGD_DRAMPWRGD_CPU1_EF_LVC1_R2
   2 PWRGD_DRAMPWRGD_CPU1_EF_LVC1_R      B @S9S_MB_2U_LIB.S9S_MB_2U(SCH_1):PWRGD_DRAMPWRGD_CPU1_EF_LVC1_R

Q_RES_0402LF-100,1%,1/16W,CHIPA  I70  R4300
   1 PWRGD_DRAMPWRGD_CPU1_CD_LVC1_R2      A @S9S_MB_2U_LIB.S9S_MB_2U(SCH_1):PWRGD_DRAMPWRGD_CPU1_CD_LVC1_R2
   2 PWRGD_DRAMPWRGD_CPU1_CD_LVC1_R      B @S9S_MB_2U_LIB.S9S_MB_2U(SCH_1):PWRGD_DRAMPWRGD_CPU1_CD_LVC1_R

Q_RES_0402LF-100,1%,1/16W,CHIPA  I72  R4299
   1 PWRGD_DRAMPWRGD_CPU1_AB_LVC1_R2      A @S9S_MB_2U_LIB.S9S_MB_2U(SCH_1):PWRGD_DRAMPWRGD_CPU1_AB_LVC1_R2
   2 PWRGD_DRAMPWRGD_CPU1_AB_LVC1_R      B @S9S_MB_2U_LIB.S9S_MB_2U(SCH_1):PWRGD_DRAMPWRGD_CPU1_AB_LVC1_R


DRAWING: @S9S_MB_2U_LIB.S9S_MB_2U(SCH_1):PAGE126 

Q_RES_0402LF-240,1%,1/16W,EMPTA  I22  R96
   1 PVNN_TERM_CPU0      A @S9S_MB_2U_LIB.S9S_MB_2U(SCH_1):PVNN_TERM_CPU0
   2 PU_CPU0_UPI2_AC_COUPLING      B @S9S_MB_2U_LIB.S9S_MB_2U(SCH_1):PU_CPU0_UPI2_AC_COUPLING

Q_RES_0402LF-240,1%,1/16W,EMPTA  I23  R95
   1 PVNN_TERM_CPU0      A @S9S_MB_2U_LIB.S9S_MB_2U(SCH_1):PVNN_TERM_CPU0
   2 PU_CPU0_UPI1_AC_COUPLING      B @S9S_MB_2U_LIB.S9S_MB_2U(SCH_1):PU_CPU0_UPI1_AC_COUPLING

Q_RES_0402LF-240,1%,1/16W,EMPTA  I25  R94
   1 PVNN_TERM_CPU0      A @S9S_MB_2U_LIB.S9S_MB_2U(SCH_1):PVNN_TERM_CPU0
   2 PU_CPU0_UPI0_AC_COUPLING      B @S9S_MB_2U_LIB.S9S_MB_2U(SCH_1):PU_CPU0_UPI0_AC_COUPLING

Q_RES_0402LF-240,1%,1/16W,EMPTA  I114  R97
   1 PVNN_TERM_CPU0      A @S9S_MB_2U_LIB.S9S_MB_2U(SCH_1):PVNN_TERM_CPU0
   2 PU_CPU0_UPI3_AC_COUPLING      B @S9S_MB_2U_LIB.S9S_MB_2U(SCH_1):PU_CPU0_UPI3_AC_COUPLING

Q_RES_0402LF-240,1%,1/16W,EMPTA  I135  R90
   1 PVNN_TERM_CPU1      A @S9S_MB_2U_LIB.S9S_MB_2U(SCH_1):PVNN_TERM_CPU1
   2 PU_CPU1_UPI0_AC_COUPLING      B @S9S_MB_2U_LIB.S9S_MB_2U(SCH_1):PU_CPU1_UPI0_AC_COUPLING

Q_RES_0402LF-240,1%,1/16W,EMPTA  I136  R91
   1 PVNN_TERM_CPU1      A @S9S_MB_2U_LIB.S9S_MB_2U(SCH_1):PVNN_TERM_CPU1
   2 PU_CPU1_UPI1_AC_COUPLING      B @S9S_MB_2U_LIB.S9S_MB_2U(SCH_1):PU_CPU1_UPI1_AC_COUPLING

Q_RES_0402LF-240,1%,1/16W,EMPTA  I140  R92
   1 PVNN_TERM_CPU1      A @S9S_MB_2U_LIB.S9S_MB_2U(SCH_1):PVNN_TERM_CPU1
   2 PU_CPU1_UPI2_AC_COUPLING      B @S9S_MB_2U_LIB.S9S_MB_2U(SCH_1):PU_CPU1_UPI2_AC_COUPLING

Q_RES_0402LF-240,1%,1/16W,EMPTA  I141  R93
   1 PVNN_TERM_CPU1      A @S9S_MB_2U_LIB.S9S_MB_2U(SCH_1):PVNN_TERM_CPU1
   2 PU_CPU1_UPI3_AC_COUPLING      B @S9S_MB_2U_LIB.S9S_MB_2U(SCH_1):PU_CPU1_UPI3_AC_COUPLING


DRAWING: @S9S_MB_2U_LIB.S9S_MB_2U(SCH_1):PAGE127 

Q_RES_0402LF-10K,1%,1/16W,CHIPA  I1  R334
   1 PD_PIROM_CPU0_ADDR1      A @S9S_MB_2U_LIB.S9S_MB_2U(SCH_1):PD_PIROM_CPU0_ADDR1
   2    GND      B @S9S_MB_2U_LIB.S9S_MB_2U(SCH_1):GND

Q_RES_0402LF-1K,1%,1/16W,EMPTYA  I5  R335
   1 P3V3_AUX      A @S9S_MB_2U_LIB.S9S_MB_2U(SCH_1):P3V3_AUX
   2 PD_PIROM_CPU0_ADDR0      B @S9S_MB_2U_LIB.S9S_MB_2U(SCH_1):PD_PIROM_CPU0_ADDR0

Q_RES_0402LF-1K,1%,1/16W,EMPTYA  I6  R333
   1 P3V3_AUX      A @S9S_MB_2U_LIB.S9S_MB_2U(SCH_1):P3V3_AUX
   2 PD_PIROM_CPU0_ADDR1      B @S9S_MB_2U_LIB.S9S_MB_2U(SCH_1):PD_PIROM_CPU0_ADDR1

Q_RES_0402LF-10K,1%,1/16W,CHIPA  I7  R515
   1 PD_PIROM_CPU0_ADDR0      A @S9S_MB_2U_LIB.S9S_MB_2U(SCH_1):PD_PIROM_CPU0_ADDR0
   2    GND      B @S9S_MB_2U_LIB.S9S_MB_2U(SCH_1):GND

Q_RES_0402LF-1K,1%,1/16W,CHIP,A  I13  R629
   1 P3V3_AUX      A @S9S_MB_2U_LIB.S9S_MB_2U(SCH_1):P3V3_AUX
   2 PU_PIROM_CPU1_ADDR0      B @S9S_MB_2U_LIB.S9S_MB_2U(SCH_1):PU_PIROM_CPU1_ADDR0

Q_RES_0402LF-1K,1%,1/16W,EMPTYA  I14  R627
   1 P3V3_AUX      A @S9S_MB_2U_LIB.S9S_MB_2U(SCH_1):P3V3_AUX
   2 PD_PIROM_CPU1_ADDR1      B @S9S_MB_2U_LIB.S9S_MB_2U(SCH_1):PD_PIROM_CPU1_ADDR1

Q_RES_0402LF-10K,1%,1/16W,EMPTA  I15  R630
   1 PU_PIROM_CPU1_ADDR0      A @S9S_MB_2U_LIB.S9S_MB_2U(SCH_1):PU_PIROM_CPU1_ADDR0
   2    GND      B @S9S_MB_2U_LIB.S9S_MB_2U(SCH_1):GND

Q_RES_0402LF-10K,1%,1/16W,CHIPA  I17  R628
   1 PD_PIROM_CPU1_ADDR1      A @S9S_MB_2U_LIB.S9S_MB_2U(SCH_1):PD_PIROM_CPU1_ADDR1
   2    GND      B @S9S_MB_2U_LIB.S9S_MB_2U(SCH_1):GND

Q_RES_0402LF-1K,1%,1/16W,EMPTYA  I20  R331
   1 P3V3_AUX      A @S9S_MB_2U_LIB.S9S_MB_2U(SCH_1):P3V3_AUX
   2 PD_PIROM_CPU0_ADDR2      B @S9S_MB_2U_LIB.S9S_MB_2U(SCH_1):PD_PIROM_CPU0_ADDR2

Q_RES_0402LF-10K,1%,1/16W,CHIPA  I21  R332
   1 PD_PIROM_CPU0_ADDR2      A @S9S_MB_2U_LIB.S9S_MB_2U(SCH_1):PD_PIROM_CPU0_ADDR2
   2    GND      B @S9S_MB_2U_LIB.S9S_MB_2U(SCH_1):GND

Q_RES_0402LF-1K,1%,1/16W,EMPTYA  I24  R625
   1 P3V3_AUX      A @S9S_MB_2U_LIB.S9S_MB_2U(SCH_1):P3V3_AUX
   2 PD_PIROM_CPU1_ADDR2      B @S9S_MB_2U_LIB.S9S_MB_2U(SCH_1):PD_PIROM_CPU1_ADDR2

Q_RES_0402LF-10K,1%,1/16W,CHIPA  I26  R626
   1 PD_PIROM_CPU1_ADDR2      A @S9S_MB_2U_LIB.S9S_MB_2U(SCH_1):PD_PIROM_CPU1_ADDR2
   2    GND      B @S9S_MB_2U_LIB.S9S_MB_2U(SCH_1):GND

Q_RES_0402LF-10K,1%,1/16W,EMPTA  I31  R997
   1 PU_PIROM_CPU0_SM_WP      A @S9S_MB_2U_LIB.S9S_MB_2U(SCH_1):PU_PIROM_CPU0_SM_WP
   2    GND      B @S9S_MB_2U_LIB.S9S_MB_2U(SCH_1):GND

Q_RES_0402LF-1K,1%,1/16W,CHIP,A  I32  R650
   1 P3V3_AUX      A @S9S_MB_2U_LIB.S9S_MB_2U(SCH_1):P3V3_AUX
   2 PU_PIROM_CPU0_SM_WP      B @S9S_MB_2U_LIB.S9S_MB_2U(SCH_1):PU_PIROM_CPU0_SM_WP

Q_RES_0402LF-1K,1%,1/16W,CHIP,A  I35  R1004
   1 P3V3_AUX      A @S9S_MB_2U_LIB.S9S_MB_2U(SCH_1):P3V3_AUX
   2 PU_PIROM_CPU1_SM_WP      B @S9S_MB_2U_LIB.S9S_MB_2U(SCH_1):PU_PIROM_CPU1_SM_WP

Q_RES_0402LF-10K,1%,1/16W,EMPTA  I36  R1005
   1 PU_PIROM_CPU1_SM_WP      A @S9S_MB_2U_LIB.S9S_MB_2U(SCH_1):PU_PIROM_CPU1_SM_WP
   2    GND      B @S9S_MB_2U_LIB.S9S_MB_2U(SCH_1):GND


DRAWING: @S9S_MB_2U_LIB.S9S_MB_2U(SCH_1):PAGE128 

Q_RES_0402LF-0,5%,1/16W,CHIP,CA  I9  R854
   1 RST_CPU0_DRAM_GH_N      A @S9S_MB_2U_LIB.S9S_MB_2U(SCH_1):RST_CPU0_DRAM_GH_N
   2 RST_CPU0_DRAM_GH_PLD_N      B @S9S_MB_2U_LIB.S9S_MB_2U(SCH_1):RST_CPU0_DRAM_GH_PLD_N

Q_RES_0402LF-0,5%,1/16W,CHIP,CA  I10  R853
   1 RST_CPU0_DRAM_EF_N      A @S9S_MB_2U_LIB.S9S_MB_2U(SCH_1):RST_CPU0_DRAM_EF_N
   2 RST_CPU0_DRAM_EF_PLD_N      B @S9S_MB_2U_LIB.S9S_MB_2U(SCH_1):RST_CPU0_DRAM_EF_PLD_N

Q_RES_0402LF-0,5%,1/16W,CHIP,CA  I11  R852
   1 RST_CPU0_DRAM_CD_N      A @S9S_MB_2U_LIB.S9S_MB_2U(SCH_1):RST_CPU0_DRAM_CD_N
   2 RST_CPU0_DRAM_CD_PLD_N      B @S9S_MB_2U_LIB.S9S_MB_2U(SCH_1):RST_CPU0_DRAM_CD_PLD_N

Q_RES_0402LF-0,5%,1/16W,CHIP,CA  I12  R851
   1 RST_CPU0_DRAM_AB_N      A @S9S_MB_2U_LIB.S9S_MB_2U(SCH_1):RST_CPU0_DRAM_AB_N
   2 RST_CPU0_DRAM_AB_PLD_N      B @S9S_MB_2U_LIB.S9S_MB_2U(SCH_1):RST_CPU0_DRAM_AB_PLD_N

Q_RES_0402LF-0,5%,1/16W,CHIP,CA  I48  R861
   1 RST_CPU1_DRAM_EF_N      A @S9S_MB_2U_LIB.S9S_MB_2U(SCH_1):RST_CPU1_DRAM_EF_N
   2 RST_CPU1_DRAM_EF_PLD_N      B @S9S_MB_2U_LIB.S9S_MB_2U(SCH_1):RST_CPU1_DRAM_EF_PLD_N

Q_RES_0402LF-0,5%,1/16W,CHIP,CA  I49  R2969
   1 RST_CPU1_DRAM_GH_N      A @S9S_MB_2U_LIB.S9S_MB_2U(SCH_1):RST_CPU1_DRAM_GH_N
   2 RST_CPU1_DRAM_GH_PLD_N      B @S9S_MB_2U_LIB.S9S_MB_2U(SCH_1):RST_CPU1_DRAM_GH_PLD_N

Q_RES_0402LF-0,5%,1/16W,CHIP,CA  I50  R859
   1 RST_CPU1_DRAM_AB_N      A @S9S_MB_2U_LIB.S9S_MB_2U(SCH_1):RST_CPU1_DRAM_AB_N
   2 RST_CPU1_DRAM_AB_PLD_N      B @S9S_MB_2U_LIB.S9S_MB_2U(SCH_1):RST_CPU1_DRAM_AB_PLD_N

Q_RES_0402LF-0,5%,1/16W,CHIP,CA  I51  R860
   1 RST_CPU1_DRAM_CD_N      A @S9S_MB_2U_LIB.S9S_MB_2U(SCH_1):RST_CPU1_DRAM_CD_N
   2 RST_CPU1_DRAM_CD_PLD_N      B @S9S_MB_2U_LIB.S9S_MB_2U(SCH_1):RST_CPU1_DRAM_CD_PLD_N

Q_RES_0402LF-10K,1%,1/16W,CHIPA  I77  R938
   1 RST_CPU0_DRAM_GH_N      A @S9S_MB_2U_LIB.S9S_MB_2U(SCH_1):RST_CPU0_DRAM_GH_N
   2    GND      B @S9S_MB_2U_LIB.S9S_MB_2U(SCH_1):GND

Q_RES_0402LF-10K,1%,1/16W,CHIPA  I78  R936
   1 RST_CPU0_DRAM_EF_N      A @S9S_MB_2U_LIB.S9S_MB_2U(SCH_1):RST_CPU0_DRAM_EF_N
   2    GND      B @S9S_MB_2U_LIB.S9S_MB_2U(SCH_1):GND

Q_RES_0402LF-10K,1%,1/16W,CHIPA  I79  R934
   1 RST_CPU0_DRAM_CD_N      A @S9S_MB_2U_LIB.S9S_MB_2U(SCH_1):RST_CPU0_DRAM_CD_N
   2    GND      B @S9S_MB_2U_LIB.S9S_MB_2U(SCH_1):GND

Q_RES_0402LF-10K,1%,1/16W,CHIPA  I80  R932
   1 RST_CPU0_DRAM_AB_N      A @S9S_MB_2U_LIB.S9S_MB_2U(SCH_1):RST_CPU0_DRAM_AB_N
   2    GND      B @S9S_MB_2U_LIB.S9S_MB_2U(SCH_1):GND

Q_RES_0402LF-10K,1%,1/16W,CHIPA  I82  R933
   1 RST_CPU1_DRAM_AB_N      A @S9S_MB_2U_LIB.S9S_MB_2U(SCH_1):RST_CPU1_DRAM_AB_N
   2    GND      B @S9S_MB_2U_LIB.S9S_MB_2U(SCH_1):GND

Q_RES_0402LF-10K,1%,1/16W,CHIPA  I83  R939
   1 RST_CPU1_DRAM_GH_N      A @S9S_MB_2U_LIB.S9S_MB_2U(SCH_1):RST_CPU1_DRAM_GH_N
   2    GND      B @S9S_MB_2U_LIB.S9S_MB_2U(SCH_1):GND

Q_RES_0402LF-10K,1%,1/16W,CHIPA  I85  R937
   1 RST_CPU1_DRAM_EF_N      A @S9S_MB_2U_LIB.S9S_MB_2U(SCH_1):RST_CPU1_DRAM_EF_N
   2    GND      B @S9S_MB_2U_LIB.S9S_MB_2U(SCH_1):GND

Q_RES_0402LF-10K,1%,1/16W,CHIPA  I86  R935
   1 RST_CPU1_DRAM_CD_N      A @S9S_MB_2U_LIB.S9S_MB_2U(SCH_1):RST_CPU1_DRAM_CD_N
   2    GND      B @S9S_MB_2U_LIB.S9S_MB_2U(SCH_1):GND


DRAWING: @S9S_MB_2U_LIB.S9S_MB_2U(SCH_1):PAGE129 

Q_RES_0402LF-0,5%,1/16W,CHIP,CA  I26  R836
   1 RST_PLD_CPU0_DRAM_AB_N      A @S9S_MB_2U_LIB.S9S_MB_2U(SCH_1):RST_PLD_CPU0_DRAM_AB_N
   2 RST_M_AB_CPU0_FPGA_N      B @S9S_MB_2U_LIB.S9S_MB_2U(SCH_1):RST_M_AB_CPU0_FPGA_N

Q_RES_0402LF-0,5%,1/16W,CHIP,CA  I59  R837
   1 RST_PLD_CPU0_DRAM_CD_N      A @S9S_MB_2U_LIB.S9S_MB_2U(SCH_1):RST_PLD_CPU0_DRAM_CD_N
   2 RST_M_CD_CPU0_FPGA_N      B @S9S_MB_2U_LIB.S9S_MB_2U(SCH_1):RST_M_CD_CPU0_FPGA_N

Q_RES_0402LF-0,5%,1/16W,CHIP,CA  I76  R838
   1 RST_PLD_CPU0_DRAM_EF_N      A @S9S_MB_2U_LIB.S9S_MB_2U(SCH_1):RST_PLD_CPU0_DRAM_EF_N
   2 RST_M_EF_CPU0_FPGA_N      B @S9S_MB_2U_LIB.S9S_MB_2U(SCH_1):RST_M_EF_CPU0_FPGA_N

Q_RES_0402LF-0,5%,1/16W,CHIP,CA  I86  R835
   1 RST_PLD_CPU0_DRAM_GH_N      A @S9S_MB_2U_LIB.S9S_MB_2U(SCH_1):RST_PLD_CPU0_DRAM_GH_N
   2 RST_M_GH_CPU0_FPGA_N      B @S9S_MB_2U_LIB.S9S_MB_2U(SCH_1):RST_M_GH_CPU0_FPGA_N

Q_CAP_C0402-1UF,25V,10%,EMPTY,A  I91  C622
   1 RST_PLD_CPU0_DRAM_AB_N      A @S9S_MB_2U_LIB.S9S_MB_2U(SCH_1):RST_PLD_CPU0_DRAM_AB_N
   2    GND      B @S9S_MB_2U_LIB.S9S_MB_2U(SCH_1):GND

Q_CAP_C0402-1UF,25V,10%,EMPTY,A  I94  C623
   1 RST_PLD_CPU0_DRAM_CD_N      A @S9S_MB_2U_LIB.S9S_MB_2U(SCH_1):RST_PLD_CPU0_DRAM_CD_N
   2    GND      B @S9S_MB_2U_LIB.S9S_MB_2U(SCH_1):GND

Q_CAP_C0402-1UF,25V,10%,EMPTY,A  I99  C624
   1 RST_PLD_CPU0_DRAM_EF_N      A @S9S_MB_2U_LIB.S9S_MB_2U(SCH_1):RST_PLD_CPU0_DRAM_EF_N
   2    GND      B @S9S_MB_2U_LIB.S9S_MB_2U(SCH_1):GND

Q_CAP_C0402-1UF,25V,10%,EMPTY,A  I102  C621
   1 RST_PLD_CPU0_DRAM_GH_N      A @S9S_MB_2U_LIB.S9S_MB_2U(SCH_1):RST_PLD_CPU0_DRAM_GH_N
   2    GND      B @S9S_MB_2U_LIB.S9S_MB_2U(SCH_1):GND

Q_RES_0402LF-10K,1%,1/16W,EMPTA  I103  R706
   1 RST_PLD_CPU0_DRAM_AB_N      A @S9S_MB_2U_LIB.S9S_MB_2U(SCH_1):RST_PLD_CPU0_DRAM_AB_N
   2    GND      B @S9S_MB_2U_LIB.S9S_MB_2U(SCH_1):GND

Q_RES_0402LF-10K,1%,1/16W,EMPTA  I106  R707
   1 RST_PLD_CPU0_DRAM_CD_N      A @S9S_MB_2U_LIB.S9S_MB_2U(SCH_1):RST_PLD_CPU0_DRAM_CD_N
   2    GND      B @S9S_MB_2U_LIB.S9S_MB_2U(SCH_1):GND

Q_RES_0402LF-10K,1%,1/16W,EMPTA  I109  R708
   1 RST_PLD_CPU0_DRAM_EF_N      A @S9S_MB_2U_LIB.S9S_MB_2U(SCH_1):RST_PLD_CPU0_DRAM_EF_N
   2    GND      B @S9S_MB_2U_LIB.S9S_MB_2U(SCH_1):GND

Q_RES_0402LF-10K,1%,1/16W,EMPTA  I112  R705
   1 RST_PLD_CPU0_DRAM_GH_N      A @S9S_MB_2U_LIB.S9S_MB_2U(SCH_1):RST_PLD_CPU0_DRAM_GH_N
   2    GND      B @S9S_MB_2U_LIB.S9S_MB_2U(SCH_1):GND

Q_RES_0402LF-1K,1%,1/16W,CHIP,A  I119  R840
   1 PVCCD_HV_CPU0      A @S9S_MB_2U_LIB.S9S_MB_2U(SCH_1):PVCCD_HV_CPU0
   2 RST_M_AB_CPU0_FPGA_N      B @S9S_MB_2U_LIB.S9S_MB_2U(SCH_1):RST_M_AB_CPU0_FPGA_N

Q_RES_0402LF-1K,1%,1/16W,CHIP,A  I121  R841
   1 PVCCD_HV_CPU0      A @S9S_MB_2U_LIB.S9S_MB_2U(SCH_1):PVCCD_HV_CPU0
   2 RST_M_CD_CPU0_FPGA_N      B @S9S_MB_2U_LIB.S9S_MB_2U(SCH_1):RST_M_CD_CPU0_FPGA_N

Q_RES_0402LF-1K,1%,1/16W,CHIP,A  I123  R842
   1 PVCCD_HV_CPU0      A @S9S_MB_2U_LIB.S9S_MB_2U(SCH_1):PVCCD_HV_CPU0
   2 RST_M_EF_CPU0_FPGA_N      B @S9S_MB_2U_LIB.S9S_MB_2U(SCH_1):RST_M_EF_CPU0_FPGA_N

Q_RES_0402LF-1K,1%,1/16W,CHIP,A  I125  R839
   1 PVCCD_HV_CPU0      A @S9S_MB_2U_LIB.S9S_MB_2U(SCH_1):PVCCD_HV_CPU0
   2 RST_M_GH_CPU0_FPGA_N      B @S9S_MB_2U_LIB.S9S_MB_2U(SCH_1):RST_M_GH_CPU0_FPGA_N


DRAWING: @S9S_MB_2U_LIB.S9S_MB_2U(SCH_1):PAGE130 

Q_RES_0402LF-0,5%,1/16W,CHIP,CA  I11  R815
   1 RST_PLD_CPU1_DRAM_GH_N      A @S9S_MB_2U_LIB.S9S_MB_2U(SCH_1):RST_PLD_CPU1_DRAM_GH_N
   2 RST_M_GH_CPU1_FPGA_N      B @S9S_MB_2U_LIB.S9S_MB_2U(SCH_1):RST_M_GH_CPU1_FPGA_N

Q_RES_0402LF-0,5%,1/16W,CHIP,CA  I22  R818
   1 RST_PLD_CPU1_DRAM_EF_N      A @S9S_MB_2U_LIB.S9S_MB_2U(SCH_1):RST_PLD_CPU1_DRAM_EF_N
   2 RST_M_EF_CPU1_FPGA_N      B @S9S_MB_2U_LIB.S9S_MB_2U(SCH_1):RST_M_EF_CPU1_FPGA_N

Q_RES_0402LF-0,5%,1/16W,CHIP,CA  I26  R817
   1 RST_PLD_CPU1_DRAM_CD_N      A @S9S_MB_2U_LIB.S9S_MB_2U(SCH_1):RST_PLD_CPU1_DRAM_CD_N
   2 RST_M_CD_CPU1_FPGA_N      B @S9S_MB_2U_LIB.S9S_MB_2U(SCH_1):RST_M_CD_CPU1_FPGA_N

Q_RES_0402LF-0,5%,1/16W,CHIP,CA  I37  R816
   1 RST_PLD_CPU1_DRAM_AB_N      A @S9S_MB_2U_LIB.S9S_MB_2U(SCH_1):RST_PLD_CPU1_DRAM_AB_N
   2 RST_M_AB_CPU1_FPGA_N      B @S9S_MB_2U_LIB.S9S_MB_2U(SCH_1):RST_M_AB_CPU1_FPGA_N

Q_CAP_C0402-1UF,25V,10%,EMPTY,A  I59  C616
   1 RST_PLD_CPU1_DRAM_EF_N      A @S9S_MB_2U_LIB.S9S_MB_2U(SCH_1):RST_PLD_CPU1_DRAM_EF_N
   2    GND      B @S9S_MB_2U_LIB.S9S_MB_2U(SCH_1):GND

Q_CAP_C0402-1UF,25V,10%,EMPTY,A  I62  C615
   1 RST_PLD_CPU1_DRAM_CD_N      A @S9S_MB_2U_LIB.S9S_MB_2U(SCH_1):RST_PLD_CPU1_DRAM_CD_N
   2    GND      B @S9S_MB_2U_LIB.S9S_MB_2U(SCH_1):GND

Q_RES_0402LF-10K,1%,1/16W,EMPTA  I63  R701
   1 RST_PLD_CPU1_DRAM_CD_N      A @S9S_MB_2U_LIB.S9S_MB_2U(SCH_1):RST_PLD_CPU1_DRAM_CD_N
   2    GND      B @S9S_MB_2U_LIB.S9S_MB_2U(SCH_1):GND

Q_CAP_C0402-1UF,25V,10%,EMPTY,A  I65  C614
   1 RST_PLD_CPU1_DRAM_AB_N      A @S9S_MB_2U_LIB.S9S_MB_2U(SCH_1):RST_PLD_CPU1_DRAM_AB_N
   2    GND      B @S9S_MB_2U_LIB.S9S_MB_2U(SCH_1):GND

Q_CAP_C0402-1UF,25V,10%,EMPTY,A  I68  C613
   1 RST_PLD_CPU1_DRAM_GH_N      A @S9S_MB_2U_LIB.S9S_MB_2U(SCH_1):RST_PLD_CPU1_DRAM_GH_N
   2    GND      B @S9S_MB_2U_LIB.S9S_MB_2U(SCH_1):GND

Q_RES_0402LF-10K,1%,1/16W,EMPTA  I75  R704
   1 RST_PLD_CPU1_DRAM_EF_N      A @S9S_MB_2U_LIB.S9S_MB_2U(SCH_1):RST_PLD_CPU1_DRAM_EF_N
   2    GND      B @S9S_MB_2U_LIB.S9S_MB_2U(SCH_1):GND

Q_RES_0402LF-10K,1%,1/16W,EMPTA  I76  R702
   1 RST_PLD_CPU1_DRAM_GH_N      A @S9S_MB_2U_LIB.S9S_MB_2U(SCH_1):RST_PLD_CPU1_DRAM_GH_N
   2    GND      B @S9S_MB_2U_LIB.S9S_MB_2U(SCH_1):GND

Q_RES_0402LF-10K,1%,1/16W,EMPTA  I79  R703
   1 RST_PLD_CPU1_DRAM_AB_N      A @S9S_MB_2U_LIB.S9S_MB_2U(SCH_1):RST_PLD_CPU1_DRAM_AB_N
   2    GND      B @S9S_MB_2U_LIB.S9S_MB_2U(SCH_1):GND

Q_RES_0402LF-1K,1%,1/16W,CHIP,A  I82  R820
   1 PVCCD_HV_CPU1      A @S9S_MB_2U_LIB.S9S_MB_2U(SCH_1):PVCCD_HV_CPU1
   2 RST_M_AB_CPU1_FPGA_N      B @S9S_MB_2U_LIB.S9S_MB_2U(SCH_1):RST_M_AB_CPU1_FPGA_N

Q_RES_0402LF-1K,1%,1/16W,CHIP,A  I84  R821
   1 PVCCD_HV_CPU1      A @S9S_MB_2U_LIB.S9S_MB_2U(SCH_1):PVCCD_HV_CPU1
   2 RST_M_CD_CPU1_FPGA_N      B @S9S_MB_2U_LIB.S9S_MB_2U(SCH_1):RST_M_CD_CPU1_FPGA_N

Q_RES_0402LF-1K,1%,1/16W,CHIP,A  I88  R822
   1 PVCCD_HV_CPU1      A @S9S_MB_2U_LIB.S9S_MB_2U(SCH_1):PVCCD_HV_CPU1
   2 RST_M_EF_CPU1_FPGA_N      B @S9S_MB_2U_LIB.S9S_MB_2U(SCH_1):RST_M_EF_CPU1_FPGA_N

Q_RES_0402LF-1K,1%,1/16W,CHIP,A  I90  R819
   1 PVCCD_HV_CPU1      A @S9S_MB_2U_LIB.S9S_MB_2U(SCH_1):PVCCD_HV_CPU1
   2 RST_M_GH_CPU1_FPGA_N      B @S9S_MB_2U_LIB.S9S_MB_2U(SCH_1):RST_M_GH_CPU1_FPGA_N


DRAWING: @S9S_MB_2U_LIB.S9S_MB_2U(SCH_1):PAGE133 

Q_RES_0402LF-10,1%,1/16W,CHIP,A  I5  R775
   1 JTAG_DBP_TMS_R      A @S9S_MB_2U_LIB.S9S_MB_2U(SCH_1):JTAG_DBP_TMS_R
   2 JTAG_DBP_TMS      B @S9S_MB_2U_LIB.S9S_MB_2U(SCH_1):JTAG_DBP_TMS

Q_RES_0402LF-100,1%,1/16W,CHIPA  I7  R776
   1 JTAG_DBP_TDO_R      A @S9S_MB_2U_LIB.S9S_MB_2U(SCH_1):JTAG_DBP_TDO_R
   2 JTAG_DBP_TDO      B @S9S_MB_2U_LIB.S9S_MB_2U(SCH_1):JTAG_DBP_TDO

Q_RES_0402LF-10,1%,1/16W,CHIP,A  I10  R777
   1 JTAG_DBP_PREQ_N_R      A @S9S_MB_2U_LIB.S9S_MB_2U(SCH_1):JTAG_DBP_PREQ_N_R
   2 JTAG_DBP_PREQ_N      B @S9S_MB_2U_LIB.S9S_MB_2U(SCH_1):JTAG_DBP_PREQ_N

Q_RES_0402LF-1K,1%,1/16W,CHIP,A  I15  R778
   1 P3V3_AUX      A @S9S_MB_2U_LIB.S9S_MB_2U(SCH_1):P3V3_AUX
   2 JTAG_DBP_BOOT_HALT_N      B @S9S_MB_2U_LIB.S9S_MB_2U(SCH_1):JTAG_DBP_BOOT_HALT_N

SCONN60_ASP21410801-SCONN60_ASA  I44  J42
   1 P1V05_PCH_AUX      1 @S9S_MB_2U_LIB.S9S_MB_2U(SCH_1):P1V05_PCH_AUX
   2 JTAG_DBP_TMS_R      2 @S9S_MB_2U_LIB.S9S_MB_2U(SCH_1):JTAG_DBP_TMS_R
   3 JTAG_DBP_CPU_GTL_TCK_R      3 @S9S_MB_2U_LIB.S9S_MB_2U(SCH_1):JTAG_DBP_CPU_GTL_TCK_R
   4 JTAG_DBP_TDO_R      4 @S9S_MB_2U_LIB.S9S_MB_2U(SCH_1):JTAG_DBP_TDO_R
   5 JTAG_DBP_TDI_R      5 @S9S_MB_2U_LIB.S9S_MB_2U(SCH_1):JTAG_DBP_TDI_R
   6 JTAG_RST_DBP_RST_CO_N      6 @S9S_MB_2U_LIB.S9S_MB_2U(SCH_1):JTAG_RST_DBP_RST_CO_N
   7 JTAG_DBP_PMODE      7 @S9S_MB_2U_LIB.S9S_MB_2U(SCH_1):JTAG_DBP_PMODE
   8 PD_TRST_P3      8 @S9S_MB_2U_LIB.S9S_MB_2U(SCH_1):PD_TRST_P3
   9 NC_MIPI60_P9      9 @S9S_MB_2U_LIB.S9S_MB_2U(SCH_1):NC_MIPI60_P9
  10 JTAG_DBP_PREQ_N_R     10 @S9S_MB_2U_LIB.S9S_MB_2U(SCH_1):JTAG_DBP_PREQ_N_R
  11 JTAG_DBP_PRDY_R1_N     11 @S9S_MB_2U_LIB.S9S_MB_2U(SCH_1):JTAG_DBP_PRDY_R1_N
  12 P1V8_PCH_AUX     12 @S9S_MB_2U_LIB.S9S_MB_2U(SCH_1):P1V8_PCH_AUX
  13 JTAG_TRC_PCH_PTI0_CLK     13 @S9S_MB_2U_LIB.S9S_MB_2U(SCH_1):JTAG_TRC_PCH_PTI0_CLK
  14    GND     14 @S9S_MB_2U_LIB.S9S_MB_2U(SCH_1):GND
  15 JTAG_DBP_PCH_DEBUG_CONSENT_N     15 @S9S_MB_2U_LIB.S9S_MB_2U(SCH_1):JTAG_DBP_PCH_DEBUG_CONSENT_N
  16    GND     16 @S9S_MB_2U_LIB.S9S_MB_2U(SCH_1):GND
  17 JTAG_DBP_PRESENT_R_N     17 @S9S_MB_2U_LIB.S9S_MB_2U(SCH_1):JTAG_DBP_PRESENT_R_N
  18 NC_DBP_P18     18 @S9S_MB_2U_LIB.S9S_MB_2U(SCH_1):NC_DBP_P18
  19 JTAG_TRC_PCH_PTI<0>     19 @S9S_MB_2U_LIB.S9S_MB_2U(SCH_1):JTAG_TRC_PCH_PTI(0)
  20 NC_DBP_P20     20 @S9S_MB_2U_LIB.S9S_MB_2U(SCH_1):NC_DBP_P20
  21 JTAG_TRC_PCH_PTI<1>     21 @S9S_MB_2U_LIB.S9S_MB_2U(SCH_1):JTAG_TRC_PCH_PTI(1)
  22 NC_DBP_P22     22 @S9S_MB_2U_LIB.S9S_MB_2U(SCH_1):NC_DBP_P22
  23 JTAG_TRC_PCH_PTI<2>     23 @S9S_MB_2U_LIB.S9S_MB_2U(SCH_1):JTAG_TRC_PCH_PTI(2)
  24 NC_DBP_P24     24 @S9S_MB_2U_LIB.S9S_MB_2U(SCH_1):NC_DBP_P24
  25 JTAG_TRC_PCH_PTI<3>     25 @S9S_MB_2U_LIB.S9S_MB_2U(SCH_1):JTAG_TRC_PCH_PTI(3)
  26 NC_DBP_P26     26 @S9S_MB_2U_LIB.S9S_MB_2U(SCH_1):NC_DBP_P26
  27 JTAG_TRC_PCH_PTI<4>     27 @S9S_MB_2U_LIB.S9S_MB_2U(SCH_1):JTAG_TRC_PCH_PTI(4)
  28 NC_DBP_P28     28 @S9S_MB_2U_LIB.S9S_MB_2U(SCH_1):NC_DBP_P28
  30 NC_DBP_P30     30 @S9S_MB_2U_LIB.S9S_MB_2U(SCH_1):NC_DBP_P30
  29 JTAG_TRC_PCH_PTI<5>     29 @S9S_MB_2U_LIB.S9S_MB_2U(SCH_1):JTAG_TRC_PCH_PTI(5)
  31 JTAG_TRC_PCH_PTI<6>     31 @S9S_MB_2U_LIB.S9S_MB_2U(SCH_1):JTAG_TRC_PCH_PTI(6)
  32 NC_DBP_P32     32 @S9S_MB_2U_LIB.S9S_MB_2U(SCH_1):NC_DBP_P32
  33 JTAG_TRC_PCH_PTI<7>     33 @S9S_MB_2U_LIB.S9S_MB_2U(SCH_1):JTAG_TRC_PCH_PTI(7)
  34 NC_DBP_P34     34 @S9S_MB_2U_LIB.S9S_MB_2U(SCH_1):NC_DBP_P34
  35 JTAG_TRC_PCH_PTI<8>     35 @S9S_MB_2U_LIB.S9S_MB_2U(SCH_1):JTAG_TRC_PCH_PTI(8)
  36 JTAG_DBP_BOOT_HALT_N     36 @S9S_MB_2U_LIB.S9S_MB_2U(SCH_1):JTAG_DBP_BOOT_HALT_N
  37 JTAG_TRC_PCH_PTI<9>     37 @S9S_MB_2U_LIB.S9S_MB_2U(SCH_1):JTAG_TRC_PCH_PTI(9)
  38 FM_CPU_FBRK_DEBUG_N     38 @S9S_MB_2U_LIB.S9S_MB_2U(SCH_1):FM_CPU_FBRK_DEBUG_N
  39 JTAG_TRC_PCH_PTI<10>     39 @S9S_MB_2U_LIB.S9S_MB_2U(SCH_1):JTAG_TRC_PCH_PTI(10)
  40 JTAG_DBP_POWER_BTN_N     40 @S9S_MB_2U_LIB.S9S_MB_2U(SCH_1):JTAG_DBP_POWER_BTN_N
  41 JTAG_TRC_PCH_PTI<11>     41 @S9S_MB_2U_LIB.S9S_MB_2U(SCH_1):JTAG_TRC_PCH_PTI(11)
  42 JTAG_RST_DBP_RSMRST_N     42 @S9S_MB_2U_LIB.S9S_MB_2U(SCH_1):JTAG_RST_DBP_RSMRST_N
  43 JTAG_TRC_PCH_PTI<12>     43 @S9S_MB_2U_LIB.S9S_MB_2U(SCH_1):JTAG_TRC_PCH_PTI(12)
  44 NC_DBP_P44     44 @S9S_MB_2U_LIB.S9S_MB_2U(SCH_1):NC_DBP_P44
  45 JTAG_TRC_PCH_PTI<13>     45 @S9S_MB_2U_LIB.S9S_MB_2U(SCH_1):JTAG_TRC_PCH_PTI(13)
  46 NC_DBP_P46     46 @S9S_MB_2U_LIB.S9S_MB_2U(SCH_1):NC_DBP_P46
  47 JTAG_TRC_PCH_PTI<14>     47 @S9S_MB_2U_LIB.S9S_MB_2U(SCH_1):JTAG_TRC_PCH_PTI(14)
  48 SMB_HOST_3V3AUX_XDP_R_SCL     48 @S9S_MB_2U_LIB.S9S_MB_2U(SCH_1):SMB_HOST_3V3AUX_XDP_R_SCL
  49 JTAG_TRC_PCH_PTI<15>     49 @S9S_MB_2U_LIB.S9S_MB_2U(SCH_1):JTAG_TRC_PCH_PTI(15)
  50 SMB_HOST_3V3AUX_XDP_R_SDA     50 @S9S_MB_2U_LIB.S9S_MB_2U(SCH_1):SMB_HOST_3V3AUX_XDP_R_SDA
  51 JTAG_DBP_TCK_R_TCK     51 @S9S_MB_2U_LIB.S9S_MB_2U(SCH_1):JTAG_DBP_TCK_R_TCK
  52 P3V3_AUX     52 @S9S_MB_2U_LIB.S9S_MB_2U(SCH_1):P3V3_AUX
  53 JTAG_DBP_CPU_HOOK9_MBP3_GTL_N     53 @S9S_MB_2U_LIB.S9S_MB_2U(SCH_1):JTAG_DBP_CPU_HOOK9_MBP3_GTL_N
  54 NC_DBP_P54     54 @S9S_MB_2U_LIB.S9S_MB_2U(SCH_1):NC_DBP_P54
  55 JTAG_DBP_CPU_HOOK8_MBP2_GTL_N     55 @S9S_MB_2U_LIB.S9S_MB_2U(SCH_1):JTAG_DBP_CPU_HOOK8_MBP2_GTL_N
  56 NC_DBP_P56     56 @S9S_MB_2U_LIB.S9S_MB_2U(SCH_1):NC_DBP_P56
  57    GND     57 @S9S_MB_2U_LIB.S9S_MB_2U(SCH_1):GND
  58    GND     58 @S9S_MB_2U_LIB.S9S_MB_2U(SCH_1):GND
  59 JTAG_TRC_PCH_PTI1_CLK     59 @S9S_MB_2U_LIB.S9S_MB_2U(SCH_1):JTAG_TRC_PCH_PTI1_CLK
  60    GND     60 @S9S_MB_2U_LIB.S9S_MB_2U(SCH_1):GND
  G1    GND     G1 @S9S_MB_2U_LIB.S9S_MB_2U(SCH_1):GND
  G2    GND     G2 @S9S_MB_2U_LIB.S9S_MB_2U(SCH_1):GND
  G3    GND     G3 @S9S_MB_2U_LIB.S9S_MB_2U(SCH_1):GND
  G4    GND     G4 @S9S_MB_2U_LIB.S9S_MB_2U(SCH_1):GND

Q_RES_0402LF-10,1%,1/16W,CHIP,A  I70  R763
   1 JTAG_DBP_TDI      A @S9S_MB_2U_LIB.S9S_MB_2U(SCH_1):JTAG_DBP_TDI
   2 JTAG_DBP_TDI_R      B @S9S_MB_2U_LIB.S9S_MB_2U(SCH_1):JTAG_DBP_TDI_R

Q_RES_0402LF-0,5%,1/16W,CHIP,CA  I71  R762
   1 JTAG_DBP_CPU_GTL_TCK      A @S9S_MB_2U_LIB.S9S_MB_2U(SCH_1):JTAG_DBP_CPU_GTL_TCK
   2 JTAG_DBP_CPU_GTL_TCK_R      B @S9S_MB_2U_LIB.S9S_MB_2U(SCH_1):JTAG_DBP_CPU_GTL_TCK_R

Q_RES_0402LF-0,5%,1/16W,CHIP,CA  I74  R765
   1 JTAG_DBP_TCK_PCH      A @S9S_MB_2U_LIB.S9S_MB_2U(SCH_1):JTAG_DBP_TCK_PCH
   2 JTAG_DBP_TCK_R_TCK      B @S9S_MB_2U_LIB.S9S_MB_2U(SCH_1):JTAG_DBP_TCK_R_TCK

Q_RES_0402LF-0,5%,1/16W,CHIP,CA  I83  R764
   1 JTAG_DBP_PRDY_N      A @S9S_MB_2U_LIB.S9S_MB_2U(SCH_1):JTAG_DBP_PRDY_N
   2 JTAG_DBP_PRDY_R1_N      B @S9S_MB_2U_LIB.S9S_MB_2U(SCH_1):JTAG_DBP_PRDY_R1_N

Q_RES_0402LF-49.9,1%,1/16W,CHIA  I92  R780
   1 FM_CPU_FBRK_DEBUG_N      A @S9S_MB_2U_LIB.S9S_MB_2U(SCH_1):FM_CPU_FBRK_DEBUG_N
   2 FM_CPU_FBRK_DEBUG_R_N      B @S9S_MB_2U_LIB.S9S_MB_2U(SCH_1):FM_CPU_FBRK_DEBUG_R_N

Q_RES_0402LF-150,1%,1/16W,CHIPA  I95  R779
   1 PVNN_TERM_CPU0      A @S9S_MB_2U_LIB.S9S_MB_2U(SCH_1):PVNN_TERM_CPU0
   2 FM_CPU_FBRK_DEBUG_N      B @S9S_MB_2U_LIB.S9S_MB_2U(SCH_1):FM_CPU_FBRK_DEBUG_N

Q_CAP_0402-0.1UF,25V,10%,X7R,CA  I96  C552
   1 FM_CPU_FBRK_DEBUG_N      A @S9S_MB_2U_LIB.S9S_MB_2U(SCH_1):FM_CPU_FBRK_DEBUG_N
   2    GND      B @S9S_MB_2U_LIB.S9S_MB_2U(SCH_1):GND

Q_CAP_C0402-1UF,25V,10%,X6S,CHA  I99  C550
   1 P1V8_PCH_AUX      A @S9S_MB_2U_LIB.S9S_MB_2U(SCH_1):P1V8_PCH_AUX
   2    GND      B @S9S_MB_2U_LIB.S9S_MB_2U(SCH_1):GND

Q_CAP_C0402-1UF,25V,10%,X6S,CHA  I100  C547
   1 P1V05_PCH_AUX      A @S9S_MB_2U_LIB.S9S_MB_2U(SCH_1):P1V05_PCH_AUX
   2    GND      B @S9S_MB_2U_LIB.S9S_MB_2U(SCH_1):GND

Q_RES_0402LF-10K,1%,1/16W,CHIPA  I102  R769
   1 PD_TRST_P3      A @S9S_MB_2U_LIB.S9S_MB_2U(SCH_1):PD_TRST_P3
   2    GND      B @S9S_MB_2U_LIB.S9S_MB_2U(SCH_1):GND

Q_CAP_C0402-1UF,25V,10%,X6S,CHA  I105  C551
   1 P3V3_AUX      A @S9S_MB_2U_LIB.S9S_MB_2U(SCH_1):P3V3_AUX
   2    GND      B @S9S_MB_2U_LIB.S9S_MB_2U(SCH_1):GND

Q_RES_0402LF-1K,1%,1/16W,EMPTYA  I111  R766
   1 P3V3_AUX      A @S9S_MB_2U_LIB.S9S_MB_2U(SCH_1):P3V3_AUX
   2 JTAG_DBP_POWER_BTN_N      B @S9S_MB_2U_LIB.S9S_MB_2U(SCH_1):JTAG_DBP_POWER_BTN_N

Q_RES_0402LF-1K,1%,1/16W,CHIP,A  I112  R768
   1 P3V3_AUX      A @S9S_MB_2U_LIB.S9S_MB_2U(SCH_1):P3V3_AUX
   2 JTAG_DBP_PRESENT_R_N      B @S9S_MB_2U_LIB.S9S_MB_2U(SCH_1):JTAG_DBP_PRESENT_R_N

Q_RES_0402LF-1K,1%,1/16W,CHIP,A  I113  R767
   1 P3V3_AUX      A @S9S_MB_2U_LIB.S9S_MB_2U(SCH_1):P3V3_AUX
   2 JTAG_RST_DBP_RST_CO_N      B @S9S_MB_2U_LIB.S9S_MB_2U(SCH_1):JTAG_RST_DBP_RST_CO_N

Q_RES_0402LF-1K,1%,1/16W,CHIP,A  I118  R772
   1 JTAG_RST_DBP_RSMRST_N      A @S9S_MB_2U_LIB.S9S_MB_2U(SCH_1):JTAG_RST_DBP_RSMRST_N
   2 RST_RSMRST_PCH_N      B @S9S_MB_2U_LIB.S9S_MB_2U(SCH_1):RST_RSMRST_PCH_N

Q_RES_0402LF-1K,1%,1/16W,CHIP,A  I120  R771
   1 JTAG_DBP_PCH_DEBUG_CONSENT_N      A @S9S_MB_2U_LIB.S9S_MB_2U(SCH_1):JTAG_DBP_PCH_DEBUG_CONSENT_N
   2 FM_PCH_CONSENT_STRAP_N      B @S9S_MB_2U_LIB.S9S_MB_2U(SCH_1):FM_PCH_CONSENT_STRAP_N

Q_RES_0402LF-1K,1%,1/16W,CHIP,A  I124  R773
   1 JTAG_DBP_BOOT_HALT_N      A @S9S_MB_2U_LIB.S9S_MB_2U(SCH_1):JTAG_DBP_BOOT_HALT_N
   2 FM_ADR_MODE0      B @S9S_MB_2U_LIB.S9S_MB_2U(SCH_1):FM_ADR_MODE0

Q_CAP_0402-0.1UF,25V,10%,X7R,CA  I129  C549
   1 JTAG_RST_DBP_RST_CO_N      A @S9S_MB_2U_LIB.S9S_MB_2U(SCH_1):JTAG_RST_DBP_RST_CO_N
   2    GND      B @S9S_MB_2U_LIB.S9S_MB_2U(SCH_1):GND

Q_CAP_0402-0.1UF,25V,10%,X7R,CA  I130  C548
   1 JTAG_DBP_POWER_BTN_N      A @S9S_MB_2U_LIB.S9S_MB_2U(SCH_1):JTAG_DBP_POWER_BTN_N
   2    GND      B @S9S_MB_2U_LIB.S9S_MB_2U(SCH_1):GND

Q_RES_0402LF-75,1%,1/16W,CHIP,A  I132  R774
   1 JTAG_DBP_CPU_GTL_TCK      A @S9S_MB_2U_LIB.S9S_MB_2U(SCH_1):JTAG_DBP_CPU_GTL_TCK
   2    GND      B @S9S_MB_2U_LIB.S9S_MB_2U(SCH_1):GND

Q_RES_0402LF-33.2,1%,1/16W,CHIA  I144  R1472
   1 JTAG_DBP_PRESENT_R_N      A @S9S_MB_2U_LIB.S9S_MB_2U(SCH_1):JTAG_DBP_PRESENT_R_N
   2 FM_BMC_DBP_PRESENT_R_N      B @S9S_MB_2U_LIB.S9S_MB_2U(SCH_1):FM_BMC_DBP_PRESENT_R_N

Q_RES_0402LF-33.2,1%,1/16W,CHIA  I148  R4502
   1 SMB_HOST_3V3AUX_SCL_R4      A @S9S_MB_2U_LIB.S9S_MB_2U(SCH_1):SMB_HOST_3V3AUX_SCL_R4
   2 SMB_HOST_3V3AUX_XDP_R_SCL      B @S9S_MB_2U_LIB.S9S_MB_2U(SCH_1):SMB_HOST_3V3AUX_XDP_R_SCL

Q_RES_0402LF-0,5%,1/16W,CHIP,CA  I153  R4503
   1 SMB_HOST_3V3AUX_SDA_R4      A @S9S_MB_2U_LIB.S9S_MB_2U(SCH_1):SMB_HOST_3V3AUX_SDA_R4
   2 SMB_HOST_3V3AUX_XDP_R_SDA      B @S9S_MB_2U_LIB.S9S_MB_2U(SCH_1):SMB_HOST_3V3AUX_XDP_R_SDA


DRAWING: @S9S_MB_2U_LIB.S9S_MB_2U(SCH_1):PAGE134 

74CBTLV3126PW-74CBTLV3126PW,SMA  I80  U17
   5 JTAG_DBP_TDI     2A @S9S_MB_2U_LIB.S9S_MB_2U(SCH_1):JTAG_DBP_TDI
   8 TP_74CB_B8     3B @S9S_MB_2U_LIB.S9S_MB_2U(SCH_1):TP_74CB_B8
   1 PWRGD_PVNN_MAIN_CPU0    1OE @S9S_MB_2U_LIB.S9S_MB_2U(SCH_1):PWRGD_PVNN_MAIN_CPU0
   4 PWRGD_PVNN_MAIN_CPU0    2OE @S9S_MB_2U_LIB.S9S_MB_2U(SCH_1):PWRGD_PVNN_MAIN_CPU0
   3 JTAG_DBP_CPU_QS_GTL_TMS     1B @S9S_MB_2U_LIB.S9S_MB_2U(SCH_1):JTAG_DBP_CPU_QS_GTL_TMS
   6 JTAG_QS_MUX_GTL_TDI     2B @S9S_MB_2U_LIB.S9S_MB_2U(SCH_1):JTAG_QS_MUX_GTL_TDI
   2 JTAG_DBP_TMS     1A @S9S_MB_2U_LIB.S9S_MB_2U(SCH_1):JTAG_DBP_TMS
   7    GND    GND @S9S_MB_2U_LIB.S9S_MB_2U(SCH_1):GND
   9 PD_74CB_A9     3A @S9S_MB_2U_LIB.S9S_MB_2U(SCH_1):PD_74CB_A9
  10 PWRGD_PVNN_MAIN_CPU0    3OE @S9S_MB_2U_LIB.S9S_MB_2U(SCH_1):PWRGD_PVNN_MAIN_CPU0
  11 JTAG_MUX_QS_GTL_TDO     4B @S9S_MB_2U_LIB.S9S_MB_2U(SCH_1):JTAG_MUX_QS_GTL_TDO
  12 JTAG_DBP_TDO     4A @S9S_MB_2U_LIB.S9S_MB_2U(SCH_1):JTAG_DBP_TDO
  13 PWRGD_PVNN_MAIN_CPU0    4OE @S9S_MB_2U_LIB.S9S_MB_2U(SCH_1):PWRGD_PVNN_MAIN_CPU0
  14 P3V3_AUX    VCC @S9S_MB_2U_LIB.S9S_MB_2U(SCH_1):P3V3_AUX

Q_RES_0402LF-0,5%,1/16W,CHIP,CA  I90  R746
   1 PD_74CB_A9      A @S9S_MB_2U_LIB.S9S_MB_2U(SCH_1):PD_74CB_A9
   2    GND      B @S9S_MB_2U_LIB.S9S_MB_2U(SCH_1):GND

Q_CAP_C0402-1UF,25V,10%,X6S,CHA  I93  C545
   1 P3V3_AUX      A @S9S_MB_2U_LIB.S9S_MB_2U(SCH_1):P3V3_AUX
   2    GND      B @S9S_MB_2U_LIB.S9S_MB_2U(SCH_1):GND

Q_RES_0402LF-10,1%,1/16W,CHIP,A  I126  R754
   1 JTAG_DBP_TMS      A @S9S_MB_2U_LIB.S9S_MB_2U(SCH_1):JTAG_DBP_TMS
   2 JTAG_DBP_TMS_PCH      B @S9S_MB_2U_LIB.S9S_MB_2U(SCH_1):JTAG_DBP_TMS_PCH

Q_RES_0402LF-10,1%,1/16W,CHIP,A  I127  R752
   1 JTAG_DBP_TDO      A @S9S_MB_2U_LIB.S9S_MB_2U(SCH_1):JTAG_DBP_TDO
   2 JTAG_DBP_TDO_PCH      B @S9S_MB_2U_LIB.S9S_MB_2U(SCH_1):JTAG_DBP_TDO_PCH

Q_RES_0402LF-10,1%,1/16W,CHIP,A  I128  R753
   1 JTAG_DBP_TDI      A @S9S_MB_2U_LIB.S9S_MB_2U(SCH_1):JTAG_DBP_TDI
   2 JTAG_DBP_TDI_PCH      B @S9S_MB_2U_LIB.S9S_MB_2U(SCH_1):JTAG_DBP_TDI_PCH

74CBTLV3126PW-74CBTLV3126PW,SMA  I129  U18
   5 JTAG_DBP_CPU_HOOK8_MBP2_GTL_N     2A @S9S_MB_2U_LIB.S9S_MB_2U(SCH_1):JTAG_DBP_CPU_HOOK8_MBP2_GTL_N
   8 H_CPU_PRDY_QS_GTL_N     3B @S9S_MB_2U_LIB.S9S_MB_2U(SCH_1):H_CPU_PRDY_QS_GTL_N
   1 PWRGD_PVNN_MAIN_CPU0    1OE @S9S_MB_2U_LIB.S9S_MB_2U(SCH_1):PWRGD_PVNN_MAIN_CPU0
   4 PWRGD_PVNN_MAIN_CPU0    2OE @S9S_MB_2U_LIB.S9S_MB_2U(SCH_1):PWRGD_PVNN_MAIN_CPU0
   3 DBP_CPU_HOOK9_MBP3_GTL_QS_N     1B @S9S_MB_2U_LIB.S9S_MB_2U(SCH_1):DBP_CPU_HOOK9_MBP3_GTL_QS_N
   6 DBP_CPU_HOOK8_MBP2_GTL_QS_N     2B @S9S_MB_2U_LIB.S9S_MB_2U(SCH_1):DBP_CPU_HOOK8_MBP2_GTL_QS_N
   2 JTAG_DBP_CPU_HOOK9_MBP3_GTL_N     1A @S9S_MB_2U_LIB.S9S_MB_2U(SCH_1):JTAG_DBP_CPU_HOOK9_MBP3_GTL_N
   7    GND    GND @S9S_MB_2U_LIB.S9S_MB_2U(SCH_1):GND
   9 JTAG_DBP_PRDY_N     3A @S9S_MB_2U_LIB.S9S_MB_2U(SCH_1):JTAG_DBP_PRDY_N
  10 PWRGD_PVNN_MAIN_CPU0    3OE @S9S_MB_2U_LIB.S9S_MB_2U(SCH_1):PWRGD_PVNN_MAIN_CPU0
  11 H_CPU_PREQ_QS_GTL_N     4B @S9S_MB_2U_LIB.S9S_MB_2U(SCH_1):H_CPU_PREQ_QS_GTL_N
  12 JTAG_DBP_PREQ_N     4A @S9S_MB_2U_LIB.S9S_MB_2U(SCH_1):JTAG_DBP_PREQ_N
  13 PWRGD_PVNN_MAIN_CPU0    4OE @S9S_MB_2U_LIB.S9S_MB_2U(SCH_1):PWRGD_PVNN_MAIN_CPU0
  14 P3V3_AUX    VCC @S9S_MB_2U_LIB.S9S_MB_2U(SCH_1):P3V3_AUX

Q_CAP_C0402-1UF,25V,10%,X6S,CHA  I135  C546
   1 P3V3_AUX      A @S9S_MB_2U_LIB.S9S_MB_2U(SCH_1):P3V3_AUX
   2    GND      B @S9S_MB_2U_LIB.S9S_MB_2U(SCH_1):GND

Q_RES_0402LF-10,1%,1/16W,CHIP,A  I147  R755
   1 JTAG_DBP_PREQ_N      A @S9S_MB_2U_LIB.S9S_MB_2U(SCH_1):JTAG_DBP_PREQ_N
   2 H_DBP_PREQ_N_PCH      B @S9S_MB_2U_LIB.S9S_MB_2U(SCH_1):H_DBP_PREQ_N_PCH

Q_RES_0402LF-10,1%,1/16W,CHIP,A  I148  R756
   1 JTAG_DBP_PRDY_N      A @S9S_MB_2U_LIB.S9S_MB_2U(SCH_1):JTAG_DBP_PRDY_N
   2 H_DBP_PRDY_N_PCH      B @S9S_MB_2U_LIB.S9S_MB_2U(SCH_1):H_DBP_PRDY_N_PCH

Q_RES_0402LF-120,1%,1/16W,CHIPA  I166  R757
   1 PVNN_TERM_CPU0      A @S9S_MB_2U_LIB.S9S_MB_2U(SCH_1):PVNN_TERM_CPU0
   2 JTAG_DBP_CPU_QS_GTL_TMS      B @S9S_MB_2U_LIB.S9S_MB_2U(SCH_1):JTAG_DBP_CPU_QS_GTL_TMS

Q_RES_0402LF-150,1%,1/16W,CHIPA  I168  R758
   1 PVNN_TERM_CPU0      A @S9S_MB_2U_LIB.S9S_MB_2U(SCH_1):PVNN_TERM_CPU0
   2 H_CPU_PREQ_QS_GTL_N      B @S9S_MB_2U_LIB.S9S_MB_2U(SCH_1):H_CPU_PREQ_QS_GTL_N

Q_RES_0402LF-150,1%,1/16W,CHIPA  I169  R759
   1 PVNN_TERM_CPU0      A @S9S_MB_2U_LIB.S9S_MB_2U(SCH_1):PVNN_TERM_CPU0
   2 H_CPU_PRDY_QS_GTL_N      B @S9S_MB_2U_LIB.S9S_MB_2U(SCH_1):H_CPU_PRDY_QS_GTL_N

Q_RES_0402LF-499,1%,1/16W,CHIPA  I174  R760
   1 PVNN_TERM_CPU0      A @S9S_MB_2U_LIB.S9S_MB_2U(SCH_1):PVNN_TERM_CPU0
   2 DBP_CPU_HOOK8_MBP2_GTL_QS_N      B @S9S_MB_2U_LIB.S9S_MB_2U(SCH_1):DBP_CPU_HOOK8_MBP2_GTL_QS_N

Q_RES_0402LF-499,1%,1/16W,CHIPA  I175  R761
   1 PVNN_TERM_CPU0      A @S9S_MB_2U_LIB.S9S_MB_2U(SCH_1):PVNN_TERM_CPU0
   2 DBP_CPU_HOOK9_MBP3_GTL_QS_N      B @S9S_MB_2U_LIB.S9S_MB_2U(SCH_1):DBP_CPU_HOOK9_MBP3_GTL_QS_N

Q_RES_0402LF-150,1%,1/16W,CHIPA  I176  R747
   1 P1V05_PCH_AUX      A @S9S_MB_2U_LIB.S9S_MB_2U(SCH_1):P1V05_PCH_AUX
   2 JTAG_DBP_TDO_PCH      B @S9S_MB_2U_LIB.S9S_MB_2U(SCH_1):JTAG_DBP_TDO_PCH

Q_RES_0402LF-150,1%,1/16W,CHIPA  I177  R751
   1 P1V05_PCH_AUX      A @S9S_MB_2U_LIB.S9S_MB_2U(SCH_1):P1V05_PCH_AUX
   2 H_DBP_PRDY_N_PCH      B @S9S_MB_2U_LIB.S9S_MB_2U(SCH_1):H_DBP_PRDY_N_PCH

Q_RES_0402LF-150,1%,1/16W,CHIPA  I178  R750
   1 P1V05_PCH_AUX      A @S9S_MB_2U_LIB.S9S_MB_2U(SCH_1):P1V05_PCH_AUX
   2 H_DBP_PREQ_N_PCH      B @S9S_MB_2U_LIB.S9S_MB_2U(SCH_1):H_DBP_PREQ_N_PCH

Q_RES_0402LF-75,1%,1/16W,CHIP,A  I179  R749
   1 P1V05_PCH_AUX      A @S9S_MB_2U_LIB.S9S_MB_2U(SCH_1):P1V05_PCH_AUX
   2 JTAG_DBP_TMS_PCH      B @S9S_MB_2U_LIB.S9S_MB_2U(SCH_1):JTAG_DBP_TMS_PCH

Q_RES_0402LF-75,1%,1/16W,CHIP,A  I180  R748
   1 P1V05_PCH_AUX      A @S9S_MB_2U_LIB.S9S_MB_2U(SCH_1):P1V05_PCH_AUX
   2 JTAG_DBP_TDI_PCH      B @S9S_MB_2U_LIB.S9S_MB_2U(SCH_1):JTAG_DBP_TDI_PCH


DRAWING: @S9S_MB_2U_LIB.S9S_MB_2U(SCH_1):PAGE135 

NC7SB3157_SMLF-NC7SB3157P6X,NCA  I58  U21
   1 JTAG_MUX_CPU1_GTL_TDI     B1 @S9S_MB_2U_LIB.S9S_MB_2U(SCH_1):JTAG_MUX_CPU1_GTL_TDI
   2    GND    GND @S9S_MB_2U_LIB.S9S_MB_2U(SCH_1):GND
   3 JTAG_MUX_CPU0_GTL_TDI     B0 @S9S_MB_2U_LIB.S9S_MB_2U(SCH_1):JTAG_MUX_CPU0_GTL_TDI
   6 FM_CPU0_SKTOCC_N      S @S9S_MB_2U_LIB.S9S_MB_2U(SCH_1):FM_CPU0_SKTOCC_N
   5 P3V3_AUX    VCC @S9S_MB_2U_LIB.S9S_MB_2U(SCH_1):P3V3_AUX
   4 JTAG_QS_MUX_GTL_TDI      A @S9S_MB_2U_LIB.S9S_MB_2U(SCH_1):JTAG_QS_MUX_GTL_TDI

Q_CAP_C0402-1UF,25V,10%,X6S,CHA  I61  C541
   1 P3V3_AUX      A @S9S_MB_2U_LIB.S9S_MB_2U(SCH_1):P3V3_AUX
   2    GND      B @S9S_MB_2U_LIB.S9S_MB_2U(SCH_1):GND

Q_RES_0402LF-150,1%,1/16W,CHIPA  I65  R743
   1 PVNN_TERM_CPU1      A @S9S_MB_2U_LIB.S9S_MB_2U(SCH_1):PVNN_TERM_CPU1
   2 JTAG_MUX_CPU1_GTL_TDI      B @S9S_MB_2U_LIB.S9S_MB_2U(SCH_1):JTAG_MUX_CPU1_GTL_TDI

Q_RES_0402LF-150,1%,1/16W,CHIPA  I66  R741
   1 PVNN_TERM_CPU0      A @S9S_MB_2U_LIB.S9S_MB_2U(SCH_1):PVNN_TERM_CPU0
   2 JTAG_MUX_CPU0_GTL_TDI      B @S9S_MB_2U_LIB.S9S_MB_2U(SCH_1):JTAG_MUX_CPU0_GTL_TDI

Q_CAP_0402-0.1UF,25V,10%,X7R,CA  I70  C539
   1 P3V3_AUX      A @S9S_MB_2U_LIB.S9S_MB_2U(SCH_1):P3V3_AUX
   2    GND      B @S9S_MB_2U_LIB.S9S_MB_2U(SCH_1):GND

NC7SB3157_SMLF-NC7SB3157P6X,NCA  I71  U22
   1 JTAG_CPU0_MUX_GTL_TDO     B1 @S9S_MB_2U_LIB.S9S_MB_2U(SCH_1):JTAG_CPU0_MUX_GTL_TDO
   2    GND    GND @S9S_MB_2U_LIB.S9S_MB_2U(SCH_1):GND
   3 JTAG_CPU1_MUX_GTL_TDO     B0 @S9S_MB_2U_LIB.S9S_MB_2U(SCH_1):JTAG_CPU1_MUX_GTL_TDO
   6 FM_CPU1_SKTOCC_N      S @S9S_MB_2U_LIB.S9S_MB_2U(SCH_1):FM_CPU1_SKTOCC_N
   5 P3V3_AUX    VCC @S9S_MB_2U_LIB.S9S_MB_2U(SCH_1):P3V3_AUX
   4 JTAG_MUX_QS_GTL_TDO      A @S9S_MB_2U_LIB.S9S_MB_2U(SCH_1):JTAG_MUX_QS_GTL_TDO

Q_RES_0402LF-75,1%,1/16W,CHIP,A  I77  R744
   1 PVNN_TERM_CPU0      A @S9S_MB_2U_LIB.S9S_MB_2U(SCH_1):PVNN_TERM_CPU0
   2 JTAG_CPU0_MUX_GTL_TDO      B @S9S_MB_2U_LIB.S9S_MB_2U(SCH_1):JTAG_CPU0_MUX_GTL_TDO

Q_RES_0402LF-75,1%,1/16W,CHIP,A  I78  R742
   1 PVNN_TERM_CPU1      A @S9S_MB_2U_LIB.S9S_MB_2U(SCH_1):PVNN_TERM_CPU1
   2 JTAG_CPU1_MUX_GTL_TDO      B @S9S_MB_2U_LIB.S9S_MB_2U(SCH_1):JTAG_CPU1_MUX_GTL_TDO

Q_CAP_C0402-1UF,25V,10%,X6S,CHA  I80  C542
   1 P3V3_AUX      A @S9S_MB_2U_LIB.S9S_MB_2U(SCH_1):P3V3_AUX
   2    GND      B @S9S_MB_2U_LIB.S9S_MB_2U(SCH_1):GND

Q_CAP_0402-0.1UF,25V,10%,X7R,CA  I81  C540
   1 P3V3_AUX      A @S9S_MB_2U_LIB.S9S_MB_2U(SCH_1):P3V3_AUX
   2    GND      B @S9S_MB_2U_LIB.S9S_MB_2U(SCH_1):GND

Q_CAP_0402-0.1UF,25V,10%,X7R,CA  I94  C544
   1 P3V3_AUX      A @S9S_MB_2U_LIB.S9S_MB_2U(SCH_1):P3V3_AUX
   2    GND      B @S9S_MB_2U_LIB.S9S_MB_2U(SCH_1):GND

74LVC1G02GW_SMLF-74LVC1G02GW,IA  I96  U23
   1 FM_CPU1_SKTOCC_N      B @S9S_MB_2U_LIB.S9S_MB_2U(SCH_1):FM_CPU1_SKTOCC_N
   2 FM_CPU0_SKTOCC_N      A @S9S_MB_2U_LIB.S9S_MB_2U(SCH_1):FM_CPU0_SKTOCC_N
   4 FM_CPU_EN      Y @S9S_MB_2U_LIB.S9S_MB_2U(SCH_1):FM_CPU_EN
   5 P3V3_AUX    VCC @S9S_MB_2U_LIB.S9S_MB_2U(SCH_1):P3V3_AUX
   3    GND    GND @S9S_MB_2U_LIB.S9S_MB_2U(SCH_1):GND

Q_RES_0402LF-33.2,1%,1/16W,CHIA  I97  R745
   1 FM_CPU_EN      A @S9S_MB_2U_LIB.S9S_MB_2U(SCH_1):FM_CPU_EN
   2 FM_CPU_EN_R      B @S9S_MB_2U_LIB.S9S_MB_2U(SCH_1):FM_CPU_EN_R

Q_CAP_0402-0.1UF,25V,10%,X7R,CA  I100  C543
   1 P3V3_AUX      A @S9S_MB_2U_LIB.S9S_MB_2U(SCH_1):P3V3_AUX
   2    GND      B @S9S_MB_2U_LIB.S9S_MB_2U(SCH_1):GND

Q_RES_0402LF-0,5%,1/16W,CHIP,CA  I106  R737
   1 FM_CPU1_SKTOCC_LVT3_N      A @S9S_MB_2U_LIB.S9S_MB_2U(SCH_1):FM_CPU1_SKTOCC_LVT3_N
   2 FM_CPU1_SKTOCC_N      B @S9S_MB_2U_LIB.S9S_MB_2U(SCH_1):FM_CPU1_SKTOCC_N

Q_RES_0402LF-10K,1%,1/16W,CHIPA  I107  R740
   1 P3V3_AUX      A @S9S_MB_2U_LIB.S9S_MB_2U(SCH_1):P3V3_AUX
   2 FM_CPU0_SKTOCC_N      B @S9S_MB_2U_LIB.S9S_MB_2U(SCH_1):FM_CPU0_SKTOCC_N

Q_RES_0402LF-10K,1%,1/16W,CHIPA  I109  R739
   1 P3V3_AUX      A @S9S_MB_2U_LIB.S9S_MB_2U(SCH_1):P3V3_AUX
   2 FM_CPU1_SKTOCC_N      B @S9S_MB_2U_LIB.S9S_MB_2U(SCH_1):FM_CPU1_SKTOCC_N

Q_RES_0402LF-0,5%,1/16W,CHIP,CA  I110  R738
   1 FM_CPU0_SKTOCC_LVT3_N      A @S9S_MB_2U_LIB.S9S_MB_2U(SCH_1):FM_CPU0_SKTOCC_LVT3_N
   2 FM_CPU0_SKTOCC_N      B @S9S_MB_2U_LIB.S9S_MB_2U(SCH_1):FM_CPU0_SKTOCC_N

74LVC1G66GV-74LVC1G66GV,SMLF,IA  I115  U16
   1 JTAG_CPU0_MUX_GTL_TDO      Y @S9S_MB_2U_LIB.S9S_MB_2U(SCH_1):JTAG_CPU0_MUX_GTL_TDO
   2 JTAG_MUX_CPU1_GTL_TDI      Z @S9S_MB_2U_LIB.S9S_MB_2U(SCH_1):JTAG_MUX_CPU1_GTL_TDI
   3    GND    GND @S9S_MB_2U_LIB.S9S_MB_2U(SCH_1):GND
   4 FM_CPU_EN_R      E @S9S_MB_2U_LIB.S9S_MB_2U(SCH_1):FM_CPU_EN_R
   5 P3V3_AUX    VCC @S9S_MB_2U_LIB.S9S_MB_2U(SCH_1):P3V3_AUX


DRAWING: @S9S_MB_2U_LIB.S9S_MB_2U(SCH_1):PAGE137 

74CBTLV3126PW-74CBTLV3126PW,SMA  I84  U86
   5 FM_BMC_EN_DET     2A @S9S_MB_2U_LIB.S9S_MB_2U(SCH_1):FM_BMC_EN_DET
   8 JTAG_DBP_TCK_PCH_R     3B @S9S_MB_2U_LIB.S9S_MB_2U(SCH_1):JTAG_DBP_TCK_PCH_R
   1 PD_JTAG_BMC_NTRST_N    1OE @S9S_MB_2U_LIB.S9S_MB_2U(SCH_1):PD_JTAG_BMC_NTRST_N
   4 JTAG_BMC_CPU_TCK    2OE @S9S_MB_2U_LIB.S9S_MB_2U(SCH_1):JTAG_BMC_CPU_TCK
   3 TP_JTAG_BMC_1B     1B @S9S_MB_2U_LIB.S9S_MB_2U(SCH_1):TP_JTAG_BMC_1B
   6 JTAG_DBP_CPU_GTL_TCK_R1     2B @S9S_MB_2U_LIB.S9S_MB_2U(SCH_1):JTAG_DBP_CPU_GTL_TCK_R1
   2 FM_BMC_EN_DET     1A @S9S_MB_2U_LIB.S9S_MB_2U(SCH_1):FM_BMC_EN_DET
   7    GND    GND @S9S_MB_2U_LIB.S9S_MB_2U(SCH_1):GND
   9 FM_BMC_EN_DET     3A @S9S_MB_2U_LIB.S9S_MB_2U(SCH_1):FM_BMC_EN_DET
  10 JTAG_BMC_PCH_TCK    3OE @S9S_MB_2U_LIB.S9S_MB_2U(SCH_1):JTAG_BMC_PCH_TCK
  11 TP_JTAG_BMC_4B     4B @S9S_MB_2U_LIB.S9S_MB_2U(SCH_1):TP_JTAG_BMC_4B
  12 FM_BMC_EN_DET     4A @S9S_MB_2U_LIB.S9S_MB_2U(SCH_1):FM_BMC_EN_DET
  13 PD_JTAG_BMC_NTRST_N    4OE @S9S_MB_2U_LIB.S9S_MB_2U(SCH_1):PD_JTAG_BMC_NTRST_N
  14 P3V3_AUX    VCC @S9S_MB_2U_LIB.S9S_MB_2U(SCH_1):P3V3_AUX

Q_RES_0402LF-0,5%,1/16W,CHIP,CA  I87  R1349
   1 JTAG_DBP_TCK_PCH_R      A @S9S_MB_2U_LIB.S9S_MB_2U(SCH_1):JTAG_DBP_TCK_PCH_R
   2 JTAG_DBP_TCK_PCH      B @S9S_MB_2U_LIB.S9S_MB_2U(SCH_1):JTAG_DBP_TCK_PCH

Q_RES_0402LF-0,5%,1/16W,CHIP,CA  I88  R1348
   1 JTAG_DBP_CPU_GTL_TCK_R1      A @S9S_MB_2U_LIB.S9S_MB_2U(SCH_1):JTAG_DBP_CPU_GTL_TCK_R1
   2 JTAG_DBP_CPU_GTL_TCK      B @S9S_MB_2U_LIB.S9S_MB_2U(SCH_1):JTAG_DBP_CPU_GTL_TCK

Q_CAP_0402-0.1UF,25V,10%,X7R,CA  I90  C1292
   1 P3V3_AUX      A @S9S_MB_2U_LIB.S9S_MB_2U(SCH_1):P3V3_AUX
   2    GND      B @S9S_MB_2U_LIB.S9S_MB_2U(SCH_1):GND

Q_CAP_C0402-1UF,25V,10%,X6S,CHA  I95  C1293
   1 FM_BMC_EN_DET      A @S9S_MB_2U_LIB.S9S_MB_2U(SCH_1):FM_BMC_EN_DET
   2    GND      B @S9S_MB_2U_LIB.S9S_MB_2U(SCH_1):GND

MOSFET_N_SMLF-BSS138K,BSS138K,A  I96  U87
   G FM_REMOTE_DEBUG_DET_R   GATE @S9S_MB_2U_LIB.S9S_MB_2U(SCH_1):FM_REMOTE_DEBUG_DET_R
   D P1V05_PCH_AUX  DRAIN @S9S_MB_2U_LIB.S9S_MB_2U(SCH_1):P1V05_PCH_AUX
   S FM_BMC_EN_DET SOURCE @S9S_MB_2U_LIB.S9S_MB_2U(SCH_1):FM_BMC_EN_DET

Q_RES_0402LF-10K,1%,1/16W,CHIPA  I97  R1375
   1 FM_BMC_EN_DET      A @S9S_MB_2U_LIB.S9S_MB_2U(SCH_1):FM_BMC_EN_DET
   2    GND      B @S9S_MB_2U_LIB.S9S_MB_2U(SCH_1):GND

Q_RES_0402LF-100,1%,1/16W,CHIPA  I98  R1370
   1 P3V3_AUX      A @S9S_MB_2U_LIB.S9S_MB_2U(SCH_1):P3V3_AUX
   2 FM_REMOTE_DEBUG_DET_R      B @S9S_MB_2U_LIB.S9S_MB_2U(SCH_1):FM_REMOTE_DEBUG_DET_R

Q_RES_0402LF-1K,1%,1/16W,EMPTYA  I102  R3025
   1 FM_REMOTE_DEBUG_DET_R      A @S9S_MB_2U_LIB.S9S_MB_2U(SCH_1):FM_REMOTE_DEBUG_DET_R
   2    GND      B @S9S_MB_2U_LIB.S9S_MB_2U(SCH_1):GND

Q_RES_0402LF-1K,1%,1/16W,CHIP,A  I103  R1374
   1 PD_JTAG_BMC_NTRST_N      A @S9S_MB_2U_LIB.S9S_MB_2U(SCH_1):PD_JTAG_BMC_NTRST_N
   2    GND      B @S9S_MB_2U_LIB.S9S_MB_2U(SCH_1):GND

Q_RES_0402LF-1K,1%,1/16W,CHIP,A  I105  R3027
   1 JTAG_BMC_CPU_TCK      A @S9S_MB_2U_LIB.S9S_MB_2U(SCH_1):JTAG_BMC_CPU_TCK
   2    GND      B @S9S_MB_2U_LIB.S9S_MB_2U(SCH_1):GND

Q_RES_0402LF-1K,1%,1/16W,CHIP,A  I106  R3026
   1 JTAG_BMC_PCH_TCK      A @S9S_MB_2U_LIB.S9S_MB_2U(SCH_1):JTAG_BMC_PCH_TCK
   2    GND      B @S9S_MB_2U_LIB.S9S_MB_2U(SCH_1):GND

NC7SB3157_SMLF-NC7SB3157P6X,NCA  I109  U85
   1 JTAG_BMC_PCH_TCK     B1 @S9S_MB_2U_LIB.S9S_MB_2U(SCH_1):JTAG_BMC_PCH_TCK
   2    GND    GND @S9S_MB_2U_LIB.S9S_MB_2U(SCH_1):GND
   3 JTAG_BMC_CPU_TCK     B0 @S9S_MB_2U_LIB.S9S_MB_2U(SCH_1):JTAG_BMC_CPU_TCK
   6 FM_JTAG_TCK_MUX_SEL      S @S9S_MB_2U_LIB.S9S_MB_2U(SCH_1):FM_JTAG_TCK_MUX_SEL
   5 P3V3_AUX    VCC @S9S_MB_2U_LIB.S9S_MB_2U(SCH_1):P3V3_AUX
   4 JTAG_BMC_DBP_TCK      A @S9S_MB_2U_LIB.S9S_MB_2U(SCH_1):JTAG_BMC_DBP_TCK

Q_CAP_C0402-1UF,25V,10%,X6S,CHA  I110  C1289
   1 P3V3_AUX      A @S9S_MB_2U_LIB.S9S_MB_2U(SCH_1):P3V3_AUX
   2    GND      B @S9S_MB_2U_LIB.S9S_MB_2U(SCH_1):GND

Q_CAP_0402-0.1UF,25V,10%,X7R,CA  I112  C1288
   1 P3V3_AUX      A @S9S_MB_2U_LIB.S9S_MB_2U(SCH_1):P3V3_AUX
   2    GND      B @S9S_MB_2U_LIB.S9S_MB_2U(SCH_1):GND

Q_RES_0402LF-1K,1%,1/16W,CHIP,A  I116  R1365
   1 FM_JTAG_TCK_MUX_SEL      A @S9S_MB_2U_LIB.S9S_MB_2U(SCH_1):FM_JTAG_TCK_MUX_SEL
   2    GND      B @S9S_MB_2U_LIB.S9S_MB_2U(SCH_1):GND


DRAWING: @S9S_MB_2U_LIB.S9S_MB_2U(SCH_1):PAGE151 

Q_RES_0402LF-100K,1%,1/16W,CHIA  I56  R1353
   1 RMII_BMC_OCP_TX_EN      A @S9S_MB_2U_LIB.S9S_MB_2U(SCH_1):RMII_BMC_OCP_TX_EN
   2    GND      B @S9S_MB_2U_LIB.S9S_MB_2U(SCH_1):GND

Q_RES_0402LF-33.2,1%,1/16W,CHIA  I3  R3231
   1 OCP_SFF_AUX_PWR_EN      A @S9S_MB_2U_LIB.S9S_MB_2U(SCH_1):OCP_SFF_AUX_PWR_EN
   2 OCP_SFF_AUX_PWR_EN_R4      B @S9S_MB_2U_LIB.S9S_MB_2U(SCH_1):OCP_SFF_AUX_PWR_EN_R4

Q_RES_0402LF-33.2,1%,1/16W,CHIA  I5  R1719
   1 OCP_SFF_AUX_PWR_EN      A @S9S_MB_2U_LIB.S9S_MB_2U(SCH_1):OCP_SFF_AUX_PWR_EN
   2 OCP_SFF_AUX_PWR_EN_R1      B @S9S_MB_2U_LIB.S9S_MB_2U(SCH_1):OCP_SFF_AUX_PWR_EN_R1

74LVC1G126SE7-74LVC1G126SE-7,SA  I7  U224
   2 RST_SMB_SWITCH_N      A @S9S_MB_2U_LIB.S9S_MB_2U(SCH_1):RST_SMB_SWITCH_N
   4 RST_HP_OCP_SFF_R_N      Y @S9S_MB_2U_LIB.S9S_MB_2U(SCH_1):RST_HP_OCP_SFF_R_N
   5 P3V3_AUX    VCC @S9S_MB_2U_LIB.S9S_MB_2U(SCH_1):P3V3_AUX
   3    GND    GND @S9S_MB_2U_LIB.S9S_MB_2U(SCH_1):GND
   1 OCP_SFF_AUX_PWR_EN_R4     OE @S9S_MB_2U_LIB.S9S_MB_2U(SCH_1):OCP_SFF_AUX_PWR_EN_R4

Q_CAP_0402-0.1UF,25V,10%,X7R,CA  I8  C1840
   1 P3V3_AUX      A @S9S_MB_2U_LIB.S9S_MB_2U(SCH_1):P3V3_AUX
   2    GND      B @S9S_MB_2U_LIB.S9S_MB_2U(SCH_1):GND

Q_RES_0402LF-100K,1%,1/16W,CHIA  I13  R3232
   1 RST_HP_OCP_SFF_R_N      A @S9S_MB_2U_LIB.S9S_MB_2U(SCH_1):RST_HP_OCP_SFF_R_N
   2    GND      B @S9S_MB_2U_LIB.S9S_MB_2U(SCH_1):GND

74LVC1G126SE7-74LVC1G126SE-7,SA  I15  U66
   2 FM_OCP_SFF_PWR_GOOD      A @S9S_MB_2U_LIB.S9S_MB_2U(SCH_1):FM_OCP_SFF_PWR_GOOD
   4 FB_BMC_ISOLATE_R1      Y @S9S_MB_2U_LIB.S9S_MB_2U(SCH_1):FB_BMC_ISOLATE_R1
   5 P3V3_AUX    VCC @S9S_MB_2U_LIB.S9S_MB_2U(SCH_1):P3V3_AUX
   3    GND    GND @S9S_MB_2U_LIB.S9S_MB_2U(SCH_1):GND
   1 OCP_SFF_AUX_PWR_EN_R1     OE @S9S_MB_2U_LIB.S9S_MB_2U(SCH_1):OCP_SFF_AUX_PWR_EN_R1

Q_RES_0402LF-0,5%,1/16W,CHIP,CA  I17  R3233
   1 RST_HP_OCP_SFF_R_N      A @S9S_MB_2U_LIB.S9S_MB_2U(SCH_1):RST_HP_OCP_SFF_R_N
   2 RST_SMB_OCP_SFF_N      B @S9S_MB_2U_LIB.S9S_MB_2U(SCH_1):RST_SMB_OCP_SFF_N

Q_RES_0402LF-0,5%,1/16W,EMPTY,A  I19  R2474
   1 FM_NCSI_OCP_V3_1_R_OE      A @S9S_MB_2U_LIB.S9S_MB_2U(SCH_1):FM_NCSI_OCP_V3_1_R_OE
   2 FB_BMC_ISOLATE      B @S9S_MB_2U_LIB.S9S_MB_2U(SCH_1):FB_BMC_ISOLATE

Q_RES_0402LF-100K,1%,1/16W,CHIA  I21  R1289
   1 FB_BMC_ISOLATE      A @S9S_MB_2U_LIB.S9S_MB_2U(SCH_1):FB_BMC_ISOLATE
   2    GND      B @S9S_MB_2U_LIB.S9S_MB_2U(SCH_1):GND

Q_CAP_0402-0.1UF,25V,10%,X7R,CA  I22  C639
   1 P3V3_AUX      A @S9S_MB_2U_LIB.S9S_MB_2U(SCH_1):P3V3_AUX
   2    GND      B @S9S_MB_2U_LIB.S9S_MB_2U(SCH_1):GND

74CBTLV3126PW-74CBTLV3126PW,SMA  I30  U68
   5 NCSI_BMC_TXD0_R     2A @S9S_MB_2U_LIB.S9S_MB_2U(SCH_1):NCSI_BMC_TXD0_R
   8 NCSI_OCP_SFF_TX_EN     3B @S9S_MB_2U_LIB.S9S_MB_2U(SCH_1):NCSI_OCP_SFF_TX_EN
   1 FB_BMC_ISOLATE    1OE @S9S_MB_2U_LIB.S9S_MB_2U(SCH_1):FB_BMC_ISOLATE
   4 FB_BMC_ISOLATE    2OE @S9S_MB_2U_LIB.S9S_MB_2U(SCH_1):FB_BMC_ISOLATE
   3 NCSI_OCP_SFF_TXD1     1B @S9S_MB_2U_LIB.S9S_MB_2U(SCH_1):NCSI_OCP_SFF_TXD1
   6 NCSI_OCP_SFF_TXD0     2B @S9S_MB_2U_LIB.S9S_MB_2U(SCH_1):NCSI_OCP_SFF_TXD0
   2 NCSI_BMC_TXD1_R     1A @S9S_MB_2U_LIB.S9S_MB_2U(SCH_1):NCSI_BMC_TXD1_R
   7    GND    GND @S9S_MB_2U_LIB.S9S_MB_2U(SCH_1):GND
   9 NCSI_BMC_TX_EN_R     3A @S9S_MB_2U_LIB.S9S_MB_2U(SCH_1):NCSI_BMC_TX_EN_R
  10 FB_BMC_ISOLATE    3OE @S9S_MB_2U_LIB.S9S_MB_2U(SCH_1):FB_BMC_ISOLATE
  11 OCP_SFF_ISO2_RBT_ARB_OUT     4B @S9S_MB_2U_LIB.S9S_MB_2U(SCH_1):OCP_SFF_ISO2_RBT_ARB_OUT
  12 OCP_SFF_RBT_ARB_OUT     4A @S9S_MB_2U_LIB.S9S_MB_2U(SCH_1):OCP_SFF_RBT_ARB_OUT
  13 FB_BMC_ISOLATE    4OE @S9S_MB_2U_LIB.S9S_MB_2U(SCH_1):FB_BMC_ISOLATE
  14 P3V3_AUX    VCC @S9S_MB_2U_LIB.S9S_MB_2U(SCH_1):P3V3_AUX

Q_CAP_0402-0.1UF,25V,10%,X7R,CA  I32  C641
   1 P3V3_AUX      A @S9S_MB_2U_LIB.S9S_MB_2U(SCH_1):P3V3_AUX
   2    GND      B @S9S_MB_2U_LIB.S9S_MB_2U(SCH_1):GND

74CBTLV3126PW-74CBTLV3126PW,SMA  I39  U67
   5 NCSI_BMC_RXD0_R     2A @S9S_MB_2U_LIB.S9S_MB_2U(SCH_1):NCSI_BMC_RXD0_R
   8 NCSI_OCP_SFF_CRS_DV     3B @S9S_MB_2U_LIB.S9S_MB_2U(SCH_1):NCSI_OCP_SFF_CRS_DV
   1 FB_BMC_ISOLATE    1OE @S9S_MB_2U_LIB.S9S_MB_2U(SCH_1):FB_BMC_ISOLATE
   4 FB_BMC_ISOLATE    2OE @S9S_MB_2U_LIB.S9S_MB_2U(SCH_1):FB_BMC_ISOLATE
   3 NCSI_OCP_SFF_RXD1     1B @S9S_MB_2U_LIB.S9S_MB_2U(SCH_1):NCSI_OCP_SFF_RXD1
   6 NCSI_OCP_SFF_RXD0     2B @S9S_MB_2U_LIB.S9S_MB_2U(SCH_1):NCSI_OCP_SFF_RXD0
   2 NCSI_BMC_RXD1_R     1A @S9S_MB_2U_LIB.S9S_MB_2U(SCH_1):NCSI_BMC_RXD1_R
   7    GND    GND @S9S_MB_2U_LIB.S9S_MB_2U(SCH_1):GND
   9 NCSI_BMC_CRS_DV_R     3A @S9S_MB_2U_LIB.S9S_MB_2U(SCH_1):NCSI_BMC_CRS_DV_R
  10 FB_BMC_ISOLATE    3OE @S9S_MB_2U_LIB.S9S_MB_2U(SCH_1):FB_BMC_ISOLATE
  11 OCP_SFF_ISO1_RBT_ARB_IN     4B @S9S_MB_2U_LIB.S9S_MB_2U(SCH_1):OCP_SFF_ISO1_RBT_ARB_IN
  12 OCP_SFF_RBT_ARB_IN_R     4A @S9S_MB_2U_LIB.S9S_MB_2U(SCH_1):OCP_SFF_RBT_ARB_IN_R
  13 FB_BMC_ISOLATE    4OE @S9S_MB_2U_LIB.S9S_MB_2U(SCH_1):FB_BMC_ISOLATE
  14 P3V3_AUX    VCC @S9S_MB_2U_LIB.S9S_MB_2U(SCH_1):P3V3_AUX

Q_CAP_0402-0.1UF,25V,10%,X7R,CA  I40  C640
   1 P3V3_AUX      A @S9S_MB_2U_LIB.S9S_MB_2U(SCH_1):P3V3_AUX
   2    GND      B @S9S_MB_2U_LIB.S9S_MB_2U(SCH_1):GND

Q_RES_0402LF-100,1%,1/16W,CHIPA  I43  R1896
   1 OCP_SFF_ISO_BIF0_EN      A @S9S_MB_2U_LIB.S9S_MB_2U(SCH_1):OCP_SFF_ISO_BIF0_EN
   2    GND      B @S9S_MB_2U_LIB.S9S_MB_2U(SCH_1):GND

Q_RES_0402LF-100,1%,1/16W,CHIPA  I50  R1897
   1 OCP_SFF_ISO_BIF1_EN      A @S9S_MB_2U_LIB.S9S_MB_2U(SCH_1):OCP_SFF_ISO_BIF1_EN
   2    GND      B @S9S_MB_2U_LIB.S9S_MB_2U(SCH_1):GND

Q_RES_0402LF-100,1%,1/16W,CHIPA  I52  R1898
   1 OCP_SFF_ISO_BIF2_EN      A @S9S_MB_2U_LIB.S9S_MB_2U(SCH_1):OCP_SFF_ISO_BIF2_EN
   2    GND      B @S9S_MB_2U_LIB.S9S_MB_2U(SCH_1):GND

Q_RES_0402LF-1K,1%,1/16W,CHIP,A  I53  R1356
   1 RMII_BMC_OCP_RX_ER      A @S9S_MB_2U_LIB.S9S_MB_2U(SCH_1):RMII_BMC_OCP_RX_ER
   2    GND      B @S9S_MB_2U_LIB.S9S_MB_2U(SCH_1):GND

Q_RES_0402LF-100K,1%,1/16W,CHIA  I54  R1355
   1 RMII_BMC_OCP_TXD_1      A @S9S_MB_2U_LIB.S9S_MB_2U(SCH_1):RMII_BMC_OCP_TXD_1
   2    GND      B @S9S_MB_2U_LIB.S9S_MB_2U(SCH_1):GND

Q_RES_0402LF-100K,1%,1/16W,CHIA  I55  R1354
   1 RMII_BMC_OCP_TXD_0      A @S9S_MB_2U_LIB.S9S_MB_2U(SCH_1):RMII_BMC_OCP_TXD_0
   2    GND      B @S9S_MB_2U_LIB.S9S_MB_2U(SCH_1):GND

Q_RES_0402LF-0,5%,1/16W,CHIP,CA  I61  R1296
   1 NCSI_BMC_TXD1_R      A @S9S_MB_2U_LIB.S9S_MB_2U(SCH_1):NCSI_BMC_TXD1_R
   2 RMII_BMC_OCP_TXD_1      B @S9S_MB_2U_LIB.S9S_MB_2U(SCH_1):RMII_BMC_OCP_TXD_1

Q_RES_0402LF-0,5%,1/16W,CHIP,CA  I65  R1295
   1 NCSI_BMC_TXD0_R      A @S9S_MB_2U_LIB.S9S_MB_2U(SCH_1):NCSI_BMC_TXD0_R
   2 RMII_BMC_OCP_TXD_0      B @S9S_MB_2U_LIB.S9S_MB_2U(SCH_1):RMII_BMC_OCP_TXD_0

Q_RES_0402LF-0,5%,1/16W,CHIP,CA  I66  R1294
   1 NCSI_BMC_TX_EN_R      A @S9S_MB_2U_LIB.S9S_MB_2U(SCH_1):NCSI_BMC_TX_EN_R
   2 RMII_BMC_OCP_TX_EN      B @S9S_MB_2U_LIB.S9S_MB_2U(SCH_1):RMII_BMC_OCP_TX_EN

Q_RES_0402LF-22,1%,1/16W,CHIP,A  I67  R1293
   1 NCSI_BMC_RXD1_R      A @S9S_MB_2U_LIB.S9S_MB_2U(SCH_1):NCSI_BMC_RXD1_R
   2 RMII_OCP_BMC_RXD_1      B @S9S_MB_2U_LIB.S9S_MB_2U(SCH_1):RMII_OCP_BMC_RXD_1

Q_RES_0402LF-22,1%,1/16W,CHIP,A  I68  R1292
   1 NCSI_BMC_RXD0_R      A @S9S_MB_2U_LIB.S9S_MB_2U(SCH_1):NCSI_BMC_RXD0_R
   2 RMII_OCP_BMC_RXD_0      B @S9S_MB_2U_LIB.S9S_MB_2U(SCH_1):RMII_OCP_BMC_RXD_0

Q_RES_0402LF-22,1%,1/16W,CHIP,A  I69  R1291
   1 NCSI_BMC_CRS_DV_R      A @S9S_MB_2U_LIB.S9S_MB_2U(SCH_1):NCSI_BMC_CRS_DV_R
   2 RMII_OCP_BMC_CRSDV      B @S9S_MB_2U_LIB.S9S_MB_2U(SCH_1):RMII_OCP_BMC_CRSDV

Q_RES_0402LF-100K,1%,1/16W,CHIA  I71  R1352
   1 RMII_OCP_BMC_RXD_1      A @S9S_MB_2U_LIB.S9S_MB_2U(SCH_1):RMII_OCP_BMC_RXD_1
   2    GND      B @S9S_MB_2U_LIB.S9S_MB_2U(SCH_1):GND

Q_RES_0402LF-100K,1%,1/16W,CHIA  I72  R1351
   1 RMII_OCP_BMC_RXD_0      A @S9S_MB_2U_LIB.S9S_MB_2U(SCH_1):RMII_OCP_BMC_RXD_0
   2    GND      B @S9S_MB_2U_LIB.S9S_MB_2U(SCH_1):GND

Q_RES_0402LF-100K,1%,1/16W,CHIA  I73  R1350
   1 RMII_OCP_BMC_CRSDV      A @S9S_MB_2U_LIB.S9S_MB_2U(SCH_1):RMII_OCP_BMC_CRSDV
   2    GND      B @S9S_MB_2U_LIB.S9S_MB_2U(SCH_1):GND

Q_RES_0402LF-0,5%,1/16W,CHIP,CA  I80  R3237
   1 OCP_SFF_RBT_ARB_OUT      A @S9S_MB_2U_LIB.S9S_MB_2U(SCH_1):OCP_SFF_RBT_ARB_OUT
   2 OCP_SFF_RBT_ARB_IN_R      B @S9S_MB_2U_LIB.S9S_MB_2U(SCH_1):OCP_SFF_RBT_ARB_IN_R

Q_RES_0402LF-22,1%,1/16W,EMPTYA  I81  R1290
   1 OCP_SFF_RBT_ARB_IN_R      A @S9S_MB_2U_LIB.S9S_MB_2U(SCH_1):OCP_SFF_RBT_ARB_IN_R
   2 OCP_SFF_RBT_ARB_IN      B @S9S_MB_2U_LIB.S9S_MB_2U(SCH_1):OCP_SFF_RBT_ARB_IN

Q_RES_0402LF-49.9,1%,1/16W,CHIA  I83  R2473
   1 FB_BMC_ISOLATE_R1      A @S9S_MB_2U_LIB.S9S_MB_2U(SCH_1):FB_BMC_ISOLATE_R1
   2 FB_BMC_ISOLATE      B @S9S_MB_2U_LIB.S9S_MB_2U(SCH_1):FB_BMC_ISOLATE


DRAWING: @S9S_MB_2U_LIB.S9S_MB_2U(SCH_1):PAGE152 

74LVC1G17GW-74LVC1G17GW,SMLF,IA  I1  U75
   5 P3V3_AUX    VCC @S9S_MB_2U_LIB.S9S_MB_2U(SCH_1):P3V3_AUX
   2 RST_HP_OCP_V3_1_N      A @S9S_MB_2U_LIB.S9S_MB_2U(SCH_1):RST_HP_OCP_V3_1_N
   3    GND    GND @S9S_MB_2U_LIB.S9S_MB_2U(SCH_1):GND
   4 RST_OCP_V3_1_BUF_N      Y @S9S_MB_2U_LIB.S9S_MB_2U(SCH_1):RST_OCP_V3_1_BUF_N
   1     NC     NC     NC

Q_CAP_0402-0.1UF,25V,10%,X7R,CA  I4  C1173
   1 P3V3_AUX      A @S9S_MB_2U_LIB.S9S_MB_2U(SCH_1):P3V3_AUX
   2    GND      B @S9S_MB_2U_LIB.S9S_MB_2U(SCH_1):GND

Q_RES_0402LF-33.2,1%,1/16W,CHIA  I6  R419
   1 RST_OCP_V3_1_BUF_N      A @S9S_MB_2U_LIB.S9S_MB_2U(SCH_1):RST_OCP_V3_1_BUF_N
   2 RST_PERST0_OCP_SFF_N      B @S9S_MB_2U_LIB.S9S_MB_2U(SCH_1):RST_PERST0_OCP_SFF_N

Q_RES_0402LF-33.2,1%,1/16W,CHIA  I8  R435
   1 RST_OCP_V3_1_BUF_N      A @S9S_MB_2U_LIB.S9S_MB_2U(SCH_1):RST_OCP_V3_1_BUF_N
   2 RST_PERST1_OCP_SFF_N      B @S9S_MB_2U_LIB.S9S_MB_2U(SCH_1):RST_PERST1_OCP_SFF_N

Q_RES_0402LF-33.2,1%,1/16W,CHIA  I10  R1504
   1 RST_OCP_V3_1_BUF_N      A @S9S_MB_2U_LIB.S9S_MB_2U(SCH_1):RST_OCP_V3_1_BUF_N
   2 RST_PERST2_OCP_SFF_N      B @S9S_MB_2U_LIB.S9S_MB_2U(SCH_1):RST_PERST2_OCP_SFF_N

Q_RES_0402LF-33.2,1%,1/16W,CHIA  I13  R1505
   1 RST_OCP_V3_1_BUF_N      A @S9S_MB_2U_LIB.S9S_MB_2U(SCH_1):RST_OCP_V3_1_BUF_N
   2 RST_PERST3_OCP_SFF_N      B @S9S_MB_2U_LIB.S9S_MB_2U(SCH_1):RST_PERST3_OCP_SFF_N

Q_CAP_0402-0.1UF,25V,10%,X7R,CA  I24  C1175
   1 P3V3_AUX      A @S9S_MB_2U_LIB.S9S_MB_2U(SCH_1):P3V3_AUX
   2    GND      B @S9S_MB_2U_LIB.S9S_MB_2U(SCH_1):GND

Q_RES_0402LF-33.2,1%,1/16W,CHIA  I26  R1594
   1 OCP_SFF_WAKE_BUFF_N      A @S9S_MB_2U_LIB.S9S_MB_2U(SCH_1):OCP_SFF_WAKE_BUFF_N
   2 OCP_SFF_WAKE_BUFF_R_N      B @S9S_MB_2U_LIB.S9S_MB_2U(SCH_1):OCP_SFF_WAKE_BUFF_R_N

Q_RES_0402LF-10K,1%,1/16W,CHIPA  I37  R1592
   1 P3V3_OCP_SFF      A @S9S_MB_2U_LIB.S9S_MB_2U(SCH_1):P3V3_OCP_SFF
   2 PU_OCP_SFF_WAKE_OE      B @S9S_MB_2U_LIB.S9S_MB_2U(SCH_1):PU_OCP_SFF_WAKE_OE

Q_RES_0402LF-33.2,1%,1/16W,CHIA  I40  R1595
   1 OCP_SFF_PWRBRK_BUFF_N      A @S9S_MB_2U_LIB.S9S_MB_2U(SCH_1):OCP_SFF_PWRBRK_BUFF_N
   2 OCP_SFF_PWRBRK_N      B @S9S_MB_2U_LIB.S9S_MB_2U(SCH_1):OCP_SFF_PWRBRK_N

Q_RES_0402LF-4.7K,1%,1/16W,CHIA  I42  R1593
   1 P3V3_AUX      A @S9S_MB_2U_LIB.S9S_MB_2U(SCH_1):P3V3_AUX
   2 OCP_SFF_PWRBRK_BUFF_N      B @S9S_MB_2U_LIB.S9S_MB_2U(SCH_1):OCP_SFF_PWRBRK_BUFF_N

Q_CAP_0402-0.1UF,25V,10%,X7R,CA  I44  C188
   1 P3V3_AUX      A @S9S_MB_2U_LIB.S9S_MB_2U(SCH_1):P3V3_AUX
   2    GND      B @S9S_MB_2U_LIB.S9S_MB_2U(SCH_1):GND

PI6CV304LE-PI6CV304LE,SMLF,IC,A  I46  U90
   1 CLK_50M_RMII_R CLK_IN @S9S_MB_2U_LIB.S9S_MB_2U(SCH_1):CLK_50M_RMII_R
   2 CLK_50M_EN     OE @S9S_MB_2U_LIB.S9S_MB_2U(SCH_1):CLK_50M_EN
   3 CLK_50M_BMC_MAC_R     Y0 @S9S_MB_2U_LIB.S9S_MB_2U(SCH_1):CLK_50M_BMC_MAC_R
   5 CLK_50M_NCSI_OCP_1     Y1 @S9S_MB_2U_LIB.S9S_MB_2U(SCH_1):CLK_50M_NCSI_OCP_1
   7 CLK_50M_NCSI_OCP_2     Y2 @S9S_MB_2U_LIB.S9S_MB_2U(SCH_1):CLK_50M_NCSI_OCP_2
   8 TP_CLK_50M_PCH_LOM     Y3 @S9S_MB_2U_LIB.S9S_MB_2U(SCH_1):TP_CLK_50M_PCH_LOM
   6 P3V3_AUX    VDD @S9S_MB_2U_LIB.S9S_MB_2U(SCH_1):P3V3_AUX
   4    GND    GND @S9S_MB_2U_LIB.S9S_MB_2U(SCH_1):GND

Q_CAP_0402-0.1UF,25V,10%,X7R,CA  I49  C1275
   1 P3V3_AUX      A @S9S_MB_2U_LIB.S9S_MB_2U(SCH_1):P3V3_AUX
   2    GND      B @S9S_MB_2U_LIB.S9S_MB_2U(SCH_1):GND

Q_RES_0402LF-27.4,1%,1/16W,CHIA  I52  R1140
   1 CLK_50M_BMC_MAC_R      A @S9S_MB_2U_LIB.S9S_MB_2U(SCH_1):CLK_50M_BMC_MAC_R
   2 CLK_50M_RMII_BMC_OCP      B @S9S_MB_2U_LIB.S9S_MB_2U(SCH_1):CLK_50M_RMII_BMC_OCP

Q_RES_0402LF-27.4,1%,1/16W,CHIA  I53  R1141
   1 CLK_50M_NCSI_OCP_1      A @S9S_MB_2U_LIB.S9S_MB_2U(SCH_1):CLK_50M_NCSI_OCP_1
   2 CLK_50M_NCSI_OCP_SFF      B @S9S_MB_2U_LIB.S9S_MB_2U(SCH_1):CLK_50M_NCSI_OCP_SFF

Q_RES_0402LF-0,5%,1/16W,CHIP,CA  I56  R1139
   1 CLK_50M_RMII      A @S9S_MB_2U_LIB.S9S_MB_2U(SCH_1):CLK_50M_RMII
   2 CLK_50M_RMII_R      B @S9S_MB_2U_LIB.S9S_MB_2U(SCH_1):CLK_50M_RMII_R

Q_CAP_0402-0.1UF,25V,10%,X7R,CA  I59  C1274
   1 P3V3_AUX      A @S9S_MB_2U_LIB.S9S_MB_2U(SCH_1):P3V3_AUX
   2    GND      B @S9S_MB_2U_LIB.S9S_MB_2U(SCH_1):GND

Q_RES_0402LF-10K,1%,1/16W,CHIPA  I61  R1138
   1 P3V3_AUX      A @S9S_MB_2U_LIB.S9S_MB_2U(SCH_1):P3V3_AUX
   2 CLK_50M_EN      B @S9S_MB_2U_LIB.S9S_MB_2U(SCH_1):CLK_50M_EN

Q_RES_0402LF-10K,1%,1/16W,CHIPA  I62  R1824
   1 P3V3_OCP_SFF      A @S9S_MB_2U_LIB.S9S_MB_2U(SCH_1):P3V3_OCP_SFF
   2 IRQ_LVC3_OCP_SFF_WAKE_N      B @S9S_MB_2U_LIB.S9S_MB_2U(SCH_1):IRQ_LVC3_OCP_SFF_WAKE_N

74LVC1G07GV-74LVC1G07GV,SMLF,IA  I63  U104
   5 P3V3_AUX    VCC @S9S_MB_2U_LIB.S9S_MB_2U(SCH_1):P3V3_AUX
   2 FM_SYS_THROTTLE_R_N      A @S9S_MB_2U_LIB.S9S_MB_2U(SCH_1):FM_SYS_THROTTLE_R_N
   3    GND    GND @S9S_MB_2U_LIB.S9S_MB_2U(SCH_1):GND
   4 OCP_SFF_PWRBRK_BUFF_N      Y @S9S_MB_2U_LIB.S9S_MB_2U(SCH_1):OCP_SFF_PWRBRK_BUFF_N
   1 NC_U104_NC1    NC1 @S9S_MB_2U_LIB.S9S_MB_2U(SCH_1):NC_U104_NC1

74LVC1G07GV-74LVC1G07GV,SMLF,IA  I65  U157
   5 P3V3_AUX    VCC @S9S_MB_2U_LIB.S9S_MB_2U(SCH_1):P3V3_AUX
   2 OCP_SFF_WAKE_BUFF_R_N      A @S9S_MB_2U_LIB.S9S_MB_2U(SCH_1):OCP_SFF_WAKE_BUFF_R_N
   3    GND    GND @S9S_MB_2U_LIB.S9S_MB_2U(SCH_1):GND
   4 IRQ_LVC3_WAKE_BUF_N      Y @S9S_MB_2U_LIB.S9S_MB_2U(SCH_1):IRQ_LVC3_WAKE_BUF_N
   1 NC_U157_NC1    NC1 @S9S_MB_2U_LIB.S9S_MB_2U(SCH_1):NC_U157_NC1

Q_CAP_0402-0.1UF,25V,10%,X7R,CA  I68  C1663
   1 P3V3_AUX      A @S9S_MB_2U_LIB.S9S_MB_2U(SCH_1):P3V3_AUX
   2    GND      B @S9S_MB_2U_LIB.S9S_MB_2U(SCH_1):GND

Q_RES_0402LF-4.7K,1%,1/16W,EMPA  I71  R2487
   1 P3V3_AUX      A @S9S_MB_2U_LIB.S9S_MB_2U(SCH_1):P3V3_AUX
   2 IRQ_LVC3_WAKE_BUF_N      B @S9S_MB_2U_LIB.S9S_MB_2U(SCH_1):IRQ_LVC3_WAKE_BUF_N

Q_RES_0402LF-4.7K,1%,1/16W,CHIA  I74  R2488
   1 P3V3_AUX      A @S9S_MB_2U_LIB.S9S_MB_2U(SCH_1):P3V3_AUX
   2 OCP_SFF_WAKE_BUFF_N      B @S9S_MB_2U_LIB.S9S_MB_2U(SCH_1):OCP_SFF_WAKE_BUFF_N

Q_RES_0402LF-33.2,1%,1/16W,CHIA  I75  R2489
   1 IRQ_LVC3_WAKE_BUF_N      A @S9S_MB_2U_LIB.S9S_MB_2U(SCH_1):IRQ_LVC3_WAKE_BUF_N
   2 IRQ_LVC3_WAKE_N      B @S9S_MB_2U_LIB.S9S_MB_2U(SCH_1):IRQ_LVC3_WAKE_N

Q_OSC4P_SMLF-50MHZ,OSC,BF65000A  I76  OSC1
   1 CLK_50M_EN     OE @S9S_MB_2U_LIB.S9S_MB_2U(SCH_1):CLK_50M_EN
   3 CLK_50M_RMII    OUT @S9S_MB_2U_LIB.S9S_MB_2U(SCH_1):CLK_50M_RMII
   2    GND    GND @S9S_MB_2U_LIB.S9S_MB_2U(SCH_1):GND
   4 P3V3_AUX    VDD @S9S_MB_2U_LIB.S9S_MB_2U(SCH_1):P3V3_AUX

Q_RES_0402LF-27.4,1%,1/16W,CHIA  I78  R3181
   1 CLK_50M_NCSI_OCP_2      A @S9S_MB_2U_LIB.S9S_MB_2U(SCH_1):CLK_50M_NCSI_OCP_2
   2 CLK_50M_NCSI_OCP_V3_2      B @S9S_MB_2U_LIB.S9S_MB_2U(SCH_1):CLK_50M_NCSI_OCP_V3_2

74LVC1G126SE7-74LVC1G126SE-7,SA  I79  U82
   2 IRQ_LVC3_OCP_SFF_WAKE_N      A @S9S_MB_2U_LIB.S9S_MB_2U(SCH_1):IRQ_LVC3_OCP_SFF_WAKE_N
   4 OCP_SFF_WAKE_BUFF_N      Y @S9S_MB_2U_LIB.S9S_MB_2U(SCH_1):OCP_SFF_WAKE_BUFF_N
   5 P3V3_AUX    VCC @S9S_MB_2U_LIB.S9S_MB_2U(SCH_1):P3V3_AUX
   3    GND    GND @S9S_MB_2U_LIB.S9S_MB_2U(SCH_1):GND
   1 PU_OCP_SFF_WAKE_OE     OE @S9S_MB_2U_LIB.S9S_MB_2U(SCH_1):PU_OCP_SFF_WAKE_OE

Q_CAP_0402-0.1UF,25V,10%,X7R,CA  I87  C2344
   1 P3V3_AUX      A @S9S_MB_2U_LIB.S9S_MB_2U(SCH_1):P3V3_AUX
   2    GND      B @S9S_MB_2U_LIB.S9S_MB_2U(SCH_1):GND

Q_RES_0402LF-0,5%,1/16W,CHIP,CA  I90  R4601
   1 CLK_50M_NCSI_OCP_SFF_ISO      A @S9S_MB_2U_LIB.S9S_MB_2U(SCH_1):CLK_50M_NCSI_OCP_SFF_ISO
   2 CLK_50M_NCSI_OCP_SFF_ISO_R      B @S9S_MB_2U_LIB.S9S_MB_2U(SCH_1):CLK_50M_NCSI_OCP_SFF_ISO_R

74LVC1G66GV-74LVC1G66GV,SMLF,IA  I92  U320
   1 CLK_50M_NCSI_OCP_SFF      Y @S9S_MB_2U_LIB.S9S_MB_2U(SCH_1):CLK_50M_NCSI_OCP_SFF
   2 CLK_50M_NCSI_OCP_SFF_ISO_R      Z @S9S_MB_2U_LIB.S9S_MB_2U(SCH_1):CLK_50M_NCSI_OCP_SFF_ISO_R
   3    GND    GND @S9S_MB_2U_LIB.S9S_MB_2U(SCH_1):GND
   4 FB_BMC_ISOLATE      E @S9S_MB_2U_LIB.S9S_MB_2U(SCH_1):FB_BMC_ISOLATE
   5 P3V3_AUX    VCC @S9S_MB_2U_LIB.S9S_MB_2U(SCH_1):P3V3_AUX


DRAWING: @S9S_MB_2U_LIB.S9S_MB_2U(SCH_1):PAGE154 

Q_RES_0402LF-33.2,1%,1/16W,CHIA  I130  R1130
   1 SMB_PEHPCPU0_LVC3_SCL      A @S9S_MB_2U_LIB.S9S_MB_2U(SCH_1):SMB_PEHPCPU0_LVC3_SCL
   2 SMB_PEHPCPU0_LVC3_R_SCL      B @S9S_MB_2U_LIB.S9S_MB_2U(SCH_1):SMB_PEHPCPU0_LVC3_R_SCL

Q_RES_0402LF-33.2,1%,1/16W,CHIA  I131  R1131
   1 SMB_PEHPCPU0_LVC3_SDA      A @S9S_MB_2U_LIB.S9S_MB_2U(SCH_1):SMB_PEHPCPU0_LVC3_SDA
   2 SMB_PEHPCPU0_LVC3_R_SDA      B @S9S_MB_2U_LIB.S9S_MB_2U(SCH_1):SMB_PEHPCPU0_LVC3_R_SDA

Q_RES_0402LF-33.2,1%,1/16W,CHIA  I132  R1921
   1 FM_SMB_CPU0_ALERT      A @S9S_MB_2U_LIB.S9S_MB_2U(SCH_1):FM_SMB_CPU0_ALERT
   2 FM_SMB_PEHPCPU0_PCIE_ALERT_N      B @S9S_MB_2U_LIB.S9S_MB_2U(SCH_1):FM_SMB_PEHPCPU0_PCIE_ALERT_N

Q_RES_0402LF-1K,1%,1/16W,EMPTYA  I133  R1127
   1 P3V3_AUX      A @S9S_MB_2U_LIB.S9S_MB_2U(SCH_1):P3V3_AUX
   2 PD_SMB_OCP1_HP_ADD0      B @S9S_MB_2U_LIB.S9S_MB_2U(SCH_1):PD_SMB_OCP1_HP_ADD0

Q_RES_0402LF-1K,1%,1/16W,EMPTYA  I134  R3037
   1 P3V3_AUX      A @S9S_MB_2U_LIB.S9S_MB_2U(SCH_1):P3V3_AUX
   2 PD_SMB_OCP1_HP_ADD1      B @S9S_MB_2U_LIB.S9S_MB_2U(SCH_1):PD_SMB_OCP1_HP_ADD1

Q_RES_0402LF-1K,1%,1/16W,CHIP,A  I137  R1128
   1 PD_SMB_OCP1_HP_ADD0      A @S9S_MB_2U_LIB.S9S_MB_2U(SCH_1):PD_SMB_OCP1_HP_ADD0
   2    GND      B @S9S_MB_2U_LIB.S9S_MB_2U(SCH_1):GND

Q_RES_0402LF-1K,1%,1/16W,CHIP,A  I140  R1126
   1 PD_SMB_OCP1_HP_ADD1      A @S9S_MB_2U_LIB.S9S_MB_2U(SCH_1):PD_SMB_OCP1_HP_ADD1
   2    GND      B @S9S_MB_2U_LIB.S9S_MB_2U(SCH_1):GND

Q_RES_0402LF-1K,1%,1/16W,EMPTYA  I142  R1123
   1 P3V3_AUX      A @S9S_MB_2U_LIB.S9S_MB_2U(SCH_1):P3V3_AUX
   2 PD_SMB_OCP1_HP_ADD2      B @S9S_MB_2U_LIB.S9S_MB_2U(SCH_1):PD_SMB_OCP1_HP_ADD2

Q_RES_0402LF-1K,1%,1/16W,CHIP,A  I143  R1124
   1 PD_SMB_OCP1_HP_ADD2      A @S9S_MB_2U_LIB.S9S_MB_2U(SCH_1):PD_SMB_OCP1_HP_ADD2
   2    GND      B @S9S_MB_2U_LIB.S9S_MB_2U(SCH_1):GND

Q_CAP_0402-0.1UF,25V,10%,X7R,CA  I148  C581
   1 P3V3_AUX      A @S9S_MB_2U_LIB.S9S_MB_2U(SCH_1):P3V3_AUX
   2    GND      B @S9S_MB_2U_LIB.S9S_MB_2U(SCH_1):GND

Q_CAP_0402-0.1UF,25V,10%,X7R,CA  I169  C578
   1 P3V3_AUX      A @S9S_MB_2U_LIB.S9S_MB_2U(SCH_1):P3V3_AUX
   2    GND      B @S9S_MB_2U_LIB.S9S_MB_2U(SCH_1):GND

Q_RES_0402LF-1K,1%,1/16W,CHIP,A  I172  R1129
   1 P3V3_AUX      A @S9S_MB_2U_LIB.S9S_MB_2U(SCH_1):P3V3_AUX
   2 HP_LVC3_OCP_V3_1_PRSNT2      B @S9S_MB_2U_LIB.S9S_MB_2U(SCH_1):HP_LVC3_OCP_V3_1_PRSNT2

MOSFET_N_SMLF-BSS138K,BSS138K,A  I177  U49
   G HP_LVC3_OCP_V3_1_PRSNT2_N   GATE @S9S_MB_2U_LIB.S9S_MB_2U(SCH_1):HP_LVC3_OCP_V3_1_PRSNT2_N
   D HP_LVC3_OCP_V3_1_PRSNT2  DRAIN @S9S_MB_2U_LIB.S9S_MB_2U(SCH_1):HP_LVC3_OCP_V3_1_PRSNT2
   S    GND SOURCE @S9S_MB_2U_LIB.S9S_MB_2U(SCH_1):GND

74LVC1G08W57-74LVC1G08W5-7,SMLA  I189  U210
   1 HP_LVC3_OCP_V3_1_PWRGD_R      A @S9S_MB_2U_LIB.S9S_MB_2U(SCH_1):HP_LVC3_OCP_V3_1_PWRGD_R
   2 RST_OCP_V3_1_N      B @S9S_MB_2U_LIB.S9S_MB_2U(SCH_1):RST_OCP_V3_1_N
   3    GND    GND @S9S_MB_2U_LIB.S9S_MB_2U(SCH_1):GND
   4 RST_HP_OCP_V3_1_N      Y @S9S_MB_2U_LIB.S9S_MB_2U(SCH_1):RST_HP_OCP_V3_1_N
   5 P3V3_AUX    VCC @S9S_MB_2U_LIB.S9S_MB_2U(SCH_1):P3V3_AUX

74LVC1G08W57-74LVC1G08W5-7,SMLA  I190  U208
   1 HP_OCP_V3_1_EN      A @S9S_MB_2U_LIB.S9S_MB_2U(SCH_1):HP_OCP_V3_1_EN
   2 HP_LVC3_OCP_V3_1_PRSNT2      B @S9S_MB_2U_LIB.S9S_MB_2U(SCH_1):HP_LVC3_OCP_V3_1_PRSNT2
   3    GND    GND @S9S_MB_2U_LIB.S9S_MB_2U(SCH_1):GND
   4 HP_LVC3_OCP_V3_1_EN      Y @S9S_MB_2U_LIB.S9S_MB_2U(SCH_1):HP_LVC3_OCP_V3_1_EN
   5 P3V3_AUX    VCC @S9S_MB_2U_LIB.S9S_MB_2U(SCH_1):P3V3_AUX

Q_CAP_0402-0.1UF,25V,10%,X7R,CA  I192  C579
   1 P3V3_AUX      A @S9S_MB_2U_LIB.S9S_MB_2U(SCH_1):P3V3_AUX
   2    GND      B @S9S_MB_2U_LIB.S9S_MB_2U(SCH_1):GND

PCA9555APW-PCA9555APW,SMLF,IC,A  I206  U209
  24 P3V3_AUX    VDD @S9S_MB_2U_LIB.S9S_MB_2U(SCH_1):P3V3_AUX
  12    GND    VSS @S9S_MB_2U_LIB.S9S_MB_2U(SCH_1):GND
   1 FM_SMB_CPU0_ALERT   INT# @S9S_MB_2U_LIB.S9S_MB_2U(SCH_1):FM_SMB_CPU0_ALERT
  23 SMB_PEHPCPU0_LVC3_R_SDA    SDA @S9S_MB_2U_LIB.S9S_MB_2U(SCH_1):SMB_PEHPCPU0_LVC3_R_SDA
  22 SMB_PEHPCPU0_LVC3_R_SCL    SCL @S9S_MB_2U_LIB.S9S_MB_2U(SCH_1):SMB_PEHPCPU0_LVC3_R_SCL
   4 TP_PCA9555_0_P00   P0_0 @S9S_MB_2U_LIB.S9S_MB_2U(SCH_1):TP_PCA9555_0_P00
   5 TP_PCA9555_0_P01   P0_1 @S9S_MB_2U_LIB.S9S_MB_2U(SCH_1):TP_PCA9555_0_P01
   6 HP_OCP_V3_1_EN   P0_2 @S9S_MB_2U_LIB.S9S_MB_2U(SCH_1):HP_OCP_V3_1_EN
   7 HP_LVC3_OCP_V3_1_ATTN_OUT_SW_N   P0_3 @S9S_MB_2U_LIB.S9S_MB_2U(SCH_1):HP_LVC3_OCP_V3_1_ATTN_OUT_SW_N
   8 HP_LVC3_OCP_V3_1_PRSNT2_N   P0_4 @S9S_MB_2U_LIB.S9S_MB_2U(SCH_1):HP_LVC3_OCP_V3_1_PRSNT2_N
   9 TP_PCA9555_0_P5   P0_5 @S9S_MB_2U_LIB.S9S_MB_2U(SCH_1):TP_PCA9555_0_P5
  10 TP_PCA9555_0_P6   P0_6 @S9S_MB_2U_LIB.S9S_MB_2U(SCH_1):TP_PCA9555_0_P6
  11 TP_PCA9555_0_P7   P0_7 @S9S_MB_2U_LIB.S9S_MB_2U(SCH_1):TP_PCA9555_0_P7
  13 TP_PCA9555_0_P10   P1_0 @S9S_MB_2U_LIB.S9S_MB_2U(SCH_1):TP_PCA9555_0_P10
  14 TP_PCA9555_0_P11   P1_1 @S9S_MB_2U_LIB.S9S_MB_2U(SCH_1):TP_PCA9555_0_P11
  15 TP_PCA9555_0_P12   P1_2 @S9S_MB_2U_LIB.S9S_MB_2U(SCH_1):TP_PCA9555_0_P12
  16 TP_PCA9555_0_P13   P1_3 @S9S_MB_2U_LIB.S9S_MB_2U(SCH_1):TP_PCA9555_0_P13
  17 TP_PCA9555_0_P14   P1_4 @S9S_MB_2U_LIB.S9S_MB_2U(SCH_1):TP_PCA9555_0_P14
  18 TP_PCA9555_0_P15   P1_5 @S9S_MB_2U_LIB.S9S_MB_2U(SCH_1):TP_PCA9555_0_P15
  19 TP_PCA9555_0_P16   P1_6 @S9S_MB_2U_LIB.S9S_MB_2U(SCH_1):TP_PCA9555_0_P16
  20 TP_PCA9555_0_P17   P1_7 @S9S_MB_2U_LIB.S9S_MB_2U(SCH_1):TP_PCA9555_0_P17
  21 PD_SMB_OCP1_HP_ADD0     A0 @S9S_MB_2U_LIB.S9S_MB_2U(SCH_1):PD_SMB_OCP1_HP_ADD0
   2 PD_SMB_OCP1_HP_ADD1     A1 @S9S_MB_2U_LIB.S9S_MB_2U(SCH_1):PD_SMB_OCP1_HP_ADD1
   3 PD_SMB_OCP1_HP_ADD2     A2 @S9S_MB_2U_LIB.S9S_MB_2U(SCH_1):PD_SMB_OCP1_HP_ADD2

74LVC1G08W57-74LVC1G08W5-7,SMLA  I221  U322
   1 HP_OCP_V3_1_RST_R      A @S9S_MB_2U_LIB.S9S_MB_2U(SCH_1):HP_OCP_V3_1_RST_R
   2 HP_LVC3_OCP_V3_1_P12V_PWRGD      B @S9S_MB_2U_LIB.S9S_MB_2U(SCH_1):HP_LVC3_OCP_V3_1_P12V_PWRGD
   3    GND    GND @S9S_MB_2U_LIB.S9S_MB_2U(SCH_1):GND
   4 HP_LVC3_OCP_V3_1_PWRGD      Y @S9S_MB_2U_LIB.S9S_MB_2U(SCH_1):HP_LVC3_OCP_V3_1_PWRGD
   5 P3V3_AUX    VCC @S9S_MB_2U_LIB.S9S_MB_2U(SCH_1):P3V3_AUX

Q_CAP_0402-0.1UF,25V,10%,X7R,CA  I223  C2346
   1 P3V3_AUX      A @S9S_MB_2U_LIB.S9S_MB_2U(SCH_1):P3V3_AUX
   2    GND      B @S9S_MB_2U_LIB.S9S_MB_2U(SCH_1):GND

APX80929SAG7-APX809-29SAG-7,SMA  I228  U52
   3 P3V3_OCP_SFF    VCC @S9S_MB_2U_LIB.S9S_MB_2U(SCH_1):P3V3_OCP_SFF
   2 HP_OCP_V3_1_RST RESET_L @S9S_MB_2U_LIB.S9S_MB_2U(SCH_1):HP_OCP_V3_1_RST
   1    GND    GND @S9S_MB_2U_LIB.S9S_MB_2U(SCH_1):GND

Q_CAP_0402-0.1UF,25V,10%,X7R,CA  I229  C580
   1 P3V3_OCP_SFF      A @S9S_MB_2U_LIB.S9S_MB_2U(SCH_1):P3V3_OCP_SFF
   2    GND      B @S9S_MB_2U_LIB.S9S_MB_2U(SCH_1):GND

Q_RES_0402LF-0,5%,1/16W,EMPTY,A  I232  R4613
   1 OCP_V3_1_P3V3_PWRGD      A @S9S_MB_2U_LIB.S9S_MB_2U(SCH_1):OCP_V3_1_P3V3_PWRGD
   2 HP_OCP_V3_1_RST_R      B @S9S_MB_2U_LIB.S9S_MB_2U(SCH_1):HP_OCP_V3_1_RST_R

Q_RES_0402LF-1K,1%,1/16W,EMPTYA  I235  R3160
   1 P3V3_AUX      A @S9S_MB_2U_LIB.S9S_MB_2U(SCH_1):P3V3_AUX
   2 HP_OCP_V3_1_RST_R      B @S9S_MB_2U_LIB.S9S_MB_2U(SCH_1):HP_OCP_V3_1_RST_R

Q_RES_0402LF-33.2,1%,1/16W,CHIA  I237  R4618
   1 HP_LVC3_OCP_V3_1_PWRGD      A @S9S_MB_2U_LIB.S9S_MB_2U(SCH_1):HP_LVC3_OCP_V3_1_PWRGD
   2 HP_LVC3_OCP_V3_1_PWRGD_R      B @S9S_MB_2U_LIB.S9S_MB_2U(SCH_1):HP_LVC3_OCP_V3_1_PWRGD_R

Q_RES_0402LF-33.2,1%,1/16W,CHIA  I238  R4614
   1 HP_OCP_V3_1_RST      A @S9S_MB_2U_LIB.S9S_MB_2U(SCH_1):HP_OCP_V3_1_RST
   2 HP_OCP_V3_1_RST_R      B @S9S_MB_2U_LIB.S9S_MB_2U(SCH_1):HP_OCP_V3_1_RST_R

Q_CAP_0402-0.1UF,25V,10%,X7R,CA  I241  C2376
   1 P3V3_AUX      A @S9S_MB_2U_LIB.S9S_MB_2U(SCH_1):P3V3_AUX
   2    GND      B @S9S_MB_2U_LIB.S9S_MB_2U(SCH_1):GND

74LVC1G08W57-74LVC1G08W5-7,SMLA  I243  U334
   1 HP_LVC3_OCP_V3_1_PWRGD_R2      A @S9S_MB_2U_LIB.S9S_MB_2U(SCH_1):HP_LVC3_OCP_V3_1_PWRGD_R2
   2 OCP_SFF_AUX_PWR_PLD_EN_R      B @S9S_MB_2U_LIB.S9S_MB_2U(SCH_1):OCP_SFF_AUX_PWR_PLD_EN_R
   3    GND    GND @S9S_MB_2U_LIB.S9S_MB_2U(SCH_1):GND
   4 OCP_SFF_AUX_PWR_EN_R2      Y @S9S_MB_2U_LIB.S9S_MB_2U(SCH_1):OCP_SFF_AUX_PWR_EN_R2
   5 P3V3_AUX    VCC @S9S_MB_2U_LIB.S9S_MB_2U(SCH_1):P3V3_AUX

Q_RES_0402LF-33.2,1%,1/16W,CHIA  I245  R4746
   1 HP_LVC3_OCP_V3_1_PWRGD_R      A @S9S_MB_2U_LIB.S9S_MB_2U(SCH_1):HP_LVC3_OCP_V3_1_PWRGD_R
   2 HP_LVC3_OCP_V3_1_PWRGD_R2      B @S9S_MB_2U_LIB.S9S_MB_2U(SCH_1):HP_LVC3_OCP_V3_1_PWRGD_R2

Q_RES_0402LF-49.9,1%,1/16W,CHIA  I247  R4750
   1 OCP_SFF_AUX_PWR_EN_R2      A @S9S_MB_2U_LIB.S9S_MB_2U(SCH_1):OCP_SFF_AUX_PWR_EN_R2
   2 OCP_SFF_AUX_PWR_EN      B @S9S_MB_2U_LIB.S9S_MB_2U(SCH_1):OCP_SFF_AUX_PWR_EN

Q_RES_0402LF-33.2,1%,1/16W,CHIA  I249  R4747
   1 OCP_SFF_AUX_PWR_PLD_EN      A @S9S_MB_2U_LIB.S9S_MB_2U(SCH_1):OCP_SFF_AUX_PWR_PLD_EN
   2 OCP_SFF_AUX_PWR_PLD_EN_R      B @S9S_MB_2U_LIB.S9S_MB_2U(SCH_1):OCP_SFF_AUX_PWR_PLD_EN_R

Q_RES_0402LF-0,5%,1/16W,EMPTY,A  I253  R4748
   1 HP_LVC3_OCP_V3_1_PWRGD_R2      A @S9S_MB_2U_LIB.S9S_MB_2U(SCH_1):HP_LVC3_OCP_V3_1_PWRGD_R2
   2 OCP_SFF_AUX_PWR_EN_R2      B @S9S_MB_2U_LIB.S9S_MB_2U(SCH_1):OCP_SFF_AUX_PWR_EN_R2

Q_RES_0402LF-0,5%,1/16W,EMPTY,A  I254  R4749
   1 OCP_SFF_AUX_PWR_PLD_EN_R      A @S9S_MB_2U_LIB.S9S_MB_2U(SCH_1):OCP_SFF_AUX_PWR_PLD_EN_R
   2 OCP_SFF_AUX_PWR_EN_R2      B @S9S_MB_2U_LIB.S9S_MB_2U(SCH_1):OCP_SFF_AUX_PWR_EN_R2

Q_RES_0402LF-10K,1%,1/16W,CHIPA  I256  R4745
   1 P3V3_AUX      A @S9S_MB_2U_LIB.S9S_MB_2U(SCH_1):P3V3_AUX
   2 OCP_SFF_AUX_PWR_PLD_EN_R      B @S9S_MB_2U_LIB.S9S_MB_2U(SCH_1):OCP_SFF_AUX_PWR_PLD_EN_R

Q_RES_0402LF-10K,1%,1/16W,CHIPA  I257  R4764
   1 P3V3_AUX      A @S9S_MB_2U_LIB.S9S_MB_2U(SCH_1):P3V3_AUX
   2 HP_OCP_V3_1_EN      B @S9S_MB_2U_LIB.S9S_MB_2U(SCH_1):HP_OCP_V3_1_EN


DRAWING: @S9S_MB_2U_LIB.S9S_MB_2U(SCH_1):PAGE164 

Q_CAP_DIFFBUS_C0201-DIFF BUS_0A  I21  C932
   1 P5E_CPU0_PE0_TX_C_DN<0>      1 @S9S_MB_2U_LIB.S9S_MB_2U(SCH_1):P5E_CPU0_PE0_TX_C_DN(0)
   2 P5E_CPU0_PE0_TX_DN<0>      2 @S9S_MB_2U_LIB.S9S_MB_2U(SCH_1):P5E_CPU0_PE0_TX_DN(0)

Q_CAP_DIFFBUS_C0201-DIFF BUS_0A  I22  C933
   1 P5E_CPU0_PE0_TX_C_DP<0>      1 @S9S_MB_2U_LIB.S9S_MB_2U(SCH_1):P5E_CPU0_PE0_TX_C_DP(0)
   2 P5E_CPU0_PE0_TX_DP<0>      2 @S9S_MB_2U_LIB.S9S_MB_2U(SCH_1):P5E_CPU0_PE0_TX_DP(0)

Q_CAP_DIFFBUS_C0201-DIFF BUS_0A  I23  C931
   1 P5E_CPU0_PE0_TX_C_DP<1>      1 @S9S_MB_2U_LIB.S9S_MB_2U(SCH_1):P5E_CPU0_PE0_TX_C_DP(1)
   2 P5E_CPU0_PE0_TX_DP<1>      2 @S9S_MB_2U_LIB.S9S_MB_2U(SCH_1):P5E_CPU0_PE0_TX_DP(1)

Q_CAP_DIFFBUS_C0201-DIFF BUS_0A  I24  C930
   1 P5E_CPU0_PE0_TX_C_DN<1>      1 @S9S_MB_2U_LIB.S9S_MB_2U(SCH_1):P5E_CPU0_PE0_TX_C_DN(1)
   2 P5E_CPU0_PE0_TX_DN<1>      2 @S9S_MB_2U_LIB.S9S_MB_2U(SCH_1):P5E_CPU0_PE0_TX_DN(1)

Q_CAP_DIFFBUS_C0201-DIFF BUS_0A  I25  C928
   1 P5E_CPU0_PE0_TX_C_DN<2>      1 @S9S_MB_2U_LIB.S9S_MB_2U(SCH_1):P5E_CPU0_PE0_TX_C_DN(2)
   2 P5E_CPU0_PE0_TX_DN<2>      2 @S9S_MB_2U_LIB.S9S_MB_2U(SCH_1):P5E_CPU0_PE0_TX_DN(2)

Q_CAP_DIFFBUS_C0201-DIFF BUS_0A  I53  C916
   1 P5E_CPU0_PE0_TX_C_DN<8>      1 @S9S_MB_2U_LIB.S9S_MB_2U(SCH_1):P5E_CPU0_PE0_TX_C_DN(8)
   2 P5E_CPU0_PE0_TX_DN<8>      2 @S9S_MB_2U_LIB.S9S_MB_2U(SCH_1):P5E_CPU0_PE0_TX_DN(8)

Q_CAP_DIFFBUS_C0201-DIFF BUS_0A  I54  C917
   1 P5E_CPU0_PE0_TX_C_DP<8>      1 @S9S_MB_2U_LIB.S9S_MB_2U(SCH_1):P5E_CPU0_PE0_TX_C_DP(8)
   2 P5E_CPU0_PE0_TX_DP<8>      2 @S9S_MB_2U_LIB.S9S_MB_2U(SCH_1):P5E_CPU0_PE0_TX_DP(8)

Q_CAP_DIFFBUS_C0201-DIFF BUS_0A  I55  C915
   1 P5E_CPU0_PE0_TX_C_DP<9>      1 @S9S_MB_2U_LIB.S9S_MB_2U(SCH_1):P5E_CPU0_PE0_TX_C_DP(9)
   2 P5E_CPU0_PE0_TX_DP<9>      2 @S9S_MB_2U_LIB.S9S_MB_2U(SCH_1):P5E_CPU0_PE0_TX_DP(9)

Q_CAP_DIFFBUS_C0201-DIFF BUS_0A  I56  C914
   1 P5E_CPU0_PE0_TX_C_DN<9>      1 @S9S_MB_2U_LIB.S9S_MB_2U(SCH_1):P5E_CPU0_PE0_TX_C_DN(9)
   2 P5E_CPU0_PE0_TX_DN<9>      2 @S9S_MB_2U_LIB.S9S_MB_2U(SCH_1):P5E_CPU0_PE0_TX_DN(9)

Q_CAP_DIFFBUS_C0201-DIFF BUS_0A  I57  C913
   1 P5E_CPU0_PE0_TX_C_DP<10>      1 @S9S_MB_2U_LIB.S9S_MB_2U(SCH_1):P5E_CPU0_PE0_TX_C_DP(10)
   2 P5E_CPU0_PE0_TX_DP<10>      2 @S9S_MB_2U_LIB.S9S_MB_2U(SCH_1):P5E_CPU0_PE0_TX_DP(10)

Q_CAP_DIFFBUS_C0201-DIFF BUS_0A  I58  C912
   1 P5E_CPU0_PE0_TX_C_DN<10>      1 @S9S_MB_2U_LIB.S9S_MB_2U(SCH_1):P5E_CPU0_PE0_TX_C_DN(10)
   2 P5E_CPU0_PE0_TX_DN<10>      2 @S9S_MB_2U_LIB.S9S_MB_2U(SCH_1):P5E_CPU0_PE0_TX_DN(10)

Q_CAP_DIFFBUS_C0201-DIFF BUS_0A  I59  C911
   1 P5E_CPU0_PE0_TX_C_DP<11>      1 @S9S_MB_2U_LIB.S9S_MB_2U(SCH_1):P5E_CPU0_PE0_TX_C_DP(11)
   2 P5E_CPU0_PE0_TX_DP<11>      2 @S9S_MB_2U_LIB.S9S_MB_2U(SCH_1):P5E_CPU0_PE0_TX_DP(11)

Q_CAP_DIFFBUS_C0201-DIFF BUS_0A  I61  C909
   1 P5E_CPU0_PE0_TX_C_DP<12>      1 @S9S_MB_2U_LIB.S9S_MB_2U(SCH_1):P5E_CPU0_PE0_TX_C_DP(12)
   2 P5E_CPU0_PE0_TX_DP<12>      2 @S9S_MB_2U_LIB.S9S_MB_2U(SCH_1):P5E_CPU0_PE0_TX_DP(12)

Q_CAP_DIFFBUS_C0201-DIFF BUS_0A  I62  C908
   1 P5E_CPU0_PE0_TX_C_DN<12>      1 @S9S_MB_2U_LIB.S9S_MB_2U(SCH_1):P5E_CPU0_PE0_TX_C_DN(12)
   2 P5E_CPU0_PE0_TX_DN<12>      2 @S9S_MB_2U_LIB.S9S_MB_2U(SCH_1):P5E_CPU0_PE0_TX_DN(12)

Q_CAP_DIFFBUS_C0201-DIFF BUS_0A  I63  C906
   1 P5E_CPU0_PE0_TX_C_DN<13>      1 @S9S_MB_2U_LIB.S9S_MB_2U(SCH_1):P5E_CPU0_PE0_TX_C_DN(13)
   2 P5E_CPU0_PE0_TX_DN<13>      2 @S9S_MB_2U_LIB.S9S_MB_2U(SCH_1):P5E_CPU0_PE0_TX_DN(13)

Q_CAP_DIFFBUS_C0201-DIFF BUS_0A  I64  C907
   1 P5E_CPU0_PE0_TX_C_DP<13>      1 @S9S_MB_2U_LIB.S9S_MB_2U(SCH_1):P5E_CPU0_PE0_TX_C_DP(13)
   2 P5E_CPU0_PE0_TX_DP<13>      2 @S9S_MB_2U_LIB.S9S_MB_2U(SCH_1):P5E_CPU0_PE0_TX_DP(13)

Q_CAP_DIFFBUS_C0201-DIFF BUS_0A  I65  C905
   1 P5E_CPU0_PE0_TX_C_DP<14>      1 @S9S_MB_2U_LIB.S9S_MB_2U(SCH_1):P5E_CPU0_PE0_TX_C_DP(14)
   2 P5E_CPU0_PE0_TX_DP<14>      2 @S9S_MB_2U_LIB.S9S_MB_2U(SCH_1):P5E_CPU0_PE0_TX_DP(14)

Q_CAP_DIFFBUS_C0201-DIFF BUS_0A  I66  C904
   1 P5E_CPU0_PE0_TX_C_DN<14>      1 @S9S_MB_2U_LIB.S9S_MB_2U(SCH_1):P5E_CPU0_PE0_TX_C_DN(14)
   2 P5E_CPU0_PE0_TX_DN<14>      2 @S9S_MB_2U_LIB.S9S_MB_2U(SCH_1):P5E_CPU0_PE0_TX_DN(14)

Q_CAP_DIFFBUS_C0201-DIFF BUS_0A  I67  C903
   1 P5E_CPU0_PE0_TX_C_DP<15>      1 @S9S_MB_2U_LIB.S9S_MB_2U(SCH_1):P5E_CPU0_PE0_TX_C_DP(15)
   2 P5E_CPU0_PE0_TX_DP<15>      2 @S9S_MB_2U_LIB.S9S_MB_2U(SCH_1):P5E_CPU0_PE0_TX_DP(15)

Q_CAP_DIFFBUS_C0201-DIFF BUS_0A  I68  C902
   1 P5E_CPU0_PE0_TX_C_DN<15>      1 @S9S_MB_2U_LIB.S9S_MB_2U(SCH_1):P5E_CPU0_PE0_TX_C_DN(15)
   2 P5E_CPU0_PE0_TX_DN<15>      2 @S9S_MB_2U_LIB.S9S_MB_2U(SCH_1):P5E_CPU0_PE0_TX_DN(15)

Q_CAP_DIFFBUS_C0201-DIFF BUS_0A  I121  C965
   1 P5E_CPU0_PE2_TX_C_DP<0>      1 @S9S_MB_2U_LIB.S9S_MB_2U(SCH_1):P5E_CPU0_PE2_TX_C_DP(0)
   2 P5E_CPU0_PE2_TX_DP<0>      2 @S9S_MB_2U_LIB.S9S_MB_2U(SCH_1):P5E_CPU0_PE2_TX_DP(0)

Q_CAP_DIFFBUS_C0201-DIFF BUS_0A  I122  C964
   1 P5E_CPU0_PE2_TX_C_DN<0>      1 @S9S_MB_2U_LIB.S9S_MB_2U(SCH_1):P5E_CPU0_PE2_TX_C_DN(0)
   2 P5E_CPU0_PE2_TX_DN<0>      2 @S9S_MB_2U_LIB.S9S_MB_2U(SCH_1):P5E_CPU0_PE2_TX_DN(0)

Q_CAP_DIFFBUS_C0201-DIFF BUS_0A  I123  C963
   1 P5E_CPU0_PE2_TX_C_DP<1>      1 @S9S_MB_2U_LIB.S9S_MB_2U(SCH_1):P5E_CPU0_PE2_TX_C_DP(1)
   2 P5E_CPU0_PE2_TX_DP<1>      2 @S9S_MB_2U_LIB.S9S_MB_2U(SCH_1):P5E_CPU0_PE2_TX_DP(1)

Q_CAP_DIFFBUS_C0201-DIFF BUS_0A  I124  C962
   1 P5E_CPU0_PE2_TX_C_DN<1>      1 @S9S_MB_2U_LIB.S9S_MB_2U(SCH_1):P5E_CPU0_PE2_TX_C_DN(1)
   2 P5E_CPU0_PE2_TX_DN<1>      2 @S9S_MB_2U_LIB.S9S_MB_2U(SCH_1):P5E_CPU0_PE2_TX_DN(1)

Q_CAP_DIFFBUS_C0201-DIFF BUS_0A  I125  C961
   1 P5E_CPU0_PE2_TX_C_DP<2>      1 @S9S_MB_2U_LIB.S9S_MB_2U(SCH_1):P5E_CPU0_PE2_TX_C_DP(2)
   2 P5E_CPU0_PE2_TX_DP<2>      2 @S9S_MB_2U_LIB.S9S_MB_2U(SCH_1):P5E_CPU0_PE2_TX_DP(2)

Q_CAP_DIFFBUS_C0201-DIFF BUS_0A  I164  C939
   1 P5E_CPU0_PE2_TX_C_DP<13>      1 @S9S_MB_2U_LIB.S9S_MB_2U(SCH_1):P5E_CPU0_PE2_TX_C_DP(13)
   2 P5E_CPU0_PE2_TX_DP<13>      2 @S9S_MB_2U_LIB.S9S_MB_2U(SCH_1):P5E_CPU0_PE2_TX_DP(13)

Q_CAP_DIFFBUS_C0201-DIFF BUS_0A  I165  C938
   1 P5E_CPU0_PE2_TX_C_DN<13>      1 @S9S_MB_2U_LIB.S9S_MB_2U(SCH_1):P5E_CPU0_PE2_TX_C_DN(13)
   2 P5E_CPU0_PE2_TX_DN<13>      2 @S9S_MB_2U_LIB.S9S_MB_2U(SCH_1):P5E_CPU0_PE2_TX_DN(13)

Q_CAP_DIFFBUS_C0201-DIFF BUS_0A  I166  C937
   1 P5E_CPU0_PE2_TX_C_DP<14>      1 @S9S_MB_2U_LIB.S9S_MB_2U(SCH_1):P5E_CPU0_PE2_TX_C_DP(14)
   2 P5E_CPU0_PE2_TX_DP<14>      2 @S9S_MB_2U_LIB.S9S_MB_2U(SCH_1):P5E_CPU0_PE2_TX_DP(14)

Q_CAP_DIFFBUS_C0201-DIFF BUS_0A  I167  C936
   1 P5E_CPU0_PE2_TX_C_DN<14>      1 @S9S_MB_2U_LIB.S9S_MB_2U(SCH_1):P5E_CPU0_PE2_TX_C_DN(14)
   2 P5E_CPU0_PE2_TX_DN<14>      2 @S9S_MB_2U_LIB.S9S_MB_2U(SCH_1):P5E_CPU0_PE2_TX_DN(14)

Q_CAP_DIFFBUS_C0201-DIFF BUS_0A  I168  C935
   1 P5E_CPU0_PE2_TX_C_DP<15>      1 @S9S_MB_2U_LIB.S9S_MB_2U(SCH_1):P5E_CPU0_PE2_TX_C_DP(15)
   2 P5E_CPU0_PE2_TX_DP<15>      2 @S9S_MB_2U_LIB.S9S_MB_2U(SCH_1):P5E_CPU0_PE2_TX_DP(15)

Q_CAP_DIFFBUS_C0201-DIFF BUS_0A  I26  C929
   1 P5E_CPU0_PE0_TX_C_DP<2>      1 @S9S_MB_2U_LIB.S9S_MB_2U(SCH_1):P5E_CPU0_PE0_TX_C_DP(2)
   2 P5E_CPU0_PE0_TX_DP<2>      2 @S9S_MB_2U_LIB.S9S_MB_2U(SCH_1):P5E_CPU0_PE0_TX_DP(2)

Q_CAP_DIFFBUS_C0201-DIFF BUS_0A  I27  C927
   1 P5E_CPU0_PE0_TX_C_DP<3>      1 @S9S_MB_2U_LIB.S9S_MB_2U(SCH_1):P5E_CPU0_PE0_TX_C_DP(3)
   2 P5E_CPU0_PE0_TX_DP<3>      2 @S9S_MB_2U_LIB.S9S_MB_2U(SCH_1):P5E_CPU0_PE0_TX_DP(3)

Q_CAP_DIFFBUS_C0201-DIFF BUS_0A  I28  C926
   1 P5E_CPU0_PE0_TX_C_DN<3>      1 @S9S_MB_2U_LIB.S9S_MB_2U(SCH_1):P5E_CPU0_PE0_TX_C_DN(3)
   2 P5E_CPU0_PE0_TX_DN<3>      2 @S9S_MB_2U_LIB.S9S_MB_2U(SCH_1):P5E_CPU0_PE0_TX_DN(3)

Q_CAP_DIFFBUS_C0201-DIFF BUS_0A  I29  C925
   1 P5E_CPU0_PE0_TX_C_DP<4>      1 @S9S_MB_2U_LIB.S9S_MB_2U(SCH_1):P5E_CPU0_PE0_TX_C_DP(4)
   2 P5E_CPU0_PE0_TX_DP<4>      2 @S9S_MB_2U_LIB.S9S_MB_2U(SCH_1):P5E_CPU0_PE0_TX_DP(4)

Q_CAP_DIFFBUS_C0201-DIFF BUS_0A  I30  C924
   1 P5E_CPU0_PE0_TX_C_DN<4>      1 @S9S_MB_2U_LIB.S9S_MB_2U(SCH_1):P5E_CPU0_PE0_TX_C_DN(4)
   2 P5E_CPU0_PE0_TX_DN<4>      2 @S9S_MB_2U_LIB.S9S_MB_2U(SCH_1):P5E_CPU0_PE0_TX_DN(4)

Q_CAP_DIFFBUS_C0201-DIFF BUS_0A  I31  C923
   1 P5E_CPU0_PE0_TX_C_DP<5>      1 @S9S_MB_2U_LIB.S9S_MB_2U(SCH_1):P5E_CPU0_PE0_TX_C_DP(5)
   2 P5E_CPU0_PE0_TX_DP<5>      2 @S9S_MB_2U_LIB.S9S_MB_2U(SCH_1):P5E_CPU0_PE0_TX_DP(5)

Q_CAP_DIFFBUS_C0201-DIFF BUS_0A  I32  C922
   1 P5E_CPU0_PE0_TX_C_DN<5>      1 @S9S_MB_2U_LIB.S9S_MB_2U(SCH_1):P5E_CPU0_PE0_TX_C_DN(5)
   2 P5E_CPU0_PE0_TX_DN<5>      2 @S9S_MB_2U_LIB.S9S_MB_2U(SCH_1):P5E_CPU0_PE0_TX_DN(5)

Q_CAP_DIFFBUS_C0201-DIFF BUS_0A  I33  C921
   1 P5E_CPU0_PE0_TX_C_DP<6>      1 @S9S_MB_2U_LIB.S9S_MB_2U(SCH_1):P5E_CPU0_PE0_TX_C_DP(6)
   2 P5E_CPU0_PE0_TX_DP<6>      2 @S9S_MB_2U_LIB.S9S_MB_2U(SCH_1):P5E_CPU0_PE0_TX_DP(6)

Q_CAP_DIFFBUS_C0201-DIFF BUS_0A  I34  C920
   1 P5E_CPU0_PE0_TX_C_DN<6>      1 @S9S_MB_2U_LIB.S9S_MB_2U(SCH_1):P5E_CPU0_PE0_TX_C_DN(6)
   2 P5E_CPU0_PE0_TX_DN<6>      2 @S9S_MB_2U_LIB.S9S_MB_2U(SCH_1):P5E_CPU0_PE0_TX_DN(6)

Q_CAP_DIFFBUS_C0201-DIFF BUS_0A  I35  C918
   1 P5E_CPU0_PE0_TX_C_DN<7>      1 @S9S_MB_2U_LIB.S9S_MB_2U(SCH_1):P5E_CPU0_PE0_TX_C_DN(7)
   2 P5E_CPU0_PE0_TX_DN<7>      2 @S9S_MB_2U_LIB.S9S_MB_2U(SCH_1):P5E_CPU0_PE0_TX_DN(7)

Q_CAP_DIFFBUS_C0201-DIFF BUS_0A  I36  C919
   1 P5E_CPU0_PE0_TX_C_DP<7>      1 @S9S_MB_2U_LIB.S9S_MB_2U(SCH_1):P5E_CPU0_PE0_TX_C_DP(7)
   2 P5E_CPU0_PE0_TX_DP<7>      2 @S9S_MB_2U_LIB.S9S_MB_2U(SCH_1):P5E_CPU0_PE0_TX_DP(7)

Q_CAP_DIFFBUS_C0201-DIFF BUS_0A  I60  C910
   1 P5E_CPU0_PE0_TX_C_DN<11>      1 @S9S_MB_2U_LIB.S9S_MB_2U(SCH_1):P5E_CPU0_PE0_TX_C_DN(11)
   2 P5E_CPU0_PE0_TX_DN<11>      2 @S9S_MB_2U_LIB.S9S_MB_2U(SCH_1):P5E_CPU0_PE0_TX_DN(11)

Q_CAP_DIFFBUS_C0201-DIFF BUS_0A  I126  C960
   1 P5E_CPU0_PE2_TX_C_DN<2>      1 @S9S_MB_2U_LIB.S9S_MB_2U(SCH_1):P5E_CPU0_PE2_TX_C_DN(2)
   2 P5E_CPU0_PE2_TX_DN<2>      2 @S9S_MB_2U_LIB.S9S_MB_2U(SCH_1):P5E_CPU0_PE2_TX_DN(2)

Q_CAP_DIFFBUS_C0201-DIFF BUS_0A  I127  C959
   1 P5E_CPU0_PE2_TX_C_DP<3>      1 @S9S_MB_2U_LIB.S9S_MB_2U(SCH_1):P5E_CPU0_PE2_TX_C_DP(3)
   2 P5E_CPU0_PE2_TX_DP<3>      2 @S9S_MB_2U_LIB.S9S_MB_2U(SCH_1):P5E_CPU0_PE2_TX_DP(3)

Q_CAP_DIFFBUS_C0201-DIFF BUS_0A  I128  C958
   1 P5E_CPU0_PE2_TX_C_DN<3>      1 @S9S_MB_2U_LIB.S9S_MB_2U(SCH_1):P5E_CPU0_PE2_TX_C_DN(3)
   2 P5E_CPU0_PE2_TX_DN<3>      2 @S9S_MB_2U_LIB.S9S_MB_2U(SCH_1):P5E_CPU0_PE2_TX_DN(3)

Q_CAP_DIFFBUS_C0201-DIFF BUS_0A  I133  C954
   1 P5E_CPU0_PE2_TX_C_DN<5>      1 @S9S_MB_2U_LIB.S9S_MB_2U(SCH_1):P5E_CPU0_PE2_TX_C_DN(5)
   2 P5E_CPU0_PE2_TX_DN<5>      2 @S9S_MB_2U_LIB.S9S_MB_2U(SCH_1):P5E_CPU0_PE2_TX_DN(5)

Q_CAP_DIFFBUS_C0201-DIFF BUS_0A  I134  C953
   1 P5E_CPU0_PE2_TX_C_DP<6>      1 @S9S_MB_2U_LIB.S9S_MB_2U(SCH_1):P5E_CPU0_PE2_TX_C_DP(6)
   2 P5E_CPU0_PE2_TX_DP<6>      2 @S9S_MB_2U_LIB.S9S_MB_2U(SCH_1):P5E_CPU0_PE2_TX_DP(6)

Q_CAP_DIFFBUS_C0201-DIFF BUS_0A  I135  C952
   1 P5E_CPU0_PE2_TX_C_DN<6>      1 @S9S_MB_2U_LIB.S9S_MB_2U(SCH_1):P5E_CPU0_PE2_TX_C_DN(6)
   2 P5E_CPU0_PE2_TX_DN<6>      2 @S9S_MB_2U_LIB.S9S_MB_2U(SCH_1):P5E_CPU0_PE2_TX_DN(6)

Q_CAP_DIFFBUS_C0201-DIFF BUS_0A  I136  C951
   1 P5E_CPU0_PE2_TX_C_DP<7>      1 @S9S_MB_2U_LIB.S9S_MB_2U(SCH_1):P5E_CPU0_PE2_TX_C_DP(7)
   2 P5E_CPU0_PE2_TX_DP<7>      2 @S9S_MB_2U_LIB.S9S_MB_2U(SCH_1):P5E_CPU0_PE2_TX_DP(7)

Q_CAP_DIFFBUS_C0201-DIFF BUS_0A  I137  C950
   1 P5E_CPU0_PE2_TX_C_DN<7>      1 @S9S_MB_2U_LIB.S9S_MB_2U(SCH_1):P5E_CPU0_PE2_TX_C_DN(7)
   2 P5E_CPU0_PE2_TX_DN<7>      2 @S9S_MB_2U_LIB.S9S_MB_2U(SCH_1):P5E_CPU0_PE2_TX_DN(7)

Q_CAP_DIFFBUS_C0201-DIFF BUS_0A  I151  C949
   1 P5E_CPU0_PE2_TX_C_DP<8>      1 @S9S_MB_2U_LIB.S9S_MB_2U(SCH_1):P5E_CPU0_PE2_TX_C_DP(8)
   2 P5E_CPU0_PE2_TX_DP<8>      2 @S9S_MB_2U_LIB.S9S_MB_2U(SCH_1):P5E_CPU0_PE2_TX_DP(8)

Q_CAP_DIFFBUS_C0201-DIFF BUS_0A  I152  C948
   1 P5E_CPU0_PE2_TX_C_DN<8>      1 @S9S_MB_2U_LIB.S9S_MB_2U(SCH_1):P5E_CPU0_PE2_TX_C_DN(8)
   2 P5E_CPU0_PE2_TX_DN<8>      2 @S9S_MB_2U_LIB.S9S_MB_2U(SCH_1):P5E_CPU0_PE2_TX_DN(8)

Q_CAP_DIFFBUS_C0201-DIFF BUS_0A  I153  C947
   1 P5E_CPU0_PE2_TX_C_DP<9>      1 @S9S_MB_2U_LIB.S9S_MB_2U(SCH_1):P5E_CPU0_PE2_TX_C_DP(9)
   2 P5E_CPU0_PE2_TX_DP<9>      2 @S9S_MB_2U_LIB.S9S_MB_2U(SCH_1):P5E_CPU0_PE2_TX_DP(9)

Q_CAP_DIFFBUS_C0201-DIFF BUS_0A  I154  C946
   1 P5E_CPU0_PE2_TX_C_DN<9>      1 @S9S_MB_2U_LIB.S9S_MB_2U(SCH_1):P5E_CPU0_PE2_TX_C_DN(9)
   2 P5E_CPU0_PE2_TX_DN<9>      2 @S9S_MB_2U_LIB.S9S_MB_2U(SCH_1):P5E_CPU0_PE2_TX_DN(9)

Q_CAP_DIFFBUS_C0201-DIFF BUS_0A  I155  C945
   1 P5E_CPU0_PE2_TX_C_DP<10>      1 @S9S_MB_2U_LIB.S9S_MB_2U(SCH_1):P5E_CPU0_PE2_TX_C_DP(10)
   2 P5E_CPU0_PE2_TX_DP<10>      2 @S9S_MB_2U_LIB.S9S_MB_2U(SCH_1):P5E_CPU0_PE2_TX_DP(10)

Q_CAP_DIFFBUS_C0201-DIFF BUS_0A  I156  C944
   1 P5E_CPU0_PE2_TX_C_DN<10>      1 @S9S_MB_2U_LIB.S9S_MB_2U(SCH_1):P5E_CPU0_PE2_TX_C_DN(10)
   2 P5E_CPU0_PE2_TX_DN<10>      2 @S9S_MB_2U_LIB.S9S_MB_2U(SCH_1):P5E_CPU0_PE2_TX_DN(10)

Q_CAP_DIFFBUS_C0201-DIFF BUS_0A  I157  C943
   1 P5E_CPU0_PE2_TX_C_DP<11>      1 @S9S_MB_2U_LIB.S9S_MB_2U(SCH_1):P5E_CPU0_PE2_TX_C_DP(11)
   2 P5E_CPU0_PE2_TX_DP<11>      2 @S9S_MB_2U_LIB.S9S_MB_2U(SCH_1):P5E_CPU0_PE2_TX_DP(11)

Q_CAP_DIFFBUS_C0201-DIFF BUS_0A  I158  C942
   1 P5E_CPU0_PE2_TX_C_DN<11>      1 @S9S_MB_2U_LIB.S9S_MB_2U(SCH_1):P5E_CPU0_PE2_TX_C_DN(11)
   2 P5E_CPU0_PE2_TX_DN<11>      2 @S9S_MB_2U_LIB.S9S_MB_2U(SCH_1):P5E_CPU0_PE2_TX_DN(11)

Q_CAP_DIFFBUS_C0201-DIFF BUS_0A  I159  C941
   1 P5E_CPU0_PE2_TX_C_DP<12>      1 @S9S_MB_2U_LIB.S9S_MB_2U(SCH_1):P5E_CPU0_PE2_TX_C_DP(12)
   2 P5E_CPU0_PE2_TX_DP<12>      2 @S9S_MB_2U_LIB.S9S_MB_2U(SCH_1):P5E_CPU0_PE2_TX_DP(12)

Q_CAP_DIFFBUS_C0201-DIFF BUS_0A  I160  C940
   1 P5E_CPU0_PE2_TX_C_DN<12>      1 @S9S_MB_2U_LIB.S9S_MB_2U(SCH_1):P5E_CPU0_PE2_TX_C_DN(12)
   2 P5E_CPU0_PE2_TX_DN<12>      2 @S9S_MB_2U_LIB.S9S_MB_2U(SCH_1):P5E_CPU0_PE2_TX_DN(12)

Q_CAP_DIFFBUS_C0201-DIFF BUS_0A  I169  C934
   1 P5E_CPU0_PE2_TX_C_DN<15>      1 @S9S_MB_2U_LIB.S9S_MB_2U(SCH_1):P5E_CPU0_PE2_TX_C_DN(15)
   2 P5E_CPU0_PE2_TX_DN<15>      2 @S9S_MB_2U_LIB.S9S_MB_2U(SCH_1):P5E_CPU0_PE2_TX_DN(15)

Q_CAP_DIFFBUS_C0201-DIFF BUS_0A  I206  C957
   1 P5E_CPU0_PE2_TX_C_DP<4>      1 @S9S_MB_2U_LIB.S9S_MB_2U(SCH_1):P5E_CPU0_PE2_TX_C_DP(4)
   2 P5E_CPU0_PE2_TX_DP<4>      2 @S9S_MB_2U_LIB.S9S_MB_2U(SCH_1):P5E_CPU0_PE2_TX_DP(4)

Q_CAP_DIFFBUS_C0201-DIFF BUS_0A  I207  C956
   1 P5E_CPU0_PE2_TX_C_DN<4>      1 @S9S_MB_2U_LIB.S9S_MB_2U(SCH_1):P5E_CPU0_PE2_TX_C_DN(4)
   2 P5E_CPU0_PE2_TX_DN<4>      2 @S9S_MB_2U_LIB.S9S_MB_2U(SCH_1):P5E_CPU0_PE2_TX_DN(4)

Q_CAP_DIFFBUS_C0201-DIFF BUS_0A  I208  C955
   1 P5E_CPU0_PE2_TX_C_DP<5>      1 @S9S_MB_2U_LIB.S9S_MB_2U(SCH_1):P5E_CPU0_PE2_TX_C_DP(5)
   2 P5E_CPU0_PE2_TX_DP<5>      2 @S9S_MB_2U_LIB.S9S_MB_2U(SCH_1):P5E_CPU0_PE2_TX_DP(5)


DRAWING: @S9S_MB_2U_LIB.S9S_MB_2U(SCH_1):PAGE165 

Q_CAP_DIFFBUS_C0201-DIFF BUS_0A  I120  C901
   1 P5E_CPU0_PE3_TX_C_DP<0>      1 @S9S_MB_2U_LIB.S9S_MB_2U(SCH_1):P5E_CPU0_PE3_TX_C_DP(0)
   2 P5E_CPU0_PE3_TX_DP<0>      2 @S9S_MB_2U_LIB.S9S_MB_2U(SCH_1):P5E_CPU0_PE3_TX_DP(0)

Q_CAP_DIFFBUS_C0201-DIFF BUS_0A  I121  C900
   1 P5E_CPU0_PE3_TX_C_DN<0>      1 @S9S_MB_2U_LIB.S9S_MB_2U(SCH_1):P5E_CPU0_PE3_TX_C_DN(0)
   2 P5E_CPU0_PE3_TX_DN<0>      2 @S9S_MB_2U_LIB.S9S_MB_2U(SCH_1):P5E_CPU0_PE3_TX_DN(0)

Q_CAP_DIFFBUS_C0201-DIFF BUS_0A  I122  C899
   1 P5E_CPU0_PE3_TX_C_DP<1>      1 @S9S_MB_2U_LIB.S9S_MB_2U(SCH_1):P5E_CPU0_PE3_TX_C_DP(1)
   2 P5E_CPU0_PE3_TX_DP<1>      2 @S9S_MB_2U_LIB.S9S_MB_2U(SCH_1):P5E_CPU0_PE3_TX_DP(1)

Q_CAP_DIFFBUS_C0201-DIFF BUS_0A  I123  C897
   1 P5E_CPU0_PE3_TX_C_DP<2>      1 @S9S_MB_2U_LIB.S9S_MB_2U(SCH_1):P5E_CPU0_PE3_TX_C_DP(2)
   2 P5E_CPU0_PE3_TX_DP<2>      2 @S9S_MB_2U_LIB.S9S_MB_2U(SCH_1):P5E_CPU0_PE3_TX_DP(2)

Q_CAP_DIFFBUS_C0201-DIFF BUS_0A  I124  C896
   1 P5E_CPU0_PE3_TX_C_DN<2>      1 @S9S_MB_2U_LIB.S9S_MB_2U(SCH_1):P5E_CPU0_PE3_TX_C_DN(2)
   2 P5E_CPU0_PE3_TX_DN<2>      2 @S9S_MB_2U_LIB.S9S_MB_2U(SCH_1):P5E_CPU0_PE3_TX_DN(2)

Q_CAP_DIFFBUS_C0201-DIFF BUS_0A  I125  C895
   1 P5E_CPU0_PE3_TX_C_DP<3>      1 @S9S_MB_2U_LIB.S9S_MB_2U(SCH_1):P5E_CPU0_PE3_TX_C_DP(3)
   2 P5E_CPU0_PE3_TX_DP<3>      2 @S9S_MB_2U_LIB.S9S_MB_2U(SCH_1):P5E_CPU0_PE3_TX_DP(3)

Q_CAP_DIFFBUS_C0201-DIFF BUS_0A  I126  C894
   1 P5E_CPU0_PE3_TX_C_DN<3>      1 @S9S_MB_2U_LIB.S9S_MB_2U(SCH_1):P5E_CPU0_PE3_TX_C_DN(3)
   2 P5E_CPU0_PE3_TX_DN<3>      2 @S9S_MB_2U_LIB.S9S_MB_2U(SCH_1):P5E_CPU0_PE3_TX_DN(3)

Q_CAP_DIFFBUS_C0201-DIFF BUS_0A  I127  C892
   1 P5E_CPU0_PE3_TX_C_DN<4>      1 @S9S_MB_2U_LIB.S9S_MB_2U(SCH_1):P5E_CPU0_PE3_TX_C_DN(4)
   2 P5E_CPU0_PE3_TX_DN<4>      2 @S9S_MB_2U_LIB.S9S_MB_2U(SCH_1):P5E_CPU0_PE3_TX_DN(4)

Q_CAP_DIFFBUS_C0201-DIFF BUS_0A  I128  C893
   1 P5E_CPU0_PE3_TX_C_DP<4>      1 @S9S_MB_2U_LIB.S9S_MB_2U(SCH_1):P5E_CPU0_PE3_TX_C_DP(4)
   2 P5E_CPU0_PE3_TX_DP<4>      2 @S9S_MB_2U_LIB.S9S_MB_2U(SCH_1):P5E_CPU0_PE3_TX_DP(4)

Q_CAP_DIFFBUS_C0201-DIFF BUS_0A  I134  C889
   1 P5E_CPU0_PE3_TX_C_DP<6>      1 @S9S_MB_2U_LIB.S9S_MB_2U(SCH_1):P5E_CPU0_PE3_TX_C_DP(6)
   2 P5E_CPU0_PE3_TX_DP<6>      2 @S9S_MB_2U_LIB.S9S_MB_2U(SCH_1):P5E_CPU0_PE3_TX_DP(6)

Q_CAP_DIFFBUS_C0201-DIFF BUS_0A  I135  C888
   1 P5E_CPU0_PE3_TX_C_DN<6>      1 @S9S_MB_2U_LIB.S9S_MB_2U(SCH_1):P5E_CPU0_PE3_TX_C_DN(6)
   2 P5E_CPU0_PE3_TX_DN<6>      2 @S9S_MB_2U_LIB.S9S_MB_2U(SCH_1):P5E_CPU0_PE3_TX_DN(6)

Q_CAP_DIFFBUS_C0201-DIFF BUS_0A  I136  C887
   1 P5E_CPU0_PE3_TX_C_DP<7>      1 @S9S_MB_2U_LIB.S9S_MB_2U(SCH_1):P5E_CPU0_PE3_TX_C_DP(7)
   2 P5E_CPU0_PE3_TX_DP<7>      2 @S9S_MB_2U_LIB.S9S_MB_2U(SCH_1):P5E_CPU0_PE3_TX_DP(7)

Q_CAP_DIFFBUS_C0201-DIFF BUS_0A  I137  C886
   1 P5E_CPU0_PE3_TX_C_DN<7>      1 @S9S_MB_2U_LIB.S9S_MB_2U(SCH_1):P5E_CPU0_PE3_TX_C_DN(7)
   2 P5E_CPU0_PE3_TX_DN<7>      2 @S9S_MB_2U_LIB.S9S_MB_2U(SCH_1):P5E_CPU0_PE3_TX_DN(7)

Q_CAP_DIFFBUS_C0201-DIFF BUS_0A  I152  C885
   1 P5E_CPU0_PE3_TX_C_DP<8>      1 @S9S_MB_2U_LIB.S9S_MB_2U(SCH_1):P5E_CPU0_PE3_TX_C_DP(8)
   2 P5E_CPU0_PE3_TX_DP<8>      2 @S9S_MB_2U_LIB.S9S_MB_2U(SCH_1):P5E_CPU0_PE3_TX_DP(8)

Q_CAP_DIFFBUS_C0201-DIFF BUS_0A  I153  C883
   1 P5E_CPU0_PE3_TX_C_DP<9>      1 @S9S_MB_2U_LIB.S9S_MB_2U(SCH_1):P5E_CPU0_PE3_TX_C_DP(9)
   2 P5E_CPU0_PE3_TX_DP<9>      2 @S9S_MB_2U_LIB.S9S_MB_2U(SCH_1):P5E_CPU0_PE3_TX_DP(9)

Q_CAP_DIFFBUS_C0201-DIFF BUS_0A  I154  C882
   1 P5E_CPU0_PE3_TX_C_DN<9>      1 @S9S_MB_2U_LIB.S9S_MB_2U(SCH_1):P5E_CPU0_PE3_TX_C_DN(9)
   2 P5E_CPU0_PE3_TX_DN<9>      2 @S9S_MB_2U_LIB.S9S_MB_2U(SCH_1):P5E_CPU0_PE3_TX_DN(9)

Q_CAP_DIFFBUS_C0201-DIFF BUS_0A  I155  C881
   1 P5E_CPU0_PE3_TX_C_DP<10>      1 @S9S_MB_2U_LIB.S9S_MB_2U(SCH_1):P5E_CPU0_PE3_TX_C_DP(10)
   2 P5E_CPU0_PE3_TX_DP<10>      2 @S9S_MB_2U_LIB.S9S_MB_2U(SCH_1):P5E_CPU0_PE3_TX_DP(10)

Q_CAP_DIFFBUS_C0201-DIFF BUS_0A  I156  C880
   1 P5E_CPU0_PE3_TX_C_DN<10>      1 @S9S_MB_2U_LIB.S9S_MB_2U(SCH_1):P5E_CPU0_PE3_TX_C_DN(10)
   2 P5E_CPU0_PE3_TX_DN<10>      2 @S9S_MB_2U_LIB.S9S_MB_2U(SCH_1):P5E_CPU0_PE3_TX_DN(10)

Q_CAP_DIFFBUS_C0201-DIFF BUS_0A  I157  C878
   1 P5E_CPU0_PE3_TX_C_DN<11>      1 @S9S_MB_2U_LIB.S9S_MB_2U(SCH_1):P5E_CPU0_PE3_TX_C_DN(11)
   2 P5E_CPU0_PE3_TX_DN<11>      2 @S9S_MB_2U_LIB.S9S_MB_2U(SCH_1):P5E_CPU0_PE3_TX_DN(11)

Q_CAP_DIFFBUS_C0201-DIFF BUS_0A  I158  C879
   1 P5E_CPU0_PE3_TX_C_DP<11>      1 @S9S_MB_2U_LIB.S9S_MB_2U(SCH_1):P5E_CPU0_PE3_TX_C_DP(11)
   2 P5E_CPU0_PE3_TX_DP<11>      2 @S9S_MB_2U_LIB.S9S_MB_2U(SCH_1):P5E_CPU0_PE3_TX_DP(11)

Q_CAP_DIFFBUS_C0201-DIFF BUS_0A  I159  C877
   1 P5E_CPU0_PE3_TX_C_DP<12>      1 @S9S_MB_2U_LIB.S9S_MB_2U(SCH_1):P5E_CPU0_PE3_TX_C_DP(12)
   2 P5E_CPU0_PE3_TX_DP<12>      2 @S9S_MB_2U_LIB.S9S_MB_2U(SCH_1):P5E_CPU0_PE3_TX_DP(12)

Q_CAP_DIFFBUS_C0201-DIFF BUS_0A  I160  C876
   1 P5E_CPU0_PE3_TX_C_DN<12>      1 @S9S_MB_2U_LIB.S9S_MB_2U(SCH_1):P5E_CPU0_PE3_TX_C_DN(12)
   2 P5E_CPU0_PE3_TX_DN<12>      2 @S9S_MB_2U_LIB.S9S_MB_2U(SCH_1):P5E_CPU0_PE3_TX_DN(12)

Q_CAP_DIFFBUS_C0201-DIFF BUS_0A  I165  C874
   1 P5E_CPU0_PE3_TX_C_DN<13>      1 @S9S_MB_2U_LIB.S9S_MB_2U(SCH_1):P5E_CPU0_PE3_TX_C_DN(13)
   2 P5E_CPU0_PE3_TX_DN<13>      2 @S9S_MB_2U_LIB.S9S_MB_2U(SCH_1):P5E_CPU0_PE3_TX_DN(13)

Q_CAP_DIFFBUS_C0201-DIFF BUS_0A  I166  C873
   1 P5E_CPU0_PE3_TX_C_DP<14>      1 @S9S_MB_2U_LIB.S9S_MB_2U(SCH_1):P5E_CPU0_PE3_TX_C_DP(14)
   2 P5E_CPU0_PE3_TX_DP<14>      2 @S9S_MB_2U_LIB.S9S_MB_2U(SCH_1):P5E_CPU0_PE3_TX_DP(14)

Q_CAP_DIFFBUS_C0201-DIFF BUS_0A  I167  C872
   1 P5E_CPU0_PE3_TX_C_DN<14>      1 @S9S_MB_2U_LIB.S9S_MB_2U(SCH_1):P5E_CPU0_PE3_TX_C_DN(14)
   2 P5E_CPU0_PE3_TX_DN<14>      2 @S9S_MB_2U_LIB.S9S_MB_2U(SCH_1):P5E_CPU0_PE3_TX_DN(14)

Q_CAP_DIFFBUS_C0201-DIFF BUS_0A  I168  C871
   1 P5E_CPU0_PE3_TX_C_DP<15>      1 @S9S_MB_2U_LIB.S9S_MB_2U(SCH_1):P5E_CPU0_PE3_TX_C_DP(15)
   2 P5E_CPU0_PE3_TX_DP<15>      2 @S9S_MB_2U_LIB.S9S_MB_2U(SCH_1):P5E_CPU0_PE3_TX_DP(15)

Q_CAP_DIFFBUS_C0201-DIFF BUS_0A  I169  C870
   1 P5E_CPU0_PE3_TX_C_DN<15>      1 @S9S_MB_2U_LIB.S9S_MB_2U(SCH_1):P5E_CPU0_PE3_TX_C_DN(15)
   2 P5E_CPU0_PE3_TX_DN<15>      2 @S9S_MB_2U_LIB.S9S_MB_2U(SCH_1):P5E_CPU0_PE3_TX_DN(15)

Q_CAP_DIFFBUS_C0201-DIFF BUS_0A  I21  C869
   1 P5E_CPU0_PE1_TX_C_DP<0>      1 @S9S_MB_2U_LIB.S9S_MB_2U(SCH_1):P5E_CPU0_PE1_TX_C_DP(0)
   2 P5E_CPU0_PE1_TX_DP<0>      2 @S9S_MB_2U_LIB.S9S_MB_2U(SCH_1):P5E_CPU0_PE1_TX_DP(0)

Q_CAP_DIFFBUS_C0201-DIFF BUS_0A  I22  C868
   1 P5E_CPU0_PE1_TX_C_DN<0>      1 @S9S_MB_2U_LIB.S9S_MB_2U(SCH_1):P5E_CPU0_PE1_TX_C_DN(0)
   2 P5E_CPU0_PE1_TX_DN<0>      2 @S9S_MB_2U_LIB.S9S_MB_2U(SCH_1):P5E_CPU0_PE1_TX_DN(0)

Q_CAP_DIFFBUS_C0201-DIFF BUS_0A  I23  C867
   1 P5E_CPU0_PE1_TX_C_DP<1>      1 @S9S_MB_2U_LIB.S9S_MB_2U(SCH_1):P5E_CPU0_PE1_TX_C_DP(1)
   2 P5E_CPU0_PE1_TX_DP<1>      2 @S9S_MB_2U_LIB.S9S_MB_2U(SCH_1):P5E_CPU0_PE1_TX_DP(1)

Q_CAP_DIFFBUS_C0201-DIFF BUS_0A  I24  C866
   1 P5E_CPU0_PE1_TX_C_DN<1>      1 @S9S_MB_2U_LIB.S9S_MB_2U(SCH_1):P5E_CPU0_PE1_TX_C_DN(1)
   2 P5E_CPU0_PE1_TX_DN<1>      2 @S9S_MB_2U_LIB.S9S_MB_2U(SCH_1):P5E_CPU0_PE1_TX_DN(1)

Q_CAP_DIFFBUS_C0201-DIFF BUS_0A  I25  C864
   1 P5E_CPU0_PE1_TX_C_DN<2>      1 @S9S_MB_2U_LIB.S9S_MB_2U(SCH_1):P5E_CPU0_PE1_TX_C_DN(2)
   2 P5E_CPU0_PE1_TX_DN<2>      2 @S9S_MB_2U_LIB.S9S_MB_2U(SCH_1):P5E_CPU0_PE1_TX_DN(2)

Q_CAP_DIFFBUS_C0201-DIFF BUS_0A  I26  C865
   1 P5E_CPU0_PE1_TX_C_DP<2>      1 @S9S_MB_2U_LIB.S9S_MB_2U(SCH_1):P5E_CPU0_PE1_TX_C_DP(2)
   2 P5E_CPU0_PE1_TX_DP<2>      2 @S9S_MB_2U_LIB.S9S_MB_2U(SCH_1):P5E_CPU0_PE1_TX_DP(2)

Q_CAP_DIFFBUS_C0201-DIFF BUS_0A  I27  C863
   1 P5E_CPU0_PE1_TX_C_DP<3>      1 @S9S_MB_2U_LIB.S9S_MB_2U(SCH_1):P5E_CPU0_PE1_TX_C_DP(3)
   2 P5E_CPU0_PE1_TX_DP<3>      2 @S9S_MB_2U_LIB.S9S_MB_2U(SCH_1):P5E_CPU0_PE1_TX_DP(3)

Q_CAP_DIFFBUS_C0201-DIFF BUS_0A  I28  C862
   1 P5E_CPU0_PE1_TX_C_DN<3>      1 @S9S_MB_2U_LIB.S9S_MB_2U(SCH_1):P5E_CPU0_PE1_TX_C_DN(3)
   2 P5E_CPU0_PE1_TX_DN<3>      2 @S9S_MB_2U_LIB.S9S_MB_2U(SCH_1):P5E_CPU0_PE1_TX_DN(3)

Q_CAP_DIFFBUS_C0201-DIFF BUS_0A  I29  C861
   1 P5E_CPU0_PE1_TX_C_DP<4>      1 @S9S_MB_2U_LIB.S9S_MB_2U(SCH_1):P5E_CPU0_PE1_TX_C_DP(4)
   2 P5E_CPU0_PE1_TX_DP<4>      2 @S9S_MB_2U_LIB.S9S_MB_2U(SCH_1):P5E_CPU0_PE1_TX_DP(4)

Q_CAP_DIFFBUS_C0201-DIFF BUS_0A  I30  C860
   1 P5E_CPU0_PE1_TX_C_DN<4>      1 @S9S_MB_2U_LIB.S9S_MB_2U(SCH_1):P5E_CPU0_PE1_TX_C_DN(4)
   2 P5E_CPU0_PE1_TX_DN<4>      2 @S9S_MB_2U_LIB.S9S_MB_2U(SCH_1):P5E_CPU0_PE1_TX_DN(4)

Q_CAP_DIFFBUS_C0201-DIFF BUS_0A  I36  C859
   1 P5E_CPU0_PE1_TX_C_DP<5>      1 @S9S_MB_2U_LIB.S9S_MB_2U(SCH_1):P5E_CPU0_PE1_TX_C_DP(5)
   2 P5E_CPU0_PE1_TX_DP<5>      2 @S9S_MB_2U_LIB.S9S_MB_2U(SCH_1):P5E_CPU0_PE1_TX_DP(5)

Q_CAP_DIFFBUS_C0201-DIFF BUS_0A  I37  C858
   1 P5E_CPU0_PE1_TX_C_DN<5>      1 @S9S_MB_2U_LIB.S9S_MB_2U(SCH_1):P5E_CPU0_PE1_TX_C_DN(5)
   2 P5E_CPU0_PE1_TX_DN<5>      2 @S9S_MB_2U_LIB.S9S_MB_2U(SCH_1):P5E_CPU0_PE1_TX_DN(5)

Q_CAP_DIFFBUS_C0201-DIFF BUS_0A  I38  C857
   1 P5E_CPU0_PE1_TX_C_DP<6>      1 @S9S_MB_2U_LIB.S9S_MB_2U(SCH_1):P5E_CPU0_PE1_TX_C_DP(6)
   2 P5E_CPU0_PE1_TX_DP<6>      2 @S9S_MB_2U_LIB.S9S_MB_2U(SCH_1):P5E_CPU0_PE1_TX_DP(6)

Q_CAP_DIFFBUS_C0201-DIFF BUS_0A  I39  C856
   1 P5E_CPU0_PE1_TX_C_DN<6>      1 @S9S_MB_2U_LIB.S9S_MB_2U(SCH_1):P5E_CPU0_PE1_TX_C_DN(6)
   2 P5E_CPU0_PE1_TX_DN<6>      2 @S9S_MB_2U_LIB.S9S_MB_2U(SCH_1):P5E_CPU0_PE1_TX_DN(6)

Q_CAP_DIFFBUS_C0201-DIFF BUS_0A  I40  C855
   1 P5E_CPU0_PE1_TX_C_DP<7>      1 @S9S_MB_2U_LIB.S9S_MB_2U(SCH_1):P5E_CPU0_PE1_TX_C_DP(7)
   2 P5E_CPU0_PE1_TX_DP<7>      2 @S9S_MB_2U_LIB.S9S_MB_2U(SCH_1):P5E_CPU0_PE1_TX_DP(7)

Q_CAP_DIFFBUS_C0201-DIFF BUS_0A  I41  C854
   1 P5E_CPU0_PE1_TX_C_DN<7>      1 @S9S_MB_2U_LIB.S9S_MB_2U(SCH_1):P5E_CPU0_PE1_TX_C_DN(7)
   2 P5E_CPU0_PE1_TX_DN<7>      2 @S9S_MB_2U_LIB.S9S_MB_2U(SCH_1):P5E_CPU0_PE1_TX_DN(7)

Q_CAP_DIFFBUS_C0201-DIFF BUS_0A  I61  C852
   1 P5E_CPU0_PE1_TX_C_DN<8>      1 @S9S_MB_2U_LIB.S9S_MB_2U(SCH_1):P5E_CPU0_PE1_TX_C_DN(8)
   2 P5E_CPU0_PE1_TX_DN<8>      2 @S9S_MB_2U_LIB.S9S_MB_2U(SCH_1):P5E_CPU0_PE1_TX_DN(8)

Q_CAP_DIFFBUS_C0201-DIFF BUS_0A  I62  C853
   1 P5E_CPU0_PE1_TX_C_DP<8>      1 @S9S_MB_2U_LIB.S9S_MB_2U(SCH_1):P5E_CPU0_PE1_TX_C_DP(8)
   2 P5E_CPU0_PE1_TX_DP<8>      2 @S9S_MB_2U_LIB.S9S_MB_2U(SCH_1):P5E_CPU0_PE1_TX_DP(8)

Q_CAP_DIFFBUS_C0201-DIFF BUS_0A  I63  C851
   1 P5E_CPU0_PE1_TX_C_DP<9>      1 @S9S_MB_2U_LIB.S9S_MB_2U(SCH_1):P5E_CPU0_PE1_TX_C_DP(9)
   2 P5E_CPU0_PE1_TX_DP<9>      2 @S9S_MB_2U_LIB.S9S_MB_2U(SCH_1):P5E_CPU0_PE1_TX_DP(9)

Q_CAP_DIFFBUS_C0201-DIFF BUS_0A  I64  C850
   1 P5E_CPU0_PE1_TX_C_DN<9>      1 @S9S_MB_2U_LIB.S9S_MB_2U(SCH_1):P5E_CPU0_PE1_TX_C_DN(9)
   2 P5E_CPU0_PE1_TX_DN<9>      2 @S9S_MB_2U_LIB.S9S_MB_2U(SCH_1):P5E_CPU0_PE1_TX_DN(9)

Q_CAP_DIFFBUS_C0201-DIFF BUS_0A  I65  C849
   1 P5E_CPU0_PE1_TX_C_DP<10>      1 @S9S_MB_2U_LIB.S9S_MB_2U(SCH_1):P5E_CPU0_PE1_TX_C_DP(10)
   2 P5E_CPU0_PE1_TX_DP<10>      2 @S9S_MB_2U_LIB.S9S_MB_2U(SCH_1):P5E_CPU0_PE1_TX_DP(10)

Q_CAP_DIFFBUS_C0201-DIFF BUS_0A  I66  C848
   1 P5E_CPU0_PE1_TX_C_DN<10>      1 @S9S_MB_2U_LIB.S9S_MB_2U(SCH_1):P5E_CPU0_PE1_TX_C_DN(10)
   2 P5E_CPU0_PE1_TX_DN<10>      2 @S9S_MB_2U_LIB.S9S_MB_2U(SCH_1):P5E_CPU0_PE1_TX_DN(10)

Q_CAP_DIFFBUS_C0201-DIFF BUS_0A  I67  C847
   1 P5E_CPU0_PE1_TX_C_DP<11>      1 @S9S_MB_2U_LIB.S9S_MB_2U(SCH_1):P5E_CPU0_PE1_TX_C_DP(11)
   2 P5E_CPU0_PE1_TX_DP<11>      2 @S9S_MB_2U_LIB.S9S_MB_2U(SCH_1):P5E_CPU0_PE1_TX_DP(11)

Q_CAP_DIFFBUS_C0201-DIFF BUS_0A  I68  C846
   1 P5E_CPU0_PE1_TX_C_DN<11>      1 @S9S_MB_2U_LIB.S9S_MB_2U(SCH_1):P5E_CPU0_PE1_TX_C_DN(11)
   2 P5E_CPU0_PE1_TX_DN<11>      2 @S9S_MB_2U_LIB.S9S_MB_2U(SCH_1):P5E_CPU0_PE1_TX_DN(11)

Q_CAP_DIFFBUS_C0201-DIFF BUS_0A  I69  C845
   1 P5E_CPU0_PE1_TX_C_DP<12>      1 @S9S_MB_2U_LIB.S9S_MB_2U(SCH_1):P5E_CPU0_PE1_TX_C_DP(12)
   2 P5E_CPU0_PE1_TX_DP<12>      2 @S9S_MB_2U_LIB.S9S_MB_2U(SCH_1):P5E_CPU0_PE1_TX_DP(12)

Q_CAP_DIFFBUS_C0201-DIFF BUS_0A  I70  C844
   1 P5E_CPU0_PE1_TX_C_DN<12>      1 @S9S_MB_2U_LIB.S9S_MB_2U(SCH_1):P5E_CPU0_PE1_TX_C_DN(12)
   2 P5E_CPU0_PE1_TX_DN<12>      2 @S9S_MB_2U_LIB.S9S_MB_2U(SCH_1):P5E_CPU0_PE1_TX_DN(12)

Q_CAP_DIFFBUS_C0201-DIFF BUS_0A  I76  C842
   1 P5E_CPU0_PE1_TX_C_DN<13>      1 @S9S_MB_2U_LIB.S9S_MB_2U(SCH_1):P5E_CPU0_PE1_TX_C_DN(13)
   2 P5E_CPU0_PE1_TX_DN<13>      2 @S9S_MB_2U_LIB.S9S_MB_2U(SCH_1):P5E_CPU0_PE1_TX_DN(13)

Q_CAP_DIFFBUS_C0201-DIFF BUS_0A  I77  C843
   1 P5E_CPU0_PE1_TX_C_DP<13>      1 @S9S_MB_2U_LIB.S9S_MB_2U(SCH_1):P5E_CPU0_PE1_TX_C_DP(13)
   2 P5E_CPU0_PE1_TX_DP<13>      2 @S9S_MB_2U_LIB.S9S_MB_2U(SCH_1):P5E_CPU0_PE1_TX_DP(13)

Q_CAP_DIFFBUS_C0201-DIFF BUS_0A  I78  C841
   1 P5E_CPU0_PE1_TX_C_DP<14>      1 @S9S_MB_2U_LIB.S9S_MB_2U(SCH_1):P5E_CPU0_PE1_TX_C_DP(14)
   2 P5E_CPU0_PE1_TX_DP<14>      2 @S9S_MB_2U_LIB.S9S_MB_2U(SCH_1):P5E_CPU0_PE1_TX_DP(14)

Q_CAP_DIFFBUS_C0201-DIFF BUS_0A  I79  C840
   1 P5E_CPU0_PE1_TX_C_DN<14>      1 @S9S_MB_2U_LIB.S9S_MB_2U(SCH_1):P5E_CPU0_PE1_TX_C_DN(14)
   2 P5E_CPU0_PE1_TX_DN<14>      2 @S9S_MB_2U_LIB.S9S_MB_2U(SCH_1):P5E_CPU0_PE1_TX_DN(14)

Q_CAP_DIFFBUS_C0201-DIFF BUS_0A  I80  C838
   1 P5E_CPU0_PE1_TX_C_DN<15>      1 @S9S_MB_2U_LIB.S9S_MB_2U(SCH_1):P5E_CPU0_PE1_TX_C_DN(15)
   2 P5E_CPU0_PE1_TX_DN<15>      2 @S9S_MB_2U_LIB.S9S_MB_2U(SCH_1):P5E_CPU0_PE1_TX_DN(15)

Q_CAP_DIFFBUS_C0201-DIFF BUS_0A  I81  C839
   1 P5E_CPU0_PE1_TX_C_DP<15>      1 @S9S_MB_2U_LIB.S9S_MB_2U(SCH_1):P5E_CPU0_PE1_TX_C_DP(15)
   2 P5E_CPU0_PE1_TX_DP<15>      2 @S9S_MB_2U_LIB.S9S_MB_2U(SCH_1):P5E_CPU0_PE1_TX_DP(15)

Q_CAP_DIFFBUS_C0201-DIFF BUS_0A  I132  C891
   1 P5E_CPU0_PE3_TX_C_DP<5>      1 @S9S_MB_2U_LIB.S9S_MB_2U(SCH_1):P5E_CPU0_PE3_TX_C_DP(5)
   2 P5E_CPU0_PE3_TX_DP<5>      2 @S9S_MB_2U_LIB.S9S_MB_2U(SCH_1):P5E_CPU0_PE3_TX_DP(5)

Q_CAP_DIFFBUS_C0201-DIFF BUS_0A  I133  C890
   1 P5E_CPU0_PE3_TX_C_DN<5>      1 @S9S_MB_2U_LIB.S9S_MB_2U(SCH_1):P5E_CPU0_PE3_TX_C_DN(5)
   2 P5E_CPU0_PE3_TX_DN<5>      2 @S9S_MB_2U_LIB.S9S_MB_2U(SCH_1):P5E_CPU0_PE3_TX_DN(5)

Q_CAP_DIFFBUS_C0201-DIFF BUS_0A  I151  C884
   1 P5E_CPU0_PE3_TX_C_DN<8>      1 @S9S_MB_2U_LIB.S9S_MB_2U(SCH_1):P5E_CPU0_PE3_TX_C_DN(8)
   2 P5E_CPU0_PE3_TX_DN<8>      2 @S9S_MB_2U_LIB.S9S_MB_2U(SCH_1):P5E_CPU0_PE3_TX_DN(8)

Q_CAP_DIFFBUS_C0201-DIFF BUS_0A  I164  C875
   1 P5E_CPU0_PE3_TX_C_DP<13>      1 @S9S_MB_2U_LIB.S9S_MB_2U(SCH_1):P5E_CPU0_PE3_TX_C_DP(13)
   2 P5E_CPU0_PE3_TX_DP<13>      2 @S9S_MB_2U_LIB.S9S_MB_2U(SCH_1):P5E_CPU0_PE3_TX_DP(13)

Q_CAP_DIFFBUS_C0201-DIFF BUS_0A  I206  C898
   1 P5E_CPU0_PE3_TX_C_DN<1>      1 @S9S_MB_2U_LIB.S9S_MB_2U(SCH_1):P5E_CPU0_PE3_TX_C_DN(1)
   2 P5E_CPU0_PE3_TX_DN<1>      2 @S9S_MB_2U_LIB.S9S_MB_2U(SCH_1):P5E_CPU0_PE3_TX_DN(1)


DRAWING: @S9S_MB_2U_LIB.S9S_MB_2U(SCH_1):PAGE166 

Q_CAP_DIFFBUS_C0201-DIFF BUS_0A  I229  C1579
   1 P5E_CPU0_PE4_TX_C_DP<0>      1 @S9S_MB_2U_LIB.S9S_MB_2U(SCH_1):P5E_CPU0_PE4_TX_C_DP(0)
   2 P5E_CPU0_PE4_TX_DP<0>      2 @S9S_MB_2U_LIB.S9S_MB_2U(SCH_1):P5E_CPU0_PE4_TX_DP(0)

Q_CAP_DIFFBUS_C0201-DIFF BUS_0A  I230  C1578
   1 P5E_CPU0_PE4_TX_C_DN<0>      1 @S9S_MB_2U_LIB.S9S_MB_2U(SCH_1):P5E_CPU0_PE4_TX_C_DN(0)
   2 P5E_CPU0_PE4_TX_DN<0>      2 @S9S_MB_2U_LIB.S9S_MB_2U(SCH_1):P5E_CPU0_PE4_TX_DN(0)

Q_CAP_DIFFBUS_C0201-DIFF BUS_0A  I231  C1575
   1 P5E_CPU0_PE4_TX_C_DP<2>      1 @S9S_MB_2U_LIB.S9S_MB_2U(SCH_1):P5E_CPU0_PE4_TX_C_DP(2)
   2 P5E_CPU0_PE4_TX_DP<2>      2 @S9S_MB_2U_LIB.S9S_MB_2U(SCH_1):P5E_CPU0_PE4_TX_DP(2)

Q_CAP_DIFFBUS_C0201-DIFF BUS_0A  I232  C1574
   1 P5E_CPU0_PE4_TX_C_DN<2>      1 @S9S_MB_2U_LIB.S9S_MB_2U(SCH_1):P5E_CPU0_PE4_TX_C_DN(2)
   2 P5E_CPU0_PE4_TX_DN<2>      2 @S9S_MB_2U_LIB.S9S_MB_2U(SCH_1):P5E_CPU0_PE4_TX_DN(2)

Q_CAP_DIFFBUS_C0201-DIFF BUS_0A  I233  C1573
   1 P5E_CPU0_PE4_TX_C_DP<3>      1 @S9S_MB_2U_LIB.S9S_MB_2U(SCH_1):P5E_CPU0_PE4_TX_C_DP(3)
   2 P5E_CPU0_PE4_TX_DP<3>      2 @S9S_MB_2U_LIB.S9S_MB_2U(SCH_1):P5E_CPU0_PE4_TX_DP(3)

Q_CAP_DIFFBUS_C0201-DIFF BUS_0A  I234  C1572
   1 P5E_CPU0_PE4_TX_C_DN<3>      1 @S9S_MB_2U_LIB.S9S_MB_2U(SCH_1):P5E_CPU0_PE4_TX_C_DN(3)
   2 P5E_CPU0_PE4_TX_DN<3>      2 @S9S_MB_2U_LIB.S9S_MB_2U(SCH_1):P5E_CPU0_PE4_TX_DN(3)

Q_CAP_DIFFBUS_C0201-DIFF BUS_0A  I235  C1570
   1 P5E_CPU0_PE4_TX_C_DN<4>      1 @S9S_MB_2U_LIB.S9S_MB_2U(SCH_1):P5E_CPU0_PE4_TX_C_DN(4)
   2 P5E_CPU0_PE4_TX_DN<4>      2 @S9S_MB_2U_LIB.S9S_MB_2U(SCH_1):P5E_CPU0_PE4_TX_DN(4)

Q_CAP_DIFFBUS_C0201-DIFF BUS_0A  I236  C1571
   1 P5E_CPU0_PE4_TX_C_DP<4>      1 @S9S_MB_2U_LIB.S9S_MB_2U(SCH_1):P5E_CPU0_PE4_TX_C_DP(4)
   2 P5E_CPU0_PE4_TX_DP<4>      2 @S9S_MB_2U_LIB.S9S_MB_2U(SCH_1):P5E_CPU0_PE4_TX_DP(4)

Q_CAP_DIFFBUS_C0201-DIFF BUS_0A  I237  C1569
   1 P5E_CPU0_PE4_TX_C_DP<5>      1 @S9S_MB_2U_LIB.S9S_MB_2U(SCH_1):P5E_CPU0_PE4_TX_C_DP(5)
   2 P5E_CPU0_PE4_TX_DP<5>      2 @S9S_MB_2U_LIB.S9S_MB_2U(SCH_1):P5E_CPU0_PE4_TX_DP(5)

Q_CAP_DIFFBUS_C0201-DIFF BUS_0A  I238  C1568
   1 P5E_CPU0_PE4_TX_C_DN<5>      1 @S9S_MB_2U_LIB.S9S_MB_2U(SCH_1):P5E_CPU0_PE4_TX_C_DN(5)
   2 P5E_CPU0_PE4_TX_DN<5>      2 @S9S_MB_2U_LIB.S9S_MB_2U(SCH_1):P5E_CPU0_PE4_TX_DN(5)

Q_CAP_DIFFBUS_C0201-DIFF BUS_0A  I239  C1567
   1 P5E_CPU0_PE4_TX_C_DP<6>      1 @S9S_MB_2U_LIB.S9S_MB_2U(SCH_1):P5E_CPU0_PE4_TX_C_DP(6)
   2 P5E_CPU0_PE4_TX_DP<6>      2 @S9S_MB_2U_LIB.S9S_MB_2U(SCH_1):P5E_CPU0_PE4_TX_DP(6)

Q_CAP_DIFFBUS_C0201-DIFF BUS_0A  I240  C1566
   1 P5E_CPU0_PE4_TX_C_DN<6>      1 @S9S_MB_2U_LIB.S9S_MB_2U(SCH_1):P5E_CPU0_PE4_TX_C_DN(6)
   2 P5E_CPU0_PE4_TX_DN<6>      2 @S9S_MB_2U_LIB.S9S_MB_2U(SCH_1):P5E_CPU0_PE4_TX_DN(6)

Q_CAP_DIFFBUS_C0201-DIFF BUS_0A  I241  C1565
   1 P5E_CPU0_PE4_TX_C_DP<7>      1 @S9S_MB_2U_LIB.S9S_MB_2U(SCH_1):P5E_CPU0_PE4_TX_C_DP(7)
   2 P5E_CPU0_PE4_TX_DP<7>      2 @S9S_MB_2U_LIB.S9S_MB_2U(SCH_1):P5E_CPU0_PE4_TX_DP(7)

Q_CAP_DIFFBUS_C0201-DIFF BUS_0A  I242  C1564
   1 P5E_CPU0_PE4_TX_C_DN<7>      1 @S9S_MB_2U_LIB.S9S_MB_2U(SCH_1):P5E_CPU0_PE4_TX_C_DN(7)
   2 P5E_CPU0_PE4_TX_DN<7>      2 @S9S_MB_2U_LIB.S9S_MB_2U(SCH_1):P5E_CPU0_PE4_TX_DN(7)

Q_CAP_DIFFBUS_C0201-DIFF BUS_0A  I259  C1563
   1 P5E_CPU0_PE4_TX_C_DP<8>      1 @S9S_MB_2U_LIB.S9S_MB_2U(SCH_1):P5E_CPU0_PE4_TX_C_DP(8)
   2 P5E_CPU0_PE4_TX_DP<8>      2 @S9S_MB_2U_LIB.S9S_MB_2U(SCH_1):P5E_CPU0_PE4_TX_DP(8)

Q_CAP_DIFFBUS_C0201-DIFF BUS_0A  I260  C1794
   1 P5E_CPU0_PE4_TX_C_DN<8>      1 @S9S_MB_2U_LIB.S9S_MB_2U(SCH_1):P5E_CPU0_PE4_TX_C_DN(8)
   2 P5E_CPU0_PE4_TX_DN<8>      2 @S9S_MB_2U_LIB.S9S_MB_2U(SCH_1):P5E_CPU0_PE4_TX_DN(8)

Q_CAP_DIFFBUS_C0201-DIFF BUS_0A  I261  C1793
   1 P5E_CPU0_PE4_TX_C_DP<9>      1 @S9S_MB_2U_LIB.S9S_MB_2U(SCH_1):P5E_CPU0_PE4_TX_C_DP(9)
   2 P5E_CPU0_PE4_TX_DP<9>      2 @S9S_MB_2U_LIB.S9S_MB_2U(SCH_1):P5E_CPU0_PE4_TX_DP(9)

Q_CAP_DIFFBUS_C0201-DIFF BUS_0A  I262  C1560
   1 P5E_CPU0_PE4_TX_C_DN<9>      1 @S9S_MB_2U_LIB.S9S_MB_2U(SCH_1):P5E_CPU0_PE4_TX_C_DN(9)
   2 P5E_CPU0_PE4_TX_DN<9>      2 @S9S_MB_2U_LIB.S9S_MB_2U(SCH_1):P5E_CPU0_PE4_TX_DN(9)

Q_CAP_DIFFBUS_C0201-DIFF BUS_0A  I263  C1559
   1 P5E_CPU0_PE4_TX_C_DP<10>      1 @S9S_MB_2U_LIB.S9S_MB_2U(SCH_1):P5E_CPU0_PE4_TX_C_DP(10)
   2 P5E_CPU0_PE4_TX_DP<10>      2 @S9S_MB_2U_LIB.S9S_MB_2U(SCH_1):P5E_CPU0_PE4_TX_DP(10)

Q_CAP_DIFFBUS_C0201-DIFF BUS_0A  I264  C1558
   1 P5E_CPU0_PE4_TX_C_DN<10>      1 @S9S_MB_2U_LIB.S9S_MB_2U(SCH_1):P5E_CPU0_PE4_TX_C_DN(10)
   2 P5E_CPU0_PE4_TX_DN<10>      2 @S9S_MB_2U_LIB.S9S_MB_2U(SCH_1):P5E_CPU0_PE4_TX_DN(10)

Q_CAP_DIFFBUS_C0201-DIFF BUS_0A  I265  C1556
   1 P5E_CPU0_PE4_TX_C_DN<11>      1 @S9S_MB_2U_LIB.S9S_MB_2U(SCH_1):P5E_CPU0_PE4_TX_C_DN(11)
   2 P5E_CPU0_PE4_TX_DN<11>      2 @S9S_MB_2U_LIB.S9S_MB_2U(SCH_1):P5E_CPU0_PE4_TX_DN(11)

Q_CAP_DIFFBUS_C0201-DIFF BUS_0A  I266  C1557
   1 P5E_CPU0_PE4_TX_C_DP<11>      1 @S9S_MB_2U_LIB.S9S_MB_2U(SCH_1):P5E_CPU0_PE4_TX_C_DP(11)
   2 P5E_CPU0_PE4_TX_DP<11>      2 @S9S_MB_2U_LIB.S9S_MB_2U(SCH_1):P5E_CPU0_PE4_TX_DP(11)

Q_CAP_DIFFBUS_C0201-DIFF BUS_0A  I267  C1555
   1 P5E_CPU0_PE4_TX_C_DP<12>      1 @S9S_MB_2U_LIB.S9S_MB_2U(SCH_1):P5E_CPU0_PE4_TX_C_DP(12)
   2 P5E_CPU0_PE4_TX_DP<12>      2 @S9S_MB_2U_LIB.S9S_MB_2U(SCH_1):P5E_CPU0_PE4_TX_DP(12)

Q_CAP_DIFFBUS_C0201-DIFF BUS_0A  I268  C1554
   1 P5E_CPU0_PE4_TX_C_DN<12>      1 @S9S_MB_2U_LIB.S9S_MB_2U(SCH_1):P5E_CPU0_PE4_TX_C_DN(12)
   2 P5E_CPU0_PE4_TX_DN<12>      2 @S9S_MB_2U_LIB.S9S_MB_2U(SCH_1):P5E_CPU0_PE4_TX_DN(12)

Q_CAP_DIFFBUS_C0201-DIFF BUS_0A  I269  C1553
   1 P5E_CPU0_PE4_TX_C_DP<13>      1 @S9S_MB_2U_LIB.S9S_MB_2U(SCH_1):P5E_CPU0_PE4_TX_C_DP(13)
   2 P5E_CPU0_PE4_TX_DP<13>      2 @S9S_MB_2U_LIB.S9S_MB_2U(SCH_1):P5E_CPU0_PE4_TX_DP(13)

Q_CAP_DIFFBUS_C0201-DIFF BUS_0A  I270  C1552
   1 P5E_CPU0_PE4_TX_C_DN<13>      1 @S9S_MB_2U_LIB.S9S_MB_2U(SCH_1):P5E_CPU0_PE4_TX_C_DN(13)
   2 P5E_CPU0_PE4_TX_DN<13>      2 @S9S_MB_2U_LIB.S9S_MB_2U(SCH_1):P5E_CPU0_PE4_TX_DN(13)

Q_CAP_DIFFBUS_C0201-DIFF BUS_0A  I271  C1792
   1 P5E_CPU0_PE4_TX_C_DP<14>      1 @S9S_MB_2U_LIB.S9S_MB_2U(SCH_1):P5E_CPU0_PE4_TX_C_DP(14)
   2 P5E_CPU0_PE4_TX_DP<14>      2 @S9S_MB_2U_LIB.S9S_MB_2U(SCH_1):P5E_CPU0_PE4_TX_DP(14)

Q_CAP_DIFFBUS_C0201-DIFF BUS_0A  I272  C1550
   1 P5E_CPU0_PE4_TX_C_DN<14>      1 @S9S_MB_2U_LIB.S9S_MB_2U(SCH_1):P5E_CPU0_PE4_TX_C_DN(14)
   2 P5E_CPU0_PE4_TX_DN<14>      2 @S9S_MB_2U_LIB.S9S_MB_2U(SCH_1):P5E_CPU0_PE4_TX_DN(14)

Q_CAP_DIFFBUS_C0201-DIFF BUS_0A  I273  C1548
   1 P5E_CPU0_PE4_TX_C_DN<15>      1 @S9S_MB_2U_LIB.S9S_MB_2U(SCH_1):P5E_CPU0_PE4_TX_C_DN(15)
   2 P5E_CPU0_PE4_TX_DN<15>      2 @S9S_MB_2U_LIB.S9S_MB_2U(SCH_1):P5E_CPU0_PE4_TX_DN(15)

Q_CAP_DIFFBUS_C0201-DIFF BUS_0A  I274  C1549
   1 P5E_CPU0_PE4_TX_C_DP<15>      1 @S9S_MB_2U_LIB.S9S_MB_2U(SCH_1):P5E_CPU0_PE4_TX_C_DP(15)
   2 P5E_CPU0_PE4_TX_DP<15>      2 @S9S_MB_2U_LIB.S9S_MB_2U(SCH_1):P5E_CPU0_PE4_TX_DP(15)

Q_CAP_DIFFBUS_C0201-DIFF BUS_0A  I311  C1577
   1 P5E_CPU0_PE4_TX_C_DP<1>      1 @S9S_MB_2U_LIB.S9S_MB_2U(SCH_1):P5E_CPU0_PE4_TX_C_DP(1)
   2 P5E_CPU0_PE4_TX_DP<1>      2 @S9S_MB_2U_LIB.S9S_MB_2U(SCH_1):P5E_CPU0_PE4_TX_DP(1)

Q_CAP_DIFFBUS_C0201-DIFF BUS_0A  I312  C1576
   1 P5E_CPU0_PE4_TX_C_DN<1>      1 @S9S_MB_2U_LIB.S9S_MB_2U(SCH_1):P5E_CPU0_PE4_TX_C_DN(1)
   2 P5E_CPU0_PE4_TX_DN<1>      2 @S9S_MB_2U_LIB.S9S_MB_2U(SCH_1):P5E_CPU0_PE4_TX_DN(1)

Q_CAP_DIFFBUS_C0201-DIFF BUS_0A  I363  C820
   1 P5E_CPU1_PE1_TX_C_DN<8>      1 @S9S_MB_2U_LIB.S9S_MB_2U(SCH_1):P5E_CPU1_PE1_TX_C_DN(8)
   2 P5E_CPU1_PE1_TX_DN<8>      2 @S9S_MB_2U_LIB.S9S_MB_2U(SCH_1):P5E_CPU1_PE1_TX_DN(8)

Q_CAP_DIFFBUS_C0201-DIFF BUS_0A  I364  C821
   1 P5E_CPU1_PE1_TX_C_DP<8>      1 @S9S_MB_2U_LIB.S9S_MB_2U(SCH_1):P5E_CPU1_PE1_TX_C_DP(8)
   2 P5E_CPU1_PE1_TX_DP<8>      2 @S9S_MB_2U_LIB.S9S_MB_2U(SCH_1):P5E_CPU1_PE1_TX_DP(8)

Q_CAP_DIFFBUS_C0201-DIFF BUS_0A  I365  C818
   1 P5E_CPU1_PE1_TX_C_DN<9>      1 @S9S_MB_2U_LIB.S9S_MB_2U(SCH_1):P5E_CPU1_PE1_TX_C_DN(9)
   2 P5E_CPU1_PE1_TX_DN<9>      2 @S9S_MB_2U_LIB.S9S_MB_2U(SCH_1):P5E_CPU1_PE1_TX_DN(9)

Q_CAP_DIFFBUS_C0201-DIFF BUS_0A  I333  C836
   1 P5E_CPU1_PE1_TX_C_DN<0>      1 @S9S_MB_2U_LIB.S9S_MB_2U(SCH_1):P5E_CPU1_PE1_TX_C_DN(0)
   2 P5E_CPU1_PE1_TX_DN<0>      2 @S9S_MB_2U_LIB.S9S_MB_2U(SCH_1):P5E_CPU1_PE1_TX_DN(0)

Q_CAP_DIFFBUS_C0201-DIFF BUS_0A  I334  C837
   1 P5E_CPU1_PE1_TX_C_DP<0>      1 @S9S_MB_2U_LIB.S9S_MB_2U(SCH_1):P5E_CPU1_PE1_TX_C_DP(0)
   2 P5E_CPU1_PE1_TX_DP<0>      2 @S9S_MB_2U_LIB.S9S_MB_2U(SCH_1):P5E_CPU1_PE1_TX_DP(0)

Q_CAP_DIFFBUS_C0201-DIFF BUS_0A  I335  C834
   1 P5E_CPU1_PE1_TX_C_DN<1>      1 @S9S_MB_2U_LIB.S9S_MB_2U(SCH_1):P5E_CPU1_PE1_TX_C_DN(1)
   2 P5E_CPU1_PE1_TX_DN<1>      2 @S9S_MB_2U_LIB.S9S_MB_2U(SCH_1):P5E_CPU1_PE1_TX_DN(1)

Q_CAP_DIFFBUS_C0201-DIFF BUS_0A  I336  C835
   1 P5E_CPU1_PE1_TX_C_DP<1>      1 @S9S_MB_2U_LIB.S9S_MB_2U(SCH_1):P5E_CPU1_PE1_TX_C_DP(1)
   2 P5E_CPU1_PE1_TX_DP<1>      2 @S9S_MB_2U_LIB.S9S_MB_2U(SCH_1):P5E_CPU1_PE1_TX_DP(1)

Q_CAP_DIFFBUS_C0201-DIFF BUS_0A  I337  C831
   1 P5E_CPU1_PE1_TX_C_DP<3>      1 @S9S_MB_2U_LIB.S9S_MB_2U(SCH_1):P5E_CPU1_PE1_TX_C_DP(3)
   2 P5E_CPU1_PE1_TX_DP<3>      2 @S9S_MB_2U_LIB.S9S_MB_2U(SCH_1):P5E_CPU1_PE1_TX_DP(3)

Q_CAP_DIFFBUS_C0201-DIFF BUS_0A  I338  C832
   1 P5E_CPU1_PE1_TX_C_DN<2>      1 @S9S_MB_2U_LIB.S9S_MB_2U(SCH_1):P5E_CPU1_PE1_TX_C_DN(2)
   2 P5E_CPU1_PE1_TX_DN<2>      2 @S9S_MB_2U_LIB.S9S_MB_2U(SCH_1):P5E_CPU1_PE1_TX_DN(2)

Q_CAP_DIFFBUS_C0201-DIFF BUS_0A  I339  C833
   1 P5E_CPU1_PE1_TX_C_DP<2>      1 @S9S_MB_2U_LIB.S9S_MB_2U(SCH_1):P5E_CPU1_PE1_TX_C_DP(2)
   2 P5E_CPU1_PE1_TX_DP<2>      2 @S9S_MB_2U_LIB.S9S_MB_2U(SCH_1):P5E_CPU1_PE1_TX_DP(2)

Q_CAP_DIFFBUS_C0201-DIFF BUS_0A  I340  C828
   1 P5E_CPU1_PE1_TX_C_DN<4>      1 @S9S_MB_2U_LIB.S9S_MB_2U(SCH_1):P5E_CPU1_PE1_TX_C_DN(4)
   2 P5E_CPU1_PE1_TX_DN<4>      2 @S9S_MB_2U_LIB.S9S_MB_2U(SCH_1):P5E_CPU1_PE1_TX_DN(4)

Q_CAP_DIFFBUS_C0201-DIFF BUS_0A  I341  C830
   1 P5E_CPU1_PE1_TX_C_DN<3>      1 @S9S_MB_2U_LIB.S9S_MB_2U(SCH_1):P5E_CPU1_PE1_TX_C_DN(3)
   2 P5E_CPU1_PE1_TX_DN<3>      2 @S9S_MB_2U_LIB.S9S_MB_2U(SCH_1):P5E_CPU1_PE1_TX_DN(3)

Q_CAP_DIFFBUS_C0201-DIFF BUS_0A  I342  C829
   1 P5E_CPU1_PE1_TX_C_DP<4>      1 @S9S_MB_2U_LIB.S9S_MB_2U(SCH_1):P5E_CPU1_PE1_TX_C_DP(4)
   2 P5E_CPU1_PE1_TX_DP<4>      2 @S9S_MB_2U_LIB.S9S_MB_2U(SCH_1):P5E_CPU1_PE1_TX_DP(4)

Q_CAP_DIFFBUS_C0201-DIFF BUS_0A  I343  C827
   1 P5E_CPU1_PE1_TX_C_DP<5>      1 @S9S_MB_2U_LIB.S9S_MB_2U(SCH_1):P5E_CPU1_PE1_TX_C_DP(5)
   2 P5E_CPU1_PE1_TX_DP<5>      2 @S9S_MB_2U_LIB.S9S_MB_2U(SCH_1):P5E_CPU1_PE1_TX_DP(5)

Q_CAP_DIFFBUS_C0201-DIFF BUS_0A  I344  C826
   1 P5E_CPU1_PE1_TX_C_DN<5>      1 @S9S_MB_2U_LIB.S9S_MB_2U(SCH_1):P5E_CPU1_PE1_TX_C_DN(5)
   2 P5E_CPU1_PE1_TX_DN<5>      2 @S9S_MB_2U_LIB.S9S_MB_2U(SCH_1):P5E_CPU1_PE1_TX_DN(5)

Q_CAP_DIFFBUS_C0201-DIFF BUS_0A  I345  C822
   1 P5E_CPU1_PE1_TX_C_DN<7>      1 @S9S_MB_2U_LIB.S9S_MB_2U(SCH_1):P5E_CPU1_PE1_TX_C_DN(7)
   2 P5E_CPU1_PE1_TX_DN<7>      2 @S9S_MB_2U_LIB.S9S_MB_2U(SCH_1):P5E_CPU1_PE1_TX_DN(7)

Q_CAP_DIFFBUS_C0201-DIFF BUS_0A  I346  C823
   1 P5E_CPU1_PE1_TX_C_DP<7>      1 @S9S_MB_2U_LIB.S9S_MB_2U(SCH_1):P5E_CPU1_PE1_TX_C_DP(7)
   2 P5E_CPU1_PE1_TX_DP<7>      2 @S9S_MB_2U_LIB.S9S_MB_2U(SCH_1):P5E_CPU1_PE1_TX_DP(7)

Q_CAP_DIFFBUS_C0201-DIFF BUS_0A  I366  C819
   1 P5E_CPU1_PE1_TX_C_DP<9>      1 @S9S_MB_2U_LIB.S9S_MB_2U(SCH_1):P5E_CPU1_PE1_TX_C_DP(9)
   2 P5E_CPU1_PE1_TX_DP<9>      2 @S9S_MB_2U_LIB.S9S_MB_2U(SCH_1):P5E_CPU1_PE1_TX_DP(9)

Q_CAP_DIFFBUS_C0201-DIFF BUS_0A  I367  C817
   1 P5E_CPU1_PE1_TX_C_DP<10>      1 @S9S_MB_2U_LIB.S9S_MB_2U(SCH_1):P5E_CPU1_PE1_TX_C_DP(10)
   2 P5E_CPU1_PE1_TX_DP<10>      2 @S9S_MB_2U_LIB.S9S_MB_2U(SCH_1):P5E_CPU1_PE1_TX_DP(10)

Q_CAP_DIFFBUS_C0201-DIFF BUS_0A  I368  C816
   1 P5E_CPU1_PE1_TX_C_DN<10>      1 @S9S_MB_2U_LIB.S9S_MB_2U(SCH_1):P5E_CPU1_PE1_TX_C_DN(10)
   2 P5E_CPU1_PE1_TX_DN<10>      2 @S9S_MB_2U_LIB.S9S_MB_2U(SCH_1):P5E_CPU1_PE1_TX_DN(10)

Q_CAP_DIFFBUS_C0201-DIFF BUS_0A  I369  C815
   1 P5E_CPU1_PE1_TX_C_DP<11>      1 @S9S_MB_2U_LIB.S9S_MB_2U(SCH_1):P5E_CPU1_PE1_TX_C_DP(11)
   2 P5E_CPU1_PE1_TX_DP<11>      2 @S9S_MB_2U_LIB.S9S_MB_2U(SCH_1):P5E_CPU1_PE1_TX_DP(11)

Q_CAP_DIFFBUS_C0201-DIFF BUS_0A  I370  C814
   1 P5E_CPU1_PE1_TX_C_DN<11>      1 @S9S_MB_2U_LIB.S9S_MB_2U(SCH_1):P5E_CPU1_PE1_TX_C_DN(11)
   2 P5E_CPU1_PE1_TX_DN<11>      2 @S9S_MB_2U_LIB.S9S_MB_2U(SCH_1):P5E_CPU1_PE1_TX_DN(11)

Q_CAP_DIFFBUS_C0201-DIFF BUS_0A  I371  C812
   1 P5E_CPU1_PE1_TX_C_DN<12>      1 @S9S_MB_2U_LIB.S9S_MB_2U(SCH_1):P5E_CPU1_PE1_TX_C_DN(12)
   2 P5E_CPU1_PE1_TX_DN<12>      2 @S9S_MB_2U_LIB.S9S_MB_2U(SCH_1):P5E_CPU1_PE1_TX_DN(12)

Q_CAP_DIFFBUS_C0201-DIFF BUS_0A  I372  C813
   1 P5E_CPU1_PE1_TX_C_DP<12>      1 @S9S_MB_2U_LIB.S9S_MB_2U(SCH_1):P5E_CPU1_PE1_TX_C_DP(12)
   2 P5E_CPU1_PE1_TX_DP<12>      2 @S9S_MB_2U_LIB.S9S_MB_2U(SCH_1):P5E_CPU1_PE1_TX_DP(12)

Q_CAP_DIFFBUS_C0201-DIFF BUS_0A  I373  C811
   1 P5E_CPU1_PE1_TX_C_DP<13>      1 @S9S_MB_2U_LIB.S9S_MB_2U(SCH_1):P5E_CPU1_PE1_TX_C_DP(13)
   2 P5E_CPU1_PE1_TX_DP<13>      2 @S9S_MB_2U_LIB.S9S_MB_2U(SCH_1):P5E_CPU1_PE1_TX_DP(13)

Q_CAP_DIFFBUS_C0201-DIFF BUS_0A  I374  C810
   1 P5E_CPU1_PE1_TX_C_DN<13>      1 @S9S_MB_2U_LIB.S9S_MB_2U(SCH_1):P5E_CPU1_PE1_TX_C_DN(13)
   2 P5E_CPU1_PE1_TX_DN<13>      2 @S9S_MB_2U_LIB.S9S_MB_2U(SCH_1):P5E_CPU1_PE1_TX_DN(13)

Q_CAP_DIFFBUS_C0201-DIFF BUS_0A  I375  C809
   1 P5E_CPU1_PE1_TX_C_DP<14>      1 @S9S_MB_2U_LIB.S9S_MB_2U(SCH_1):P5E_CPU1_PE1_TX_C_DP(14)
   2 P5E_CPU1_PE1_TX_DP<14>      2 @S9S_MB_2U_LIB.S9S_MB_2U(SCH_1):P5E_CPU1_PE1_TX_DP(14)

Q_CAP_DIFFBUS_C0201-DIFF BUS_0A  I376  C808
   1 P5E_CPU1_PE1_TX_C_DN<14>      1 @S9S_MB_2U_LIB.S9S_MB_2U(SCH_1):P5E_CPU1_PE1_TX_C_DN(14)
   2 P5E_CPU1_PE1_TX_DN<14>      2 @S9S_MB_2U_LIB.S9S_MB_2U(SCH_1):P5E_CPU1_PE1_TX_DN(14)

Q_CAP_DIFFBUS_C0201-DIFF BUS_0A  I377  C806
   1 P5E_CPU1_PE1_TX_C_DN<15>      1 @S9S_MB_2U_LIB.S9S_MB_2U(SCH_1):P5E_CPU1_PE1_TX_C_DN(15)
   2 P5E_CPU1_PE1_TX_DN<15>      2 @S9S_MB_2U_LIB.S9S_MB_2U(SCH_1):P5E_CPU1_PE1_TX_DN(15)

Q_CAP_DIFFBUS_C0201-DIFF BUS_0A  I378  C807
   1 P5E_CPU1_PE1_TX_C_DP<15>      1 @S9S_MB_2U_LIB.S9S_MB_2U(SCH_1):P5E_CPU1_PE1_TX_C_DP(15)
   2 P5E_CPU1_PE1_TX_DP<15>      2 @S9S_MB_2U_LIB.S9S_MB_2U(SCH_1):P5E_CPU1_PE1_TX_DP(15)

Q_CAP_DIFFBUS_C0201-DIFF BUS_0A  I415  C825
   1 P5E_CPU1_PE1_TX_C_DP<6>      1 @S9S_MB_2U_LIB.S9S_MB_2U(SCH_1):P5E_CPU1_PE1_TX_C_DP(6)
   2 P5E_CPU1_PE1_TX_DP<6>      2 @S9S_MB_2U_LIB.S9S_MB_2U(SCH_1):P5E_CPU1_PE1_TX_DP(6)

Q_CAP_DIFFBUS_C0201-DIFF BUS_0A  I416  C824
   1 P5E_CPU1_PE1_TX_C_DN<6>      1 @S9S_MB_2U_LIB.S9S_MB_2U(SCH_1):P5E_CPU1_PE1_TX_C_DN(6)
   2 P5E_CPU1_PE1_TX_DN<6>      2 @S9S_MB_2U_LIB.S9S_MB_2U(SCH_1):P5E_CPU1_PE1_TX_DN(6)


DRAWING: @S9S_MB_2U_LIB.S9S_MB_2U(SCH_1):PAGE167 

Q_CAP_DIFFBUS_C0201-DIFF BUS_0A  I122  C773
   1 P5E_CPU1_PE2_TX_C_DP<0>      1 @S9S_MB_2U_LIB.S9S_MB_2U(SCH_1):P5E_CPU1_PE2_TX_C_DP(0)
   2 P5E_CPU1_PE2_TX_DP<0>      2 @S9S_MB_2U_LIB.S9S_MB_2U(SCH_1):P5E_CPU1_PE2_TX_DP(0)

Q_CAP_DIFFBUS_C0201-DIFF BUS_0A  I123  C772
   1 P5E_CPU1_PE2_TX_C_DN<0>      1 @S9S_MB_2U_LIB.S9S_MB_2U(SCH_1):P5E_CPU1_PE2_TX_C_DN(0)
   2 P5E_CPU1_PE2_TX_DN<0>      2 @S9S_MB_2U_LIB.S9S_MB_2U(SCH_1):P5E_CPU1_PE2_TX_DN(0)

Q_CAP_DIFFBUS_C0201-DIFF BUS_0A  I124  C771
   1 P5E_CPU1_PE2_TX_C_DP<1>      1 @S9S_MB_2U_LIB.S9S_MB_2U(SCH_1):P5E_CPU1_PE2_TX_C_DP(1)
   2 P5E_CPU1_PE2_TX_DP<1>      2 @S9S_MB_2U_LIB.S9S_MB_2U(SCH_1):P5E_CPU1_PE2_TX_DP(1)

Q_CAP_DIFFBUS_C0201-DIFF BUS_0A  I125  C770
   1 P5E_CPU1_PE2_TX_C_DN<1>      1 @S9S_MB_2U_LIB.S9S_MB_2U(SCH_1):P5E_CPU1_PE2_TX_C_DN(1)
   2 P5E_CPU1_PE2_TX_DN<1>      2 @S9S_MB_2U_LIB.S9S_MB_2U(SCH_1):P5E_CPU1_PE2_TX_DN(1)

Q_CAP_DIFFBUS_C0201-DIFF BUS_0A  I126  C769
   1 P5E_CPU1_PE2_TX_C_DP<2>      1 @S9S_MB_2U_LIB.S9S_MB_2U(SCH_1):P5E_CPU1_PE2_TX_C_DP(2)
   2 P5E_CPU1_PE2_TX_DP<2>      2 @S9S_MB_2U_LIB.S9S_MB_2U(SCH_1):P5E_CPU1_PE2_TX_DP(2)

Q_CAP_DIFFBUS_C0201-DIFF BUS_0A  I127  C768
   1 P5E_CPU1_PE2_TX_C_DN<2>      1 @S9S_MB_2U_LIB.S9S_MB_2U(SCH_1):P5E_CPU1_PE2_TX_C_DN(2)
   2 P5E_CPU1_PE2_TX_DN<2>      2 @S9S_MB_2U_LIB.S9S_MB_2U(SCH_1):P5E_CPU1_PE2_TX_DN(2)

Q_CAP_DIFFBUS_C0201-DIFF BUS_0A  I128  C767
   1 P5E_CPU1_PE2_TX_C_DP<3>      1 @S9S_MB_2U_LIB.S9S_MB_2U(SCH_1):P5E_CPU1_PE2_TX_C_DP(3)
   2 P5E_CPU1_PE2_TX_DP<3>      2 @S9S_MB_2U_LIB.S9S_MB_2U(SCH_1):P5E_CPU1_PE2_TX_DP(3)

Q_CAP_DIFFBUS_C0201-DIFF BUS_0A  I129  C766
   1 P5E_CPU1_PE2_TX_C_DN<3>      1 @S9S_MB_2U_LIB.S9S_MB_2U(SCH_1):P5E_CPU1_PE2_TX_C_DN(3)
   2 P5E_CPU1_PE2_TX_DN<3>      2 @S9S_MB_2U_LIB.S9S_MB_2U(SCH_1):P5E_CPU1_PE2_TX_DN(3)

Q_CAP_DIFFBUS_C0201-DIFF BUS_0A  I130  C764
   1 P5E_CPU1_PE2_TX_C_DN<4>      1 @S9S_MB_2U_LIB.S9S_MB_2U(SCH_1):P5E_CPU1_PE2_TX_C_DN(4)
   2 P5E_CPU1_PE2_TX_DN<4>      2 @S9S_MB_2U_LIB.S9S_MB_2U(SCH_1):P5E_CPU1_PE2_TX_DN(4)

Q_CAP_DIFFBUS_C0201-DIFF BUS_0A  I131  C765
   1 P5E_CPU1_PE2_TX_C_DP<4>      1 @S9S_MB_2U_LIB.S9S_MB_2U(SCH_1):P5E_CPU1_PE2_TX_C_DP(4)
   2 P5E_CPU1_PE2_TX_DP<4>      2 @S9S_MB_2U_LIB.S9S_MB_2U(SCH_1):P5E_CPU1_PE2_TX_DP(4)

Q_CAP_DIFFBUS_C0201-DIFF BUS_0A  I135  C763
   1 P5E_CPU1_PE2_TX_C_DP<5>      1 @S9S_MB_2U_LIB.S9S_MB_2U(SCH_1):P5E_CPU1_PE2_TX_C_DP(5)
   2 P5E_CPU1_PE2_TX_DP<5>      2 @S9S_MB_2U_LIB.S9S_MB_2U(SCH_1):P5E_CPU1_PE2_TX_DP(5)

Q_CAP_DIFFBUS_C0201-DIFF BUS_0A  I136  C762
   1 P5E_CPU1_PE2_TX_C_DN<5>      1 @S9S_MB_2U_LIB.S9S_MB_2U(SCH_1):P5E_CPU1_PE2_TX_C_DN(5)
   2 P5E_CPU1_PE2_TX_DN<5>      2 @S9S_MB_2U_LIB.S9S_MB_2U(SCH_1):P5E_CPU1_PE2_TX_DN(5)

Q_CAP_DIFFBUS_C0201-DIFF BUS_0A  I137  C761
   1 P5E_CPU1_PE2_TX_C_DP<6>      1 @S9S_MB_2U_LIB.S9S_MB_2U(SCH_1):P5E_CPU1_PE2_TX_C_DP(6)
   2 P5E_CPU1_PE2_TX_DP<6>      2 @S9S_MB_2U_LIB.S9S_MB_2U(SCH_1):P5E_CPU1_PE2_TX_DP(6)

Q_CAP_DIFFBUS_C0201-DIFF BUS_0A  I138  C760
   1 P5E_CPU1_PE2_TX_C_DN<6>      1 @S9S_MB_2U_LIB.S9S_MB_2U(SCH_1):P5E_CPU1_PE2_TX_C_DN(6)
   2 P5E_CPU1_PE2_TX_DN<6>      2 @S9S_MB_2U_LIB.S9S_MB_2U(SCH_1):P5E_CPU1_PE2_TX_DN(6)

Q_CAP_DIFFBUS_C0201-DIFF BUS_0A  I139  C759
   1 P5E_CPU1_PE2_TX_C_DP<7>      1 @S9S_MB_2U_LIB.S9S_MB_2U(SCH_1):P5E_CPU1_PE2_TX_C_DP(7)
   2 P5E_CPU1_PE2_TX_DP<7>      2 @S9S_MB_2U_LIB.S9S_MB_2U(SCH_1):P5E_CPU1_PE2_TX_DP(7)

Q_CAP_DIFFBUS_C0201-DIFF BUS_0A  I140  C758
   1 P5E_CPU1_PE2_TX_C_DN<7>      1 @S9S_MB_2U_LIB.S9S_MB_2U(SCH_1):P5E_CPU1_PE2_TX_C_DN(7)
   2 P5E_CPU1_PE2_TX_DN<7>      2 @S9S_MB_2U_LIB.S9S_MB_2U(SCH_1):P5E_CPU1_PE2_TX_DN(7)

Q_CAP_DIFFBUS_C0201-DIFF BUS_0A  I154  C756
   1 P5E_CPU1_PE2_TX_C_DN<8>      1 @S9S_MB_2U_LIB.S9S_MB_2U(SCH_1):P5E_CPU1_PE2_TX_C_DN(8)
   2 P5E_CPU1_PE2_TX_DN<8>      2 @S9S_MB_2U_LIB.S9S_MB_2U(SCH_1):P5E_CPU1_PE2_TX_DN(8)

Q_CAP_DIFFBUS_C0201-DIFF BUS_0A  I155  C757
   1 P5E_CPU1_PE2_TX_C_DP<8>      1 @S9S_MB_2U_LIB.S9S_MB_2U(SCH_1):P5E_CPU1_PE2_TX_C_DP(8)
   2 P5E_CPU1_PE2_TX_DP<8>      2 @S9S_MB_2U_LIB.S9S_MB_2U(SCH_1):P5E_CPU1_PE2_TX_DP(8)

Q_CAP_DIFFBUS_C0201-DIFF BUS_0A  I156  C755
   1 P5E_CPU1_PE2_TX_C_DP<9>      1 @S9S_MB_2U_LIB.S9S_MB_2U(SCH_1):P5E_CPU1_PE2_TX_C_DP(9)
   2 P5E_CPU1_PE2_TX_DP<9>      2 @S9S_MB_2U_LIB.S9S_MB_2U(SCH_1):P5E_CPU1_PE2_TX_DP(9)

Q_CAP_DIFFBUS_C0201-DIFF BUS_0A  I157  C754
   1 P5E_CPU1_PE2_TX_C_DN<9>      1 @S9S_MB_2U_LIB.S9S_MB_2U(SCH_1):P5E_CPU1_PE2_TX_C_DN(9)
   2 P5E_CPU1_PE2_TX_DN<9>      2 @S9S_MB_2U_LIB.S9S_MB_2U(SCH_1):P5E_CPU1_PE2_TX_DN(9)

Q_CAP_DIFFBUS_C0201-DIFF BUS_0A  I158  C753
   1 P5E_CPU1_PE2_TX_C_DP<10>      1 @S9S_MB_2U_LIB.S9S_MB_2U(SCH_1):P5E_CPU1_PE2_TX_C_DP(10)
   2 P5E_CPU1_PE2_TX_DP<10>      2 @S9S_MB_2U_LIB.S9S_MB_2U(SCH_1):P5E_CPU1_PE2_TX_DP(10)

Q_CAP_DIFFBUS_C0201-DIFF BUS_0A  I159  C752
   1 P5E_CPU1_PE2_TX_C_DN<10>      1 @S9S_MB_2U_LIB.S9S_MB_2U(SCH_1):P5E_CPU1_PE2_TX_C_DN(10)
   2 P5E_CPU1_PE2_TX_DN<10>      2 @S9S_MB_2U_LIB.S9S_MB_2U(SCH_1):P5E_CPU1_PE2_TX_DN(10)

Q_CAP_DIFFBUS_C0201-DIFF BUS_0A  I160  C750
   1 P5E_CPU1_PE2_TX_C_DN<11>      1 @S9S_MB_2U_LIB.S9S_MB_2U(SCH_1):P5E_CPU1_PE2_TX_C_DN(11)
   2 P5E_CPU1_PE2_TX_DN<11>      2 @S9S_MB_2U_LIB.S9S_MB_2U(SCH_1):P5E_CPU1_PE2_TX_DN(11)

Q_CAP_DIFFBUS_C0201-DIFF BUS_0A  I161  C751
   1 P5E_CPU1_PE2_TX_C_DP<11>      1 @S9S_MB_2U_LIB.S9S_MB_2U(SCH_1):P5E_CPU1_PE2_TX_C_DP(11)
   2 P5E_CPU1_PE2_TX_DP<11>      2 @S9S_MB_2U_LIB.S9S_MB_2U(SCH_1):P5E_CPU1_PE2_TX_DP(11)

Q_CAP_DIFFBUS_C0201-DIFF BUS_0A  I162  C749
   1 P5E_CPU1_PE2_TX_C_DP<12>      1 @S9S_MB_2U_LIB.S9S_MB_2U(SCH_1):P5E_CPU1_PE2_TX_C_DP(12)
   2 P5E_CPU1_PE2_TX_DP<12>      2 @S9S_MB_2U_LIB.S9S_MB_2U(SCH_1):P5E_CPU1_PE2_TX_DP(12)

Q_CAP_DIFFBUS_C0201-DIFF BUS_0A  I163  C748
   1 P5E_CPU1_PE2_TX_C_DN<12>      1 @S9S_MB_2U_LIB.S9S_MB_2U(SCH_1):P5E_CPU1_PE2_TX_C_DN(12)
   2 P5E_CPU1_PE2_TX_DN<12>      2 @S9S_MB_2U_LIB.S9S_MB_2U(SCH_1):P5E_CPU1_PE2_TX_DN(12)

Q_CAP_DIFFBUS_C0201-DIFF BUS_0A  I167  C747
   1 P5E_CPU1_PE2_TX_C_DP<13>      1 @S9S_MB_2U_LIB.S9S_MB_2U(SCH_1):P5E_CPU1_PE2_TX_C_DP(13)
   2 P5E_CPU1_PE2_TX_DP<13>      2 @S9S_MB_2U_LIB.S9S_MB_2U(SCH_1):P5E_CPU1_PE2_TX_DP(13)

Q_CAP_DIFFBUS_C0201-DIFF BUS_0A  I168  C746
   1 P5E_CPU1_PE2_TX_C_DN<13>      1 @S9S_MB_2U_LIB.S9S_MB_2U(SCH_1):P5E_CPU1_PE2_TX_C_DN(13)
   2 P5E_CPU1_PE2_TX_DN<13>      2 @S9S_MB_2U_LIB.S9S_MB_2U(SCH_1):P5E_CPU1_PE2_TX_DN(13)

Q_CAP_DIFFBUS_C0201-DIFF BUS_0A  I169  C745
   1 P5E_CPU1_PE2_TX_C_DP<14>      1 @S9S_MB_2U_LIB.S9S_MB_2U(SCH_1):P5E_CPU1_PE2_TX_C_DP(14)
   2 P5E_CPU1_PE2_TX_DP<14>      2 @S9S_MB_2U_LIB.S9S_MB_2U(SCH_1):P5E_CPU1_PE2_TX_DP(14)

Q_CAP_DIFFBUS_C0201-DIFF BUS_0A  I170  C744
   1 P5E_CPU1_PE2_TX_C_DN<14>      1 @S9S_MB_2U_LIB.S9S_MB_2U(SCH_1):P5E_CPU1_PE2_TX_C_DN(14)
   2 P5E_CPU1_PE2_TX_DN<14>      2 @S9S_MB_2U_LIB.S9S_MB_2U(SCH_1):P5E_CPU1_PE2_TX_DN(14)

Q_CAP_DIFFBUS_C0201-DIFF BUS_0A  I171  C743
   1 P5E_CPU1_PE2_TX_C_DP<15>      1 @S9S_MB_2U_LIB.S9S_MB_2U(SCH_1):P5E_CPU1_PE2_TX_C_DP(15)
   2 P5E_CPU1_PE2_TX_DP<15>      2 @S9S_MB_2U_LIB.S9S_MB_2U(SCH_1):P5E_CPU1_PE2_TX_DP(15)

Q_CAP_DIFFBUS_C0201-DIFF BUS_0A  I172  C742
   1 P5E_CPU1_PE2_TX_C_DN<15>      1 @S9S_MB_2U_LIB.S9S_MB_2U(SCH_1):P5E_CPU1_PE2_TX_C_DN(15)
   2 P5E_CPU1_PE2_TX_DN<15>      2 @S9S_MB_2U_LIB.S9S_MB_2U(SCH_1):P5E_CPU1_PE2_TX_DN(15)

Q_CAP_DIFFBUS_C0201-DIFF BUS_0A  I229  C740
   1 P5E_CPU1_PE0_TX_C_DN<0>      1 @S9S_MB_2U_LIB.S9S_MB_2U(SCH_1):P5E_CPU1_PE0_TX_C_DN(0)
   2 P5E_CPU1_PE0_TX_DN<0>      2 @S9S_MB_2U_LIB.S9S_MB_2U(SCH_1):P5E_CPU1_PE0_TX_DN(0)

Q_CAP_DIFFBUS_C0201-DIFF BUS_0A  I230  C741
   1 P5E_CPU1_PE0_TX_C_DP<0>      1 @S9S_MB_2U_LIB.S9S_MB_2U(SCH_1):P5E_CPU1_PE0_TX_C_DP(0)
   2 P5E_CPU1_PE0_TX_DP<0>      2 @S9S_MB_2U_LIB.S9S_MB_2U(SCH_1):P5E_CPU1_PE0_TX_DP(0)

Q_CAP_DIFFBUS_C0201-DIFF BUS_0A  I231  C739
   1 P5E_CPU1_PE0_TX_C_DP<1>      1 @S9S_MB_2U_LIB.S9S_MB_2U(SCH_1):P5E_CPU1_PE0_TX_C_DP(1)
   2 P5E_CPU1_PE0_TX_DP<1>      2 @S9S_MB_2U_LIB.S9S_MB_2U(SCH_1):P5E_CPU1_PE0_TX_DP(1)

Q_CAP_DIFFBUS_C0201-DIFF BUS_0A  I232  C738
   1 P5E_CPU1_PE0_TX_C_DN<1>      1 @S9S_MB_2U_LIB.S9S_MB_2U(SCH_1):P5E_CPU1_PE0_TX_C_DN(1)
   2 P5E_CPU1_PE0_TX_DN<1>      2 @S9S_MB_2U_LIB.S9S_MB_2U(SCH_1):P5E_CPU1_PE0_TX_DN(1)

Q_CAP_DIFFBUS_C0201-DIFF BUS_0A  I233  C737
   1 P5E_CPU1_PE0_TX_C_DP<2>      1 @S9S_MB_2U_LIB.S9S_MB_2U(SCH_1):P5E_CPU1_PE0_TX_C_DP(2)
   2 P5E_CPU1_PE0_TX_DP<2>      2 @S9S_MB_2U_LIB.S9S_MB_2U(SCH_1):P5E_CPU1_PE0_TX_DP(2)

Q_CAP_DIFFBUS_C0201-DIFF BUS_0A  I234  C736
   1 P5E_CPU1_PE0_TX_C_DN<2>      1 @S9S_MB_2U_LIB.S9S_MB_2U(SCH_1):P5E_CPU1_PE0_TX_C_DN(2)
   2 P5E_CPU1_PE0_TX_DN<2>      2 @S9S_MB_2U_LIB.S9S_MB_2U(SCH_1):P5E_CPU1_PE0_TX_DN(2)

Q_CAP_DIFFBUS_C0201-DIFF BUS_0A  I235  C734
   1 P5E_CPU1_PE0_TX_C_DN<3>      1 @S9S_MB_2U_LIB.S9S_MB_2U(SCH_1):P5E_CPU1_PE0_TX_C_DN(3)
   2 P5E_CPU1_PE0_TX_DN<3>      2 @S9S_MB_2U_LIB.S9S_MB_2U(SCH_1):P5E_CPU1_PE0_TX_DN(3)

Q_CAP_DIFFBUS_C0201-DIFF BUS_0A  I236  C735
   1 P5E_CPU1_PE0_TX_C_DP<3>      1 @S9S_MB_2U_LIB.S9S_MB_2U(SCH_1):P5E_CPU1_PE0_TX_C_DP(3)
   2 P5E_CPU1_PE0_TX_DP<3>      2 @S9S_MB_2U_LIB.S9S_MB_2U(SCH_1):P5E_CPU1_PE0_TX_DP(3)

Q_CAP_DIFFBUS_C0201-DIFF BUS_0A  I237  C733
   1 P5E_CPU1_PE0_TX_C_DP<4>      1 @S9S_MB_2U_LIB.S9S_MB_2U(SCH_1):P5E_CPU1_PE0_TX_C_DP(4)
   2 P5E_CPU1_PE0_TX_DP<4>      2 @S9S_MB_2U_LIB.S9S_MB_2U(SCH_1):P5E_CPU1_PE0_TX_DP(4)

Q_CAP_DIFFBUS_C0201-DIFF BUS_0A  I246  C732
   1 P5E_CPU1_PE0_TX_C_DN<4>      1 @S9S_MB_2U_LIB.S9S_MB_2U(SCH_1):P5E_CPU1_PE0_TX_C_DN(4)
   2 P5E_CPU1_PE0_TX_DN<4>      2 @S9S_MB_2U_LIB.S9S_MB_2U(SCH_1):P5E_CPU1_PE0_TX_DN(4)

Q_CAP_DIFFBUS_C0201-DIFF BUS_0A  I247  C731
   1 P5E_CPU1_PE0_TX_C_DP<5>      1 @S9S_MB_2U_LIB.S9S_MB_2U(SCH_1):P5E_CPU1_PE0_TX_C_DP(5)
   2 P5E_CPU1_PE0_TX_DP<5>      2 @S9S_MB_2U_LIB.S9S_MB_2U(SCH_1):P5E_CPU1_PE0_TX_DP(5)

Q_CAP_DIFFBUS_C0201-DIFF BUS_0A  I248  C730
   1 P5E_CPU1_PE0_TX_C_DN<5>      1 @S9S_MB_2U_LIB.S9S_MB_2U(SCH_1):P5E_CPU1_PE0_TX_C_DN(5)
   2 P5E_CPU1_PE0_TX_DN<5>      2 @S9S_MB_2U_LIB.S9S_MB_2U(SCH_1):P5E_CPU1_PE0_TX_DN(5)

Q_CAP_DIFFBUS_C0201-DIFF BUS_0A  I249  C729
   1 P5E_CPU1_PE0_TX_C_DP<6>      1 @S9S_MB_2U_LIB.S9S_MB_2U(SCH_1):P5E_CPU1_PE0_TX_C_DP(6)
   2 P5E_CPU1_PE0_TX_DP<6>      2 @S9S_MB_2U_LIB.S9S_MB_2U(SCH_1):P5E_CPU1_PE0_TX_DP(6)

Q_CAP_DIFFBUS_C0201-DIFF BUS_0A  I250  C728
   1 P5E_CPU1_PE0_TX_C_DN<6>      1 @S9S_MB_2U_LIB.S9S_MB_2U(SCH_1):P5E_CPU1_PE0_TX_C_DN(6)
   2 P5E_CPU1_PE0_TX_DN<6>      2 @S9S_MB_2U_LIB.S9S_MB_2U(SCH_1):P5E_CPU1_PE0_TX_DN(6)

Q_CAP_DIFFBUS_C0201-DIFF BUS_0A  I251  C727
   1 P5E_CPU1_PE0_TX_C_DP<7>      1 @S9S_MB_2U_LIB.S9S_MB_2U(SCH_1):P5E_CPU1_PE0_TX_C_DP(7)
   2 P5E_CPU1_PE0_TX_DP<7>      2 @S9S_MB_2U_LIB.S9S_MB_2U(SCH_1):P5E_CPU1_PE0_TX_DP(7)

Q_CAP_DIFFBUS_C0201-DIFF BUS_0A  I274  C725
   1 P5E_CPU1_PE0_TX_C_DP<8>      1 @S9S_MB_2U_LIB.S9S_MB_2U(SCH_1):P5E_CPU1_PE0_TX_C_DP(8)
   2 P5E_CPU1_PE0_TX_DP<8>      2 @S9S_MB_2U_LIB.S9S_MB_2U(SCH_1):P5E_CPU1_PE0_TX_DP(8)

Q_CAP_DIFFBUS_C0201-DIFF BUS_0A  I275  C724
   1 P5E_CPU1_PE0_TX_C_DN<8>      1 @S9S_MB_2U_LIB.S9S_MB_2U(SCH_1):P5E_CPU1_PE0_TX_C_DN(8)
   2 P5E_CPU1_PE0_TX_DN<8>      2 @S9S_MB_2U_LIB.S9S_MB_2U(SCH_1):P5E_CPU1_PE0_TX_DN(8)

Q_CAP_DIFFBUS_C0201-DIFF BUS_0A  I276  C722
   1 P5E_CPU1_PE0_TX_C_DN<9>      1 @S9S_MB_2U_LIB.S9S_MB_2U(SCH_1):P5E_CPU1_PE0_TX_C_DN(9)
   2 P5E_CPU1_PE0_TX_DN<9>      2 @S9S_MB_2U_LIB.S9S_MB_2U(SCH_1):P5E_CPU1_PE0_TX_DN(9)

Q_CAP_DIFFBUS_C0201-DIFF BUS_0A  I277  C723
   1 P5E_CPU1_PE0_TX_C_DP<9>      1 @S9S_MB_2U_LIB.S9S_MB_2U(SCH_1):P5E_CPU1_PE0_TX_C_DP(9)
   2 P5E_CPU1_PE0_TX_DP<9>      2 @S9S_MB_2U_LIB.S9S_MB_2U(SCH_1):P5E_CPU1_PE0_TX_DP(9)

Q_CAP_DIFFBUS_C0201-DIFF BUS_0A  I278  C721
   1 P5E_CPU1_PE0_TX_C_DP<10>      1 @S9S_MB_2U_LIB.S9S_MB_2U(SCH_1):P5E_CPU1_PE0_TX_C_DP(10)
   2 P5E_CPU1_PE0_TX_DP<10>      2 @S9S_MB_2U_LIB.S9S_MB_2U(SCH_1):P5E_CPU1_PE0_TX_DP(10)

Q_CAP_DIFFBUS_C0201-DIFF BUS_0A  I279  C720
   1 P5E_CPU1_PE0_TX_C_DN<10>      1 @S9S_MB_2U_LIB.S9S_MB_2U(SCH_1):P5E_CPU1_PE0_TX_C_DN(10)
   2 P5E_CPU1_PE0_TX_DN<10>      2 @S9S_MB_2U_LIB.S9S_MB_2U(SCH_1):P5E_CPU1_PE0_TX_DN(10)

Q_CAP_DIFFBUS_C0201-DIFF BUS_0A  I280  C719
   1 P5E_CPU1_PE0_TX_C_DP<11>      1 @S9S_MB_2U_LIB.S9S_MB_2U(SCH_1):P5E_CPU1_PE0_TX_C_DP(11)
   2 P5E_CPU1_PE0_TX_DP<11>      2 @S9S_MB_2U_LIB.S9S_MB_2U(SCH_1):P5E_CPU1_PE0_TX_DP(11)

Q_CAP_DIFFBUS_C0201-DIFF BUS_0A  I281  C718
   1 P5E_CPU1_PE0_TX_C_DN<11>      1 @S9S_MB_2U_LIB.S9S_MB_2U(SCH_1):P5E_CPU1_PE0_TX_C_DN(11)
   2 P5E_CPU1_PE0_TX_DN<11>      2 @S9S_MB_2U_LIB.S9S_MB_2U(SCH_1):P5E_CPU1_PE0_TX_DN(11)

Q_CAP_DIFFBUS_C0201-DIFF BUS_0A  I282  C717
   1 P5E_CPU1_PE0_TX_C_DP<12>      1 @S9S_MB_2U_LIB.S9S_MB_2U(SCH_1):P5E_CPU1_PE0_TX_C_DP(12)
   2 P5E_CPU1_PE0_TX_DP<12>      2 @S9S_MB_2U_LIB.S9S_MB_2U(SCH_1):P5E_CPU1_PE0_TX_DP(12)

Q_CAP_DIFFBUS_C0201-DIFF BUS_0A  I283  C716
   1 P5E_CPU1_PE0_TX_C_DN<12>      1 @S9S_MB_2U_LIB.S9S_MB_2U(SCH_1):P5E_CPU1_PE0_TX_C_DN(12)
   2 P5E_CPU1_PE0_TX_DN<12>      2 @S9S_MB_2U_LIB.S9S_MB_2U(SCH_1):P5E_CPU1_PE0_TX_DN(12)

Q_CAP_DIFFBUS_C0201-DIFF BUS_0A  I294  C715
   1 P5E_CPU1_PE0_TX_C_DP<13>      1 @S9S_MB_2U_LIB.S9S_MB_2U(SCH_1):P5E_CPU1_PE0_TX_C_DP(13)
   2 P5E_CPU1_PE0_TX_DP<13>      2 @S9S_MB_2U_LIB.S9S_MB_2U(SCH_1):P5E_CPU1_PE0_TX_DP(13)

Q_CAP_DIFFBUS_C0201-DIFF BUS_0A  I295  C714
   1 P5E_CPU1_PE0_TX_C_DN<13>      1 @S9S_MB_2U_LIB.S9S_MB_2U(SCH_1):P5E_CPU1_PE0_TX_C_DN(13)
   2 P5E_CPU1_PE0_TX_DN<13>      2 @S9S_MB_2U_LIB.S9S_MB_2U(SCH_1):P5E_CPU1_PE0_TX_DN(13)

Q_CAP_DIFFBUS_C0201-DIFF BUS_0A  I296  C712
   1 P5E_CPU1_PE0_TX_C_DN<14>      1 @S9S_MB_2U_LIB.S9S_MB_2U(SCH_1):P5E_CPU1_PE0_TX_C_DN(14)
   2 P5E_CPU1_PE0_TX_DN<14>      2 @S9S_MB_2U_LIB.S9S_MB_2U(SCH_1):P5E_CPU1_PE0_TX_DN(14)

Q_CAP_DIFFBUS_C0201-DIFF BUS_0A  I297  C713
   1 P5E_CPU1_PE0_TX_C_DP<14>      1 @S9S_MB_2U_LIB.S9S_MB_2U(SCH_1):P5E_CPU1_PE0_TX_C_DP(14)
   2 P5E_CPU1_PE0_TX_DP<14>      2 @S9S_MB_2U_LIB.S9S_MB_2U(SCH_1):P5E_CPU1_PE0_TX_DP(14)

Q_CAP_DIFFBUS_C0201-DIFF BUS_0A  I298  C711
   1 P5E_CPU1_PE0_TX_C_DP<15>      1 @S9S_MB_2U_LIB.S9S_MB_2U(SCH_1):P5E_CPU1_PE0_TX_C_DP(15)
   2 P5E_CPU1_PE0_TX_DP<15>      2 @S9S_MB_2U_LIB.S9S_MB_2U(SCH_1):P5E_CPU1_PE0_TX_DP(15)

Q_CAP_DIFFBUS_C0201-DIFF BUS_0A  I299  C710
   1 P5E_CPU1_PE0_TX_C_DN<15>      1 @S9S_MB_2U_LIB.S9S_MB_2U(SCH_1):P5E_CPU1_PE0_TX_C_DN(15)
   2 P5E_CPU1_PE0_TX_DN<15>      2 @S9S_MB_2U_LIB.S9S_MB_2U(SCH_1):P5E_CPU1_PE0_TX_DN(15)

Q_CAP_DIFFBUS_C0201-DIFF BUS_0A  I312  C726
   1 P5E_CPU1_PE0_TX_C_DN<7>      1 @S9S_MB_2U_LIB.S9S_MB_2U(SCH_1):P5E_CPU1_PE0_TX_C_DN(7)
   2 P5E_CPU1_PE0_TX_DN<7>      2 @S9S_MB_2U_LIB.S9S_MB_2U(SCH_1):P5E_CPU1_PE0_TX_DN(7)


DRAWING: @S9S_MB_2U_LIB.S9S_MB_2U(SCH_1):PAGE168 

Q_CAP_DIFFBUS_C0201-DIFF BUS_0A  I125  C708
   1 P5E_CPU1_PE4_TX_C_DN<0>      1 @S9S_MB_2U_LIB.S9S_MB_2U(SCH_1):P5E_CPU1_PE4_TX_C_DN(0)
   2 P5E_CPU1_PE4_TX_DN<0>      2 @S9S_MB_2U_LIB.S9S_MB_2U(SCH_1):P5E_CPU1_PE4_TX_DN(0)

Q_CAP_DIFFBUS_C0201-DIFF BUS_0A  I126  C709
   1 P5E_CPU1_PE4_TX_C_DP<0>      1 @S9S_MB_2U_LIB.S9S_MB_2U(SCH_1):P5E_CPU1_PE4_TX_C_DP(0)
   2 P5E_CPU1_PE4_TX_DP<0>      2 @S9S_MB_2U_LIB.S9S_MB_2U(SCH_1):P5E_CPU1_PE4_TX_DP(0)

Q_CAP_DIFFBUS_C0201-DIFF BUS_0A  I127  C706
   1 P5E_CPU1_PE4_TX_C_DN<1>      1 @S9S_MB_2U_LIB.S9S_MB_2U(SCH_1):P5E_CPU1_PE4_TX_C_DN(1)
   2 P5E_CPU1_PE4_TX_DN<1>      2 @S9S_MB_2U_LIB.S9S_MB_2U(SCH_1):P5E_CPU1_PE4_TX_DN(1)

Q_CAP_DIFFBUS_C0201-DIFF BUS_0A  I128  C707
   1 P5E_CPU1_PE4_TX_C_DP<1>      1 @S9S_MB_2U_LIB.S9S_MB_2U(SCH_1):P5E_CPU1_PE4_TX_C_DP(1)
   2 P5E_CPU1_PE4_TX_DP<1>      2 @S9S_MB_2U_LIB.S9S_MB_2U(SCH_1):P5E_CPU1_PE4_TX_DP(1)

Q_CAP_DIFFBUS_C0201-DIFF BUS_0A  I129  C704
   1 P5E_CPU1_PE4_TX_C_DN<2>      1 @S9S_MB_2U_LIB.S9S_MB_2U(SCH_1):P5E_CPU1_PE4_TX_C_DN(2)
   2 P5E_CPU1_PE4_TX_DN<2>      2 @S9S_MB_2U_LIB.S9S_MB_2U(SCH_1):P5E_CPU1_PE4_TX_DN(2)

Q_CAP_DIFFBUS_C0201-DIFF BUS_0A  I130  C705
   1 P5E_CPU1_PE4_TX_C_DP<2>      1 @S9S_MB_2U_LIB.S9S_MB_2U(SCH_1):P5E_CPU1_PE4_TX_C_DP(2)
   2 P5E_CPU1_PE4_TX_DP<2>      2 @S9S_MB_2U_LIB.S9S_MB_2U(SCH_1):P5E_CPU1_PE4_TX_DP(2)

Q_CAP_DIFFBUS_C0201-DIFF BUS_0A  I131  C701
   1 P5E_CPU1_PE4_TX_C_DP<4>      1 @S9S_MB_2U_LIB.S9S_MB_2U(SCH_1):P5E_CPU1_PE4_TX_C_DP(4)
   2 P5E_CPU1_PE4_TX_DP<4>      2 @S9S_MB_2U_LIB.S9S_MB_2U(SCH_1):P5E_CPU1_PE4_TX_DP(4)

Q_CAP_DIFFBUS_C0201-DIFF BUS_0A  I132  C702
   1 P5E_CPU1_PE4_TX_C_DN<3>      1 @S9S_MB_2U_LIB.S9S_MB_2U(SCH_1):P5E_CPU1_PE4_TX_C_DN(3)
   2 P5E_CPU1_PE4_TX_DN<3>      2 @S9S_MB_2U_LIB.S9S_MB_2U(SCH_1):P5E_CPU1_PE4_TX_DN(3)

Q_CAP_DIFFBUS_C0201-DIFF BUS_0A  I133  C703
   1 P5E_CPU1_PE4_TX_C_DP<3>      1 @S9S_MB_2U_LIB.S9S_MB_2U(SCH_1):P5E_CPU1_PE4_TX_C_DP(3)
   2 P5E_CPU1_PE4_TX_DP<3>      2 @S9S_MB_2U_LIB.S9S_MB_2U(SCH_1):P5E_CPU1_PE4_TX_DP(3)

Q_CAP_DIFFBUS_C0201-DIFF BUS_0A  I134  C700
   1 P5E_CPU1_PE4_TX_C_DN<4>      1 @S9S_MB_2U_LIB.S9S_MB_2U(SCH_1):P5E_CPU1_PE4_TX_C_DN(4)
   2 P5E_CPU1_PE4_TX_DN<4>      2 @S9S_MB_2U_LIB.S9S_MB_2U(SCH_1):P5E_CPU1_PE4_TX_DN(4)

Q_CAP_DIFFBUS_C0201-DIFF BUS_0A  I135  C698
   1 P5E_CPU1_PE4_TX_C_DN<5>      1 @S9S_MB_2U_LIB.S9S_MB_2U(SCH_1):P5E_CPU1_PE4_TX_C_DN(5)
   2 P5E_CPU1_PE4_TX_DN<5>      2 @S9S_MB_2U_LIB.S9S_MB_2U(SCH_1):P5E_CPU1_PE4_TX_DN(5)

Q_CAP_DIFFBUS_C0201-DIFF BUS_0A  I136  C699
   1 P5E_CPU1_PE4_TX_C_DP<5>      1 @S9S_MB_2U_LIB.S9S_MB_2U(SCH_1):P5E_CPU1_PE4_TX_C_DP(5)
   2 P5E_CPU1_PE4_TX_DP<5>      2 @S9S_MB_2U_LIB.S9S_MB_2U(SCH_1):P5E_CPU1_PE4_TX_DP(5)

Q_CAP_DIFFBUS_C0201-DIFF BUS_0A  I137  C696
   1 P5E_CPU1_PE4_TX_C_DN<6>      1 @S9S_MB_2U_LIB.S9S_MB_2U(SCH_1):P5E_CPU1_PE4_TX_C_DN(6)
   2 P5E_CPU1_PE4_TX_DN<6>      2 @S9S_MB_2U_LIB.S9S_MB_2U(SCH_1):P5E_CPU1_PE4_TX_DN(6)

Q_CAP_DIFFBUS_C0201-DIFF BUS_0A  I138  C697
   1 P5E_CPU1_PE4_TX_C_DP<6>      1 @S9S_MB_2U_LIB.S9S_MB_2U(SCH_1):P5E_CPU1_PE4_TX_C_DP(6)
   2 P5E_CPU1_PE4_TX_DP<6>      2 @S9S_MB_2U_LIB.S9S_MB_2U(SCH_1):P5E_CPU1_PE4_TX_DP(6)

Q_CAP_DIFFBUS_C0201-DIFF BUS_0A  I139  C695
   1 P5E_CPU1_PE4_TX_C_DP<7>      1 @S9S_MB_2U_LIB.S9S_MB_2U(SCH_1):P5E_CPU1_PE4_TX_C_DP(7)
   2 P5E_CPU1_PE4_TX_DP<7>      2 @S9S_MB_2U_LIB.S9S_MB_2U(SCH_1):P5E_CPU1_PE4_TX_DP(7)

Q_CAP_DIFFBUS_C0201-DIFF BUS_0A  I140  C694
   1 P5E_CPU1_PE4_TX_C_DN<7>      1 @S9S_MB_2U_LIB.S9S_MB_2U(SCH_1):P5E_CPU1_PE4_TX_C_DN(7)
   2 P5E_CPU1_PE4_TX_DN<7>      2 @S9S_MB_2U_LIB.S9S_MB_2U(SCH_1):P5E_CPU1_PE4_TX_DN(7)

Q_CAP_DIFFBUS_C0201-DIFF BUS_0A  I157  C693
   1 P5E_CPU1_PE4_TX_C_DP<8>      1 @S9S_MB_2U_LIB.S9S_MB_2U(SCH_1):P5E_CPU1_PE4_TX_C_DP(8)
   2 P5E_CPU1_PE4_TX_DP<8>      2 @S9S_MB_2U_LIB.S9S_MB_2U(SCH_1):P5E_CPU1_PE4_TX_DP(8)

Q_CAP_DIFFBUS_C0201-DIFF BUS_0A  I158  C692
   1 P5E_CPU1_PE4_TX_C_DN<8>      1 @S9S_MB_2U_LIB.S9S_MB_2U(SCH_1):P5E_CPU1_PE4_TX_C_DN(8)
   2 P5E_CPU1_PE4_TX_DN<8>      2 @S9S_MB_2U_LIB.S9S_MB_2U(SCH_1):P5E_CPU1_PE4_TX_DN(8)

Q_CAP_DIFFBUS_C0201-DIFF BUS_0A  I159  C690
   1 P5E_CPU1_PE4_TX_C_DN<9>      1 @S9S_MB_2U_LIB.S9S_MB_2U(SCH_1):P5E_CPU1_PE4_TX_C_DN(9)
   2 P5E_CPU1_PE4_TX_DN<9>      2 @S9S_MB_2U_LIB.S9S_MB_2U(SCH_1):P5E_CPU1_PE4_TX_DN(9)

Q_CAP_DIFFBUS_C0201-DIFF BUS_0A  I160  C691
   1 P5E_CPU1_PE4_TX_C_DP<9>      1 @S9S_MB_2U_LIB.S9S_MB_2U(SCH_1):P5E_CPU1_PE4_TX_C_DP(9)
   2 P5E_CPU1_PE4_TX_DP<9>      2 @S9S_MB_2U_LIB.S9S_MB_2U(SCH_1):P5E_CPU1_PE4_TX_DP(9)

Q_CAP_DIFFBUS_C0201-DIFF BUS_0A  I161  C687
   1 P5E_CPU1_PE4_TX_C_DP<11>      1 @S9S_MB_2U_LIB.S9S_MB_2U(SCH_1):P5E_CPU1_PE4_TX_C_DP(11)
   2 P5E_CPU1_PE4_TX_DP<11>      2 @S9S_MB_2U_LIB.S9S_MB_2U(SCH_1):P5E_CPU1_PE4_TX_DP(11)

Q_CAP_DIFFBUS_C0201-DIFF BUS_0A  I162  C688
   1 P5E_CPU1_PE4_TX_C_DN<10>      1 @S9S_MB_2U_LIB.S9S_MB_2U(SCH_1):P5E_CPU1_PE4_TX_C_DN(10)
   2 P5E_CPU1_PE4_TX_DN<10>      2 @S9S_MB_2U_LIB.S9S_MB_2U(SCH_1):P5E_CPU1_PE4_TX_DN(10)

Q_CAP_DIFFBUS_C0201-DIFF BUS_0A  I163  C689
   1 P5E_CPU1_PE4_TX_C_DP<10>      1 @S9S_MB_2U_LIB.S9S_MB_2U(SCH_1):P5E_CPU1_PE4_TX_C_DP(10)
   2 P5E_CPU1_PE4_TX_DP<10>      2 @S9S_MB_2U_LIB.S9S_MB_2U(SCH_1):P5E_CPU1_PE4_TX_DP(10)

Q_CAP_DIFFBUS_C0201-DIFF BUS_0A  I164  C686
   1 P5E_CPU1_PE4_TX_C_DN<11>      1 @S9S_MB_2U_LIB.S9S_MB_2U(SCH_1):P5E_CPU1_PE4_TX_C_DN(11)
   2 P5E_CPU1_PE4_TX_DN<11>      2 @S9S_MB_2U_LIB.S9S_MB_2U(SCH_1):P5E_CPU1_PE4_TX_DN(11)

Q_CAP_DIFFBUS_C0201-DIFF BUS_0A  I165  C685
   1 P5E_CPU1_PE4_TX_C_DP<12>      1 @S9S_MB_2U_LIB.S9S_MB_2U(SCH_1):P5E_CPU1_PE4_TX_C_DP(12)
   2 P5E_CPU1_PE4_TX_DP<12>      2 @S9S_MB_2U_LIB.S9S_MB_2U(SCH_1):P5E_CPU1_PE4_TX_DP(12)

Q_CAP_DIFFBUS_C0201-DIFF BUS_0A  I166  C684
   1 P5E_CPU1_PE4_TX_C_DN<12>      1 @S9S_MB_2U_LIB.S9S_MB_2U(SCH_1):P5E_CPU1_PE4_TX_C_DN(12)
   2 P5E_CPU1_PE4_TX_DN<12>      2 @S9S_MB_2U_LIB.S9S_MB_2U(SCH_1):P5E_CPU1_PE4_TX_DN(12)

Q_CAP_DIFFBUS_C0201-DIFF BUS_0A  I167  C682
   1 P5E_CPU1_PE4_TX_C_DN<13>      1 @S9S_MB_2U_LIB.S9S_MB_2U(SCH_1):P5E_CPU1_PE4_TX_C_DN(13)
   2 P5E_CPU1_PE4_TX_DN<13>      2 @S9S_MB_2U_LIB.S9S_MB_2U(SCH_1):P5E_CPU1_PE4_TX_DN(13)

Q_CAP_DIFFBUS_C0201-DIFF BUS_0A  I168  C683
   1 P5E_CPU1_PE4_TX_C_DP<13>      1 @S9S_MB_2U_LIB.S9S_MB_2U(SCH_1):P5E_CPU1_PE4_TX_C_DP(13)
   2 P5E_CPU1_PE4_TX_DP<13>      2 @S9S_MB_2U_LIB.S9S_MB_2U(SCH_1):P5E_CPU1_PE4_TX_DP(13)

Q_CAP_DIFFBUS_C0201-DIFF BUS_0A  I169  C679
   1 P5E_CPU1_PE4_TX_C_DP<15>      1 @S9S_MB_2U_LIB.S9S_MB_2U(SCH_1):P5E_CPU1_PE4_TX_C_DP(15)
   2 P5E_CPU1_PE4_TX_DP<15>      2 @S9S_MB_2U_LIB.S9S_MB_2U(SCH_1):P5E_CPU1_PE4_TX_DP(15)

Q_CAP_DIFFBUS_C0201-DIFF BUS_0A  I170  C680
   1 P5E_CPU1_PE4_TX_C_DN<14>      1 @S9S_MB_2U_LIB.S9S_MB_2U(SCH_1):P5E_CPU1_PE4_TX_C_DN(14)
   2 P5E_CPU1_PE4_TX_DN<14>      2 @S9S_MB_2U_LIB.S9S_MB_2U(SCH_1):P5E_CPU1_PE4_TX_DN(14)

Q_CAP_DIFFBUS_C0201-DIFF BUS_0A  I171  C681
   1 P5E_CPU1_PE4_TX_C_DP<14>      1 @S9S_MB_2U_LIB.S9S_MB_2U(SCH_1):P5E_CPU1_PE4_TX_C_DP(14)
   2 P5E_CPU1_PE4_TX_DP<14>      2 @S9S_MB_2U_LIB.S9S_MB_2U(SCH_1):P5E_CPU1_PE4_TX_DP(14)

Q_CAP_DIFFBUS_C0201-DIFF BUS_0A  I172  C678
   1 P5E_CPU1_PE4_TX_C_DN<15>      1 @S9S_MB_2U_LIB.S9S_MB_2U(SCH_1):P5E_CPU1_PE4_TX_C_DN(15)
   2 P5E_CPU1_PE4_TX_DN<15>      2 @S9S_MB_2U_LIB.S9S_MB_2U(SCH_1):P5E_CPU1_PE4_TX_DN(15)

Q_CAP_DIFFBUS_C0201-DIFF BUS_0A  I229  C1547
   1 P5E_CPU1_PE3_TX_C_DP<0>      1 @S9S_MB_2U_LIB.S9S_MB_2U(SCH_1):P5E_CPU1_PE3_TX_C_DP(0)
   2 P5E_CPU1_PE3_TX_DP<0>      2 @S9S_MB_2U_LIB.S9S_MB_2U(SCH_1):P5E_CPU1_PE3_TX_DP(0)

Q_CAP_DIFFBUS_C0201-DIFF BUS_0A  I230  C1546
   1 P5E_CPU1_PE3_TX_C_DN<0>      1 @S9S_MB_2U_LIB.S9S_MB_2U(SCH_1):P5E_CPU1_PE3_TX_C_DN(0)
   2 P5E_CPU1_PE3_TX_DN<0>      2 @S9S_MB_2U_LIB.S9S_MB_2U(SCH_1):P5E_CPU1_PE3_TX_DN(0)

Q_CAP_DIFFBUS_C0201-DIFF BUS_0A  I231  C1545
   1 P5E_CPU1_PE3_TX_C_DP<1>      1 @S9S_MB_2U_LIB.S9S_MB_2U(SCH_1):P5E_CPU1_PE3_TX_C_DP(1)
   2 P5E_CPU1_PE3_TX_DP<1>      2 @S9S_MB_2U_LIB.S9S_MB_2U(SCH_1):P5E_CPU1_PE3_TX_DP(1)

Q_CAP_DIFFBUS_C0201-DIFF BUS_0A  I232  C1544
   1 P5E_CPU1_PE3_TX_C_DN<1>      1 @S9S_MB_2U_LIB.S9S_MB_2U(SCH_1):P5E_CPU1_PE3_TX_C_DN(1)
   2 P5E_CPU1_PE3_TX_DN<1>      2 @S9S_MB_2U_LIB.S9S_MB_2U(SCH_1):P5E_CPU1_PE3_TX_DN(1)

Q_CAP_DIFFBUS_C0201-DIFF BUS_0A  I233  C1542
   1 P5E_CPU1_PE3_TX_C_DN<2>      1 @S9S_MB_2U_LIB.S9S_MB_2U(SCH_1):P5E_CPU1_PE3_TX_C_DN(2)
   2 P5E_CPU1_PE3_TX_DN<2>      2 @S9S_MB_2U_LIB.S9S_MB_2U(SCH_1):P5E_CPU1_PE3_TX_DN(2)

Q_CAP_DIFFBUS_C0201-DIFF BUS_0A  I234  C1543
   1 P5E_CPU1_PE3_TX_C_DP<2>      1 @S9S_MB_2U_LIB.S9S_MB_2U(SCH_1):P5E_CPU1_PE3_TX_C_DP(2)
   2 P5E_CPU1_PE3_TX_DP<2>      2 @S9S_MB_2U_LIB.S9S_MB_2U(SCH_1):P5E_CPU1_PE3_TX_DP(2)

Q_CAP_DIFFBUS_C0201-DIFF BUS_0A  I235  C1541
   1 P5E_CPU1_PE3_TX_C_DP<3>      1 @S9S_MB_2U_LIB.S9S_MB_2U(SCH_1):P5E_CPU1_PE3_TX_C_DP(3)
   2 P5E_CPU1_PE3_TX_DP<3>      2 @S9S_MB_2U_LIB.S9S_MB_2U(SCH_1):P5E_CPU1_PE3_TX_DP(3)

Q_CAP_DIFFBUS_C0201-DIFF BUS_0A  I236  C1540
   1 P5E_CPU1_PE3_TX_C_DN<3>      1 @S9S_MB_2U_LIB.S9S_MB_2U(SCH_1):P5E_CPU1_PE3_TX_C_DN(3)
   2 P5E_CPU1_PE3_TX_DN<3>      2 @S9S_MB_2U_LIB.S9S_MB_2U(SCH_1):P5E_CPU1_PE3_TX_DN(3)

Q_CAP_DIFFBUS_C0201-DIFF BUS_0A  I237  C1539
   1 P5E_CPU1_PE3_TX_C_DP<4>      1 @S9S_MB_2U_LIB.S9S_MB_2U(SCH_1):P5E_CPU1_PE3_TX_C_DP(4)
   2 P5E_CPU1_PE3_TX_DP<4>      2 @S9S_MB_2U_LIB.S9S_MB_2U(SCH_1):P5E_CPU1_PE3_TX_DP(4)

Q_CAP_DIFFBUS_C0201-DIFF BUS_0A  I238  C1538
   1 P5E_CPU1_PE3_TX_C_DN<4>      1 @S9S_MB_2U_LIB.S9S_MB_2U(SCH_1):P5E_CPU1_PE3_TX_C_DN(4)
   2 P5E_CPU1_PE3_TX_DN<4>      2 @S9S_MB_2U_LIB.S9S_MB_2U(SCH_1):P5E_CPU1_PE3_TX_DN(4)

Q_CAP_DIFFBUS_C0201-DIFF BUS_0A  I249  C1537
   1 P5E_CPU1_PE3_TX_C_DP<5>      1 @S9S_MB_2U_LIB.S9S_MB_2U(SCH_1):P5E_CPU1_PE3_TX_C_DP(5)
   2 P5E_CPU1_PE3_TX_DP<5>      2 @S9S_MB_2U_LIB.S9S_MB_2U(SCH_1):P5E_CPU1_PE3_TX_DP(5)

Q_CAP_DIFFBUS_C0201-DIFF BUS_0A  I250  C1536
   1 P5E_CPU1_PE3_TX_C_DN<5>      1 @S9S_MB_2U_LIB.S9S_MB_2U(SCH_1):P5E_CPU1_PE3_TX_C_DN(5)
   2 P5E_CPU1_PE3_TX_DN<5>      2 @S9S_MB_2U_LIB.S9S_MB_2U(SCH_1):P5E_CPU1_PE3_TX_DN(5)

Q_CAP_DIFFBUS_C0201-DIFF BUS_0A  I251  C1534
   1 P5E_CPU1_PE3_TX_C_DN<6>      1 @S9S_MB_2U_LIB.S9S_MB_2U(SCH_1):P5E_CPU1_PE3_TX_C_DN(6)
   2 P5E_CPU1_PE3_TX_DN<6>      2 @S9S_MB_2U_LIB.S9S_MB_2U(SCH_1):P5E_CPU1_PE3_TX_DN(6)

Q_CAP_DIFFBUS_C0201-DIFF BUS_0A  I252  C1535
   1 P5E_CPU1_PE3_TX_C_DP<6>      1 @S9S_MB_2U_LIB.S9S_MB_2U(SCH_1):P5E_CPU1_PE3_TX_C_DP(6)
   2 P5E_CPU1_PE3_TX_DP<6>      2 @S9S_MB_2U_LIB.S9S_MB_2U(SCH_1):P5E_CPU1_PE3_TX_DP(6)

Q_CAP_DIFFBUS_C0201-DIFF BUS_0A  I253  C1533
   1 P5E_CPU1_PE3_TX_C_DP<7>      1 @S9S_MB_2U_LIB.S9S_MB_2U(SCH_1):P5E_CPU1_PE3_TX_C_DP(7)
   2 P5E_CPU1_PE3_TX_DP<7>      2 @S9S_MB_2U_LIB.S9S_MB_2U(SCH_1):P5E_CPU1_PE3_TX_DP(7)

Q_CAP_DIFFBUS_C0201-DIFF BUS_0A  I254  C1532
   1 P5E_CPU1_PE3_TX_C_DN<7>      1 @S9S_MB_2U_LIB.S9S_MB_2U(SCH_1):P5E_CPU1_PE3_TX_C_DN(7)
   2 P5E_CPU1_PE3_TX_DN<7>      2 @S9S_MB_2U_LIB.S9S_MB_2U(SCH_1):P5E_CPU1_PE3_TX_DN(7)

Q_CAP_DIFFBUS_C0201-DIFF BUS_0A  I277  C1530
   1 P5E_CPU1_PE3_TX_C_DN<8>      1 @S9S_MB_2U_LIB.S9S_MB_2U(SCH_1):P5E_CPU1_PE3_TX_C_DN(8)
   2 P5E_CPU1_PE3_TX_DN<8>      2 @S9S_MB_2U_LIB.S9S_MB_2U(SCH_1):P5E_CPU1_PE3_TX_DN(8)

Q_CAP_DIFFBUS_C0201-DIFF BUS_0A  I278  C1531
   1 P5E_CPU1_PE3_TX_C_DP<8>      1 @S9S_MB_2U_LIB.S9S_MB_2U(SCH_1):P5E_CPU1_PE3_TX_C_DP(8)
   2 P5E_CPU1_PE3_TX_DP<8>      2 @S9S_MB_2U_LIB.S9S_MB_2U(SCH_1):P5E_CPU1_PE3_TX_DP(8)

Q_CAP_DIFFBUS_C0201-DIFF BUS_0A  I279  C1529
   1 P5E_CPU1_PE3_TX_C_DP<9>      1 @S9S_MB_2U_LIB.S9S_MB_2U(SCH_1):P5E_CPU1_PE3_TX_C_DP(9)
   2 P5E_CPU1_PE3_TX_DP<9>      2 @S9S_MB_2U_LIB.S9S_MB_2U(SCH_1):P5E_CPU1_PE3_TX_DP(9)

Q_CAP_DIFFBUS_C0201-DIFF BUS_0A  I280  C1528
   1 P5E_CPU1_PE3_TX_C_DN<9>      1 @S9S_MB_2U_LIB.S9S_MB_2U(SCH_1):P5E_CPU1_PE3_TX_C_DN(9)
   2 P5E_CPU1_PE3_TX_DN<9>      2 @S9S_MB_2U_LIB.S9S_MB_2U(SCH_1):P5E_CPU1_PE3_TX_DN(9)

Q_CAP_DIFFBUS_C0201-DIFF BUS_0A  I281  C1527
   1 P5E_CPU1_PE3_TX_C_DP<10>      1 @S9S_MB_2U_LIB.S9S_MB_2U(SCH_1):P5E_CPU1_PE3_TX_C_DP(10)
   2 P5E_CPU1_PE3_TX_DP<10>      2 @S9S_MB_2U_LIB.S9S_MB_2U(SCH_1):P5E_CPU1_PE3_TX_DP(10)

Q_CAP_DIFFBUS_C0201-DIFF BUS_0A  I282  C1526
   1 P5E_CPU1_PE3_TX_C_DN<10>      1 @S9S_MB_2U_LIB.S9S_MB_2U(SCH_1):P5E_CPU1_PE3_TX_C_DN(10)
   2 P5E_CPU1_PE3_TX_DN<10>      2 @S9S_MB_2U_LIB.S9S_MB_2U(SCH_1):P5E_CPU1_PE3_TX_DN(10)

Q_CAP_DIFFBUS_C0201-DIFF BUS_0A  I283  C1525
   1 P5E_CPU1_PE3_TX_C_DP<11>      1 @S9S_MB_2U_LIB.S9S_MB_2U(SCH_1):P5E_CPU1_PE3_TX_C_DP(11)
   2 P5E_CPU1_PE3_TX_DP<11>      2 @S9S_MB_2U_LIB.S9S_MB_2U(SCH_1):P5E_CPU1_PE3_TX_DP(11)

Q_CAP_DIFFBUS_C0201-DIFF BUS_0A  I284  C1524
   1 P5E_CPU1_PE3_TX_C_DN<11>      1 @S9S_MB_2U_LIB.S9S_MB_2U(SCH_1):P5E_CPU1_PE3_TX_C_DN(11)
   2 P5E_CPU1_PE3_TX_DN<11>      2 @S9S_MB_2U_LIB.S9S_MB_2U(SCH_1):P5E_CPU1_PE3_TX_DN(11)

Q_CAP_DIFFBUS_C0201-DIFF BUS_0A  I285  C1523
   1 P5E_CPU1_PE3_TX_C_DP<12>      1 @S9S_MB_2U_LIB.S9S_MB_2U(SCH_1):P5E_CPU1_PE3_TX_C_DP(12)
   2 P5E_CPU1_PE3_TX_DP<12>      2 @S9S_MB_2U_LIB.S9S_MB_2U(SCH_1):P5E_CPU1_PE3_TX_DP(12)

Q_CAP_DIFFBUS_C0201-DIFF BUS_0A  I286  C1522
   1 P5E_CPU1_PE3_TX_C_DN<12>      1 @S9S_MB_2U_LIB.S9S_MB_2U(SCH_1):P5E_CPU1_PE3_TX_C_DN(12)
   2 P5E_CPU1_PE3_TX_DN<12>      2 @S9S_MB_2U_LIB.S9S_MB_2U(SCH_1):P5E_CPU1_PE3_TX_DN(12)

Q_CAP_DIFFBUS_C0201-DIFF BUS_0A  I297  C1520
   1 P5E_CPU1_PE3_TX_C_DN<13>      1 @S9S_MB_2U_LIB.S9S_MB_2U(SCH_1):P5E_CPU1_PE3_TX_C_DN(13)
   2 P5E_CPU1_PE3_TX_DN<13>      2 @S9S_MB_2U_LIB.S9S_MB_2U(SCH_1):P5E_CPU1_PE3_TX_DN(13)

Q_CAP_DIFFBUS_C0201-DIFF BUS_0A  I298  C1521
   1 P5E_CPU1_PE3_TX_C_DP<13>      1 @S9S_MB_2U_LIB.S9S_MB_2U(SCH_1):P5E_CPU1_PE3_TX_C_DP(13)
   2 P5E_CPU1_PE3_TX_DP<13>      2 @S9S_MB_2U_LIB.S9S_MB_2U(SCH_1):P5E_CPU1_PE3_TX_DP(13)

Q_CAP_DIFFBUS_C0201-DIFF BUS_0A  I299  C1519
   1 P5E_CPU1_PE3_TX_C_DP<14>      1 @S9S_MB_2U_LIB.S9S_MB_2U(SCH_1):P5E_CPU1_PE3_TX_C_DP(14)
   2 P5E_CPU1_PE3_TX_DP<14>      2 @S9S_MB_2U_LIB.S9S_MB_2U(SCH_1):P5E_CPU1_PE3_TX_DP(14)

Q_CAP_DIFFBUS_C0201-DIFF BUS_0A  I300  C1518
   1 P5E_CPU1_PE3_TX_C_DN<14>      1 @S9S_MB_2U_LIB.S9S_MB_2U(SCH_1):P5E_CPU1_PE3_TX_C_DN(14)
   2 P5E_CPU1_PE3_TX_DN<14>      2 @S9S_MB_2U_LIB.S9S_MB_2U(SCH_1):P5E_CPU1_PE3_TX_DN(14)

Q_CAP_DIFFBUS_C0201-DIFF BUS_0A  I301  C1517
   1 P5E_CPU1_PE3_TX_C_DP<15>      1 @S9S_MB_2U_LIB.S9S_MB_2U(SCH_1):P5E_CPU1_PE3_TX_C_DP(15)
   2 P5E_CPU1_PE3_TX_DP<15>      2 @S9S_MB_2U_LIB.S9S_MB_2U(SCH_1):P5E_CPU1_PE3_TX_DP(15)

Q_CAP_DIFFBUS_C0201-DIFF BUS_0A  I302  C1516
   1 P5E_CPU1_PE3_TX_C_DN<15>      1 @S9S_MB_2U_LIB.S9S_MB_2U(SCH_1):P5E_CPU1_PE3_TX_C_DN(15)
   2 P5E_CPU1_PE3_TX_DN<15>      2 @S9S_MB_2U_LIB.S9S_MB_2U(SCH_1):P5E_CPU1_PE3_TX_DN(15)


DRAWING: @S9S_MB_2U_LIB.S9S_MB_2U(SCH_1):PAGE169 

Q_CAP_DIFFBUS_C0201-DIFF BUS_0A  I21  C153
   1 DMI_CPU0_PCH_TX_C_DN<0>      1 @S9S_MB_2U_LIB.S9S_MB_2U(SCH_1):DMI_CPU0_PCH_TX_C_DN(0)
   2 DMI_CPU0_PCH_TX_DN<0>      2 @S9S_MB_2U_LIB.S9S_MB_2U(SCH_1):DMI_CPU0_PCH_TX_DN(0)

Q_CAP_DIFFBUS_C0201-DIFF BUS_0A  I22  C154
   1 DMI_CPU0_PCH_TX_C_DP<0>      1 @S9S_MB_2U_LIB.S9S_MB_2U(SCH_1):DMI_CPU0_PCH_TX_C_DP(0)
   2 DMI_CPU0_PCH_TX_DP<0>      2 @S9S_MB_2U_LIB.S9S_MB_2U(SCH_1):DMI_CPU0_PCH_TX_DP(0)

Q_CAP_DIFFBUS_C0201-DIFF BUS_0A  I23  C152
   1 DMI_CPU0_PCH_TX_C_DP<1>      1 @S9S_MB_2U_LIB.S9S_MB_2U(SCH_1):DMI_CPU0_PCH_TX_C_DP(1)
   2 DMI_CPU0_PCH_TX_DP<1>      2 @S9S_MB_2U_LIB.S9S_MB_2U(SCH_1):DMI_CPU0_PCH_TX_DP(1)

Q_CAP_DIFFBUS_C0201-DIFF BUS_0A  I24  C151
   1 DMI_CPU0_PCH_TX_C_DN<1>      1 @S9S_MB_2U_LIB.S9S_MB_2U(SCH_1):DMI_CPU0_PCH_TX_C_DN(1)
   2 DMI_CPU0_PCH_TX_DN<1>      2 @S9S_MB_2U_LIB.S9S_MB_2U(SCH_1):DMI_CPU0_PCH_TX_DN(1)

Q_CAP_DIFFBUS_C0201-DIFF BUS_0A  I25  C149
   1 DMI_CPU0_PCH_TX_C_DN<2>      1 @S9S_MB_2U_LIB.S9S_MB_2U(SCH_1):DMI_CPU0_PCH_TX_C_DN(2)
   2 DMI_CPU0_PCH_TX_DN<2>      2 @S9S_MB_2U_LIB.S9S_MB_2U(SCH_1):DMI_CPU0_PCH_TX_DN(2)

Q_CAP_DIFFBUS_C0201-DIFF BUS_0A  I26  C150
   1 DMI_CPU0_PCH_TX_C_DP<2>      1 @S9S_MB_2U_LIB.S9S_MB_2U(SCH_1):DMI_CPU0_PCH_TX_C_DP(2)
   2 DMI_CPU0_PCH_TX_DP<2>      2 @S9S_MB_2U_LIB.S9S_MB_2U(SCH_1):DMI_CPU0_PCH_TX_DP(2)

Q_CAP_DIFFBUS_C0201-DIFF BUS_0A  I27  C148
   1 DMI_CPU0_PCH_TX_C_DP<3>      1 @S9S_MB_2U_LIB.S9S_MB_2U(SCH_1):DMI_CPU0_PCH_TX_C_DP(3)
   2 DMI_CPU0_PCH_TX_DP<3>      2 @S9S_MB_2U_LIB.S9S_MB_2U(SCH_1):DMI_CPU0_PCH_TX_DP(3)

Q_CAP_DIFFBUS_C0201-DIFF BUS_0A  I28  C147
   1 DMI_CPU0_PCH_TX_C_DN<3>      1 @S9S_MB_2U_LIB.S9S_MB_2U(SCH_1):DMI_CPU0_PCH_TX_C_DN(3)
   2 DMI_CPU0_PCH_TX_DN<3>      2 @S9S_MB_2U_LIB.S9S_MB_2U(SCH_1):DMI_CPU0_PCH_TX_DN(3)

Q_CAP_DIFFBUS_C0201-DIFF BUS_0A  I29  C146
   1 DMI_CPU0_PCH_TX_C_DP<4>      1 @S9S_MB_2U_LIB.S9S_MB_2U(SCH_1):DMI_CPU0_PCH_TX_C_DP(4)
   2 DMI_CPU0_PCH_TX_DP<4>      2 @S9S_MB_2U_LIB.S9S_MB_2U(SCH_1):DMI_CPU0_PCH_TX_DP(4)

Q_CAP_DIFFBUS_C0201-DIFF BUS_0A  I30  C145
   1 DMI_CPU0_PCH_TX_C_DN<4>      1 @S9S_MB_2U_LIB.S9S_MB_2U(SCH_1):DMI_CPU0_PCH_TX_C_DN(4)
   2 DMI_CPU0_PCH_TX_DN<4>      2 @S9S_MB_2U_LIB.S9S_MB_2U(SCH_1):DMI_CPU0_PCH_TX_DN(4)

Q_CAP_DIFFBUS_C0201-DIFF BUS_0A  I31  C144
   1 DMI_CPU0_PCH_TX_C_DP<5>      1 @S9S_MB_2U_LIB.S9S_MB_2U(SCH_1):DMI_CPU0_PCH_TX_C_DP(5)
   2 DMI_CPU0_PCH_TX_DP<5>      2 @S9S_MB_2U_LIB.S9S_MB_2U(SCH_1):DMI_CPU0_PCH_TX_DP(5)

Q_CAP_DIFFBUS_C0201-DIFF BUS_0A  I32  C143
   1 DMI_CPU0_PCH_TX_C_DN<5>      1 @S9S_MB_2U_LIB.S9S_MB_2U(SCH_1):DMI_CPU0_PCH_TX_C_DN(5)
   2 DMI_CPU0_PCH_TX_DN<5>      2 @S9S_MB_2U_LIB.S9S_MB_2U(SCH_1):DMI_CPU0_PCH_TX_DN(5)

Q_CAP_DIFFBUS_C0201-DIFF BUS_0A  I33  C142
   1 DMI_CPU0_PCH_TX_C_DP<6>      1 @S9S_MB_2U_LIB.S9S_MB_2U(SCH_1):DMI_CPU0_PCH_TX_C_DP(6)
   2 DMI_CPU0_PCH_TX_DP<6>      2 @S9S_MB_2U_LIB.S9S_MB_2U(SCH_1):DMI_CPU0_PCH_TX_DP(6)

Q_CAP_DIFFBUS_C0201-DIFF BUS_0A  I34  C141
   1 DMI_CPU0_PCH_TX_C_DN<6>      1 @S9S_MB_2U_LIB.S9S_MB_2U(SCH_1):DMI_CPU0_PCH_TX_C_DN(6)
   2 DMI_CPU0_PCH_TX_DN<6>      2 @S9S_MB_2U_LIB.S9S_MB_2U(SCH_1):DMI_CPU0_PCH_TX_DN(6)

Q_CAP_DIFFBUS_C0201-DIFF BUS_0A  I35  C139
   1 DMI_CPU0_PCH_TX_C_DN<7>      1 @S9S_MB_2U_LIB.S9S_MB_2U(SCH_1):DMI_CPU0_PCH_TX_C_DN(7)
   2 DMI_CPU0_PCH_TX_DN<7>      2 @S9S_MB_2U_LIB.S9S_MB_2U(SCH_1):DMI_CPU0_PCH_TX_DN(7)

Q_CAP_DIFFBUS_C0201-DIFF BUS_0A  I36  C1791
   1 DMI_CPU0_PCH_TX_C_DP<7>      1 @S9S_MB_2U_LIB.S9S_MB_2U(SCH_1):DMI_CPU0_PCH_TX_C_DP(7)
   2 DMI_CPU0_PCH_TX_DP<7>      2 @S9S_MB_2U_LIB.S9S_MB_2U(SCH_1):DMI_CPU0_PCH_TX_DP(7)

Q_CAP_DIFFBUS_C0201-DIFF BUS_0A  I113  C155
   1 DMI_CPU0_PCH_RX_C_DN<7>      1 @S9S_MB_2U_LIB.S9S_MB_2U(SCH_1):DMI_CPU0_PCH_RX_C_DN(7)
   2 DMI_CPU0_PCH_RX_DN<7>      2 @S9S_MB_2U_LIB.S9S_MB_2U(SCH_1):DMI_CPU0_PCH_RX_DN(7)

Q_CAP_DIFFBUS_C0201-DIFF BUS_0A  I114  C156
   1 DMI_CPU0_PCH_RX_C_DP<7>      1 @S9S_MB_2U_LIB.S9S_MB_2U(SCH_1):DMI_CPU0_PCH_RX_C_DP(7)
   2 DMI_CPU0_PCH_RX_DP<7>      2 @S9S_MB_2U_LIB.S9S_MB_2U(SCH_1):DMI_CPU0_PCH_RX_DP(7)

Q_CAP_DIFFBUS_C0201-DIFF BUS_0A  I115  C157
   1 DMI_CPU0_PCH_RX_C_DN<6>      1 @S9S_MB_2U_LIB.S9S_MB_2U(SCH_1):DMI_CPU0_PCH_RX_C_DN(6)
   2 DMI_CPU0_PCH_RX_DN<6>      2 @S9S_MB_2U_LIB.S9S_MB_2U(SCH_1):DMI_CPU0_PCH_RX_DN(6)

Q_CAP_DIFFBUS_C0201-DIFF BUS_0A  I116  C158
   1 DMI_CPU0_PCH_RX_C_DP<6>      1 @S9S_MB_2U_LIB.S9S_MB_2U(SCH_1):DMI_CPU0_PCH_RX_C_DP(6)
   2 DMI_CPU0_PCH_RX_DP<6>      2 @S9S_MB_2U_LIB.S9S_MB_2U(SCH_1):DMI_CPU0_PCH_RX_DP(6)

Q_CAP_DIFFBUS_C0201-DIFF BUS_0A  I117  C159
   1 DMI_CPU0_PCH_RX_C_DN<5>      1 @S9S_MB_2U_LIB.S9S_MB_2U(SCH_1):DMI_CPU0_PCH_RX_C_DN(5)
   2 DMI_CPU0_PCH_RX_DN<5>      2 @S9S_MB_2U_LIB.S9S_MB_2U(SCH_1):DMI_CPU0_PCH_RX_DN(5)

Q_CAP_DIFFBUS_C0201-DIFF BUS_0A  I118  C160
   1 DMI_CPU0_PCH_RX_C_DP<5>      1 @S9S_MB_2U_LIB.S9S_MB_2U(SCH_1):DMI_CPU0_PCH_RX_C_DP(5)
   2 DMI_CPU0_PCH_RX_DP<5>      2 @S9S_MB_2U_LIB.S9S_MB_2U(SCH_1):DMI_CPU0_PCH_RX_DP(5)

Q_CAP_DIFFBUS_C0201-DIFF BUS_0A  I119  C161
   1 DMI_CPU0_PCH_RX_C_DN<4>      1 @S9S_MB_2U_LIB.S9S_MB_2U(SCH_1):DMI_CPU0_PCH_RX_C_DN(4)
   2 DMI_CPU0_PCH_RX_DN<4>      2 @S9S_MB_2U_LIB.S9S_MB_2U(SCH_1):DMI_CPU0_PCH_RX_DN(4)

Q_CAP_DIFFBUS_C0201-DIFF BUS_0A  I120  C162
   1 DMI_CPU0_PCH_RX_C_DP<4>      1 @S9S_MB_2U_LIB.S9S_MB_2U(SCH_1):DMI_CPU0_PCH_RX_C_DP(4)
   2 DMI_CPU0_PCH_RX_DP<4>      2 @S9S_MB_2U_LIB.S9S_MB_2U(SCH_1):DMI_CPU0_PCH_RX_DP(4)

Q_CAP_DIFFBUS_C0201-DIFF BUS_0A  I121  C163
   1 DMI_CPU0_PCH_RX_C_DN<3>      1 @S9S_MB_2U_LIB.S9S_MB_2U(SCH_1):DMI_CPU0_PCH_RX_C_DN(3)
   2 DMI_CPU0_PCH_RX_DN<3>      2 @S9S_MB_2U_LIB.S9S_MB_2U(SCH_1):DMI_CPU0_PCH_RX_DN(3)

Q_CAP_DIFFBUS_C0201-DIFF BUS_0A  I122  C164
   1 DMI_CPU0_PCH_RX_C_DP<3>      1 @S9S_MB_2U_LIB.S9S_MB_2U(SCH_1):DMI_CPU0_PCH_RX_C_DP(3)
   2 DMI_CPU0_PCH_RX_DP<3>      2 @S9S_MB_2U_LIB.S9S_MB_2U(SCH_1):DMI_CPU0_PCH_RX_DP(3)

Q_CAP_DIFFBUS_C0201-DIFF BUS_0A  I123  C165
   1 DMI_CPU0_PCH_RX_C_DN<2>      1 @S9S_MB_2U_LIB.S9S_MB_2U(SCH_1):DMI_CPU0_PCH_RX_C_DN(2)
   2 DMI_CPU0_PCH_RX_DN<2>      2 @S9S_MB_2U_LIB.S9S_MB_2U(SCH_1):DMI_CPU0_PCH_RX_DN(2)

Q_CAP_DIFFBUS_C0201-DIFF BUS_0A  I124  C166
   1 DMI_CPU0_PCH_RX_C_DP<2>      1 @S9S_MB_2U_LIB.S9S_MB_2U(SCH_1):DMI_CPU0_PCH_RX_C_DP(2)
   2 DMI_CPU0_PCH_RX_DP<2>      2 @S9S_MB_2U_LIB.S9S_MB_2U(SCH_1):DMI_CPU0_PCH_RX_DP(2)

Q_CAP_DIFFBUS_C0201-DIFF BUS_0A  I125  C168
   1 DMI_CPU0_PCH_RX_C_DP<1>      1 @S9S_MB_2U_LIB.S9S_MB_2U(SCH_1):DMI_CPU0_PCH_RX_C_DP(1)
   2 DMI_CPU0_PCH_RX_DP<1>      2 @S9S_MB_2U_LIB.S9S_MB_2U(SCH_1):DMI_CPU0_PCH_RX_DP(1)

Q_CAP_DIFFBUS_C0201-DIFF BUS_0A  I126  C167
   1 DMI_CPU0_PCH_RX_C_DN<1>      1 @S9S_MB_2U_LIB.S9S_MB_2U(SCH_1):DMI_CPU0_PCH_RX_C_DN(1)
   2 DMI_CPU0_PCH_RX_DN<1>      2 @S9S_MB_2U_LIB.S9S_MB_2U(SCH_1):DMI_CPU0_PCH_RX_DN(1)

Q_CAP_DIFFBUS_C0201-DIFF BUS_0A  I127  C169
   1 DMI_CPU0_PCH_RX_C_DN<0>      1 @S9S_MB_2U_LIB.S9S_MB_2U(SCH_1):DMI_CPU0_PCH_RX_C_DN(0)
   2 DMI_CPU0_PCH_RX_DN<0>      2 @S9S_MB_2U_LIB.S9S_MB_2U(SCH_1):DMI_CPU0_PCH_RX_DN(0)

Q_CAP_DIFFBUS_C0201-DIFF BUS_0A  I128  C170
   1 DMI_CPU0_PCH_RX_C_DP<0>      1 @S9S_MB_2U_LIB.S9S_MB_2U(SCH_1):DMI_CPU0_PCH_RX_C_DP(0)
   2 DMI_CPU0_PCH_RX_DP<0>      2 @S9S_MB_2U_LIB.S9S_MB_2U(SCH_1):DMI_CPU0_PCH_RX_DP(0)


DRAWING: @S9S_MB_2U_LIB.S9S_MB_2U(SCH_1):PAGE171 

Q_CAP_0402-18PF,50V,5%,C0G,CH0A  I10  C1507
   1 XTAL_PCH_RTC2_R      A @S9S_MB_2U_LIB.S9S_MB_2U(SCH_1):XTAL_PCH_RTC2_R
   2    GND      B @S9S_MB_2U_LIB.S9S_MB_2U(SCH_1):GND

Q_CRYSTAL_SMLF-32.768KHZ,IC,BGA  I11  Y1
   1 XTAL_PCH_RTC2_R      1 @S9S_MB_2U_LIB.S9S_MB_2U(SCH_1):XTAL_PCH_RTC2_R
   2 XTAL_PCH_RTC1      2 @S9S_MB_2U_LIB.S9S_MB_2U(SCH_1):XTAL_PCH_RTC1

Q_CAP_0402-18PF,50V,5%,C0G,CH0A  I17  C1508
   1 XTAL_PCH_RTC1      A @S9S_MB_2U_LIB.S9S_MB_2U(SCH_1):XTAL_PCH_RTC1
   2    GND      B @S9S_MB_2U_LIB.S9S_MB_2U(SCH_1):GND

Q_RES_0402LF-60.4,1%,1/16W,CHIA  I69  R477
   1 PD_PCH_XCLK_BIASREF      A @S9S_MB_2U_LIB.S9S_MB_2U(SCH_1):PD_PCH_XCLK_BIASREF
   2    GND      B @S9S_MB_2U_LIB.S9S_MB_2U(SCH_1):GND

Q_RES_0603LF-10M,1%,1/10W,CHIPA  I74  R120
   1 XTAL_PCH_RTC2_R      A @S9S_MB_2U_LIB.S9S_MB_2U(SCH_1):XTAL_PCH_RTC2_R
   2 XTAL_PCH_RTC1      B @S9S_MB_2U_LIB.S9S_MB_2U(SCH_1):XTAL_PCH_RTC1

Q_XTAL_4P_13BI_24GND-25MHZ,SMLA  I75  Y7
   1 XTAL_PCH_25M_IN_R     X1 @S9S_MB_2U_LIB.S9S_MB_2U(SCH_1):XTAL_PCH_25M_IN_R
   2    GND     G1 @S9S_MB_2U_LIB.S9S_MB_2U(SCH_1):GND
   4    GND     G2 @S9S_MB_2U_LIB.S9S_MB_2U(SCH_1):GND
   3 XTAL_PCH_25M_OUT     X2 @S9S_MB_2U_LIB.S9S_MB_2U(SCH_1):XTAL_PCH_25M_OUT

Q_CAP_0402-27PF  ,50V ,5% ,EMPA  I76  C104
   1 XTAL_PCH_25M_OUT      A @S9S_MB_2U_LIB.S9S_MB_2U(SCH_1):XTAL_PCH_25M_OUT
   2    GND      B @S9S_MB_2U_LIB.S9S_MB_2U(SCH_1):GND

Q_CAP_0402-27PF  ,50V ,5% ,EMPA  I77  C103
   1 XTAL_PCH_25M_IN_R      A @S9S_MB_2U_LIB.S9S_MB_2U(SCH_1):XTAL_PCH_25M_IN_R
   2    GND      B @S9S_MB_2U_LIB.S9S_MB_2U(SCH_1):GND

EMMITSBURG_REV0P9-GFNOCPU04302A  I78  U4
 J23 TP_PCH_RSVD<19> RSVD_J23 @S9S_MB_2U_LIB.S9S_MB_2U(SCH_1):TP_PCH_RSVD(19)
 H24 TP_PCH_RSVD<18> RSVD_H24 @S9S_MB_2U_LIB.S9S_MB_2U(SCH_1):TP_PCH_RSVD(18)
 N29 PD_PCH_XCLK_BIASREF XCLK_BIASREF @S9S_MB_2U_LIB.S9S_MB_2U(SCH_1):PD_PCH_XCLK_BIASREF
 A16 TP_CLK_100M_PCH_0_DN CLKOUT_SRC_N_0 @S9S_MB_2U_LIB.S9S_MB_2U(SCH_1):TP_CLK_100M_PCH_0_DN
 G23 TP_CLK_100M_PCH_1_DN CLKOUT_SRC_N_1 @S9S_MB_2U_LIB.S9S_MB_2U(SCH_1):TP_CLK_100M_PCH_1_DN
 J16 TP_CLK_100M_PCH_10_DN CLKOUT_SRC_N_10 @S9S_MB_2U_LIB.S9S_MB_2U(SCH_1):TP_CLK_100M_PCH_10_DN
 G16 TP_CLK_100M_PCH_11_DN CLKOUT_SRC_N_11 @S9S_MB_2U_LIB.S9S_MB_2U(SCH_1):TP_CLK_100M_PCH_11_DN
 A10 TP_CLK_100M_PCH_12_DN CLKOUT_SRC_N_12 @S9S_MB_2U_LIB.S9S_MB_2U(SCH_1):TP_CLK_100M_PCH_12_DN
  A8 TP_CLK_100M_PCH_13_DN CLKOUT_SRC_N_13 @S9S_MB_2U_LIB.S9S_MB_2U(SCH_1):TP_CLK_100M_PCH_13_DN
  B7 TP_CLK_100M_PCH_14_DN CLKOUT_SRC_N_14 @S9S_MB_2U_LIB.S9S_MB_2U(SCH_1):TP_CLK_100M_PCH_14_DN
  B5 TP_CLK_100M_PCH_15_DN CLKOUT_SRC_N_15 @S9S_MB_2U_LIB.S9S_MB_2U(SCH_1):TP_CLK_100M_PCH_15_DN
 A18 TP_CLK_100M_PCH_16_DN CLKOUT_SRC_N_16 @S9S_MB_2U_LIB.S9S_MB_2U(SCH_1):TP_CLK_100M_PCH_16_DN
 H21 CLK_100M_PE_M2_0_R_DN CLKOUT_SRC_N_2 @S9S_MB_2U_LIB.S9S_MB_2U(SCH_1):CLK_100M_PE_M2_0_R_DN
 B17 CLK_100M_E1S_0_R_DN CLKOUT_SRC_N_3 @S9S_MB_2U_LIB.S9S_MB_2U(SCH_1):CLK_100M_E1S_0_R_DN
 B19 TP_CLK_100M_PCH_4_DN CLKOUT_SRC_N_4 @S9S_MB_2U_LIB.S9S_MB_2U(SCH_1):TP_CLK_100M_PCH_4_DN
 A12 TP_CLK_100M_PCH_5_DN CLKOUT_SRC_N_5 @S9S_MB_2U_LIB.S9S_MB_2U(SCH_1):TP_CLK_100M_PCH_5_DN
 B11 CLK_100M_BMC_P3E_DN CLKOUT_SRC_N_6 @S9S_MB_2U_LIB.S9S_MB_2U(SCH_1):CLK_100M_BMC_P3E_DN
 A14 TP_CLK_100M_PCH_7_DN CLKOUT_SRC_N_7 @S9S_MB_2U_LIB.S9S_MB_2U(SCH_1):TP_CLK_100M_PCH_7_DN
 F18 TP_CLK_100M_PCH_8_DN CLKOUT_SRC_N_8 @S9S_MB_2U_LIB.S9S_MB_2U(SCH_1):TP_CLK_100M_PCH_8_DN
 B15 TP_CLK_100M_PCH_9_DN CLKOUT_SRC_N_9 @S9S_MB_2U_LIB.S9S_MB_2U(SCH_1):TP_CLK_100M_PCH_9_DN
 C16 TP_CLK_100M_PCH_0_DP CLKOUT_SRC_P_0 @S9S_MB_2U_LIB.S9S_MB_2U(SCH_1):TP_CLK_100M_PCH_0_DP
 F21 TP_CLK_100M_PCH_1_DP CLKOUT_SRC_P_1 @S9S_MB_2U_LIB.S9S_MB_2U(SCH_1):TP_CLK_100M_PCH_1_DP
 K18 TP_CLK_100M_PCH_10_DP CLKOUT_SRC_P_10 @S9S_MB_2U_LIB.S9S_MB_2U(SCH_1):TP_CLK_100M_PCH_10_DP
 H15 TP_CLK_100M_PCH_11_DP CLKOUT_SRC_P_11 @S9S_MB_2U_LIB.S9S_MB_2U(SCH_1):TP_CLK_100M_PCH_11_DP
 C10 TP_CLK_100M_PCH_12_DP CLKOUT_SRC_P_12 @S9S_MB_2U_LIB.S9S_MB_2U(SCH_1):TP_CLK_100M_PCH_12_DP
  C8 TP_CLK_100M_PCH_13_DP CLKOUT_SRC_P_13 @S9S_MB_2U_LIB.S9S_MB_2U(SCH_1):TP_CLK_100M_PCH_13_DP
  D7 TP_CLK_100M_PCH_14_DP CLKOUT_SRC_P_14 @S9S_MB_2U_LIB.S9S_MB_2U(SCH_1):TP_CLK_100M_PCH_14_DP
  C6 TP_CLK_100M_PCH_15_DP CLKOUT_SRC_P_15 @S9S_MB_2U_LIB.S9S_MB_2U(SCH_1):TP_CLK_100M_PCH_15_DP
 C18 TP_CLK_100M_PCH_16_DP CLKOUT_SRC_P_16 @S9S_MB_2U_LIB.S9S_MB_2U(SCH_1):TP_CLK_100M_PCH_16_DP
 K21 CLK_100M_PE_M2_0_R_DP CLKOUT_SRC_P_2 @S9S_MB_2U_LIB.S9S_MB_2U(SCH_1):CLK_100M_PE_M2_0_R_DP
 D17 CLK_100M_E1S_0_R_DP CLKOUT_SRC_P_3 @S9S_MB_2U_LIB.S9S_MB_2U(SCH_1):CLK_100M_E1S_0_R_DP
 D19 TP_CLK_100M_PCH_4_DP CLKOUT_SRC_P_4 @S9S_MB_2U_LIB.S9S_MB_2U(SCH_1):TP_CLK_100M_PCH_4_DP
 C12 TP_CLK_100M_PCH_5_DP CLKOUT_SRC_P_5 @S9S_MB_2U_LIB.S9S_MB_2U(SCH_1):TP_CLK_100M_PCH_5_DP
 D11 CLK_100M_BMC_P3E_DP CLKOUT_SRC_P_6 @S9S_MB_2U_LIB.S9S_MB_2U(SCH_1):CLK_100M_BMC_P3E_DP
 C14 TP_CLK_100M_PCH_7_DP CLKOUT_SRC_P_7 @S9S_MB_2U_LIB.S9S_MB_2U(SCH_1):TP_CLK_100M_PCH_7_DP
 H18 TP_CLK_100M_PCH_8_DP CLKOUT_SRC_P_8 @S9S_MB_2U_LIB.S9S_MB_2U(SCH_1):TP_CLK_100M_PCH_8_DP
 D15 TP_CLK_100M_PCH_9_DP CLKOUT_SRC_P_9 @S9S_MB_2U_LIB.S9S_MB_2U(SCH_1):TP_CLK_100M_PCH_9_DP
 D27 CLK_25M_PCH_CPU0_DN PMSYNC_CLK_N_0 @S9S_MB_2U_LIB.S9S_MB_2U(SCH_1):CLK_25M_PCH_CPU0_DN
 C28 CLK_25M_PCH_CPU1_DN PMSYNC_CLK_N_1 @S9S_MB_2U_LIB.S9S_MB_2U(SCH_1):CLK_25M_PCH_CPU1_DN
 B27 CLK_25M_PCH_CPU0_DP PMSYNC_CLK_P_0 @S9S_MB_2U_LIB.S9S_MB_2U(SCH_1):CLK_25M_PCH_CPU0_DP
 A28 CLK_25M_PCH_CPU1_DP PMSYNC_CLK_P_1 @S9S_MB_2U_LIB.S9S_MB_2U(SCH_1):CLK_25M_PCH_CPU1_DP
 D25 CLK_25M_PCH_REF_NS_DN REFCLK_INJ_NS_N @S9S_MB_2U_LIB.S9S_MB_2U(SCH_1):CLK_25M_PCH_REF_NS_DN
 B25 CLK_25M_PCH_REF_NS_DP REFCLK_INJ_NS_P @S9S_MB_2U_LIB.S9S_MB_2U(SCH_1):CLK_25M_PCH_REF_NS_DP
 D21 CLK_100M_CK440_PCH_EXTCLK_DN REFCLK_INJ_S_N @S9S_MB_2U_LIB.S9S_MB_2U(SCH_1):CLK_100M_CK440_PCH_EXTCLK_DN
 B21 CLK_100M_CK440_PCH_EXTCLK_DP REFCLK_INJ_S_P @S9S_MB_2U_LIB.S9S_MB_2U(SCH_1):CLK_100M_CK440_PCH_EXTCLK_DP
 BE6 XTAL_PCH_RTC1  RTCX1 @S9S_MB_2U_LIB.S9S_MB_2U(SCH_1):XTAL_PCH_RTC1
 BF7 XTAL_PCH_RTC2  RTCX2 @S9S_MB_2U_LIB.S9S_MB_2U(SCH_1):XTAL_PCH_RTC2
 BF5 RTC_EXT_CAP RTC_EXTCAP @S9S_MB_2U_LIB.S9S_MB_2U(SCH_1):RTC_EXT_CAP
 B23 XTAL_PCH_25M_IN XTAL_IN @S9S_MB_2U_LIB.S9S_MB_2U(SCH_1):XTAL_PCH_25M_IN
 D23 XTAL_PCH_25M_OUT XTAL_OUT @S9S_MB_2U_LIB.S9S_MB_2U(SCH_1):XTAL_PCH_25M_OUT

Q_CAP_0402-0.1UF,25V,10%,X7R,CA  I89  C609
   1 RTC_EXT_CAP      A @S9S_MB_2U_LIB.S9S_MB_2U(SCH_1):RTC_EXT_CAP
   2    GND      B @S9S_MB_2U_LIB.S9S_MB_2U(SCH_1):GND

Q_RES_0603LF-200K,0.1%,1/10W,EA  I92  R1316
   1 XTAL_PCH_25M_IN_R      A @S9S_MB_2U_LIB.S9S_MB_2U(SCH_1):XTAL_PCH_25M_IN_R
   2 XTAL_PCH_25M_OUT      B @S9S_MB_2U_LIB.S9S_MB_2U(SCH_1):XTAL_PCH_25M_OUT

Q_RES_0402LF-0,5%,1/16W,EMPTY,A  I103  R1720
   1 XTAL_PCH_25M_IN_R      A @S9S_MB_2U_LIB.S9S_MB_2U(SCH_1):XTAL_PCH_25M_IN_R
   2 XTAL_PCH_25M_IN      B @S9S_MB_2U_LIB.S9S_MB_2U(SCH_1):XTAL_PCH_25M_IN

Q_RES_0402LF-0,5%,1/16W,CHIP,CA  I104  R1721
   1 XTAL_PCH_RTC2_R      A @S9S_MB_2U_LIB.S9S_MB_2U(SCH_1):XTAL_PCH_RTC2_R
   2 XTAL_PCH_RTC2      B @S9S_MB_2U_LIB.S9S_MB_2U(SCH_1):XTAL_PCH_RTC2

Q_RES_0402LF-0,5%,1/16W,CHIP,CA  I116  R4305
   1 CLK_100M_PE_M2_0_R_DP      A @S9S_MB_2U_LIB.S9S_MB_2U(SCH_1):CLK_100M_PE_M2_0_R_DP
   2 CLK_100M_PE_M2_0_DP      B @S9S_MB_2U_LIB.S9S_MB_2U(SCH_1):CLK_100M_PE_M2_0_DP

Q_RES_0402LF-0,5%,1/16W,CHIP,CA  I117  R4306
   1 CLK_100M_PE_M2_0_R_DN      A @S9S_MB_2U_LIB.S9S_MB_2U(SCH_1):CLK_100M_PE_M2_0_R_DN
   2 CLK_100M_PE_M2_0_DN      B @S9S_MB_2U_LIB.S9S_MB_2U(SCH_1):CLK_100M_PE_M2_0_DN

Q_RES_0402LF-22,1%,1/16W,CHIP,A  I121  R4303
   1 CLK_100M_E1S_0_R_DP      A @S9S_MB_2U_LIB.S9S_MB_2U(SCH_1):CLK_100M_E1S_0_R_DP
   2 CLK_100M_E1S_0_DP      B @S9S_MB_2U_LIB.S9S_MB_2U(SCH_1):CLK_100M_E1S_0_DP

Q_RES_0402LF-22,1%,1/16W,CHIP,A  I122  R4304
   1 CLK_100M_E1S_0_R_DN      A @S9S_MB_2U_LIB.S9S_MB_2U(SCH_1):CLK_100M_E1S_0_R_DN
   2 CLK_100M_E1S_0_DN      B @S9S_MB_2U_LIB.S9S_MB_2U(SCH_1):CLK_100M_E1S_0_DN


DRAWING: @S9S_MB_2U_LIB.S9S_MB_2U(SCH_1):PAGE172 

Q_RES_0402LF-113,1%,1/16W,CHIPA  I10  R496
   1 PD_PCH_USB2_COMP      A @S9S_MB_2U_LIB.S9S_MB_2U(SCH_1):PD_PCH_USB2_COMP
   2    GND      B @S9S_MB_2U_LIB.S9S_MB_2U(SCH_1):GND

EMMITSBURG_REV0P9-GFNOCPU04302A  I11  U4
BC40 NC_PCH_RSVD<14> RSVD_BC40 @S9S_MB_2U_LIB.S9S_MB_2U(SCH_1):NC_PCH_RSVD(14)
AR42 USB2_0_DN USB2N_0 @S9S_MB_2U_LIB.S9S_MB_2U(SCH_1):USB2_0_DN
AP43 TP_USB2_1_DN USB2N_1 @S9S_MB_2U_LIB.S9S_MB_2U(SCH_1):TP_USB2_1_DN
AY43 TP_USB2_10_DN USB2N_10 @S9S_MB_2U_LIB.S9S_MB_2U(SCH_1):TP_USB2_10_DN
AH42 TP_USB2_11_DN USB2N_11 @S9S_MB_2U_LIB.S9S_MB_2U(SCH_1):TP_USB2_11_DN
BA42 TP_USB2_12_DN USB2N_12 @S9S_MB_2U_LIB.S9S_MB_2U(SCH_1):TP_USB2_12_DN
AG43 TP_USB2_13_DN USB2N_13 @S9S_MB_2U_LIB.S9S_MB_2U(SCH_1):TP_USB2_13_DN
AT43 TP_USB2_2_DN USB2N_2 @S9S_MB_2U_LIB.S9S_MB_2U(SCH_1):TP_USB2_2_DN
AN42 USB2_3_DN USB2N_3 @S9S_MB_2U_LIB.S9S_MB_2U(SCH_1):USB2_3_DN
AU42 TP_USB2_4_DN USB2N_4 @S9S_MB_2U_LIB.S9S_MB_2U(SCH_1):TP_USB2_4_DN
AL43 USB2_5_DN USB2N_5 @S9S_MB_2U_LIB.S9S_MB_2U(SCH_1):USB2_5_DN
AV43 TP_USB2_6_DN USB2N_6 @S9S_MB_2U_LIB.S9S_MB_2U(SCH_1):TP_USB2_6_DN
AK42 USB2_7_DN USB2N_7 @S9S_MB_2U_LIB.S9S_MB_2U(SCH_1):USB2_7_DN
AW42 USB2_8_DN USB2N_8 @S9S_MB_2U_LIB.S9S_MB_2U(SCH_1):USB2_8_DN
AJ43 TP_USB2_9_DN USB2N_9 @S9S_MB_2U_LIB.S9S_MB_2U(SCH_1):TP_USB2_9_DN
AR40 USB2_0_DP USB2P_0 @S9S_MB_2U_LIB.S9S_MB_2U(SCH_1):USB2_0_DP
AP41 TP_USB2_1_DP USB2P_1 @S9S_MB_2U_LIB.S9S_MB_2U(SCH_1):TP_USB2_1_DP
AY41 TP_USB2_10_DP USB2P_10 @S9S_MB_2U_LIB.S9S_MB_2U(SCH_1):TP_USB2_10_DP
AH40 TP_USB2_11_DP USB2P_11 @S9S_MB_2U_LIB.S9S_MB_2U(SCH_1):TP_USB2_11_DP
BA40 TP_USB2_12_DP USB2P_12 @S9S_MB_2U_LIB.S9S_MB_2U(SCH_1):TP_USB2_12_DP
AG41 TP_USB2_13_DP USB2P_13 @S9S_MB_2U_LIB.S9S_MB_2U(SCH_1):TP_USB2_13_DP
AT41 TP_USB2_2_DP USB2P_2 @S9S_MB_2U_LIB.S9S_MB_2U(SCH_1):TP_USB2_2_DP
AN40 USB2_3_DP USB2P_3 @S9S_MB_2U_LIB.S9S_MB_2U(SCH_1):USB2_3_DP
AU40 TP_USB2_4_DP USB2P_4 @S9S_MB_2U_LIB.S9S_MB_2U(SCH_1):TP_USB2_4_DP
AL41 USB2_5_DP USB2P_5 @S9S_MB_2U_LIB.S9S_MB_2U(SCH_1):USB2_5_DP
AV41 TP_USB2_6_DP USB2P_6 @S9S_MB_2U_LIB.S9S_MB_2U(SCH_1):TP_USB2_6_DP
AK40 USB2_7_DP USB2P_7 @S9S_MB_2U_LIB.S9S_MB_2U(SCH_1):USB2_7_DP
AW40 USB2_8_DP USB2P_8 @S9S_MB_2U_LIB.S9S_MB_2U(SCH_1):USB2_8_DP
AJ41 TP_USB2_9_DP USB2P_9 @S9S_MB_2U_LIB.S9S_MB_2U(SCH_1):TP_USB2_9_DP
BB41 PD_PCH_USB2_COMP USB2_COMP @S9S_MB_2U_LIB.S9S_MB_2U(SCH_1):PD_PCH_USB2_COMP


DRAWING: @S9S_MB_2U_LIB.S9S_MB_2U(SCH_1):PAGE174 

EMMITSBURG_REV0P9-GFNOCPU04302A  I36  U4
 AN7 PU_ACPRESENT ACPRESENT @S9S_MB_2U_LIB.S9S_MB_2U(SCH_1):PU_ACPRESENT
 G10 PWRGD_CPUPWRGD_GTL CPUPWRGD @S9S_MB_2U_LIB.S9S_MB_2U(SCH_1):PWRGD_CPUPWRGD_GTL
  F8 FM_PCIE_EV_BIF_EN CPU_CATERR_N @S9S_MB_2U_LIB.S9S_MB_2U(SCH_1):FM_PCIE_EV_BIF_EN
  J7 H_CPU_ERR0_PCH_R_N CPU_ERR0_N @S9S_MB_2U_LIB.S9S_MB_2U(SCH_1):H_CPU_ERR0_PCH_R_N
  G7 H_CPU_ERR1_PCH_R_N CPU_ERR1_N @S9S_MB_2U_LIB.S9S_MB_2U(SCH_1):H_CPU_ERR1_PCH_R_N
  L7 H_CPU_ERR2_PCH_R_N CPU_ERR2_N @S9S_MB_2U_LIB.S9S_MB_2U(SCH_1):H_CPU_ERR2_PCH_R_N
  E4 TP_PCH_CPU_MEMTRIP_N CPU_MEMTRIP_N @S9S_MB_2U_LIB.S9S_MB_2U(SCH_1):TP_PCH_CPU_MEMTRIP_N
 F11 TP_PCH_CPU_MSMI_N CPU_MSMI_N @S9S_MB_2U_LIB.S9S_MB_2U(SCH_1):TP_PCH_CPU_MSMI_N
  F5 FM_PCH_CPU_PWR_DEBUG_N CPU_PWR_DEBUG_N @S9S_MB_2U_LIB.S9S_MB_2U(SCH_1):FM_PCH_CPU_PWR_DEBUG_N
  F3 H_THERMTRIP_LVC1_N CPU_THRMTRIP_N @S9S_MB_2U_LIB.S9S_MB_2U(SCH_1):H_THERMTRIP_LVC1_N
BE40 JTAG_DBP_PMODE DBG_PMODE @S9S_MB_2U_LIB.S9S_MB_2U(SCH_1):JTAG_DBP_PMODE
 BE8 PWRGD_DSW_PWROK DSW_PWROK @S9S_MB_2U_LIB.S9S_MB_2U(SCH_1):PWRGD_DSW_PWROK
AN10 FM_PCH_SPARE0 GPP_O_0 @S9S_MB_2U_LIB.S9S_MB_2U(SCH_1):FM_PCH_SPARE0
AU10 FM_PCH_SKIP_RTC_CLOCK GPP_O_7 @S9S_MB_2U_LIB.S9S_MB_2U(SCH_1):FM_PCH_SKIP_RTC_CLOCK
 BG8 FM_INTRUDER_HDR_PCH_N INTRUDER_N @S9S_MB_2U_LIB.S9S_MB_2U(SCH_1):FM_INTRUDER_HDR_PCH_N
BD35 JTAG_DBP_CPU_GTL_TCK  JTAGX @S9S_MB_2U_LIB.S9S_MB_2U(SCH_1):JTAG_DBP_CPU_GTL_TCK
BF35 JTAG_DBP_TCK_PCH JTAG_TCK @S9S_MB_2U_LIB.S9S_MB_2U(SCH_1):JTAG_DBP_TCK_PCH
BE38 JTAG_DBP_TDI_PCH JTAG_TDI @S9S_MB_2U_LIB.S9S_MB_2U(SCH_1):JTAG_DBP_TDI_PCH
BE36 JTAG_DBP_TDO_PCH JTAG_TDO @S9S_MB_2U_LIB.S9S_MB_2U(SCH_1):JTAG_DBP_TDO_PCH
BD37 JTAG_DBP_TMS_PCH JTAG_TMS @S9S_MB_2U_LIB.S9S_MB_2U(SCH_1):JTAG_DBP_TMS_PCH
 AJ7 TP_PCH_GPP_O_11 LANPHYPC @S9S_MB_2U_LIB.S9S_MB_2U(SCH_1):TP_PCH_GPP_O_11
 AU7 PU_LAN_WAKE_N LAN_WAKE_N @S9S_MB_2U_LIB.S9S_MB_2U(SCH_1):PU_LAN_WAKE_N
 J10 PECI_PCH ME_PECI @S9S_MB_2U_LIB.S9S_MB_2U(SCH_1):PECI_PCH
 BE4 PWRGD_PCH_PWROK PCH_PWROK @S9S_MB_2U_LIB.S9S_MB_2U(SCH_1):PWRGD_PCH_PWROK
  M8 TP_PLTRST_N PLTRST_CPU_N @S9S_MB_2U_LIB.S9S_MB_2U(SCH_1):TP_PLTRST_N
BB37 H_DBP_PRDY_N_PCH PRDY_N @S9S_MB_2U_LIB.S9S_MB_2U(SCH_1):H_DBP_PRDY_N_PCH
BF37 H_DBP_PREQ_N_PCH PREQ_N @S9S_MB_2U_LIB.S9S_MB_2U(SCH_1):H_DBP_PREQ_N_PCH
AR10 FM_BMC_PWRBTN_N PWRBTN_N @S9S_MB_2U_LIB.S9S_MB_2U(SCH_1):FM_BMC_PWRBTN_N
 BD9 RST_RSMRST_PCH_N RSMRST_N @S9S_MB_2U_LIB.S9S_MB_2U(SCH_1):RST_RSMRST_PCH_N
BG36 NC_PCH_RSVD<17> RSVD_BG36 @S9S_MB_2U_LIB.S9S_MB_2U(SCH_1):NC_PCH_RSVD(17)
BF39 NC_PCH_RSVD<5> RSVD_BF39 @S9S_MB_2U_LIB.S9S_MB_2U(SCH_1):NC_PCH_RSVD(5)
AV21 NC_PCH_RSVD<4> RSVD_AV21 @S9S_MB_2U_LIB.S9S_MB_2U(SCH_1):NC_PCH_RSVD(4)
AW26 NC_PCH_RSVD<3> RSVD_AW23 @S9S_MB_2U_LIB.S9S_MB_2U(SCH_1):NC_PCH_RSVD(3)
AM11 TP_PCH_SLP_A_N SLP_A_N @S9S_MB_2U_LIB.S9S_MB_2U(SCH_1):TP_PCH_SLP_A_N
 AK8 TP_SLP_LAN_N SLP_LAN_N @S9S_MB_2U_LIB.S9S_MB_2U(SCH_1):TP_SLP_LAN_N
 AP8 FM_PCH_SLP_S3_N SLP_S3_N @S9S_MB_2U_LIB.S9S_MB_2U(SCH_1):FM_PCH_SLP_S3_N
AL13 FM_PCH_SLP_S4_N SLP_S4_N @S9S_MB_2U_LIB.S9S_MB_2U(SCH_1):FM_PCH_SLP_S4_N
AJ13 TP_PCH_SLP_S5_N SLP_S5_N @S9S_MB_2U_LIB.S9S_MB_2U(SCH_1):TP_PCH_SLP_S5_N
 AL7 FM_PCH_SLP_SUS_N SLP_SUS_N @S9S_MB_2U_LIB.S9S_MB_2U(SCH_1):FM_PCH_SLP_SUS_N
 AR7 PD_SUSCLK SUSCLK @S9S_MB_2U_LIB.S9S_MB_2U(SCH_1):PD_SUSCLK
AL10 PWRGD_SYS_PWROK SYS_PWROK @S9S_MB_2U_LIB.S9S_MB_2U(SCH_1):PWRGD_SYS_PWROK
AJ10 RST_PCH_RSTBTN_R_N SYS_RESET_N @S9S_MB_2U_LIB.S9S_MB_2U(SCH_1):RST_PCH_RSTBTN_R_N
 H11 FM_PCH_TRIGGER0_R_N TRIGGER0_N @S9S_MB_2U_LIB.S9S_MB_2U(SCH_1):FM_PCH_TRIGGER0_R_N
  K8 FM_PCH_TRIGGER1_R_N TRIGGER1_N @S9S_MB_2U_LIB.S9S_MB_2U(SCH_1):FM_PCH_TRIGGER1_R_N
AH11 IRQ_LVC3_WAKE_N WAKE_N @S9S_MB_2U_LIB.S9S_MB_2U(SCH_1):IRQ_LVC3_WAKE_N

Q_RES_0402LF-1K,1%,1/16W,CHIP,A  I37  R1026
   1 JTAG_DBP_PMODE      A @S9S_MB_2U_LIB.S9S_MB_2U(SCH_1):JTAG_DBP_PMODE
   2 P1V05_PCH_AUX      B @S9S_MB_2U_LIB.S9S_MB_2U(SCH_1):P1V05_PCH_AUX

Q_RES_0402LF-75,1%,1/16W,EMPTYA  I38  R1025
   1 JTAG_DBP_CPU_GTL_TCK      A @S9S_MB_2U_LIB.S9S_MB_2U(SCH_1):JTAG_DBP_CPU_GTL_TCK
   2    GND      B @S9S_MB_2U_LIB.S9S_MB_2U(SCH_1):GND

Q_RES_0402LF-100,1%,1/16W,CHIPA  I41  R1024
   1 JTAG_DBP_TCK_PCH      A @S9S_MB_2U_LIB.S9S_MB_2U(SCH_1):JTAG_DBP_TCK_PCH
   2    GND      B @S9S_MB_2U_LIB.S9S_MB_2U(SCH_1):GND

Q_RES_0402LF-10K,1%,1/16W,CHIPA  I48  R1198
   1 P3V3_AUX      A @S9S_MB_2U_LIB.S9S_MB_2U(SCH_1):P3V3_AUX
   2 PU_ACPRESENT      B @S9S_MB_2U_LIB.S9S_MB_2U(SCH_1):PU_ACPRESENT

Q_RES_0402LF-1K,1%,1/16W,EMPTYA  I50  R1197
   1    GND      A @S9S_MB_2U_LIB.S9S_MB_2U(SCH_1):GND
   2 PD_SUSCLK      B @S9S_MB_2U_LIB.S9S_MB_2U(SCH_1):PD_SUSCLK

Q_RES_0402LF-49.9,1%,1/16W,CHIA  I58  R1201
   1 FM_PCH_TRIGGER1_N      A @S9S_MB_2U_LIB.S9S_MB_2U(SCH_1):FM_PCH_TRIGGER1_N
   2 FM_PCH_TRIGGER1_R_N      B @S9S_MB_2U_LIB.S9S_MB_2U(SCH_1):FM_PCH_TRIGGER1_R_N

Q_RES_0402LF-100,1%,1/16W,CHIPA  I60  R1200
   1 FM_PCH_TRIGGER0_N      A @S9S_MB_2U_LIB.S9S_MB_2U(SCH_1):FM_PCH_TRIGGER0_N
   2 FM_PCH_TRIGGER0_R_N      B @S9S_MB_2U_LIB.S9S_MB_2U(SCH_1):FM_PCH_TRIGGER0_R_N

Q_RES_0402LF-4.75K,1%,1/16W,CHA  I63  R696
   1 P3V3_AUX      A @S9S_MB_2U_LIB.S9S_MB_2U(SCH_1):P3V3_AUX
   2 RST_PCH_RSTBTN_R_N      B @S9S_MB_2U_LIB.S9S_MB_2U(SCH_1):RST_PCH_RSTBTN_R_N

Q_RES_0402LF-33.2,1%,1/16W,CHIA  I66  R697
   1 FM_BMC_RSTBTN_OUT_N      A @S9S_MB_2U_LIB.S9S_MB_2U(SCH_1):FM_BMC_RSTBTN_OUT_N
   2 RST_PCH_RSTBTN_R_N      B @S9S_MB_2U_LIB.S9S_MB_2U(SCH_1):RST_PCH_RSTBTN_R_N

Q_RES_0402LF-200,1%,1/16W,EMPTA  I74  R1486
   1 PVNN_TERM_CPU0      A @S9S_MB_2U_LIB.S9S_MB_2U(SCH_1):PVNN_TERM_CPU0
   2 FM_PCH_TRIGGER1_R_N      B @S9S_MB_2U_LIB.S9S_MB_2U(SCH_1):FM_PCH_TRIGGER1_R_N

Q_RES_0402LF-200,1%,1/16W,EMPTA  I75  R1485
   1 PVNN_TERM_CPU0      A @S9S_MB_2U_LIB.S9S_MB_2U(SCH_1):PVNN_TERM_CPU0
   2 FM_PCH_TRIGGER0_R_N      B @S9S_MB_2U_LIB.S9S_MB_2U(SCH_1):FM_PCH_TRIGGER0_R_N

Q_RES_0402LF-10K,1%,1/16W,CHIPA  I77  R453
   1 P3V3_AUX      A @S9S_MB_2U_LIB.S9S_MB_2U(SCH_1):P3V3_AUX
   2 PU_LAN_WAKE_N      B @S9S_MB_2U_LIB.S9S_MB_2U(SCH_1):PU_LAN_WAKE_N

Q_RES_0402LF-2.49K,1%,1/16W,CHA  I82  R1675
   1 FM_PCIE_EV_BIF_EN      A @S9S_MB_2U_LIB.S9S_MB_2U(SCH_1):FM_PCIE_EV_BIF_EN
   2 P3V3_AUX      B @S9S_MB_2U_LIB.S9S_MB_2U(SCH_1):P3V3_AUX

Q_RES_0402LF-1K,1%,1/16W,EMPTYA  I94  R1676
   1 FM_PCIE_EV_BIF_EN      A @S9S_MB_2U_LIB.S9S_MB_2U(SCH_1):FM_PCIE_EV_BIF_EN
   2    GND      B @S9S_MB_2U_LIB.S9S_MB_2U(SCH_1):GND

Q_RES_0402LF-1M,1%,1/16W,CHIP,A  I96  R2966
   1 P3V3_RTC_AUX      A @S9S_MB_2U_LIB.S9S_MB_2U(SCH_1):P3V3_RTC_AUX
   2 FM_INTRUDER_HDR_PCH_N      B @S9S_MB_2U_LIB.S9S_MB_2U(SCH_1):FM_INTRUDER_HDR_PCH_N

Q_RES_0402LF-1K,1%,1/16W,CHIP,A  I98  R494
   1 P3V3_AUX      A @S9S_MB_2U_LIB.S9S_MB_2U(SCH_1):P3V3_AUX
   2 IRQ_LVC3_WAKE_N      B @S9S_MB_2U_LIB.S9S_MB_2U(SCH_1):IRQ_LVC3_WAKE_N

Q_RES_0402LF-33.2,1%,1/16W,CHIA  I99  R1736
   1 FM_PCH_SLP_SUS_N      A @S9S_MB_2U_LIB.S9S_MB_2U(SCH_1):FM_PCH_SLP_SUS_N
   2 FM_SLP_SUS_RSM_RST_N      B @S9S_MB_2U_LIB.S9S_MB_2U(SCH_1):FM_SLP_SUS_RSM_RST_N


DRAWING: @S9S_MB_2U_LIB.S9S_MB_2U(SCH_1):PAGE175 

EMMITSBURG_REV0P9-GFNOCPU04302A  I93  U4
BD25 JTAG_TRC_PCH_PTI<11> GPPC_B_18_HS_UART1_RTS_N @S9S_MB_2U_LIB.S9S_MB_2U(SCH_1):JTAG_TRC_PCH_PTI(11)
BG20 IRQ_LPC_PIRQA_N_ESPI_ALERT0_N GPPC_A_0_ESPI_ALERT0_N @S9S_MB_2U_LIB.S9S_MB_2U(SCH_1):IRQ_LPC_PIRQA_N_ESPI_ALERT0_N
BD17 PD_PCH_GPPC_A_10 GPPC_A_10_SRCCLKREQ_N_0 @S9S_MB_2U_LIB.S9S_MB_2U(SCH_1):PD_PCH_GPPC_A_10
BG18 E1S_0_CLKREQ_N GPPC_A_11_SRCCLKREQ_N_1 @S9S_MB_2U_LIB.S9S_MB_2U(SCH_1):E1S_0_CLKREQ_N
BG16 M2_SSD0_CLKREQ_EN_N GPPC_A_12_SRCCLKREQ_N_2 @S9S_MB_2U_LIB.S9S_MB_2U(SCH_1):M2_SSD0_CLKREQ_EN_N
BF15 FM_BMC_READY_R_N GPPC_A_13_SRCCLKREQ_N_3 @S9S_MB_2U_LIB.S9S_MB_2U(SCH_1):FM_BMC_READY_R_N
BE12 PD_PCH_GPPC_A_14 GPPC_A_14_SRCCLKREQ_N_4 @S9S_MB_2U_LIB.S9S_MB_2U(SCH_1):PD_PCH_GPPC_A_14
BE14 PD_PCH_GPPC_A_15 GPPC_A_15_SRCCLKREQ_N_5 @S9S_MB_2U_LIB.S9S_MB_2U(SCH_1):PD_PCH_GPPC_A_15
BD11 FM_PCH_SATA_RAID_KEY GPPC_A_16_SRCCLKREQ_N_6 @S9S_MB_2U_LIB.S9S_MB_2U(SCH_1):FM_PCH_SATA_RAID_KEY
BF13 IRQ_BMC_PCH_NMI GPPC_A_17_SRCCLKREQ_N_7 @S9S_MB_2U_LIB.S9S_MB_2U(SCH_1):IRQ_BMC_PCH_NMI
BF11 PD_PCH_GPPC_A_18 GPPC_A_18_SRCCLKREQ_N_8 @S9S_MB_2U_LIB.S9S_MB_2U(SCH_1):PD_PCH_GPPC_A_18
BG14 PD_PCH_GPPC_A_19 GPPC_A_19_SRCCLKREQ_N_9 @S9S_MB_2U_LIB.S9S_MB_2U(SCH_1):PD_PCH_GPPC_A_19
BD15 ESPI_ALERT1_N_LPC_RCIN_N GPPC_A_1_ESPI_ALERT1_N @S9S_MB_2U_LIB.S9S_MB_2U(SCH_1):ESPI_ALERT1_N_LPC_RCIN_N
BG12 ESPI_LAD0_DATA_IO0 GPPC_A_2_ESPI_IO_0 @S9S_MB_2U_LIB.S9S_MB_2U(SCH_1):ESPI_LAD0_DATA_IO0
BF19 ESPI_LAD0_DATA_IO1 GPPC_A_3_ESPI_IO_1 @S9S_MB_2U_LIB.S9S_MB_2U(SCH_1):ESPI_LAD0_DATA_IO1
BE18 ESPI_LAD0_DATA_IO2 GPPC_A_4_ESPI_IO_2 @S9S_MB_2U_LIB.S9S_MB_2U(SCH_1):ESPI_LAD0_DATA_IO2
BD19 ESPI_LAD0_DATA_IO3 GPPC_A_5_ESPI_IO_3 @S9S_MB_2U_LIB.S9S_MB_2U(SCH_1):ESPI_LAD0_DATA_IO3
BE20 ESPI_LFRAME_N_BMC_CS0_N GPPC_A_6_ESPI_CS0_N @S9S_MB_2U_LIB.S9S_MB_2U(SCH_1):ESPI_LFRAME_N_BMC_CS0_N
BE16 IRQ_LPC_SERIRQ_ESPI_CS1_N GPPC_A_7_ESPI_CS1_N @S9S_MB_2U_LIB.S9S_MB_2U(SCH_1):IRQ_LPC_SERIRQ_ESPI_CS1_N
BF17 RST_ESPI_RESET_N GPPC_A_8_ESPI_RESET_N @S9S_MB_2U_LIB.S9S_MB_2U(SCH_1):RST_ESPI_RESET_N
BD13 CLK_24M_66M_LPC0_ESPI GPPC_A_9_ESPI_CLK @S9S_MB_2U_LIB.S9S_MB_2U(SCH_1):CLK_24M_66M_LPC0_ESPI
BD33 JTAG_TRC_PCH_PTI0_CLK GPPC_B_0_GSXDOUT @S9S_MB_2U_LIB.S9S_MB_2U(SCH_1):JTAG_TRC_PCH_PTI0_CLK
BG24 PU_OC5_USB_N GPPC_B_10_USB2_OCB_5 @S9S_MB_2U_LIB.S9S_MB_2U(SCH_1):PU_OC5_USB_N
BG22 PU_OC6_USB_N GPPC_B_11_USB2_OCB_6 @S9S_MB_2U_LIB.S9S_MB_2U(SCH_1):PU_OC6_USB_N
BD29 JTAG_TRC_PCH_PTI<5> GPPC_B_12_HS_UART0_RXD @S9S_MB_2U_LIB.S9S_MB_2U(SCH_1):JTAG_TRC_PCH_PTI(5)
BE28 JTAG_TRC_PCH_PTI<6> GPPC_B_13_HS_UART0_TXD @S9S_MB_2U_LIB.S9S_MB_2U(SCH_1):JTAG_TRC_PCH_PTI(6)
BF29 JTAG_TRC_PCH_PTI<7> GPPC_B_14_HS_UART0_RTS_N @S9S_MB_2U_LIB.S9S_MB_2U(SCH_1):JTAG_TRC_PCH_PTI(7)
BD27 JTAG_TRC_PCH_PTI<8> GPPC_B_15_HS_UART0_CTS_N @S9S_MB_2U_LIB.S9S_MB_2U(SCH_1):JTAG_TRC_PCH_PTI(8)
BE26 JTAG_TRC_PCH_PTI<9> GPPC_B_16_HS_UART1_RXD @S9S_MB_2U_LIB.S9S_MB_2U(SCH_1):JTAG_TRC_PCH_PTI(9)
BF27 JTAG_TRC_PCH_PTI<10> GPPC_B_17_HS_UART1_TXD @S9S_MB_2U_LIB.S9S_MB_2U(SCH_1):JTAG_TRC_PCH_PTI(10)
BF25 JTAG_TRC_PCH_PTI<12> GPPC_B_19_HS_UART1_CTS_N @S9S_MB_2U_LIB.S9S_MB_2U(SCH_1):JTAG_TRC_PCH_PTI(12)
BE32 JTAG_TRC_PCH_PTI<0> GPPC_B_1_GSXSLOAD @S9S_MB_2U_LIB.S9S_MB_2U(SCH_1):JTAG_TRC_PCH_PTI(0)
BE24 JTAG_TRC_PCH_PTI<13> GPPC_B_20 @S9S_MB_2U_LIB.S9S_MB_2U(SCH_1):JTAG_TRC_PCH_PTI(13)
BF23 JTAG_TRC_PCH_PTI<14> GPPC_B_21 @S9S_MB_2U_LIB.S9S_MB_2U(SCH_1):JTAG_TRC_PCH_PTI(14)
BE22 JTAG_TRC_PCH_PTI<15> GPPC_B_22 @S9S_MB_2U_LIB.S9S_MB_2U(SCH_1):JTAG_TRC_PCH_PTI(15)
BD23 JTAG_TRC_PCH_PTI1_CLK GPPC_B_23 @S9S_MB_2U_LIB.S9S_MB_2U(SCH_1):JTAG_TRC_PCH_PTI1_CLK
BF33 JTAG_TRC_PCH_PTI<1> GPPC_B_2_GSXDIN @S9S_MB_2U_LIB.S9S_MB_2U(SCH_1):JTAG_TRC_PCH_PTI(1)
BD31 JTAG_TRC_PCH_PTI<2> GPPC_B_3_GSXRESET_N @S9S_MB_2U_LIB.S9S_MB_2U(SCH_1):JTAG_TRC_PCH_PTI(2)
BE30 JTAG_TRC_PCH_PTI<3> GPPC_B_4_GSXCLK @S9S_MB_2U_LIB.S9S_MB_2U(SCH_1):JTAG_TRC_PCH_PTI(3)
BF31 JTAG_TRC_PCH_PTI<4> GPPC_B_5_USB2_OCB_0 @S9S_MB_2U_LIB.S9S_MB_2U(SCH_1):JTAG_TRC_PCH_PTI(4)
BG32 USB_OC1_REAR_R_N GPPC_B_6_USB2_OCB_1 @S9S_MB_2U_LIB.S9S_MB_2U(SCH_1):USB_OC1_REAR_R_N
BG30 PU_OC2_USB_N GPPC_B_7_USB2_OCB_2 @S9S_MB_2U_LIB.S9S_MB_2U(SCH_1):PU_OC2_USB_N
BG28 PU_OC3_USB_N GPPC_B_8_USB2_OCB_3 @S9S_MB_2U_LIB.S9S_MB_2U(SCH_1):PU_OC3_USB_N
BG26 PU_OC4_USB_N GPPC_B_9_USB2_OCB_4 @S9S_MB_2U_LIB.S9S_MB_2U(SCH_1):PU_OC4_USB_N
 BC4 SMB_SML0_3V3AUX_PCH_SCL GPPC_C_0_ME_SML0CLK @S9S_MB_2U_LIB.S9S_MB_2U(SCH_1):SMB_SML0_3V3AUX_PCH_SCL
 AP3 PD_PCH_GPPC_C10 GPPC_C_10_ME_SML2DATA @S9S_MB_2U_LIB.S9S_MB_2U(SCH_1):PD_PCH_GPPC_C10
 AV3 FM_PMBUS_ALERT_B_EN GPPC_C_11_ME_SML2ALERT_N @S9S_MB_2U_LIB.S9S_MB_2U(SCH_1):FM_PMBUS_ALERT_B_EN
 AN4 PU_SMB_SML3_3V3AUX_PCH_SCL GPPC_C_12_ME_SML3CLK @S9S_MB_2U_LIB.S9S_MB_2U(SCH_1):PU_SMB_SML3_3V3AUX_PCH_SCL
 AY1 PU_SMB_SML3_3V3AUX_PCH_SDA GPPC_C_13_ME_SML3DATA @S9S_MB_2U_LIB.S9S_MB_2U(SCH_1):PU_SMB_SML3_3V3AUX_PCH_SDA
 AW2 FM_THROTTLE_N GPPC_C_14_ME_SML3ALERT_N @S9S_MB_2U_LIB.S9S_MB_2U(SCH_1):FM_THROTTLE_N
 BA2 PU_SMB_SML4_3V3AUX_PCH_SCL GPPC_C_15_ME_SML4CLK @S9S_MB_2U_LIB.S9S_MB_2U(SCH_1):PU_SMB_SML4_3V3AUX_PCH_SCL
 AV1 PU_SMB_SML4_3V3AUX_PCH_SDA GPPC_C_16_ME_SML4DATA @S9S_MB_2U_LIB.S9S_MB_2U(SCH_1):PU_SMB_SML4_3V3AUX_PCH_SDA
 AL3 FM_BIOS_POST_CMPLT_N GPPC_C_17_ME_SML4ALERT_N @S9S_MB_2U_LIB.S9S_MB_2U(SCH_1):FM_BIOS_POST_CMPLT_N
 AL5 FM_ADR_MODE1 GPPC_C_18 @S9S_MB_2U_LIB.S9S_MB_2U(SCH_1):FM_ADR_MODE1
 AL1 PU_SMB_PCH_PLD_3V3AUX_SCL GPPC_C_19_MC_SMBCLK @S9S_MB_2U_LIB.S9S_MB_2U(SCH_1):PU_SMB_PCH_PLD_3V3AUX_SCL
 BA4 SMB_SML0_3V3AUX_PCH_SDA GPPC_C_1_ME_SML0DATA @S9S_MB_2U_LIB.S9S_MB_2U(SCH_1):SMB_SML0_3V3AUX_PCH_SDA
 AT1 PU_SMB_PCH_PLD_3V3AUX_SDA GPPC_C_20_MC_SMBDATA @S9S_MB_2U_LIB.S9S_MB_2U(SCH_1):PU_SMB_PCH_PLD_3V3AUX_SDA
 AN2 PU_PCH_PLD_3V3AUX_ALERT_N GPPC_C_21_MC_SMBALERT_N @S9S_MB_2U_LIB.S9S_MB_2U(SCH_1):PU_PCH_PLD_3V3AUX_ALERT_N
 AU2 IRQ_SML0_ALERT_N GPPC_C_2_ME_SML0ALERT_N @S9S_MB_2U_LIB.S9S_MB_2U(SCH_1):IRQ_SML0_ALERT_N
 AU4 SMB_SML0B_3V3AUX_SDA GPPC_C_3_ME_SML0BDATA @S9S_MB_2U_LIB.S9S_MB_2U(SCH_1):SMB_SML0B_3V3AUX_SDA
 BB3 SMB_SML0B_3V3AUX_SCL GPPC_C_4_ME_SML0BCLK @S9S_MB_2U_LIB.S9S_MB_2U(SCH_1):SMB_SML0B_3V3AUX_SCL
 AT3 PD_PCH_GPPC_C5 GPPC_C_5_ME_SML0BALERT_N @S9S_MB_2U_LIB.S9S_MB_2U(SCH_1):PD_PCH_GPPC_C5
 AP1 SMB_SML1_PMBUS_3V3AUX_PCH_SCL_1 GPPC_C_6_ME_SML1CLK @S9S_MB_2U_LIB.S9S_MB_2U(SCH_1):SMB_SML1_PMBUS_3V3AUX_PCH_SCL_R1
 AW4 SMB_SML1_PMBUS_3V3AUX_PCH_SDA_1 GPPC_C_7_ME_SML1DATA @S9S_MB_2U_LIB.S9S_MB_2U(SCH_1):SMB_SML1_PMBUS_3V3AUX_PCH_SDA_R1
 AR4 IRQ_SML1_PMBUS_ALERT_N GPPC_C_8_ME_SML1ALERT_N @S9S_MB_2U_LIB.S9S_MB_2U(SCH_1):IRQ_SML1_PMBUS_ALERT_N
 AR2 PD_PCH_GPPC_C9 GPPC_C_9_ME_SML2CLK @S9S_MB_2U_LIB.S9S_MB_2U(SCH_1):PD_PCH_GPPC_C9
 AF2 SMB_HOST_BMC_3V3AUX_SCL GPP_D_0_HS_SMBCLK_DMA_SMBCLK @S9S_MB_2U_LIB.S9S_MB_2U(SCH_1):SMB_HOST_BMC_3V3AUX_SCL
 AB2 IRQ_PCH_SCI_WHEA_N GPP_D_10_BM_BUSY_N_SX_EXIT_HOLDOFF_N @S9S_MB_2U_LIB.S9S_MB_2U(SCH_1):IRQ_PCH_SCI_WHEA_N
 AB4 RST_PLTRST_N GPP_D_11_PLTRST_N @S9S_MB_2U_LIB.S9S_MB_2U(SCH_1):RST_PLTRST_N
 AH2 FM_PCHHOT_N GPP_D_12_PCHHOT_N @S9S_MB_2U_LIB.S9S_MB_2U(SCH_1):FM_PCHHOT_N
 AC1 FM_ADR_COMPLETE GPP_D_13_ADR_COMPLETE @S9S_MB_2U_LIB.S9S_MB_2U(SCH_1):FM_ADR_COMPLETE
 AH4 FM_ADR_TRIGGER_R_N GPP_D_14_ADR_TRIGGER_N @S9S_MB_2U_LIB.S9S_MB_2U(SCH_1):FM_ADR_TRIGGER_R_N
 AC3 PU_PCH_VRALERT_N GPP_D_15_VRALERT_N @S9S_MB_2U_LIB.S9S_MB_2U(SCH_1):PU_PCH_VRALERT_N
 AD4 FM_ADR_ACK GPP_D_16_ADR_ACK @S9S_MB_2U_LIB.S9S_MB_2U(SCH_1):FM_ADR_ACK
  Y2 FM_PLT_BMC_THERMTRIP_R_N GPP_D_17_THERMTRIP_N @S9S_MB_2U_LIB.S9S_MB_2U(SCH_1):FM_PLT_BMC_THERMTRIP_R_N
 AF4 FM_CPU_RMCA_CATERR_DLY_N GPP_D_18_MEMTRIP_N @S9S_MB_2U_LIB.S9S_MB_2U(SCH_1):FM_CPU_RMCA_CATERR_DLY_N
  Y4 FM_BIOS_IMAGE_SWAP_N GPP_D_19_MSMI_N @S9S_MB_2U_LIB.S9S_MB_2U(SCH_1):FM_BIOS_IMAGE_SWAP_N
 AE1 SMB_HOST_BMC_3V3AUX_SDA GPP_D_1_HS_SMBDATA_DMA_SMBDATA @S9S_MB_2U_LIB.S9S_MB_2U(SCH_1):SMB_HOST_BMC_3V3AUX_SDA
 AG3 TP_PCH_GPP_D_20 GPP_D_20_CATERR_N @S9S_MB_2U_LIB.S9S_MB_2U(SCH_1):TP_PCH_GPP_D_20
 AA1 FM_PCH_GLB_RST_WARN_N GPP_D_21_GLB_RST_WARN_N @S9S_MB_2U_LIB.S9S_MB_2U(SCH_1):FM_PCH_GLB_RST_WARN_N
 AA3 FM_BIOS_DEBUG_EN_R_N GPP_D_22_USB2_OCB_7 @S9S_MB_2U_LIB.S9S_MB_2U(SCH_1):FM_BIOS_DEBUG_EN_R_N
  W1 FM_PCH_BOOT_BIOS_STRAP GPP_D_23 @S9S_MB_2U_LIB.S9S_MB_2U(SCH_1):FM_PCH_BOOT_BIOS_STRAP
 AD2 TP_PCH_GPP_D_2 GPP_D_2_HS_SMBALERT_N_DMA_SMBALERT_N @S9S_MB_2U_LIB.S9S_MB_2U(SCH_1):TP_PCH_GPP_D_2
 AJ1 FM_FLASH_SECURITY_STRAP GPP_D_6 @S9S_MB_2U_LIB.S9S_MB_2U(SCH_1):FM_FLASH_SECURITY_STRAP
 AG1 FM_ESPI_FLASH_MODE GPP_D_7 @S9S_MB_2U_LIB.S9S_MB_2U(SCH_1):FM_ESPI_FLASH_MODE
 AE3 FM_PCH_CRASHLOG_TRIG_N GPP_D_8_CRASHLOG_TRIG_N @S9S_MB_2U_LIB.S9S_MB_2U(SCH_1):FM_PCH_CRASHLOG_TRIG_N
 AJ3 PU_LPC_PME_N GPP_D_9_PME_N @S9S_MB_2U_LIB.S9S_MB_2U(SCH_1):PU_LPC_PME_N

Q_RES_0402LF-33.2,1%,1/16W,CHIA  I102  R699
   1 FM_PCH_CRASHLOG_TRIG_R_N      A @S9S_MB_2U_LIB.S9S_MB_2U(SCH_1):FM_PCH_CRASHLOG_TRIG_R_N
   2 FM_PCH_CRASHLOG_TRIG_N      B @S9S_MB_2U_LIB.S9S_MB_2U(SCH_1):FM_PCH_CRASHLOG_TRIG_N

Q_RES_0402LF-2K,1%,1/16W,CHIP,A  I109  R1451
   1 PU_SMB_SML3_3V3AUX_PCH_SCL      A @S9S_MB_2U_LIB.S9S_MB_2U(SCH_1):PU_SMB_SML3_3V3AUX_PCH_SCL
   2 P3V3_AUX      B @S9S_MB_2U_LIB.S9S_MB_2U(SCH_1):P3V3_AUX

Q_RES_0402LF-2K,1%,1/16W,CHIP,A  I112  R1452
   1 PU_SMB_SML3_3V3AUX_PCH_SDA      A @S9S_MB_2U_LIB.S9S_MB_2U(SCH_1):PU_SMB_SML3_3V3AUX_PCH_SDA
   2 P3V3_AUX      B @S9S_MB_2U_LIB.S9S_MB_2U(SCH_1):P3V3_AUX

Q_RES_0402LF-2K,1%,1/16W,CHIP,A  I120  R1453
   1 PU_SMB_SML4_3V3AUX_PCH_SCL      A @S9S_MB_2U_LIB.S9S_MB_2U(SCH_1):PU_SMB_SML4_3V3AUX_PCH_SCL
   2 P3V3_AUX      B @S9S_MB_2U_LIB.S9S_MB_2U(SCH_1):P3V3_AUX

Q_RES_0402LF-2K,1%,1/16W,CHIP,A  I121  R1454
   1 PU_SMB_SML4_3V3AUX_PCH_SDA      A @S9S_MB_2U_LIB.S9S_MB_2U(SCH_1):PU_SMB_SML4_3V3AUX_PCH_SDA
   2 P3V3_AUX      B @S9S_MB_2U_LIB.S9S_MB_2U(SCH_1):P3V3_AUX

Q_RES_0402LF-100,1%,1/16W,CHIPA  I125  R1487
   1 FM_PCH_SATA_RAID_KEY      A @S9S_MB_2U_LIB.S9S_MB_2U(SCH_1):FM_PCH_SATA_RAID_KEY
   2    GND      B @S9S_MB_2U_LIB.S9S_MB_2U(SCH_1):GND

Q_RES_0402LF-2K,1%,1/16W,CHIP,A  I137  R1545
   1 SMB_SML0B_3V3AUX_SCL      A @S9S_MB_2U_LIB.S9S_MB_2U(SCH_1):SMB_SML0B_3V3AUX_SCL
   2 P3V3_AUX      B @S9S_MB_2U_LIB.S9S_MB_2U(SCH_1):P3V3_AUX

Q_RES_0402LF-2K,1%,1/16W,CHIP,A  I138  R1546
   1 SMB_SML0B_3V3AUX_SDA      A @S9S_MB_2U_LIB.S9S_MB_2U(SCH_1):SMB_SML0B_3V3AUX_SDA
   2 P3V3_AUX      B @S9S_MB_2U_LIB.S9S_MB_2U(SCH_1):P3V3_AUX

Q_RES_0402LF-2K,1%,1/16W,CHIP,A  I141  R1582
   1 PU_SMB_PCH_PLD_3V3AUX_SDA      A @S9S_MB_2U_LIB.S9S_MB_2U(SCH_1):PU_SMB_PCH_PLD_3V3AUX_SDA
   2 P3V3_AUX      B @S9S_MB_2U_LIB.S9S_MB_2U(SCH_1):P3V3_AUX

Q_RES_0402LF-2K,1%,1/16W,CHIP,A  I142  R1581
   1 PU_SMB_PCH_PLD_3V3AUX_SCL      A @S9S_MB_2U_LIB.S9S_MB_2U(SCH_1):PU_SMB_PCH_PLD_3V3AUX_SCL
   2 P3V3_AUX      B @S9S_MB_2U_LIB.S9S_MB_2U(SCH_1):P3V3_AUX

Q_RES_0402LF-10K,1%,1/16W,CHIPA  I144  R1583
   1 PU_PCH_PLD_3V3AUX_ALERT_N      A @S9S_MB_2U_LIB.S9S_MB_2U(SCH_1):PU_PCH_PLD_3V3AUX_ALERT_N
   2 P3V3_AUX      B @S9S_MB_2U_LIB.S9S_MB_2U(SCH_1):P3V3_AUX

Q_RES_0402LF-33.2,1%,1/16W,CHIA  I148  R1600
   1 IRQ_SML0_ALERT_N      A @S9S_MB_2U_LIB.S9S_MB_2U(SCH_1):IRQ_SML0_ALERT_N
   2 IRQ_SML0_ALERT_R_N      B @S9S_MB_2U_LIB.S9S_MB_2U(SCH_1):IRQ_SML0_ALERT_R_N

Q_RES_0402LF-10K,1%,1/16W,CHIPA  I151  R1601
   1 IRQ_SML0_ALERT_N      A @S9S_MB_2U_LIB.S9S_MB_2U(SCH_1):IRQ_SML0_ALERT_N
   2 P3V3_AUX      B @S9S_MB_2U_LIB.S9S_MB_2U(SCH_1):P3V3_AUX

Q_RES_0402LF-33.2,1%,1/16W,CHIA  I178  R1656
   1 IRQ_SML1_PMBUS_ALERT_N      A @S9S_MB_2U_LIB.S9S_MB_2U(SCH_1):IRQ_SML1_PMBUS_ALERT_N
   2 IRQ_SML1_PMBUS_PLD_ALERT_N      B @S9S_MB_2U_LIB.S9S_MB_2U(SCH_1):IRQ_SML1_PMBUS_PLD_ALERT_N

Q_RES_0402LF-33.2,1%,1/16W,CHIA  I180  R1657
   1 IRQ_SML1_PMBUS_ALERT_N      A @S9S_MB_2U_LIB.S9S_MB_2U(SCH_1):IRQ_SML1_PMBUS_ALERT_N
   2 IRQ_SML1_PMBUS_BMC_ALERT_N      B @S9S_MB_2U_LIB.S9S_MB_2U(SCH_1):IRQ_SML1_PMBUS_BMC_ALERT_N

Q_RES_0402LF-10K,1%,1/16W,CHIPA  I181  R1659
   1 FM_PMBUS_ALERT_B_EN      A @S9S_MB_2U_LIB.S9S_MB_2U(SCH_1):FM_PMBUS_ALERT_B_EN
   2 P3V3_AUX      B @S9S_MB_2U_LIB.S9S_MB_2U(SCH_1):P3V3_AUX

Q_RES_0402LF-10K,1%,1/16W,CHIPA  I188  R1828
   1 USB_OC1_REAR_R_N      A @S9S_MB_2U_LIB.S9S_MB_2U(SCH_1):USB_OC1_REAR_R_N
   2 P3V3_AUX      B @S9S_MB_2U_LIB.S9S_MB_2U(SCH_1):P3V3_AUX

Q_RES_0402LF-33.2,1%,1/16W,CHIA  I193  R1827
   1 USB_OC1_REAR_R_N      A @S9S_MB_2U_LIB.S9S_MB_2U(SCH_1):USB_OC1_REAR_R_N
   2 USB_OC1_REAR_N      B @S9S_MB_2U_LIB.S9S_MB_2U(SCH_1):USB_OC1_REAR_N

Q_RES_0402LF-33.2,1%,1/16W,CHIA  I213  R474
   1 FM_PCHHOT_N      A @S9S_MB_2U_LIB.S9S_MB_2U(SCH_1):FM_PCHHOT_N
   2 FM_PCHHOT_R_N      B @S9S_MB_2U_LIB.S9S_MB_2U(SCH_1):FM_PCHHOT_R_N

Q_RES_0402LF-33.2,1%,1/16W,CHIA  I222  R1268
   1 IRQ_BMC_PCH_NMI_R      A @S9S_MB_2U_LIB.S9S_MB_2U(SCH_1):IRQ_BMC_PCH_NMI_R
   2 IRQ_BMC_PCH_NMI      B @S9S_MB_2U_LIB.S9S_MB_2U(SCH_1):IRQ_BMC_PCH_NMI

Q_RES_0402LF-4.75K,1%,1/16W,CHA  I225  R1269
   1 IRQ_BMC_PCH_NMI      A @S9S_MB_2U_LIB.S9S_MB_2U(SCH_1):IRQ_BMC_PCH_NMI
   2    GND      B @S9S_MB_2U_LIB.S9S_MB_2U(SCH_1):GND

Q_RES_0402LF-10K,1%,1/16W,CHIPA  I234  R635
   1 PU_OC3_USB_N      A @S9S_MB_2U_LIB.S9S_MB_2U(SCH_1):PU_OC3_USB_N
   2 P3V3_AUX      B @S9S_MB_2U_LIB.S9S_MB_2U(SCH_1):P3V3_AUX

Q_RES_0402LF-10K,1%,1/16W,CHIPA  I236  R727
   1 PU_OC4_USB_N      A @S9S_MB_2U_LIB.S9S_MB_2U(SCH_1):PU_OC4_USB_N
   2 P3V3_AUX      B @S9S_MB_2U_LIB.S9S_MB_2U(SCH_1):P3V3_AUX

Q_RES_0402LF-10K,1%,1/16W,CHIPA  I239  R770
   1 PU_OC5_USB_N      A @S9S_MB_2U_LIB.S9S_MB_2U(SCH_1):PU_OC5_USB_N
   2 P3V3_AUX      B @S9S_MB_2U_LIB.S9S_MB_2U(SCH_1):P3V3_AUX

Q_RES_0402LF-10K,1%,1/16W,CHIPA  I241  R913
   1 PU_OC6_USB_N      A @S9S_MB_2U_LIB.S9S_MB_2U(SCH_1):PU_OC6_USB_N
   2 P3V3_AUX      B @S9S_MB_2U_LIB.S9S_MB_2U(SCH_1):P3V3_AUX

Q_RES_0402LF-0,5%,1/16W,CHIP,CA  I253  R2971
   1 FM_BIOS_DEBUG_EN_N      A @S9S_MB_2U_LIB.S9S_MB_2U(SCH_1):FM_BIOS_DEBUG_EN_N
   2 FM_BIOS_DEBUG_EN_R_N      B @S9S_MB_2U_LIB.S9S_MB_2U(SCH_1):FM_BIOS_DEBUG_EN_R_N

CONN3_210HP1030BR1-CONN3_210-HA  I256  JP4
   3 SMB_SML0_3V3AUX_PCH_SDA      3 @S9S_MB_2U_LIB.S9S_MB_2U(SCH_1):SMB_SML0_3V3AUX_PCH_SDA
   2    GND      2 @S9S_MB_2U_LIB.S9S_MB_2U(SCH_1):GND
   1 SMB_SML0_3V3AUX_PCH_SCL      1 @S9S_MB_2U_LIB.S9S_MB_2U(SCH_1):SMB_SML0_3V3AUX_PCH_SCL

CONN3_210HP1030BR1-CONN3_210-HA  I263  JP9
   3 SMB_SML1_PMBUS_3V3AUX_PCH_SDA_1      3 @S9S_MB_2U_LIB.S9S_MB_2U(SCH_1):SMB_SML1_PMBUS_3V3AUX_PCH_SDA_R1
   2    GND      2 @S9S_MB_2U_LIB.S9S_MB_2U(SCH_1):GND
   1 SMB_SML1_PMBUS_3V3AUX_PCH_SCL_1      1 @S9S_MB_2U_LIB.S9S_MB_2U(SCH_1):SMB_SML1_PMBUS_3V3AUX_PCH_SCL_R1

Q_RES_0402LF-10K,1%,1/16W,CHIPA  I272  R3938
   1 PU_OC2_USB_N      A @S9S_MB_2U_LIB.S9S_MB_2U(SCH_1):PU_OC2_USB_N
   2 P3V3_AUX      B @S9S_MB_2U_LIB.S9S_MB_2U(SCH_1):P3V3_AUX

Q_RES_0402LF-0,5%,1/16W,EMPTY,A  I275  R4084
   1 E1S_0_PRSNT_N      A @S9S_MB_2U_LIB.S9S_MB_2U(SCH_1):E1S_0_PRSNT_N
   2 E1S_0_CLKREQ_N      B @S9S_MB_2U_LIB.S9S_MB_2U(SCH_1):E1S_0_CLKREQ_N

Q_RES_0402LF-0,5%,1/16W,EMPTY,A  I274  R4083
   1 E1S_0_PERST1_CLKREQ_N      A @S9S_MB_2U_LIB.S9S_MB_2U(SCH_1):E1S_0_PERST1_CLKREQ_N
   2 E1S_0_CLKREQ_N      B @S9S_MB_2U_LIB.S9S_MB_2U(SCH_1):E1S_0_CLKREQ_N

Q_RES_0402LF-10K,1%,1/16W,CHIPA  I284  R4095
   1 PD_PCH_GPPC_A_19      A @S9S_MB_2U_LIB.S9S_MB_2U(SCH_1):PD_PCH_GPPC_A_19
   2    GND      B @S9S_MB_2U_LIB.S9S_MB_2U(SCH_1):GND

Q_RES_0402LF-10K,1%,1/16W,CHIPA  I285  R4096
   1 PD_PCH_GPPC_A_18      A @S9S_MB_2U_LIB.S9S_MB_2U(SCH_1):PD_PCH_GPPC_A_18
   2    GND      B @S9S_MB_2U_LIB.S9S_MB_2U(SCH_1):GND

Q_RES_0402LF-10K,1%,1/16W,CHIPA  I286  R4097
   1 PD_PCH_GPPC_A_15      A @S9S_MB_2U_LIB.S9S_MB_2U(SCH_1):PD_PCH_GPPC_A_15
   2    GND      B @S9S_MB_2U_LIB.S9S_MB_2U(SCH_1):GND

Q_RES_0402LF-10K,1%,1/16W,CHIPA  I287  R4098
   1 PD_PCH_GPPC_A_14      A @S9S_MB_2U_LIB.S9S_MB_2U(SCH_1):PD_PCH_GPPC_A_14
   2    GND      B @S9S_MB_2U_LIB.S9S_MB_2U(SCH_1):GND

Q_RES_0402LF-10K,1%,1/16W,CHIPA  I288  R4099
   1 PD_PCH_GPPC_A_10      A @S9S_MB_2U_LIB.S9S_MB_2U(SCH_1):PD_PCH_GPPC_A_10
   2    GND      B @S9S_MB_2U_LIB.S9S_MB_2U(SCH_1):GND

Q_RES_0402LF-10K,1%,1/16W,CHIPA  I298  R4102
   1 PD_PCH_GPPC_C5      A @S9S_MB_2U_LIB.S9S_MB_2U(SCH_1):PD_PCH_GPPC_C5
   2    GND      B @S9S_MB_2U_LIB.S9S_MB_2U(SCH_1):GND

Q_RES_0402LF-10K,1%,1/16W,CHIPA  I299  R4101
   1 PD_PCH_GPPC_C9      A @S9S_MB_2U_LIB.S9S_MB_2U(SCH_1):PD_PCH_GPPC_C9
   2    GND      B @S9S_MB_2U_LIB.S9S_MB_2U(SCH_1):GND

Q_RES_0402LF-10K,1%,1/16W,CHIPA  I300  R4100
   1 PD_PCH_GPPC_C10      A @S9S_MB_2U_LIB.S9S_MB_2U(SCH_1):PD_PCH_GPPC_C10
   2    GND      B @S9S_MB_2U_LIB.S9S_MB_2U(SCH_1):GND

Q_RES_0402LF-33.2,1%,1/16W,CHIA  I305  R4505
   1 SMB_SML1_PMBUS_3V3AUX_PCH_SCL      A @S9S_MB_2U_LIB.S9S_MB_2U(SCH_1):SMB_SML1_PMBUS_3V3AUX_PCH_SCL
   2 SMB_SML1_PMBUS_3V3AUX_PCH_SCL_1      B @S9S_MB_2U_LIB.S9S_MB_2U(SCH_1):SMB_SML1_PMBUS_3V3AUX_PCH_SCL_R1

Q_RES_0402LF-0,5%,1/16W,CHIP,CA  I308  R4504
   1 SMB_SML1_PMBUS_3V3AUX_PCH_SDA      A @S9S_MB_2U_LIB.S9S_MB_2U(SCH_1):SMB_SML1_PMBUS_3V3AUX_PCH_SDA
   2 SMB_SML1_PMBUS_3V3AUX_PCH_SDA_1      B @S9S_MB_2U_LIB.S9S_MB_2U(SCH_1):SMB_SML1_PMBUS_3V3AUX_PCH_SDA_R1

Q_RES_0402LF-49.9,1%,1/16W,CHIA  I314  R4766
   1 E1S_0_CLK_OE_N      A @S9S_MB_2U_LIB.S9S_MB_2U(SCH_1):E1S_0_CLK_OE_N
   2 E1S_0_CLKREQ_N      B @S9S_MB_2U_LIB.S9S_MB_2U(SCH_1):E1S_0_CLKREQ_N

Q_RES_0402LF-10K,1%,1/16W,CHIPA  I315  R4768
   1 E1S_0_CLK_OE_N      A @S9S_MB_2U_LIB.S9S_MB_2U(SCH_1):E1S_0_CLK_OE_N
   2 P3V3_AUX      B @S9S_MB_2U_LIB.S9S_MB_2U(SCH_1):P3V3_AUX


DRAWING: @S9S_MB_2U_LIB.S9S_MB_2U(SCH_1):PAGE176 

EMMITSBURG_REV0P9-GFNOCPU04302A  I22  U4
  G4 FM_PCH_VISA_DEFAULT GPPC_H_0 @S9S_MB_2U_LIB.S9S_MB_2U(SCH_1):FM_PCH_VISA_DEFAULT
  K1 FM_PCH_IO_EXPANDER GPPC_H_1 @S9S_MB_2U_LIB.S9S_MB_2U(SCH_1):FM_PCH_IO_EXPANDER
  J2 TP_PCH_MGPIO_TEST1 GPPC_H_15_FLEX_CLK_OUT_0 @S9S_MB_2U_LIB.S9S_MB_2U(SCH_1):TP_PCH_MGPIO_TEST1
  G2 FM_PCH_RING_OSC_BYPASS_MGPIO_TE GPPC_H_16_FLEX_CLK_OUT_1 @S9S_MB_2U_LIB.S9S_MB_2U(SCH_1):FM_PCH_RING_OSC_BYPASS_MGPIO_TEST2
  H3 FM_PCH_XTAL_INPUT_MODE_MGPIO_TE GPPC_H_17_FLEX_CLK_OUT_2 @S9S_MB_2U_LIB.S9S_MB_2U(SCH_1):FM_PCH_XTAL_INPUT_MODE_MGPIO_TEST3
  J4 PU_PCH_PMCALERT_N GPPC_H_18_PMCALERT_N @S9S_MB_2U_LIB.S9S_MB_2U(SCH_1):PU_PCH_PMCALERT_N
  L4 FM_LT_KEY_DOWNGRADE_N GPPC_H_19 @S9S_MB_2U_LIB.S9S_MB_2U(SCH_1):FM_LT_KEY_DOWNGRADE_N
  L2 FM_PCH_EXTERNALCLKMODE GPPC_H_6 @S9S_MB_2U_LIB.S9S_MB_2U(SCH_1):FM_PCH_EXTERNALCLKMODE
  K3 FM_PCH_MCRO_LDO GPPC_H_7 @S9S_MB_2U_LIB.S9S_MB_2U(SCH_1):FM_PCH_MCRO_LDO
BA26 TP_PCH_GPP_E_0 GPP_E_0_SATA1_XPCIE_0 @S9S_MB_2U_LIB.S9S_MB_2U(SCH_1):TP_PCH_GPP_E_0
AV31 PD_PCH_GPP_E_10 GPP_E_10_SATA0_SDATAOUT_SATA0_GP @S9S_MB_2U_LIB.S9S_MB_2U(SCH_1):PD_PCH_GPP_E_10
AV34 PD_PCH_GPP_E_11 GPP_E_11_SATA1_SCLOCK_SATA1_LED_N @S9S_MB_2U_LIB.S9S_MB_2U(SCH_1):PD_PCH_GPP_E_11
BB28 PD_PCH_GPP_E_12 GPP_E_12_SATA1_SLOAD_SATA1_GP @S9S_MB_2U_LIB.S9S_MB_2U(SCH_1):PD_PCH_GPP_E_12
BA32 PD_PCH_GPP_E_13 GPP_E_13_SATA1_SDATAOUT_SATA1_DEVSLP @S9S_MB_2U_LIB.S9S_MB_2U(SCH_1):PD_PCH_GPP_E_13
BB34 PD_PCH_GPP_E_14 GPP_E_14_SATA2_SCLOCK_SATA2_LED_N @S9S_MB_2U_LIB.S9S_MB_2U(SCH_1):PD_PCH_GPP_E_14
AW20 FM_ME_AUTHN_FAIL GPP_E_15_SATA2_SLOAD_SATA2_GP @S9S_MB_2U_LIB.S9S_MB_2U(SCH_1):FM_ME_AUTHN_FAIL
AW29 FM_ME_BT_DONE GPP_E_16_SATA2_SDATAOUT_SATA2_DEVSLP @S9S_MB_2U_LIB.S9S_MB_2U(SCH_1):FM_ME_BT_DONE
BA36 FM_DEBUG_PORT_PRSNT_R_N GPP_E_17_ERR0_N @S9S_MB_2U_LIB.S9S_MB_2U(SCH_1):FM_DEBUG_PORT_PRSNT_R_N
BA20 FM_PS_PWROK_DLY_R_SEL GPP_E_18_ERR1_N @S9S_MB_2U_LIB.S9S_MB_2U(SCH_1):FM_PS_PWROK_DLY_R_SEL
BB31 FM_TPM_PRSNT_N GPP_E_19_ERR2_N @S9S_MB_2U_LIB.S9S_MB_2U(SCH_1):FM_TPM_PRSNT_N
BA23 TP_PCH_GPP_E_1 GPP_E_1_SATA1_XPCIE_1 @S9S_MB_2U_LIB.S9S_MB_2U(SCH_1):TP_PCH_GPP_E_1
AW23 TP_PCH_GPP_E_2 GPP_E_2_SATA1_XPCIE_2 @S9S_MB_2U_LIB.S9S_MB_2U(SCH_1):TP_PCH_GPP_E_2
BB21 PD_PCH_GPP_E_3 GPP_E_3_SATA1_XPCIE_3 @S9S_MB_2U_LIB.S9S_MB_2U(SCH_1):PD_PCH_GPP_E_3
AV24 TP_EDSFF1A_TYPE_ID GPP_E_4_SATA0_XPCIE_2 @S9S_MB_2U_LIB.S9S_MB_2U(SCH_1):TP_EDSFF1A_TYPE_ID
AV28 TP_EDSFF1B_TYPE_ID GPP_E_5_SATA0_XPCIE_3 @S9S_MB_2U_LIB.S9S_MB_2U(SCH_1):TP_EDSFF1B_TYPE_ID
BB24 FM_M2_E1S_E6_PEDET GPP_E_6_SATA0_USB3_XPCIE_0 @S9S_MB_2U_LIB.S9S_MB_2U(SCH_1):FM_M2_E1S_E6_PEDET
AW32 FM_M2_SSD0_E7_PEDET GPP_E_7_SATA0_USB3_XPCIE_1 @S9S_MB_2U_LIB.S9S_MB_2U(SCH_1):FM_M2_SSD0_E7_PEDET
AW36 PD_PCH_GPP_E_8 GPP_E_8_SATA0_SCLOCK_SATA0_LED_N @S9S_MB_2U_LIB.S9S_MB_2U(SCH_1):PD_PCH_GPP_E_8
BA29 PD_PCH_GPP_E_9 GPP_E_9_SATA0_SLOAD_SATA0_DEVSLP @S9S_MB_2U_LIB.S9S_MB_2U(SCH_1):PD_PCH_GPP_E_9
  U3 FM_PCH_BMC_RST_R_N GPP_I_12_HDA_BCLK @S9S_MB_2U_LIB.S9S_MB_2U(SCH_1):FM_PCH_BMC_RST_R_N
  N2 PD_GPP_I_13 GPP_I_13_HDA_RST_N @S9S_MB_2U_LIB.S9S_MB_2U(SCH_1):PD_GPP_I_13
  P1 PD_GPP_I_14 GPP_I_14_HDA_SYNC @S9S_MB_2U_LIB.S9S_MB_2U(SCH_1):PD_GPP_I_14
  R2 PD_GPP_I_15 GPP_I_15_HDA_SDO @S9S_MB_2U_LIB.S9S_MB_2U(SCH_1):PD_GPP_I_15
  U1 PD_GPP_I_16 GPP_I_16_HDA_SDI_0 @S9S_MB_2U_LIB.S9S_MB_2U(SCH_1):PD_GPP_I_16
  V4 PD_GPP_I_17 GPP_I_17_HDA_SDI_1 @S9S_MB_2U_LIB.S9S_MB_2U(SCH_1):PD_GPP_I_17
  N4 IRQ_TPM_SPI_N GPP_I_21 @S9S_MB_2U_LIB.S9S_MB_2U(SCH_1):IRQ_TPM_SPI_N
  P3 FM_PCH_DFXTESTMODE GPP_I_22 @S9S_MB_2U_LIB.S9S_MB_2U(SCH_1):FM_PCH_DFXTESTMODE
  R4 FM_PCH_XTALSEL GPP_I_23 @S9S_MB_2U_LIB.S9S_MB_2U(SCH_1):FM_PCH_XTALSEL
 AF8 H_CPU0_PMSYNC_PCH_R2 GPP_L_0_PM_SYNC_0 @S9S_MB_2U_LIB.S9S_MB_2U(SCH_1):H_CPU0_PMSYNC_PCH_R2
 AE7 H_CPU0_PMDOWN_PCH GPP_L_1_PM_DOWN_0 @S9S_MB_2U_LIB.S9S_MB_2U(SCH_1):H_CPU0_PMDOWN_PCH
AC10 TP_GPP_L_2 GPP_L_2 @S9S_MB_2U_LIB.S9S_MB_2U(SCH_1):TP_GPP_L_2
AF11 FM_BIOS_ADV_FUNCTIONS GPP_L_3 @S9S_MB_2U_LIB.S9S_MB_2U(SCH_1):FM_BIOS_ADV_FUNCTIONS
 AG7 FM_ME_RCVR_N GPP_L_4 @S9S_MB_2U_LIB.S9S_MB_2U(SCH_1):FM_ME_RCVR_N
 AB8 FM_PASSWORD_CLEAR_N GPP_L_5 @S9S_MB_2U_LIB.S9S_MB_2U(SCH_1):FM_PASSWORD_CLEAR_N
AG10 FM_MFG_MODE GPP_L_6 @S9S_MB_2U_LIB.S9S_MB_2U(SCH_1):FM_MFG_MODE
 AC7 TP_GPP_L_7 GPP_L_7 @S9S_MB_2U_LIB.S9S_MB_2U(SCH_1):TP_GPP_L_7
AE10 TP_GPP_L_8 GPP_L_8 @S9S_MB_2U_LIB.S9S_MB_2U(SCH_1):TP_GPP_L_8
  N7 FAB_REV_ID0 GPP_M_0 @S9S_MB_2U_LIB.S9S_MB_2U(SCH_1):FAB_REV_ID0
AA13 FAB_REV_ID1 GPP_M_1 @S9S_MB_2U_LIB.S9S_MB_2U(SCH_1):FAB_REV_ID1
  R7 FM_PCH_BIOS_RCVR_MODE GPP_M_11 @S9S_MB_2U_LIB.S9S_MB_2U(SCH_1):FM_PCH_BIOS_RCVR_MODE
  U7 TP_GPP_M_12 GPP_M_12 @S9S_MB_2U_LIB.S9S_MB_2U(SCH_1):TP_GPP_M_12
  T8 PD_GPP_M_15 GPP_M_15 @S9S_MB_2U_LIB.S9S_MB_2U(SCH_1):PD_GPP_M_15
 N10 PD_GPP_M_16 GPP_M_16 @S9S_MB_2U_LIB.S9S_MB_2U(SCH_1):PD_GPP_M_16
 W13 PD_GPP_M_17 GPP_M_17 @S9S_MB_2U_LIB.S9S_MB_2U(SCH_1):PD_GPP_M_17
 AA7 FAB_REV_ID2 GPP_M_2 @S9S_MB_2U_LIB.S9S_MB_2U(SCH_1):FAB_REV_ID2
AA10 FM_BOARD_SKU_ID0 GPP_M_3 @S9S_MB_2U_LIB.S9S_MB_2U(SCH_1):FM_BOARD_SKU_ID0
  W7 FM_BOARD_SKU_ID1 GPP_M_4 @S9S_MB_2U_LIB.S9S_MB_2U(SCH_1):FM_BOARD_SKU_ID1
  V8 FM_BOARD_SKU_ID2 GPP_M_5 @S9S_MB_2U_LIB.S9S_MB_2U(SCH_1):FM_BOARD_SKU_ID2
 R10 FM_BOARD_SKU_ID3 GPP_M_6 @S9S_MB_2U_LIB.S9S_MB_2U(SCH_1):FM_BOARD_SKU_ID3
AB11 FM_BOARD_SKU_ID4 GPP_M_7 @S9S_MB_2U_LIB.S9S_MB_2U(SCH_1):FM_BOARD_SKU_ID4
 W10 PD_GPP_M_8 GPP_M_8 @S9S_MB_2U_LIB.S9S_MB_2U(SCH_1):PD_GPP_M_8

Q_RES_0402LF-10K,1%,1/16W,EMPTA  I173  R2508
   1 P3V3_AUX      A @S9S_MB_2U_LIB.S9S_MB_2U(SCH_1):P3V3_AUX
   2 FM_M2_SSD0_E7_PEDET      B @S9S_MB_2U_LIB.S9S_MB_2U(SCH_1):FM_M2_SSD0_E7_PEDET

Q_RES_0402LF-1K,1%,1/16W,EMPTYA  I174  R2509
   1 FM_M2_SSD0_E7_PEDET      A @S9S_MB_2U_LIB.S9S_MB_2U(SCH_1):FM_M2_SSD0_E7_PEDET
   2    GND      B @S9S_MB_2U_LIB.S9S_MB_2U(SCH_1):GND

Q_RES_0402LF-10K,1%,1/16W,EMPTA  I175  R2510
   1 P3V3_AUX      A @S9S_MB_2U_LIB.S9S_MB_2U(SCH_1):P3V3_AUX
   2 FM_M2_E1S_E6_PEDET      B @S9S_MB_2U_LIB.S9S_MB_2U(SCH_1):FM_M2_E1S_E6_PEDET

Q_RES_0402LF-1K,1%,1/16W,EMPTYA  I176  R2511
   1 FM_M2_E1S_E6_PEDET      A @S9S_MB_2U_LIB.S9S_MB_2U(SCH_1):FM_M2_E1S_E6_PEDET
   2    GND      B @S9S_MB_2U_LIB.S9S_MB_2U(SCH_1):GND

Q_RES_0402LF-10K,1%,1/16W,CHIPA  I183  R4105
   1 PD_GPP_M_15      A @S9S_MB_2U_LIB.S9S_MB_2U(SCH_1):PD_GPP_M_15
   2    GND      B @S9S_MB_2U_LIB.S9S_MB_2U(SCH_1):GND

Q_RES_0402LF-10K,1%,1/16W,CHIPA  I184  R4106
   1 PD_GPP_M_8      A @S9S_MB_2U_LIB.S9S_MB_2U(SCH_1):PD_GPP_M_8
   2    GND      B @S9S_MB_2U_LIB.S9S_MB_2U(SCH_1):GND

Q_RES_0402LF-10K,1%,1/16W,CHIPA  I185  R4104
   1 PD_GPP_M_16      A @S9S_MB_2U_LIB.S9S_MB_2U(SCH_1):PD_GPP_M_16
   2    GND      B @S9S_MB_2U_LIB.S9S_MB_2U(SCH_1):GND

Q_RES_0402LF-10K,1%,1/16W,CHIPA  I186  R4103
   1 PD_GPP_M_17      A @S9S_MB_2U_LIB.S9S_MB_2U(SCH_1):PD_GPP_M_17
   2    GND      B @S9S_MB_2U_LIB.S9S_MB_2U(SCH_1):GND

Q_RES_0402LF-10K,1%,1/16W,CHIPA  I195  R4109
   1 PD_GPP_I_15      A @S9S_MB_2U_LIB.S9S_MB_2U(SCH_1):PD_GPP_I_15
   2    GND      B @S9S_MB_2U_LIB.S9S_MB_2U(SCH_1):GND

Q_RES_0402LF-10K,1%,1/16W,CHIPA  I196  R4108
   1 PD_GPP_I_16      A @S9S_MB_2U_LIB.S9S_MB_2U(SCH_1):PD_GPP_I_16
   2    GND      B @S9S_MB_2U_LIB.S9S_MB_2U(SCH_1):GND

Q_RES_0402LF-10K,1%,1/16W,CHIPA  I197  R4107
   1 PD_GPP_I_17      A @S9S_MB_2U_LIB.S9S_MB_2U(SCH_1):PD_GPP_I_17
   2    GND      B @S9S_MB_2U_LIB.S9S_MB_2U(SCH_1):GND

Q_RES_0402LF-10K,1%,1/16W,CHIPA  I201  R4115
   1 PD_PCH_GPP_E_9      A @S9S_MB_2U_LIB.S9S_MB_2U(SCH_1):PD_PCH_GPP_E_9
   2    GND      B @S9S_MB_2U_LIB.S9S_MB_2U(SCH_1):GND

Q_RES_0402LF-10K,1%,1/16W,CHIPA  I202  R4110
   1 PD_PCH_GPP_E_14      A @S9S_MB_2U_LIB.S9S_MB_2U(SCH_1):PD_PCH_GPP_E_14
   2    GND      B @S9S_MB_2U_LIB.S9S_MB_2U(SCH_1):GND

Q_RES_0402LF-10K,1%,1/16W,CHIPA  I203  R4112
   1 PD_PCH_GPP_E_12      A @S9S_MB_2U_LIB.S9S_MB_2U(SCH_1):PD_PCH_GPP_E_12
   2    GND      B @S9S_MB_2U_LIB.S9S_MB_2U(SCH_1):GND

Q_RES_0402LF-10K,1%,1/16W,CHIPA  I204  R4111
   1 PD_PCH_GPP_E_13      A @S9S_MB_2U_LIB.S9S_MB_2U(SCH_1):PD_PCH_GPP_E_13
   2    GND      B @S9S_MB_2U_LIB.S9S_MB_2U(SCH_1):GND

Q_RES_0402LF-10K,1%,1/16W,CHIPA  I205  R4114
   1 PD_PCH_GPP_E_10      A @S9S_MB_2U_LIB.S9S_MB_2U(SCH_1):PD_PCH_GPP_E_10
   2    GND      B @S9S_MB_2U_LIB.S9S_MB_2U(SCH_1):GND

Q_RES_0402LF-10K,1%,1/16W,CHIPA  I206  R4113
   1 PD_PCH_GPP_E_11      A @S9S_MB_2U_LIB.S9S_MB_2U(SCH_1):PD_PCH_GPP_E_11
   2    GND      B @S9S_MB_2U_LIB.S9S_MB_2U(SCH_1):GND

Q_RES_0402LF-10K,1%,1/16W,CHIPA  I207  R4116
   1 PD_PCH_GPP_E_8      A @S9S_MB_2U_LIB.S9S_MB_2U(SCH_1):PD_PCH_GPP_E_8
   2    GND      B @S9S_MB_2U_LIB.S9S_MB_2U(SCH_1):GND

Q_RES_0402LF-10K,1%,1/16W,CHIPA  I209  R4117
   1 PD_PCH_GPP_E_3      A @S9S_MB_2U_LIB.S9S_MB_2U(SCH_1):PD_PCH_GPP_E_3
   2    GND      B @S9S_MB_2U_LIB.S9S_MB_2U(SCH_1):GND

Q_RES_0402LF-10K,1%,1/16W,CHIPA  I239  R4564
   1 PD_GPP_I_14      A @S9S_MB_2U_LIB.S9S_MB_2U(SCH_1):PD_GPP_I_14
   2    GND      B @S9S_MB_2U_LIB.S9S_MB_2U(SCH_1):GND

Q_RES_0402LF-10K,1%,1/16W,CHIPA  I240  R4565
   1 PD_GPP_I_13      A @S9S_MB_2U_LIB.S9S_MB_2U(SCH_1):PD_GPP_I_13
   2    GND      B @S9S_MB_2U_LIB.S9S_MB_2U(SCH_1):GND

Q_RES_0402LF-10K,1%,1/16W,CHIPA  I246  R4722
   1 FM_PCH_BMC_RST_R_N      A @S9S_MB_2U_LIB.S9S_MB_2U(SCH_1):FM_PCH_BMC_RST_R_N
   2 P3V3_AUX      B @S9S_MB_2U_LIB.S9S_MB_2U(SCH_1):P3V3_AUX


DRAWING: @S9S_MB_2U_LIB.S9S_MB_2U(SCH_1):PAGE177 

Q_RES_0402LF-10K,1%,1/16W,CHIPA  I24  R498
   1 P3V3_AUX      A @S9S_MB_2U_LIB.S9S_MB_2U(SCH_1):P3V3_AUX
   2 FM_PCH_PRSNT_N      B @S9S_MB_2U_LIB.S9S_MB_2U(SCH_1):FM_PCH_PRSNT_N

EMMITSBURG_REV0P9-GFNOCPU04302A  I27  U4
BB18 FM_XTAL_INPUT_FREQUENCY_0_MGPIO GPPC_S_0_TIME_SYNC_0 @S9S_MB_2U_LIB.S9S_MB_2U(SCH_1):FM_XTAL_INPUT_FREQUENCY_0_MGPIO_TEST4
AW10 FM_JTAG_ODT_DISABLE GPPC_S_10 @S9S_MB_2U_LIB.S9S_MB_2U(SCH_1):FM_JTAG_ODT_DISABLE
 BB8 FM_ESPI_CS_SWIZZLE GPPC_S_11 @S9S_MB_2U_LIB.S9S_MB_2U(SCH_1):FM_ESPI_CS_SWIZZLE
AU16 FM_PCH_SPKR GPPC_S_1_SPKR_TIME_SYNC_1 @S9S_MB_2U_LIB.S9S_MB_2U(SCH_1):FM_PCH_SPKR
AR16 FM_XTAL_INPUT_FREQUENCY_1_MGPIO GPPC_S_2_CPU_GP_0 @S9S_MB_2U_LIB.S9S_MB_2U(SCH_1):FM_XTAL_INPUT_FREQUENCY_1_MGPIO_TEST5
AV11 FM_ADR_MODE0 GPPC_S_3_CPU_GP_1 @S9S_MB_2U_LIB.S9S_MB_2U(SCH_1):FM_ADR_MODE0
AU13 FM_SPI_3V3_1V8_VOLTAGE GPPC_S_4_CPU_GP_2 @S9S_MB_2U_LIB.S9S_MB_2U(SCH_1):FM_SPI_3V3_1V8_VOLTAGE
AT18 FM_PCH_CONSENT_STRAP_N GPPC_S_5_CPU_GP_3 @S9S_MB_2U_LIB.S9S_MB_2U(SCH_1):FM_PCH_CONSENT_STRAP_N
AR13 FM_EUP_LOT6_N GPPC_S_6_SUSWARN_N_SUSPWRDNACK @S9S_MB_2U_LIB.S9S_MB_2U(SCH_1):FM_EUP_LOT6_N
 BA7 FM_SUSACK_N GPPC_S_7_SUSACK_N @S9S_MB_2U_LIB.S9S_MB_2U(SCH_1):FM_SUSACK_N
AP15 IRQ_PCH_CPU_NMI_EVENT_R_N GPPC_S_8_NMI_N @S9S_MB_2U_LIB.S9S_MB_2U(SCH_1):IRQ_PCH_CPU_NMI_EVENT_R_N
AV18 IRQ_SMI_ACTIVE_N GPPC_S_9_SMI_N @S9S_MB_2U_LIB.S9S_MB_2U(SCH_1):IRQ_SMI_ACTIVE_N
 T11 TP_PCH_GPP_N_1 GPP_N_1 @S9S_MB_2U_LIB.S9S_MB_2U(SCH_1):TP_PCH_GPP_N_1
 V11 TP_PCH_GPP_N_4 GPP_N_4 @S9S_MB_2U_LIB.S9S_MB_2U(SCH_1):TP_PCH_GPP_N_4
 BG3 TP_PCH_CGC_DUT_DETECTED NC_CGC_DUT_DETECT_N @S9S_MB_2U_LIB.S9S_MB_2U(SCH_1):TP_PCH_CGC_DUT_DETECTED
 BD7 RST_RTCRST_N RCTRST_N @S9S_MB_2U_LIB.S9S_MB_2U(SCH_1):RST_RTCRST_N
BB15 SPI_PCH_CLK SPI0_CLK @S9S_MB_2U_LIB.S9S_MB_2U(SCH_1):SPI_PCH_CLK
AW13 SPI_PCH_CS0_R_N SPI0_FLASH_0_CS_N @S9S_MB_2U_LIB.S9S_MB_2U(SCH_1):SPI_PCH_CS0_R_N
BA10 TP_SPI_PCH_CS1_R_N SPI0_FLASH_1_CS_N @S9S_MB_2U_LIB.S9S_MB_2U(SCH_1):TP_SPI_PCH_CS1_R_N
AV15 SPI_PCH_IO2 SPI0_IO_2 @S9S_MB_2U_LIB.S9S_MB_2U(SCH_1):SPI_PCH_IO2
BA16 SPI_PCH_IO3 SPI0_IO_3 @S9S_MB_2U_LIB.S9S_MB_2U(SCH_1):SPI_PCH_IO3
BA13 SPI_PCH_IO0 SPI0_MOSI_IO_0 @S9S_MB_2U_LIB.S9S_MB_2U(SCH_1):SPI_PCH_IO0
AW16 SPI_PCH_IO1 SPI0_MISO_IO_1 @S9S_MB_2U_LIB.S9S_MB_2U(SCH_1):SPI_PCH_IO1
BB11 SPI_PCH_TPM_CS_N SPI0_TPM_CS_N @S9S_MB_2U_LIB.S9S_MB_2U(SCH_1):SPI_PCH_TPM_CS_N
 BF9 RST_SRTCRST_N SRTCRST_N @S9S_MB_2U_LIB.S9S_MB_2U(SCH_1):RST_SRTCRST_N
 A41 FM_PCH_PRSNT_N VSS_A41 @S9S_MB_2U_LIB.S9S_MB_2U(SCH_1):FM_PCH_PRSNT_N

Q_RES_0402LF-1K,1%,1/16W,CHIP,A  I62  R1203
   1 P3V_BAT      A @S9S_MB_2U_LIB.S9S_MB_2U(SCH_1):P3V_BAT
   2 P3V_BAT_R      B @S9S_MB_2U_LIB.S9S_MB_2U(SCH_1):P3V_BAT_R

CONN2_AAABAT029Y19-CONN2_AAA-BA  I63  BT1
   1 P3V_BAT      1 @S9S_MB_2U_LIB.S9S_MB_2U(SCH_1):P3V_BAT
   2    GND      2 @S9S_MB_2U_LIB.S9S_MB_2U(SCH_1):GND

BAS70057F-BAS70-05-7-F,SMLF,ICA  I64  U62
   2 P3V3_AUX      A @S9S_MB_2U_LIB.S9S_MB_2U(SCH_1):P3V3_AUX
   1 P3V_BAT_R      B @S9S_MB_2U_LIB.S9S_MB_2U(SCH_1):P3V_BAT_R
   3 P3V3_RTC_AUX      C @S9S_MB_2U_LIB.S9S_MB_2U(SCH_1):P3V3_RTC_AUX

Q_CAP_C0402-1UF,25V,10%,X6S,CHA  I65  C611
   1 P3V3_RTC_AUX      A @S9S_MB_2U_LIB.S9S_MB_2U(SCH_1):P3V3_RTC_AUX
   2    GND      B @S9S_MB_2U_LIB.S9S_MB_2U(SCH_1):GND

Q_CAP_C0402-1UF,25V,10%,X6S,CHA  I68  C610
   1 RST_SRTCRST_N      A @S9S_MB_2U_LIB.S9S_MB_2U(SCH_1):RST_SRTCRST_N
   2    GND      B @S9S_MB_2U_LIB.S9S_MB_2U(SCH_1):GND

Q_RES_0402LF-20K,1%,1/16W,CHIPA  I70  R1202
   1 P3V3_RTC_AUX      A @S9S_MB_2U_LIB.S9S_MB_2U(SCH_1):P3V3_RTC_AUX
   2 RST_SRTCRST_N      B @S9S_MB_2U_LIB.S9S_MB_2U(SCH_1):RST_SRTCRST_N

Q_RES_0402LF-0,5%,1/16W,CHIP,CA  I80  R1461
   1 FM_EUP_LOT6_N      A @S9S_MB_2U_LIB.S9S_MB_2U(SCH_1):FM_EUP_LOT6_N
   2 FM_SUSACK_N      B @S9S_MB_2U_LIB.S9S_MB_2U(SCH_1):FM_SUSACK_N

Q_RES_0402LF-0,5%,1/16W,EMPTY,A  I85  R1839
   1 RST_PFR_OVR_RTC      A @S9S_MB_2U_LIB.S9S_MB_2U(SCH_1):RST_PFR_OVR_RTC
   2 RST_RTCRST_N      B @S9S_MB_2U_LIB.S9S_MB_2U(SCH_1):RST_RTCRST_N

Q_RES_0402LF-0,5%,1/16W,EMPTY,A  I89  R1840
   1 RST_PFR_OVR_SRTC      A @S9S_MB_2U_LIB.S9S_MB_2U(SCH_1):RST_PFR_OVR_SRTC
   2 RST_SRTCRST_N      B @S9S_MB_2U_LIB.S9S_MB_2U(SCH_1):RST_SRTCRST_N

Q_RES_0402LF-33.2,1%,1/16W,CHIA  I100  R501
   1 SPI_PCH_CS0_R_N      A @S9S_MB_2U_LIB.S9S_MB_2U(SCH_1):SPI_PCH_CS0_R_N
   2 SPI_SYS_CS0_N      B @S9S_MB_2U_LIB.S9S_MB_2U(SCH_1):SPI_SYS_CS0_N

Q_RES_0402LF-33.2,1%,1/16W,CHIA  I102  R1395
   1 SPI_PCH_TPM_CS_N      A @S9S_MB_2U_LIB.S9S_MB_2U(SCH_1):SPI_PCH_TPM_CS_N
   2 SPI_TPM_CS_N      B @S9S_MB_2U_LIB.S9S_MB_2U(SCH_1):SPI_TPM_CS_N

Q_RES_0402LF-33.2,1%,1/16W,CHIA  I106  R499
   1 SPI_PCH_CLK      A @S9S_MB_2U_LIB.S9S_MB_2U(SCH_1):SPI_PCH_CLK
   2 SPI_SYS_CLK      B @S9S_MB_2U_LIB.S9S_MB_2U(SCH_1):SPI_SYS_CLK

Q_RES_0402LF-0,5%,1/16W,CHIP,CA  I118  R915
   1 SPI_PCH_IO0      A @S9S_MB_2U_LIB.S9S_MB_2U(SCH_1):SPI_PCH_IO0
   2 SPI_SYS_MOSI      B @S9S_MB_2U_LIB.S9S_MB_2U(SCH_1):SPI_SYS_MOSI

Q_RES_0402LF-0,5%,1/16W,CHIP,CA  I119  R916
   1 SPI_PCH_IO1      A @S9S_MB_2U_LIB.S9S_MB_2U(SCH_1):SPI_PCH_IO1
   2 SPI_SYS_MISO      B @S9S_MB_2U_LIB.S9S_MB_2U(SCH_1):SPI_SYS_MISO

Q_RES_0402LF-0,5%,1/16W,CHIP,CA  I120  R918
   1 SPI_PCH_IO2      A @S9S_MB_2U_LIB.S9S_MB_2U(SCH_1):SPI_PCH_IO2
   2 SPI_SYS_WP_IO2      B @S9S_MB_2U_LIB.S9S_MB_2U(SCH_1):SPI_SYS_WP_IO2

Q_RES_0402LF-0,5%,1/16W,CHIP,CA  I121  R917
   1 SPI_PCH_IO3      A @S9S_MB_2U_LIB.S9S_MB_2U(SCH_1):SPI_PCH_IO3
   2 SPI_SYS_HOLD_IO3      B @S9S_MB_2U_LIB.S9S_MB_2U(SCH_1):SPI_SYS_HOLD_IO3

MOSFET_NCH_GDS_ESD_PROTECTED-2A  I123  Q34
   D RST_RTCRST_N      D @S9S_MB_2U_LIB.S9S_MB_2U(SCH_1):RST_RTCRST_N
   G RST_PFR_OVR_RTC      G @S9S_MB_2U_LIB.S9S_MB_2U(SCH_1):RST_PFR_OVR_RTC
   S    GND      S @S9S_MB_2U_LIB.S9S_MB_2U(SCH_1):GND

MOSFET_NCH_GDS_ESD_PROTECTED-2A  I124  Q35
   D RST_SRTCRST_N      D @S9S_MB_2U_LIB.S9S_MB_2U(SCH_1):RST_SRTCRST_N
   G RST_PFR_OVR_SRTC      G @S9S_MB_2U_LIB.S9S_MB_2U(SCH_1):RST_PFR_OVR_SRTC
   S    GND      S @S9S_MB_2U_LIB.S9S_MB_2U(SCH_1):GND

Q_RES_0402LF-100K,1%,1/16W,CHIA  I125  R4712
   1 RST_PFR_OVR_RTC      A @S9S_MB_2U_LIB.S9S_MB_2U(SCH_1):RST_PFR_OVR_RTC
   2    GND      B @S9S_MB_2U_LIB.S9S_MB_2U(SCH_1):GND

Q_RES_0402LF-100K,1%,1/16W,CHIA  I127  R4713
   1 RST_PFR_OVR_SRTC      A @S9S_MB_2U_LIB.S9S_MB_2U(SCH_1):RST_PFR_OVR_SRTC
   2    GND      B @S9S_MB_2U_LIB.S9S_MB_2U(SCH_1):GND


DRAWING: @S9S_MB_2U_LIB.S9S_MB_2U(SCH_1):PAGE178 

EMMITSBURG_REV0P9-GFNOCPU04302A  I11  U4
AF15 TP_PCH_RSVD<16> RSVD_AF15 @S9S_MB_2U_LIB.S9S_MB_2U(SCH_1):TP_PCH_RSVD(16)
AN26 TP_PCH_RSVD<15> RSVD_AN26 @S9S_MB_2U_LIB.S9S_MB_2U(SCH_1):TP_PCH_RSVD(15)
 W24 P1V05_PCH_AUX VCCP_1P05_W24 @S9S_MB_2U_LIB.S9S_MB_2U(SCH_1):P1V05_PCH_AUX
 W22 P1V05_PCH_AUX VCCP_1P05_W22 @S9S_MB_2U_LIB.S9S_MB_2U(SCH_1):P1V05_PCH_AUX
 W20 P1V05_PCH_AUX VCCP_1P05_W20 @S9S_MB_2U_LIB.S9S_MB_2U(SCH_1):P1V05_PCH_AUX
 W19 P1V05_PCH_AUX VCCP_1P05_W19 @S9S_MB_2U_LIB.S9S_MB_2U(SCH_1):P1V05_PCH_AUX
 W17 P1V05_PCH_AUX VCCP_1P05_W17 @S9S_MB_2U_LIB.S9S_MB_2U(SCH_1):P1V05_PCH_AUX
AB24 P1V05_PCH_AUX VCCP_1P05_AB24 @S9S_MB_2U_LIB.S9S_MB_2U(SCH_1):P1V05_PCH_AUX
AB22 P1V05_PCH_AUX VCCP_1P05_AB22 @S9S_MB_2U_LIB.S9S_MB_2U(SCH_1):P1V05_PCH_AUX
AB20 P1V05_PCH_AUX VCCP_1P05_AB20 @S9S_MB_2U_LIB.S9S_MB_2U(SCH_1):P1V05_PCH_AUX
AB19 P1V05_PCH_AUX VCCP_1P05_AB19 @S9S_MB_2U_LIB.S9S_MB_2U(SCH_1):P1V05_PCH_AUX
AJ27 P1V05_PCH_AUX VCCP_1P05_AJ27 @S9S_MB_2U_LIB.S9S_MB_2U(SCH_1):P1V05_PCH_AUX
AJ25 P1V05_PCH_AUX VCCP_1P05_AJ25 @S9S_MB_2U_LIB.S9S_MB_2U(SCH_1):P1V05_PCH_AUX
AG27 P1V05_PCH_AUX VCCP_1P05_AG27 @S9S_MB_2U_LIB.S9S_MB_2U(SCH_1):P1V05_PCH_AUX
AG25 P1V05_PCH_AUX VCCP_1P05_AG25 @S9S_MB_2U_LIB.S9S_MB_2U(SCH_1):P1V05_PCH_AUX
AF27 P1V05_PCH_AUX VCCP_1P05_AF27 @S9S_MB_2U_LIB.S9S_MB_2U(SCH_1):P1V05_PCH_AUX
AF25 P1V05_PCH_AUX VCCP_1P05_AF25 @S9S_MB_2U_LIB.S9S_MB_2U(SCH_1):P1V05_PCH_AUX
AD27 P1V05_PCH_AUX VCCP_1P05_AD27 @S9S_MB_2U_LIB.S9S_MB_2U(SCH_1):P1V05_PCH_AUX
AD25 P1V05_PCH_AUX VCCP_1P05_AD25 @S9S_MB_2U_LIB.S9S_MB_2U(SCH_1):P1V05_PCH_AUX
AB27 P1V05_PCH_PLL_AUX VCCP_1P05_FILTERED_AB27 @S9S_MB_2U_LIB.S9S_MB_2U(SCH_1):P1V05_PCH_PLL_AUX
 N26 P1V05_PCH_AUX VCCP_1P05_N26 @S9S_MB_2U_LIB.S9S_MB_2U(SCH_1):P1V05_PCH_AUX
 N23 P1V05_PCH_AUX VCCP_1P05_N23 @S9S_MB_2U_LIB.S9S_MB_2U(SCH_1):P1V05_PCH_AUX
AR26 P1V05_PCH_AUX VCCP_1P05_AR26 @S9S_MB_2U_LIB.S9S_MB_2U(SCH_1):P1V05_PCH_AUX
 M24 P1V05_PCH_AUX VCCP_1P05_M24 @S9S_MB_2U_LIB.S9S_MB_2U(SCH_1):P1V05_PCH_AUX
 P15 P1V05_PCH_AUX VCCP_1P05_P15 @S9S_MB_2U_LIB.S9S_MB_2U(SCH_1):P1V05_PCH_AUX
AL25 P1V05_PCH_PLL_AUX VCCP_1P05_FILTERED_AL25 @S9S_MB_2U_LIB.S9S_MB_2U(SCH_1):P1V05_PCH_PLL_AUX
AG29 P1V05_PCH_PLL_AUX VCCP_1P05_FILTERED_AG29 @S9S_MB_2U_LIB.S9S_MB_2U(SCH_1):P1V05_PCH_PLL_AUX
AE29 P1V05_PCH_PLL_AUX VCCP_1P05_FILTERED_AE29 @S9S_MB_2U_LIB.S9S_MB_2U(SCH_1):P1V05_PCH_PLL_AUX
 R29 P1V05_PCH_PLL_AUX VCCP_1P05_FILTERED_R29 @S9S_MB_2U_LIB.S9S_MB_2U(SCH_1):P1V05_PCH_PLL_AUX
 U27 P1V05_PCH_PLL_AUX VCCP_1P05_FILTERED_U27 @S9S_MB_2U_LIB.S9S_MB_2U(SCH_1):P1V05_PCH_PLL_AUX
AA29 P1V05_PCH_PLL_AUX VCCP_1P05_FILTERED_AA29 @S9S_MB_2U_LIB.S9S_MB_2U(SCH_1):P1V05_PCH_PLL_AUX
 R26 P1V05_PCH_PLL_AUX VCCP_1P05_FILTERED_R26 @S9S_MB_2U_LIB.S9S_MB_2U(SCH_1):P1V05_PCH_PLL_AUX
 R23 P1V05_PCH_PLL_AUX VCCP_1P05_FILTERED_R23 @S9S_MB_2U_LIB.S9S_MB_2U(SCH_1):P1V05_PCH_PLL_AUX
 N20 P1V8_PCH_AUX VCCP_1P8_N20 @S9S_MB_2U_LIB.S9S_MB_2U(SCH_1):P1V8_PCH_AUX
 U24 P1V8_PCH_AUX VCCP_1P8_U24 @S9S_MB_2U_LIB.S9S_MB_2U(SCH_1):P1V8_PCH_AUX
 U22 P1V8_PCH_AUX VCCP_1P8_U22 @S9S_MB_2U_LIB.S9S_MB_2U(SCH_1):P1V8_PCH_AUX
 U20 P1V8_PCH_AUX VCCP_1P8_U20 @S9S_MB_2U_LIB.S9S_MB_2U(SCH_1):P1V8_PCH_AUX
 U19 P1V8_PCH_AUX VCCP_1P8_U19 @S9S_MB_2U_LIB.S9S_MB_2U(SCH_1):P1V8_PCH_AUX
 U17 P1V8_PCH_AUX VCCP_1P8_U17 @S9S_MB_2U_LIB.S9S_MB_2U(SCH_1):P1V8_PCH_AUX
AB34 P1V8_PCH_PLL_AUX VCCP_1P8_FILTERED_AB34 @S9S_MB_2U_LIB.S9S_MB_2U(SCH_1):P1V8_PCH_PLL_AUX
 W29 P1V8_PCH_PLL_AUX VCCP_1P8_FILTERED_W29 @S9S_MB_2U_LIB.S9S_MB_2U(SCH_1):P1V8_PCH_PLL_AUX
 U29 P1V8_PCH_PLL_AUX VCCP_1P8_FILTERED_U29 @S9S_MB_2U_LIB.S9S_MB_2U(SCH_1):P1V8_PCH_PLL_AUX
 W27 P1V8_PCH_PLL_AUX VCCP_1P8_FILTERED_W27 @S9S_MB_2U_LIB.S9S_MB_2U(SCH_1):P1V8_PCH_PLL_AUX
AB31 P1V8_PCH_PLL_AUX VCCP_1P8_FILTERED_AB31 @S9S_MB_2U_LIB.S9S_MB_2U(SCH_1):P1V8_PCH_PLL_AUX
 P21 P3V3_AUX VCCP_3P3_P21 @S9S_MB_2U_LIB.S9S_MB_2U(SCH_1):P3V3_AUX
AL17 P3V3_AUX VCCP_3P3_AL17 @S9S_MB_2U_LIB.S9S_MB_2U(SCH_1):P3V3_AUX
AJ17 P3V3_AUX VCCP_3P3_AJ17 @S9S_MB_2U_LIB.S9S_MB_2U(SCH_1):P3V3_AUX
AG17 P3V3_AUX VCCP_3P3_AG17 @S9S_MB_2U_LIB.S9S_MB_2U(SCH_1):P3V3_AUX
AF17 P3V3_AUX VCCP_3P3_AF17 @S9S_MB_2U_LIB.S9S_MB_2U(SCH_1):P3V3_AUX
AK15 P3V3_AUX VCCP_3P3_AK15 @S9S_MB_2U_LIB.S9S_MB_2U(SCH_1):P3V3_AUX
AD15 P3V3_AUX VCCP_3P3_DSW_AD15 @S9S_MB_2U_LIB.S9S_MB_2U(SCH_1):P3V3_AUX
 V15 P3V3_AUX VCCP_3P3_DSW_V15 @S9S_MB_2U_LIB.S9S_MB_2U(SCH_1):P3V3_AUX
 T15 P3V3_AUX VCCP_GPPD_1P8_3P3 @S9S_MB_2U_LIB.S9S_MB_2U(SCH_1):P3V3_AUX
AN20 P3V3_AUX VCCP_GPPE_1P8_3P3 @S9S_MB_2U_LIB.S9S_MB_2U(SCH_1):P3V3_AUX
AD17 P3V3_AUX VCCP_GPPI_1P8_3P3 @S9S_MB_2U_LIB.S9S_MB_2U(SCH_1):P3V3_AUX
AR23 P1V05_PCH_AUX VCCP_VNN_AR23 @S9S_MB_2U_LIB.S9S_MB_2U(SCH_1):P1V05_PCH_AUX
AP21 P1V05_PCH_AUX VCCP_VNN_AP21 @S9S_MB_2U_LIB.S9S_MB_2U(SCH_1):P1V05_PCH_AUX
AN23 P1V05_PCH_AUX VCCP_VNN_AN23 @S9S_MB_2U_LIB.S9S_MB_2U(SCH_1):P1V05_PCH_AUX
AL22 P1V05_PCH_AUX VCCP_VNN_AL22 @S9S_MB_2U_LIB.S9S_MB_2U(SCH_1):P1V05_PCH_AUX
AL20 P1V05_PCH_AUX VCCP_VNN_AL20 @S9S_MB_2U_LIB.S9S_MB_2U(SCH_1):P1V05_PCH_AUX
AJ22 P1V05_PCH_AUX VCCP_VNN_AJ22 @S9S_MB_2U_LIB.S9S_MB_2U(SCH_1):P1V05_PCH_AUX
AJ20 P1V05_PCH_AUX VCCP_VNN_AJ20 @S9S_MB_2U_LIB.S9S_MB_2U(SCH_1):P1V05_PCH_AUX
AG22 P1V05_PCH_AUX VCCP_VNN_AG22 @S9S_MB_2U_LIB.S9S_MB_2U(SCH_1):P1V05_PCH_AUX
AG20 P1V05_PCH_AUX VCCP_VNN_AG20 @S9S_MB_2U_LIB.S9S_MB_2U(SCH_1):P1V05_PCH_AUX
AF22 P1V05_PCH_AUX VCCP_VNN_AF22 @S9S_MB_2U_LIB.S9S_MB_2U(SCH_1):P1V05_PCH_AUX
AF20 P1V05_PCH_AUX VCCP_VNN_AF20 @S9S_MB_2U_LIB.S9S_MB_2U(SCH_1):P1V05_PCH_AUX
AH15 P3V3_RTC_AUX VCCRTC @S9S_MB_2U_LIB.S9S_MB_2U(SCH_1):P3V3_RTC_AUX
BG40    GND VSS_BG40 @S9S_MB_2U_LIB.S9S_MB_2U(SCH_1):GND


DRAWING: @S9S_MB_2U_LIB.S9S_MB_2U(SCH_1):PAGE179 

Q_RES_0402LF-200,1%,1/16W,CHIPA  I2  R497
   1 PD_RCOMP_1P8_3P3      A @S9S_MB_2U_LIB.S9S_MB_2U(SCH_1):PD_RCOMP_1P8_3P3
   2    GND      B @S9S_MB_2U_LIB.S9S_MB_2U(SCH_1):GND

EMMITSBURG_REV0P9-GFNOCPU04302A  I4  U4
AC13 PD_RCOMP_1P8_3P3 GPIO_RCOMP_1P8_3P3 @S9S_MB_2U_LIB.S9S_MB_2U(SCH_1):PD_RCOMP_1P8_3P3
 L13 TP_PCH_RSVD<13> RSVD_L13 @S9S_MB_2U_LIB.S9S_MB_2U(SCH_1):TP_PCH_RSVD(13)
 N13 TP_PCH_RSVD<12> RSVD_N13 @S9S_MB_2U_LIB.S9S_MB_2U(SCH_1):TP_PCH_RSVD(12)
BB43 TP_PCH_RSVD<7> RSVD_BB43 @S9S_MB_2U_LIB.S9S_MB_2U(SCH_1):TP_PCH_RSVD(7)
 P18 TP_PCH_RSVD<6> RSVD_P18 @S9S_MB_2U_LIB.S9S_MB_2U(SCH_1):TP_PCH_RSVD(6)
  A4 TP_PCH_RSVD<2> RSVD_A4 @S9S_MB_2U_LIB.S9S_MB_2U(SCH_1):TP_PCH_RSVD(2)
  F1 TP_PCH_RSVD<1> RSVD_F1 @S9S_MB_2U_LIB.S9S_MB_2U(SCH_1):TP_PCH_RSVD(1)
  H1 TP_PCH_RSVD<0> RSVD_H1 @S9S_MB_2U_LIB.S9S_MB_2U(SCH_1):TP_PCH_RSVD(0)


DRAWING: @S9S_MB_2U_LIB.S9S_MB_2U(SCH_1):PAGE180 

EMMITSBURG_REV0P9-GFNOCPU04302A  I7  U4
  Y8    GND VSS_Y8 @S9S_MB_2U_LIB.S9S_MB_2U(SCH_1):GND
 Y34    GND VSS_Y34 @S9S_MB_2U_LIB.S9S_MB_2U(SCH_1):GND
 Y31    GND VSS_Y31 @S9S_MB_2U_LIB.S9S_MB_2U(SCH_1):GND
 Y15    GND VSS_Y15 @S9S_MB_2U_LIB.S9S_MB_2U(SCH_1):GND
 Y11    GND VSS_Y11 @S9S_MB_2U_LIB.S9S_MB_2U(SCH_1):GND
  W5    GND VSS_W5 @S9S_MB_2U_LIB.S9S_MB_2U(SCH_1):GND
 W39    GND VSS_W39 @S9S_MB_2U_LIB.S9S_MB_2U(SCH_1):GND
  W3    GND VSS_W3 @S9S_MB_2U_LIB.S9S_MB_2U(SCH_1):GND
 W25    GND VSS_W25 @S9S_MB_2U_LIB.S9S_MB_2U(SCH_1):GND
 V31    GND VSS_V31 @S9S_MB_2U_LIB.S9S_MB_2U(SCH_1):GND
  V2    GND VSS_V2 @S9S_MB_2U_LIB.S9S_MB_2U(SCH_1):GND
  U5    GND VSS_U5 @S9S_MB_2U_LIB.S9S_MB_2U(SCH_1):GND
 U39    GND VSS_U39 @S9S_MB_2U_LIB.S9S_MB_2U(SCH_1):GND
 U25    GND VSS_U25 @S9S_MB_2U_LIB.S9S_MB_2U(SCH_1):GND
 U13    GND VSS_U13 @S9S_MB_2U_LIB.S9S_MB_2U(SCH_1):GND
 U10    GND VSS_U10 @S9S_MB_2U_LIB.S9S_MB_2U(SCH_1):GND
 T31    GND VSS_T31 @S9S_MB_2U_LIB.S9S_MB_2U(SCH_1):GND
 R36    GND VSS_R36 @S9S_MB_2U_LIB.S9S_MB_2U(SCH_1):GND
 R20    GND VSS_R20 @S9S_MB_2U_LIB.S9S_MB_2U(SCH_1):GND
 R16    GND VSS_R16 @S9S_MB_2U_LIB.S9S_MB_2U(SCH_1):GND
 R13    GND VSS_R13 @S9S_MB_2U_LIB.S9S_MB_2U(SCH_1):GND
  P8    GND VSS_P8 @S9S_MB_2U_LIB.S9S_MB_2U(SCH_1):GND
  P5    GND VSS_P5 @S9S_MB_2U_LIB.S9S_MB_2U(SCH_1):GND
 P43    GND VSS_P43 @S9S_MB_2U_LIB.S9S_MB_2U(SCH_1):GND
 P41    GND VSS_P41 @S9S_MB_2U_LIB.S9S_MB_2U(SCH_1):GND
 P39    GND VSS_P39 @S9S_MB_2U_LIB.S9S_MB_2U(SCH_1):GND
 P37    GND VSS_P37 @S9S_MB_2U_LIB.S9S_MB_2U(SCH_1):GND
 P31    GND VSS_P31 @S9S_MB_2U_LIB.S9S_MB_2U(SCH_1):GND
 P28    GND VSS_P28 @S9S_MB_2U_LIB.S9S_MB_2U(SCH_1):GND
 P24    GND VSS_P24 @S9S_MB_2U_LIB.S9S_MB_2U(SCH_1):GND
 P11    GND VSS_P11 @S9S_MB_2U_LIB.S9S_MB_2U(SCH_1):GND
 N32    GND VSS_N32 @S9S_MB_2U_LIB.S9S_MB_2U(SCH_1):GND
 N16    GND VSS_N16 @S9S_MB_2U_LIB.S9S_MB_2U(SCH_1):GND
  M5    GND VSS_M5 @S9S_MB_2U_LIB.S9S_MB_2U(SCH_1):GND
 M39    GND VSS_M39 @S9S_MB_2U_LIB.S9S_MB_2U(SCH_1):GND
 M37    GND VSS_M37 @S9S_MB_2U_LIB.S9S_MB_2U(SCH_1):GND
 M34    GND VSS_M34 @S9S_MB_2U_LIB.S9S_MB_2U(SCH_1):GND
 M31    GND VSS_M31 @S9S_MB_2U_LIB.S9S_MB_2U(SCH_1):GND
  M3    GND VSS_M3 @S9S_MB_2U_LIB.S9S_MB_2U(SCH_1):GND
 M28    GND VSS_M28 @S9S_MB_2U_LIB.S9S_MB_2U(SCH_1):GND
 M21    GND VSS_M21 @S9S_MB_2U_LIB.S9S_MB_2U(SCH_1):GND
 M18    GND VSS_M18 @S9S_MB_2U_LIB.S9S_MB_2U(SCH_1):GND
 M15    GND VSS_M15 @S9S_MB_2U_LIB.S9S_MB_2U(SCH_1):GND
 M11    GND VSS_M11 @S9S_MB_2U_LIB.S9S_MB_2U(SCH_1):GND
  M1    GND VSS_M1 @S9S_MB_2U_LIB.S9S_MB_2U(SCH_1):GND
 L36    GND VSS_L36 @S9S_MB_2U_LIB.S9S_MB_2U(SCH_1):GND
 L29    GND VSS_L29 @S9S_MB_2U_LIB.S9S_MB_2U(SCH_1):GND
 L26    GND VSS_L26 @S9S_MB_2U_LIB.S9S_MB_2U(SCH_1):GND
 L23    GND VSS_L23 @S9S_MB_2U_LIB.S9S_MB_2U(SCH_1):GND
 L20    GND VSS_L20 @S9S_MB_2U_LIB.S9S_MB_2U(SCH_1):GND
 L16    GND VSS_L16 @S9S_MB_2U_LIB.S9S_MB_2U(SCH_1):GND
 L10    GND VSS_L10 @S9S_MB_2U_LIB.S9S_MB_2U(SCH_1):GND
  K5    GND VSS_K5 @S9S_MB_2U_LIB.S9S_MB_2U(SCH_1):GND
 K39    GND VSS_K39 @S9S_MB_2U_LIB.S9S_MB_2U(SCH_1):GND
 K34    GND VSS_K34 @S9S_MB_2U_LIB.S9S_MB_2U(SCH_1):GND
 K24    GND VSS_K24 @S9S_MB_2U_LIB.S9S_MB_2U(SCH_1):GND
 K15    GND VSS_K15 @S9S_MB_2U_LIB.S9S_MB_2U(SCH_1):GND
 K11    GND VSS_K11 @S9S_MB_2U_LIB.S9S_MB_2U(SCH_1):GND
 J26    GND VSS_J26 @S9S_MB_2U_LIB.S9S_MB_2U(SCH_1):GND
 J20    GND VSS_J20 @S9S_MB_2U_LIB.S9S_MB_2U(SCH_1):GND
 J13    GND VSS_J13 @S9S_MB_2U_LIB.S9S_MB_2U(SCH_1):GND
  H8    GND VSS_H8 @S9S_MB_2U_LIB.S9S_MB_2U(SCH_1):GND
  H5    GND VSS_H5 @S9S_MB_2U_LIB.S9S_MB_2U(SCH_1):GND
 H39    GND VSS_H39 @S9S_MB_2U_LIB.S9S_MB_2U(SCH_1):GND
 G26    GND VSS_G26 @S9S_MB_2U_LIB.S9S_MB_2U(SCH_1):GND
 G20    GND VSS_G20 @S9S_MB_2U_LIB.S9S_MB_2U(SCH_1):GND
 G13    GND VSS_G13 @S9S_MB_2U_LIB.S9S_MB_2U(SCH_1):GND
 F39    GND VSS_F39 @S9S_MB_2U_LIB.S9S_MB_2U(SCH_1):GND
 F34    GND VSS_F34 @S9S_MB_2U_LIB.S9S_MB_2U(SCH_1):GND
 F31    GND VSS_F31 @S9S_MB_2U_LIB.S9S_MB_2U(SCH_1):GND
 F24    GND VSS_F24 @S9S_MB_2U_LIB.S9S_MB_2U(SCH_1):GND
 F15    GND VSS_F15 @S9S_MB_2U_LIB.S9S_MB_2U(SCH_1):GND
  E6    GND VSS_E6 @S9S_MB_2U_LIB.S9S_MB_2U(SCH_1):GND
 E38    GND VSS_E38 @S9S_MB_2U_LIB.S9S_MB_2U(SCH_1):GND
 E36    GND VSS_E36 @S9S_MB_2U_LIB.S9S_MB_2U(SCH_1):GND
 E34    GND VSS_E34 @S9S_MB_2U_LIB.S9S_MB_2U(SCH_1):GND
 E32    GND VSS_E32 @S9S_MB_2U_LIB.S9S_MB_2U(SCH_1):GND
 E30    GND VSS_E30 @S9S_MB_2U_LIB.S9S_MB_2U(SCH_1):GND
 E28    GND VSS_E28 @S9S_MB_2U_LIB.S9S_MB_2U(SCH_1):GND
 E26    GND VSS_E26 @S9S_MB_2U_LIB.S9S_MB_2U(SCH_1):GND
 E24    GND VSS_E24 @S9S_MB_2U_LIB.S9S_MB_2U(SCH_1):GND
 E22    GND VSS_E22 @S9S_MB_2U_LIB.S9S_MB_2U(SCH_1):GND
 E20    GND VSS_E20 @S9S_MB_2U_LIB.S9S_MB_2U(SCH_1):GND
 E18    GND VSS_E18 @S9S_MB_2U_LIB.S9S_MB_2U(SCH_1):GND
 E16    GND VSS_E16 @S9S_MB_2U_LIB.S9S_MB_2U(SCH_1):GND
 E14    GND VSS_E14 @S9S_MB_2U_LIB.S9S_MB_2U(SCH_1):GND
 E12    GND VSS_E12 @S9S_MB_2U_LIB.S9S_MB_2U(SCH_1):GND
 E10    GND VSS_E10 @S9S_MB_2U_LIB.S9S_MB_2U(SCH_1):GND
  D9    GND VSS_D9 @S9S_MB_2U_LIB.S9S_MB_2U(SCH_1):GND
  D5    GND VSS_D5 @S9S_MB_2U_LIB.S9S_MB_2U(SCH_1):GND
 D29    GND VSS_D29 @S9S_MB_2U_LIB.S9S_MB_2U(SCH_1):GND
 D13    GND VSS_D13 @S9S_MB_2U_LIB.S9S_MB_2U(SCH_1):GND
  C4    GND VSS_C4 @S9S_MB_2U_LIB.S9S_MB_2U(SCH_1):GND
 C26    GND VSS_C26 @S9S_MB_2U_LIB.S9S_MB_2U(SCH_1):GND
 C24    GND VSS_C24 @S9S_MB_2U_LIB.S9S_MB_2U(SCH_1):GND
 C22    GND VSS_C22 @S9S_MB_2U_LIB.S9S_MB_2U(SCH_1):GND
 C20    GND VSS_C20 @S9S_MB_2U_LIB.S9S_MB_2U(SCH_1):GND
BG34    GND VSS_BG34 @S9S_MB_2U_LIB.S9S_MB_2U(SCH_1):GND
BG10    GND VSS_BG10 @S9S_MB_2U_LIB.S9S_MB_2U(SCH_1):GND
BF21    GND VSS_BF21 @S9S_MB_2U_LIB.S9S_MB_2U(SCH_1):GND
BE34    GND VSS_BE34 @S9S_MB_2U_LIB.S9S_MB_2U(SCH_1):GND
BE10    GND VSS_BE10 @S9S_MB_2U_LIB.S9S_MB_2U(SCH_1):GND
BD39    GND VSS_BD39 @S9S_MB_2U_LIB.S9S_MB_2U(SCH_1):GND
BD21    GND VSS_BD21 @S9S_MB_2U_LIB.S9S_MB_2U(SCH_1):GND
 BC8    GND VSS_BC8 @S9S_MB_2U_LIB.S9S_MB_2U(SCH_1):GND
 BC6    GND VSS_BC6 @S9S_MB_2U_LIB.S9S_MB_2U(SCH_1):GND
BC38    GND VSS_BC38 @S9S_MB_2U_LIB.S9S_MB_2U(SCH_1):GND
BC34    GND VSS_BC34 @S9S_MB_2U_LIB.S9S_MB_2U(SCH_1):GND
BC32    GND VSS_BC32 @S9S_MB_2U_LIB.S9S_MB_2U(SCH_1):GND
BC30    GND VSS_BC30 @S9S_MB_2U_LIB.S9S_MB_2U(SCH_1):GND
BC28    GND VSS_BC28 @S9S_MB_2U_LIB.S9S_MB_2U(SCH_1):GND
BC26    GND VSS_BC26 @S9S_MB_2U_LIB.S9S_MB_2U(SCH_1):GND
BC24    GND VSS_BC24 @S9S_MB_2U_LIB.S9S_MB_2U(SCH_1):GND
BC22    GND VSS_BC22 @S9S_MB_2U_LIB.S9S_MB_2U(SCH_1):GND
BC20    GND VSS_BC20 @S9S_MB_2U_LIB.S9S_MB_2U(SCH_1):GND
BC18    GND VSS_BC18 @S9S_MB_2U_LIB.S9S_MB_2U(SCH_1):GND
BC16    GND VSS_BC16 @S9S_MB_2U_LIB.S9S_MB_2U(SCH_1):GND
BC14    GND VSS_BC14 @S9S_MB_2U_LIB.S9S_MB_2U(SCH_1):GND
BC12    GND VSS_BC12 @S9S_MB_2U_LIB.S9S_MB_2U(SCH_1):GND
BC10    GND VSS_BC10 @S9S_MB_2U_LIB.S9S_MB_2U(SCH_1):GND
 BB5    GND VSS_BB5 @S9S_MB_2U_LIB.S9S_MB_2U(SCH_1):GND
BB39    GND VSS_BB39 @S9S_MB_2U_LIB.S9S_MB_2U(SCH_1):GND
  B9    GND VSS_B9 @S9S_MB_2U_LIB.S9S_MB_2U(SCH_1):GND
 B29    GND VSS_B29 @S9S_MB_2U_LIB.S9S_MB_2U(SCH_1):GND
 B13    GND VSS_B13 @S9S_MB_2U_LIB.S9S_MB_2U(SCH_1):GND
 AY8    GND VSS_AY8 @S9S_MB_2U_LIB.S9S_MB_2U(SCH_1):GND
 AY5    GND VSS_AY5 @S9S_MB_2U_LIB.S9S_MB_2U(SCH_1):GND
AY37    GND VSS_AY37 @S9S_MB_2U_LIB.S9S_MB_2U(SCH_1):GND
AY34    GND VSS_AY34 @S9S_MB_2U_LIB.S9S_MB_2U(SCH_1):GND
AY31    GND VSS_AY31 @S9S_MB_2U_LIB.S9S_MB_2U(SCH_1):GND
AY28    GND VSS_AY28 @S9S_MB_2U_LIB.S9S_MB_2U(SCH_1):GND
AY39    GND VSS_AY39 @S9S_MB_2U_LIB.S9S_MB_2U(SCH_1):GND
 F41    GND VSS_F41 @S9S_MB_2U_LIB.S9S_MB_2U(SCH_1):GND
 E40    GND VSS_E40 @S9S_MB_2U_LIB.S9S_MB_2U(SCH_1):GND
 BD5    GND VSS_BD5 @S9S_MB_2U_LIB.S9S_MB_2U(SCH_1):GND
BC36    GND VSS_BC36 @S9S_MB_2U_LIB.S9S_MB_2U(SCH_1):GND
 AY3    GND VSS_AY3 @S9S_MB_2U_LIB.S9S_MB_2U(SCH_1):GND
 C38    GND VSS_C38 @S9S_MB_2U_LIB.S9S_MB_2U(SCH_1):GND
 B39    GND VSS_B39 @S9S_MB_2U_LIB.S9S_MB_2U(SCH_1):GND
  E8    GND VSS_E8 @S9S_MB_2U_LIB.S9S_MB_2U(SCH_1):GND

EMMITSBURG_REV0P9-GFNOCPU04302A  I9  U4
 D43    GND VSS_D43 @S9S_MB_2U_LIB.S9S_MB_2U(SCH_1):GND
  D1    GND VSS_D1 @S9S_MB_2U_LIB.S9S_MB_2U(SCH_1):GND
 C43    GND VSS_C43 @S9S_MB_2U_LIB.S9S_MB_2U(SCH_1):GND
 C41    GND VSS_C41 @S9S_MB_2U_LIB.S9S_MB_2U(SCH_1):GND
  C3    GND VSS_C3 @S9S_MB_2U_LIB.S9S_MB_2U(SCH_1):GND
BG41    GND VSS_BG41 @S9S_MB_2U_LIB.S9S_MB_2U(SCH_1):GND
BE43    GND VSS_BE43 @S9S_MB_2U_LIB.S9S_MB_2U(SCH_1):GND
BE41    GND VSS_BE41 @S9S_MB_2U_LIB.S9S_MB_2U(SCH_1):GND
 BE3    GND VSS_BE3 @S9S_MB_2U_LIB.S9S_MB_2U(SCH_1):GND
 BE1    GND VSS_BE1 @S9S_MB_2U_LIB.S9S_MB_2U(SCH_1):GND
BD43    GND VSS_BD43 @S9S_MB_2U_LIB.S9S_MB_2U(SCH_1):GND
 BD1    GND VSS_BD1 @S9S_MB_2U_LIB.S9S_MB_2U(SCH_1):GND
 E42    GND VSS_E42 @S9S_MB_2U_LIB.S9S_MB_2U(SCH_1):GND
  E2    GND VSS_E2 @S9S_MB_2U_LIB.S9S_MB_2U(SCH_1):GND
 D41    GND VSS_D41 @S9S_MB_2U_LIB.S9S_MB_2U(SCH_1):GND
  D3    GND VSS_D3 @S9S_MB_2U_LIB.S9S_MB_2U(SCH_1):GND
BD41    GND VSS_BD41 @S9S_MB_2U_LIB.S9S_MB_2U(SCH_1):GND
 BD3    GND VSS_BD3 @S9S_MB_2U_LIB.S9S_MB_2U(SCH_1):GND
BC42    GND VSS_BC42 @S9S_MB_2U_LIB.S9S_MB_2U(SCH_1):GND
 BC2    GND VSS_BC2 @S9S_MB_2U_LIB.S9S_MB_2U(SCH_1):GND
 F43    GND VSS_F43 @S9S_MB_2U_LIB.S9S_MB_2U(SCH_1):GND
 BG6    GND VSS_BG6 @S9S_MB_2U_LIB.S9S_MB_2U(SCH_1):GND
 BG4    GND VSS_BG4 @S9S_MB_2U_LIB.S9S_MB_2U(SCH_1):GND
BG38    GND VSS_BG38 @S9S_MB_2U_LIB.S9S_MB_2U(SCH_1):GND
 BB1    GND VSS_BB1 @S9S_MB_2U_LIB.S9S_MB_2U(SCH_1):GND
  A6    GND VSS_A6 @S9S_MB_2U_LIB.S9S_MB_2U(SCH_1):GND
 A40    GND VSS_A40 @S9S_MB_2U_LIB.S9S_MB_2U(SCH_1):GND
 A38    GND VSS_A38 @S9S_MB_2U_LIB.S9S_MB_2U(SCH_1):GND
AY24    GND VSS_AY24 @S9S_MB_2U_LIB.S9S_MB_2U(SCH_1):GND
AY21    GND VSS_AY21 @S9S_MB_2U_LIB.S9S_MB_2U(SCH_1):GND
AY18    GND VSS_AY18 @S9S_MB_2U_LIB.S9S_MB_2U(SCH_1):GND
AY15    GND VSS_AY15 @S9S_MB_2U_LIB.S9S_MB_2U(SCH_1):GND
AY11    GND VSS_AY11 @S9S_MB_2U_LIB.S9S_MB_2U(SCH_1):GND
 AW7    GND VSS_AW7 @S9S_MB_2U_LIB.S9S_MB_2U(SCH_1):GND
 AV8    GND VSS_AV8 @S9S_MB_2U_LIB.S9S_MB_2U(SCH_1):GND
 AV5    GND VSS_AV5 @S9S_MB_2U_LIB.S9S_MB_2U(SCH_1):GND
AV39    GND VSS_AV39 @S9S_MB_2U_LIB.S9S_MB_2U(SCH_1):GND
AV37    GND VSS_AV37 @S9S_MB_2U_LIB.S9S_MB_2U(SCH_1):GND
AU36    GND VSS_AU36 @S9S_MB_2U_LIB.S9S_MB_2U(SCH_1):GND
AU32    GND VSS_AU32 @S9S_MB_2U_LIB.S9S_MB_2U(SCH_1):GND
AU29    GND VSS_AU29 @S9S_MB_2U_LIB.S9S_MB_2U(SCH_1):GND
AU26    GND VSS_AU26 @S9S_MB_2U_LIB.S9S_MB_2U(SCH_1):GND
AU23    GND VSS_AU23 @S9S_MB_2U_LIB.S9S_MB_2U(SCH_1):GND
AU20    GND VSS_AU20 @S9S_MB_2U_LIB.S9S_MB_2U(SCH_1):GND
 AT8    GND VSS_AT8 @S9S_MB_2U_LIB.S9S_MB_2U(SCH_1):GND
 AT5    GND VSS_AT5 @S9S_MB_2U_LIB.S9S_MB_2U(SCH_1):GND
AT39    GND VSS_AT39 @S9S_MB_2U_LIB.S9S_MB_2U(SCH_1):GND
AT34    GND VSS_AT34 @S9S_MB_2U_LIB.S9S_MB_2U(SCH_1):GND
AT31    GND VSS_AT31 @S9S_MB_2U_LIB.S9S_MB_2U(SCH_1):GND
AT28    GND VSS_AT28 @S9S_MB_2U_LIB.S9S_MB_2U(SCH_1):GND
AT24    GND VSS_AT24 @S9S_MB_2U_LIB.S9S_MB_2U(SCH_1):GND
AT21    GND VSS_AT21 @S9S_MB_2U_LIB.S9S_MB_2U(SCH_1):GND
AT15    GND VSS_AT15 @S9S_MB_2U_LIB.S9S_MB_2U(SCH_1):GND
AT11    GND VSS_AT11 @S9S_MB_2U_LIB.S9S_MB_2U(SCH_1):GND
AR32    GND VSS_AR32 @S9S_MB_2U_LIB.S9S_MB_2U(SCH_1):GND
AR20    GND VSS_AR20 @S9S_MB_2U_LIB.S9S_MB_2U(SCH_1):GND
 AP5    GND VSS_AP5 @S9S_MB_2U_LIB.S9S_MB_2U(SCH_1):GND
AP39    GND VSS_AP39 @S9S_MB_2U_LIB.S9S_MB_2U(SCH_1):GND
AP37    GND VSS_AP37 @S9S_MB_2U_LIB.S9S_MB_2U(SCH_1):GND
AP28    GND VSS_AP28 @S9S_MB_2U_LIB.S9S_MB_2U(SCH_1):GND
AP24    GND VSS_AP24 @S9S_MB_2U_LIB.S9S_MB_2U(SCH_1):GND
AP18    GND VSS_AP18 @S9S_MB_2U_LIB.S9S_MB_2U(SCH_1):GND
AP11    GND VSS_AP11 @S9S_MB_2U_LIB.S9S_MB_2U(SCH_1):GND
AN32    GND VSS_AN32 @S9S_MB_2U_LIB.S9S_MB_2U(SCH_1):GND
AN29    GND VSS_AN29 @S9S_MB_2U_LIB.S9S_MB_2U(SCH_1):GND
AN16    GND VSS_AN16 @S9S_MB_2U_LIB.S9S_MB_2U(SCH_1):GND
AN13    GND VSS_AN13 @S9S_MB_2U_LIB.S9S_MB_2U(SCH_1):GND
 AM8    GND VSS_AM8 @S9S_MB_2U_LIB.S9S_MB_2U(SCH_1):GND
AM31    GND VSS_AM31 @S9S_MB_2U_LIB.S9S_MB_2U(SCH_1):GND
AM15    GND VSS_AM15 @S9S_MB_2U_LIB.S9S_MB_2U(SCH_1):GND
AL39    GND VSS_AL39 @S9S_MB_2U_LIB.S9S_MB_2U(SCH_1):GND
AL29    GND VSS_AL29 @S9S_MB_2U_LIB.S9S_MB_2U(SCH_1):GND
AL27    GND VSS_AL27 @S9S_MB_2U_LIB.S9S_MB_2U(SCH_1):GND
AL24    GND VSS_AL24 @S9S_MB_2U_LIB.S9S_MB_2U(SCH_1):GND
AL19    GND VSS_AL19 @S9S_MB_2U_LIB.S9S_MB_2U(SCH_1):GND
 AK4    GND VSS_AK4 @S9S_MB_2U_LIB.S9S_MB_2U(SCH_1):GND
AK37    GND VSS_AK37 @S9S_MB_2U_LIB.S9S_MB_2U(SCH_1):GND
 AK2    GND VSS_AK2 @S9S_MB_2U_LIB.S9S_MB_2U(SCH_1):GND
AK11    GND VSS_AK11 @S9S_MB_2U_LIB.S9S_MB_2U(SCH_1):GND
 AJ5    GND VSS_AJ5 @S9S_MB_2U_LIB.S9S_MB_2U(SCH_1):GND
AJ39    GND VSS_AJ39 @S9S_MB_2U_LIB.S9S_MB_2U(SCH_1):GND
AJ36    GND VSS_AJ36 @S9S_MB_2U_LIB.S9S_MB_2U(SCH_1):GND
AJ29    GND VSS_AJ29 @S9S_MB_2U_LIB.S9S_MB_2U(SCH_1):GND
AJ24    GND VSS_AJ24 @S9S_MB_2U_LIB.S9S_MB_2U(SCH_1):GND
AJ19    GND VSS_AJ19 @S9S_MB_2U_LIB.S9S_MB_2U(SCH_1):GND
 AH8    GND VSS_AH8 @S9S_MB_2U_LIB.S9S_MB_2U(SCH_1):GND
AH31    GND VSS_AH31 @S9S_MB_2U_LIB.S9S_MB_2U(SCH_1):GND
 AG5    GND VSS_AG5 @S9S_MB_2U_LIB.S9S_MB_2U(SCH_1):GND
AG39    GND VSS_AG39 @S9S_MB_2U_LIB.S9S_MB_2U(SCH_1):GND
AG24    GND VSS_AG24 @S9S_MB_2U_LIB.S9S_MB_2U(SCH_1):GND
AG19    GND VSS_AG19 @S9S_MB_2U_LIB.S9S_MB_2U(SCH_1):GND
AG13    GND VSS_AG13 @S9S_MB_2U_LIB.S9S_MB_2U(SCH_1):GND
AF42    GND VSS_AF42 @S9S_MB_2U_LIB.S9S_MB_2U(SCH_1):GND
AF40    GND VSS_AF40 @S9S_MB_2U_LIB.S9S_MB_2U(SCH_1):GND
AF31    GND VSS_AF31 @S9S_MB_2U_LIB.S9S_MB_2U(SCH_1):GND
AF24    GND VSS_AF24 @S9S_MB_2U_LIB.S9S_MB_2U(SCH_1):GND
AF19    GND VSS_AF19 @S9S_MB_2U_LIB.S9S_MB_2U(SCH_1):GND
 AE5    GND VSS_AE5 @S9S_MB_2U_LIB.S9S_MB_2U(SCH_1):GND
AE39    GND VSS_AE39 @S9S_MB_2U_LIB.S9S_MB_2U(SCH_1):GND
AE13    GND VSS_AE13 @S9S_MB_2U_LIB.S9S_MB_2U(SCH_1):GND
 AD8    GND VSS_AD8 @S9S_MB_2U_LIB.S9S_MB_2U(SCH_1):GND
AD34    GND VSS_AD34 @S9S_MB_2U_LIB.S9S_MB_2U(SCH_1):GND
AD31    GND VSS_AD31 @S9S_MB_2U_LIB.S9S_MB_2U(SCH_1):GND
AD24    GND VSS_AD24 @S9S_MB_2U_LIB.S9S_MB_2U(SCH_1):GND
AD22    GND VSS_AD22 @S9S_MB_2U_LIB.S9S_MB_2U(SCH_1):GND
AD20    GND VSS_AD20 @S9S_MB_2U_LIB.S9S_MB_2U(SCH_1):GND
AD19    GND VSS_AD19 @S9S_MB_2U_LIB.S9S_MB_2U(SCH_1):GND
AD11    GND VSS_AD11 @S9S_MB_2U_LIB.S9S_MB_2U(SCH_1):GND
 AC5    GND VSS_AC5 @S9S_MB_2U_LIB.S9S_MB_2U(SCH_1):GND
AC39    GND VSS_AC39 @S9S_MB_2U_LIB.S9S_MB_2U(SCH_1):GND
AC36    GND VSS_AC36 @S9S_MB_2U_LIB.S9S_MB_2U(SCH_1):GND
AC32    GND VSS_AC32 @S9S_MB_2U_LIB.S9S_MB_2U(SCH_1):GND
AC29    GND VSS_AC29 @S9S_MB_2U_LIB.S9S_MB_2U(SCH_1):GND
AB37    GND VSS_AB37 @S9S_MB_2U_LIB.S9S_MB_2U(SCH_1):GND
AB25    GND VSS_AB25 @S9S_MB_2U_LIB.S9S_MB_2U(SCH_1):GND
AB17    GND VSS_AB17 @S9S_MB_2U_LIB.S9S_MB_2U(SCH_1):GND
AB15    GND VSS_AB15 @S9S_MB_2U_LIB.S9S_MB_2U(SCH_1):GND
 AA5    GND VSS_AA5 @S9S_MB_2U_LIB.S9S_MB_2U(SCH_1):GND
AA39    GND VSS_AA39 @S9S_MB_2U_LIB.S9S_MB_2U(SCH_1):GND
AA36    GND VSS_AA36 @S9S_MB_2U_LIB.S9S_MB_2U(SCH_1):GND
AA32    GND VSS_AA32 @S9S_MB_2U_LIB.S9S_MB_2U(SCH_1):GND
AA27    GND VSS_AA27 @S9S_MB_2U_LIB.S9S_MB_2U(SCH_1):GND
AA25    GND VSS_AA25 @S9S_MB_2U_LIB.S9S_MB_2U(SCH_1):GND
AA24    GND VSS_AA24 @S9S_MB_2U_LIB.S9S_MB_2U(SCH_1):GND
AA22    GND VSS_AA22 @S9S_MB_2U_LIB.S9S_MB_2U(SCH_1):GND
AA20    GND VSS_AA20 @S9S_MB_2U_LIB.S9S_MB_2U(SCH_1):GND
AA19    GND VSS_AA19 @S9S_MB_2U_LIB.S9S_MB_2U(SCH_1):GND
AA17    GND VSS_AA17 @S9S_MB_2U_LIB.S9S_MB_2U(SCH_1):GND
 A26    GND VSS_A26 @S9S_MB_2U_LIB.S9S_MB_2U(SCH_1):GND
 A24    GND VSS_A24 @S9S_MB_2U_LIB.S9S_MB_2U(SCH_1):GND
 A22    GND VSS_A22 @S9S_MB_2U_LIB.S9S_MB_2U(SCH_1):GND
 A20    GND VSS_A20 @S9S_MB_2U_LIB.S9S_MB_2U(SCH_1):GND


DRAWING: @S9S_MB_2U_LIB.S9S_MB_2U(SCH_1):PAGE181 

Q_CAP_C0603-22UF,4V,20%,X6S,CHA  I6  C1178
   1 P1V05_PCH_AUX      A @S9S_MB_2U_LIB.S9S_MB_2U(SCH_1):P1V05_PCH_AUX
   2    GND      B @S9S_MB_2U_LIB.S9S_MB_2U(SCH_1):GND

Q_CAP_C0603-22UF,4V,20%,X6S,CHA  I7  C1185
   1 P1V05_PCH_AUX      A @S9S_MB_2U_LIB.S9S_MB_2U(SCH_1):P1V05_PCH_AUX
   2    GND      B @S9S_MB_2U_LIB.S9S_MB_2U(SCH_1):GND

Q_CAP_C0603-22UF,4V,20%,X6S,CHA  I8  C1192
   1 P1V05_PCH_AUX      A @S9S_MB_2U_LIB.S9S_MB_2U(SCH_1):P1V05_PCH_AUX
   2    GND      B @S9S_MB_2U_LIB.S9S_MB_2U(SCH_1):GND

Q_CAP_C0402-10UF,6.3V,20%,X6S,A  I12  C1205
   1 P1V05_PCH_AUX      A @S9S_MB_2U_LIB.S9S_MB_2U(SCH_1):P1V05_PCH_AUX
   2    GND      B @S9S_MB_2U_LIB.S9S_MB_2U(SCH_1):GND

Q_CAP_C0402-10UF,6.3V,20%,X6S,A  I13  C1228
   1 P1V05_PCH_AUX      A @S9S_MB_2U_LIB.S9S_MB_2U(SCH_1):P1V05_PCH_AUX
   2    GND      B @S9S_MB_2U_LIB.S9S_MB_2U(SCH_1):GND

Q_CAP_C0603-22UF,4V,20%,X6S,CHA  I25  C1186
   1 P1V8_PCH_AUX      A @S9S_MB_2U_LIB.S9S_MB_2U(SCH_1):P1V8_PCH_AUX
   2    GND      B @S9S_MB_2U_LIB.S9S_MB_2U(SCH_1):GND

Q_CAP_C0603-22UF,4V,20%,X6S,CHA  I27  C1181
   1 P1V8_PCH_AUX      A @S9S_MB_2U_LIB.S9S_MB_2U(SCH_1):P1V8_PCH_AUX
   2    GND      B @S9S_MB_2U_LIB.S9S_MB_2U(SCH_1):GND

Q_CAP_C0603-22UF,4V,20%,X6S,CHA  I29  C1202
   1 P1V8_PCH_AUX      A @S9S_MB_2U_LIB.S9S_MB_2U(SCH_1):P1V8_PCH_AUX
   2    GND      B @S9S_MB_2U_LIB.S9S_MB_2U(SCH_1):GND

Q_CAP_C0603-22UF,4V,20%,X6S,CHA  I30  C1197
   1 P1V8_PCH_AUX      A @S9S_MB_2U_LIB.S9S_MB_2U(SCH_1):P1V8_PCH_AUX
   2    GND      B @S9S_MB_2U_LIB.S9S_MB_2U(SCH_1):GND

Q_CAP_C0402-10UF,6.3V,20%,X6S,A  I32  C1207
   1 P1V8_PCH_AUX      A @S9S_MB_2U_LIB.S9S_MB_2U(SCH_1):P1V8_PCH_AUX
   2    GND      B @S9S_MB_2U_LIB.S9S_MB_2U(SCH_1):GND

Q_CAP_C0603-22UF,4V,20%,X6S,CHA  I40  C1187
   1 P1V05_PCH_AUX      A @S9S_MB_2U_LIB.S9S_MB_2U(SCH_1):P1V05_PCH_AUX
   2    GND      B @S9S_MB_2U_LIB.S9S_MB_2U(SCH_1):GND

Q_CAP_C0603-22UF,4V,20%,X6S,CHA  I42  C1182
   1 P1V05_PCH_AUX      A @S9S_MB_2U_LIB.S9S_MB_2U(SCH_1):P1V05_PCH_AUX
   2    GND      B @S9S_MB_2U_LIB.S9S_MB_2U(SCH_1):GND

Q_CAP_C0603-22UF,4V,20%,X6S,CHA  I43  C1198
   1 P1V05_PCH_AUX      A @S9S_MB_2U_LIB.S9S_MB_2U(SCH_1):P1V05_PCH_AUX
   2    GND      B @S9S_MB_2U_LIB.S9S_MB_2U(SCH_1):GND

Q_CAP_C0402-10UF,6.3V,20%,X6S,A  I45  C1210
   1 P1V05_PCH_AUX      A @S9S_MB_2U_LIB.S9S_MB_2U(SCH_1):P1V05_PCH_AUX
   2    GND      B @S9S_MB_2U_LIB.S9S_MB_2U(SCH_1):GND

Q_CAP_C0402-10UF,6.3V,20%,X6S,A  I48  C1203
   1 P1V05_PCH_AUX      A @S9S_MB_2U_LIB.S9S_MB_2U(SCH_1):P1V05_PCH_AUX
   2    GND      B @S9S_MB_2U_LIB.S9S_MB_2U(SCH_1):GND

Q_CAP_C0402-10UF,6.3V,20%,X6S,A  I49  C1231
   1 P1V05_PCH_AUX      A @S9S_MB_2U_LIB.S9S_MB_2U(SCH_1):P1V05_PCH_AUX
   2    GND      B @S9S_MB_2U_LIB.S9S_MB_2U(SCH_1):GND

Q_CAP_C0402-2.2UF,10V,10%,X6S,A  I51  C1183
   1 P1V05_PCH_AUX      A @S9S_MB_2U_LIB.S9S_MB_2U(SCH_1):P1V05_PCH_AUX
   2    GND      B @S9S_MB_2U_LIB.S9S_MB_2U(SCH_1):GND

Q_CAP_C0402-2.2UF,10V,10%,X6S,A  I58  C1189
   1 P1V05_PCH_AUX      A @S9S_MB_2U_LIB.S9S_MB_2U(SCH_1):P1V05_PCH_AUX
   2    GND      B @S9S_MB_2U_LIB.S9S_MB_2U(SCH_1):GND

Q_CAP_C0402-2.2UF,10V,10%,X6S,A  I59  C1200
   1 P1V05_PCH_AUX      A @S9S_MB_2U_LIB.S9S_MB_2U(SCH_1):P1V05_PCH_AUX
   2    GND      B @S9S_MB_2U_LIB.S9S_MB_2U(SCH_1):GND

Q_CAP_C0402-2.2UF,10V,10%,X6S,A  I60  C1204
   1 P1V05_PCH_AUX      A @S9S_MB_2U_LIB.S9S_MB_2U(SCH_1):P1V05_PCH_AUX
   2    GND      B @S9S_MB_2U_LIB.S9S_MB_2U(SCH_1):GND

Q_CAP_C0402-2.2UF,10V,10%,X6S,A  I61  C1214
   1 P1V05_PCH_AUX      A @S9S_MB_2U_LIB.S9S_MB_2U(SCH_1):P1V05_PCH_AUX
   2    GND      B @S9S_MB_2U_LIB.S9S_MB_2U(SCH_1):GND

Q_CAP_C0402-2.2UF,10V,10%,X6S,A  I63  C1242
   1 P1V05_PCH_AUX      A @S9S_MB_2U_LIB.S9S_MB_2U(SCH_1):P1V05_PCH_AUX
   2    GND      B @S9S_MB_2U_LIB.S9S_MB_2U(SCH_1):GND

Q_CAP_C0402-10UF,6.3V,20%,X6S,A  I78  C1206
   1 P3V3_AUX      A @S9S_MB_2U_LIB.S9S_MB_2U(SCH_1):P3V3_AUX
   2    GND      B @S9S_MB_2U_LIB.S9S_MB_2U(SCH_1):GND

Q_CAP_C0603-22UF,6.3V,20%,X6S,A  I87  C1201
   1 P3V3_AUX      A @S9S_MB_2U_LIB.S9S_MB_2U(SCH_1):P3V3_AUX
   2    GND      B @S9S_MB_2U_LIB.S9S_MB_2U(SCH_1):GND

Q_CAP_C0603-22UF,6.3V,20%,X6S,A  I89  C1191
   1 P3V3_AUX      A @S9S_MB_2U_LIB.S9S_MB_2U(SCH_1):P3V3_AUX
   2    GND      B @S9S_MB_2U_LIB.S9S_MB_2U(SCH_1):GND

Q_CAP_C0603-22UF,6.3V,20%,X6S,A  I91  C1184
   1 P3V3_AUX      A @S9S_MB_2U_LIB.S9S_MB_2U(SCH_1):P3V3_AUX
   2    GND      B @S9S_MB_2U_LIB.S9S_MB_2U(SCH_1):GND

Q_CAP_C0402-10UF,6.3V,20%,X6S,A  I104  C1262
   1 P1V05_PCH_PLL_AUX      A @S9S_MB_2U_LIB.S9S_MB_2U(SCH_1):P1V05_PCH_PLL_AUX
   2    GND      B @S9S_MB_2U_LIB.S9S_MB_2U(SCH_1):GND

Q_CAP_C0603-10UF,6.3V,20%,X6S,A  I110  C1251
   1 P1V05_PCH_PLL_AUX      A @S9S_MB_2U_LIB.S9S_MB_2U(SCH_1):P1V05_PCH_PLL_AUX
   2    GND      B @S9S_MB_2U_LIB.S9S_MB_2U(SCH_1):GND

Q_CAP_C0603-10UF,6.3V,20%,X6S,A  I111  C1254
   1 P1V05_PCH_PLL_AUX      A @S9S_MB_2U_LIB.S9S_MB_2U(SCH_1):P1V05_PCH_PLL_AUX
   2    GND      B @S9S_MB_2U_LIB.S9S_MB_2U(SCH_1):GND

Q_CAP_C0402-10UF,6.3V,20%,X6S,A  I119  C1263
   1 P1V8_PCH_PLL_AUX      A @S9S_MB_2U_LIB.S9S_MB_2U(SCH_1):P1V8_PCH_PLL_AUX
   2    GND      B @S9S_MB_2U_LIB.S9S_MB_2U(SCH_1):GND

Q_CAP_C0603-10UF,6.3V,20%,X6S,A  I123  C1255
   1 P1V8_PCH_PLL_AUX      A @S9S_MB_2U_LIB.S9S_MB_2U(SCH_1):P1V8_PCH_PLL_AUX
   2    GND      B @S9S_MB_2U_LIB.S9S_MB_2U(SCH_1):GND

Q_CAP_C0603-10UF,6.3V,20%,X6S,A  I125  C1252
   1 P1V8_PCH_PLL_AUX      A @S9S_MB_2U_LIB.S9S_MB_2U(SCH_1):P1V8_PCH_PLL_AUX
   2    GND      B @S9S_MB_2U_LIB.S9S_MB_2U(SCH_1):GND

Q_CAP_C0402-10UF,6.3V,20%,X6S,A  I127  C1266
   1 P1V8_PCH_PLL_AUX      A @S9S_MB_2U_LIB.S9S_MB_2U(SCH_1):P1V8_PCH_PLL_AUX
   2    GND      B @S9S_MB_2U_LIB.S9S_MB_2U(SCH_1):GND

Q_RES_0402LF-0,5%,1/16W,CHIP,CA  I129  R1463
   1 P1V05_PCH_AUX      A @S9S_MB_2U_LIB.S9S_MB_2U(SCH_1):P1V05_PCH_AUX
   2 P1V05_PCH_PLL_AUX      B @S9S_MB_2U_LIB.S9S_MB_2U(SCH_1):P1V05_PCH_PLL_AUX

Q_CAP_C0603-10UF,6.3V,20%,X6S,A  I131  C1260
   1 P1V05_PCH_PLL_AUX      A @S9S_MB_2U_LIB.S9S_MB_2U(SCH_1):P1V05_PCH_PLL_AUX
   2    GND      B @S9S_MB_2U_LIB.S9S_MB_2U(SCH_1):GND

Q_CAP_0402-1UF,6.3V,10%,EMPTY,A  I133  C1264
   1 P1V05_PCH_PLL_AUX      A @S9S_MB_2U_LIB.S9S_MB_2U(SCH_1):P1V05_PCH_PLL_AUX
   2    GND      B @S9S_MB_2U_LIB.S9S_MB_2U(SCH_1):GND

Q_CAP_0402-1UF,6.3V,10%,EMPTY,A  I136  C1256
   1 P1V05_PCH_PLL_AUX      A @S9S_MB_2U_LIB.S9S_MB_2U(SCH_1):P1V05_PCH_PLL_AUX
   2    GND      B @S9S_MB_2U_LIB.S9S_MB_2U(SCH_1):GND

Q_CAP_0402-1UF,6.3V,10%,EMPTY,A  I137  C1250
   1 P1V05_PCH_AUX      A @S9S_MB_2U_LIB.S9S_MB_2U(SCH_1):P1V05_PCH_AUX
   2    GND      B @S9S_MB_2U_LIB.S9S_MB_2U(SCH_1):GND

Q_CAP_0402-1UF,6.3V,10%,EMPTY,A  I140  C1265
   1 P1V8_PCH_PLL_AUX      A @S9S_MB_2U_LIB.S9S_MB_2U(SCH_1):P1V8_PCH_PLL_AUX
   2    GND      B @S9S_MB_2U_LIB.S9S_MB_2U(SCH_1):GND

Q_CAP_C0603-10UF,6.3V,20%,X6S,A  I142  C1261
   1 P1V8_PCH_PLL_AUX      A @S9S_MB_2U_LIB.S9S_MB_2U(SCH_1):P1V8_PCH_PLL_AUX
   2    GND      B @S9S_MB_2U_LIB.S9S_MB_2U(SCH_1):GND

Q_RES_0402LF-0,5%,1/16W,CHIP,CA  I144  R1464
   1 P1V8_PCH_AUX      A @S9S_MB_2U_LIB.S9S_MB_2U(SCH_1):P1V8_PCH_AUX
   2 P1V8_PCH_PLL_AUX      B @S9S_MB_2U_LIB.S9S_MB_2U(SCH_1):P1V8_PCH_PLL_AUX

Q_INDUCTOR_SMLF-BLM18PG121SN1DA  I145  L10
   2 P1V8_PCH_PLL_AUX      2 @S9S_MB_2U_LIB.S9S_MB_2U(SCH_1):P1V8_PCH_PLL_AUX
   1 P1V8_PCH_AUX      1 @S9S_MB_2U_LIB.S9S_MB_2U(SCH_1):P1V8_PCH_AUX

Q_CAP_0402-1UF,6.3V,10%,EMPTY,A  I146  C1257
   1 P1V8_PCH_PLL_AUX      A @S9S_MB_2U_LIB.S9S_MB_2U(SCH_1):P1V8_PCH_PLL_AUX
   2    GND      B @S9S_MB_2U_LIB.S9S_MB_2U(SCH_1):GND

Q_CAP_0402-1UF,6.3V,10%,EMPTY,A  I147  C1253
   1 P1V8_PCH_AUX      A @S9S_MB_2U_LIB.S9S_MB_2U(SCH_1):P1V8_PCH_AUX
   2    GND      B @S9S_MB_2U_LIB.S9S_MB_2U(SCH_1):GND

Q_CAP_C0805-47UF,4V,20%,X6S,CHA  I151  C1273
   1 P1V8_PCH_PLL_AUX      A @S9S_MB_2U_LIB.S9S_MB_2U(SCH_1):P1V8_PCH_PLL_AUX
   2    GND      B @S9S_MB_2U_LIB.S9S_MB_2U(SCH_1):GND

Q_CAP_C0805-47UF,4V,20%,X6S,CHA  I152  C1244
   1 P1V05_PCH_AUX      A @S9S_MB_2U_LIB.S9S_MB_2U(SCH_1):P1V05_PCH_AUX
   2    GND      B @S9S_MB_2U_LIB.S9S_MB_2U(SCH_1):GND

Q_CAP_C0805-47UF,4V,20%,X6S,CHA  I153  C1246
   1 P1V05_PCH_AUX      A @S9S_MB_2U_LIB.S9S_MB_2U(SCH_1):P1V05_PCH_AUX
   2    GND      B @S9S_MB_2U_LIB.S9S_MB_2U(SCH_1):GND

Q_CAP_C0805-47UF,4V,20%,X6S,CHA  I154  C1247
   1 P1V05_PCH_AUX      A @S9S_MB_2U_LIB.S9S_MB_2U(SCH_1):P1V05_PCH_AUX
   2    GND      B @S9S_MB_2U_LIB.S9S_MB_2U(SCH_1):GND

Q_CAP_C0805-47UF,4V,20%,X6S,CHA  I155  C1248
   1 P1V05_PCH_AUX      A @S9S_MB_2U_LIB.S9S_MB_2U(SCH_1):P1V05_PCH_AUX
   2    GND      B @S9S_MB_2U_LIB.S9S_MB_2U(SCH_1):GND

Q_CAP_C0805-47UF,4V,20%,X6S,CHA  I156  C1249
   1 P1V05_PCH_AUX      A @S9S_MB_2U_LIB.S9S_MB_2U(SCH_1):P1V05_PCH_AUX
   2    GND      B @S9S_MB_2U_LIB.S9S_MB_2U(SCH_1):GND

Q_CAP_C0805-47UF,4V,20%,X6S,CHA  I157  C1258
   1 P1V05_PCH_PLL_AUX      A @S9S_MB_2U_LIB.S9S_MB_2U(SCH_1):P1V05_PCH_PLL_AUX
   2    GND      B @S9S_MB_2U_LIB.S9S_MB_2U(SCH_1):GND

Q_CAP_C0805-47UF,4V,20%,X6S,CHA  I158  C1259
   1 P1V8_PCH_PLL_AUX      A @S9S_MB_2U_LIB.S9S_MB_2U(SCH_1):P1V8_PCH_PLL_AUX
   2    GND      B @S9S_MB_2U_LIB.S9S_MB_2U(SCH_1):GND

Q_CAP_C0805-47UF,4V,20%,X6S,CHA  I159  C1272
   1 P1V05_PCH_PLL_AUX      A @S9S_MB_2U_LIB.S9S_MB_2U(SCH_1):P1V05_PCH_PLL_AUX
   2    GND      B @S9S_MB_2U_LIB.S9S_MB_2U(SCH_1):GND

Q_CAP_C0805-47UF,6.3V,20%,X6S,A  I162  C1243
   1 P3V3_AUX      A @S9S_MB_2U_LIB.S9S_MB_2U(SCH_1):P3V3_AUX
   2    GND      B @S9S_MB_2U_LIB.S9S_MB_2U(SCH_1):GND

Q_CAP_C0805-47UF,6.3V,20%,X6S,A  I163  C1245
   1 P3V3_AUX      A @S9S_MB_2U_LIB.S9S_MB_2U(SCH_1):P3V3_AUX
   2    GND      B @S9S_MB_2U_LIB.S9S_MB_2U(SCH_1):GND

Q_INDUCTOR_SMLF-BLM15PX121SN1DA  I164  L2
   2 P1V05_PCH_PLL_AUX      2 @S9S_MB_2U_LIB.S9S_MB_2U(SCH_1):P1V05_PCH_PLL_AUX
   1 P1V05_PCH_AUX      1 @S9S_MB_2U_LIB.S9S_MB_2U(SCH_1):P1V05_PCH_AUX

Q_RES_0402LF-0,5%,1/16W,CHIP,CA  I165  R4803
   1 P1V05_PCH_AUX      A @S9S_MB_2U_LIB.S9S_MB_2U(SCH_1):P1V05_PCH_AUX
   2 P1V05_PCH_PLL_AUX      B @S9S_MB_2U_LIB.S9S_MB_2U(SCH_1):P1V05_PCH_PLL_AUX


DRAWING: @S9S_MB_2U_LIB.S9S_MB_2U(SCH_1):PAGE182 

Q_CAP_C0603-22UF,6.3V,20%,X6S,A  I88  C1920
   1 P3V3_M2_0      A @S9S_MB_2U_LIB.S9S_MB_2U(SCH_1):P3V3_M2_0
   2    GND      B @S9S_MB_2U_LIB.S9S_MB_2U(SCH_1):GND

Q_CAP_C0603-22UF,6.3V,20%,X6S,A  I90  C1921
   1 P3V3_M2_0      A @S9S_MB_2U_LIB.S9S_MB_2U(SCH_1):P3V3_M2_0
   2    GND      B @S9S_MB_2U_LIB.S9S_MB_2U(SCH_1):GND

Q_CAP_C0603-22UF,6.3V,20%,X6S,A  I96  C1922
   1 P3V3_M2_0      A @S9S_MB_2U_LIB.S9S_MB_2U(SCH_1):P3V3_M2_0
   2    GND      B @S9S_MB_2U_LIB.S9S_MB_2U(SCH_1):GND

Q_CAP_0402-0.1UF,25V,10%,X7R,CA  I97  C1923
   1 P3V3_M2_0      A @S9S_MB_2U_LIB.S9S_MB_2U(SCH_1):P3V3_M2_0
   2    GND      B @S9S_MB_2U_LIB.S9S_MB_2U(SCH_1):GND

Q_CAP_0402-0.1UF,25V,10%,X7R,CA  I98  C1924
   1 P3V3_M2_0      A @S9S_MB_2U_LIB.S9S_MB_2U(SCH_1):P3V3_M2_0
   2    GND      B @S9S_MB_2U_LIB.S9S_MB_2U(SCH_1):GND

Q_CAP_0402-0.1UF,25V,10%,X7R,CA  I100  C1925
   1 P3V3_M2_0      A @S9S_MB_2U_LIB.S9S_MB_2U(SCH_1):P3V3_M2_0
   2    GND      B @S9S_MB_2U_LIB.S9S_MB_2U(SCH_1):GND

Q_RES_0402LF-1K,1%,1/16W,CHIP,A  I105  R1605
   1 PD_M2_0_DEVSLP      A @S9S_MB_2U_LIB.S9S_MB_2U(SCH_1):PD_M2_0_DEVSLP
   2    GND      B @S9S_MB_2U_LIB.S9S_MB_2U(SCH_1):GND

Q_RES_0402LF-0,5%,1/16W,CHIP,CA  I162  R486
   1 M2_SSD0_CLKREQ_EN_N      A @S9S_MB_2U_LIB.S9S_MB_2U(SCH_1):M2_SSD0_CLKREQ_EN_N
   2 M2_SSD0_CLKREQ_EN_N_BUF      B @S9S_MB_2U_LIB.S9S_MB_2U(SCH_1):M2_SSD0_CLKREQ_EN_N_BUF

Q_RES_0402LF-4.7K,1%,1/16W,EMPA  I164  R491
   1 M2_SSD0_CLKREQ_EN_N      A @S9S_MB_2U_LIB.S9S_MB_2U(SCH_1):M2_SSD0_CLKREQ_EN_N
   2    GND      B @S9S_MB_2U_LIB.S9S_MB_2U(SCH_1):GND

Q_RES_0402LF-10K,1%,1/16W,CHIPA  I167  R1396
   1 FM_M2_SSD_0_PEDET      A @S9S_MB_2U_LIB.S9S_MB_2U(SCH_1):FM_M2_SSD_0_PEDET
   2 P3V3_AUX      B @S9S_MB_2U_LIB.S9S_MB_2U(SCH_1):P3V3_AUX

Q_RES_0402LF-1K,1%,1/16W,CHIP,A  I173  R487
   1 P3V3_AUX      A @S9S_MB_2U_LIB.S9S_MB_2U(SCH_1):P3V3_AUX
   2 M2_SSD0_CLKREQ_EN_N_BUF      B @S9S_MB_2U_LIB.S9S_MB_2U(SCH_1):M2_SSD0_CLKREQ_EN_N_BUF

Q_RES_0402LF-4.7K,1%,1/16W,CHIA  I176  R478
   1 P3V3_AUX      A @S9S_MB_2U_LIB.S9S_MB_2U(SCH_1):P3V3_AUX
   2 PCIE_M2_SSD0_PRSNT_N      B @S9S_MB_2U_LIB.S9S_MB_2U(SCH_1):PCIE_M2_SSD0_PRSNT_N

SCONN75K_APCI0155P004A-SCONN75A  I178  J59
   2 P3V3_M2_0 3.3V_1 @S9S_MB_2U_LIB.S9S_MB_2U(SCH_1):P3V3_M2_0
   4 P3V3_M2_0 3.3V_2 @S9S_MB_2U_LIB.S9S_MB_2U(SCH_1):P3V3_M2_0
  10 LED_M2_SSD_0_ACT_N DAS_DSS#||LED1# @S9S_MB_2U_LIB.S9S_MB_2U(SCH_1):LED_M2_SSD_0_ACT_N
  12 P3V3_M2_0 3.3V_3 @S9S_MB_2U_LIB.S9S_MB_2U(SCH_1):P3V3_M2_0
  14 P3V3_M2_0 3.3V_4 @S9S_MB_2U_LIB.S9S_MB_2U(SCH_1):P3V3_M2_0
  16 P3V3_M2_0 3.3V_5 @S9S_MB_2U_LIB.S9S_MB_2U(SCH_1):P3V3_M2_0
  18 P3V3_M2_0 3.3V_6 @S9S_MB_2U_LIB.S9S_MB_2U(SCH_1):P3V3_M2_0
  38 PD_M2_0_DEVSLP DEVSLP @S9S_MB_2U_LIB.S9S_MB_2U(SCH_1):PD_M2_0_DEVSLP
  50 RST_PCIE_PCH_DEV_0_N PERST# @S9S_MB_2U_LIB.S9S_MB_2U(SCH_1):RST_PCIE_PCH_DEV_0_N
  52 M2_SSD0_CLKREQ_EN_N_BUF CLKREQ# @S9S_MB_2U_LIB.S9S_MB_2U(SCH_1):M2_SSD0_CLKREQ_EN_N_BUF
  54 M2_0_PEWAKE_N PEWAKE# @S9S_MB_2U_LIB.S9S_MB_2U(SCH_1):M2_0_PEWAKE_N
  58 NC_M2_0_NC18   NC18 @S9S_MB_2U_LIB.S9S_MB_2U(SCH_1):NC_M2_0_NC18
  68 NC_M2_0_SUSCLK SUSCLK @S9S_MB_2U_LIB.S9S_MB_2U(SCH_1):NC_M2_0_SUSCLK
  70 P3V3_M2_0 3.3V_7 @S9S_MB_2U_LIB.S9S_MB_2U(SCH_1):P3V3_M2_0
  72 P3V3_M2_0 3.3V_8 @S9S_MB_2U_LIB.S9S_MB_2U(SCH_1):P3V3_M2_0
  74 P3V3_M2_0 3.3V_9 @S9S_MB_2U_LIB.S9S_MB_2U(SCH_1):P3V3_M2_0
  41 P3E_PCH_M2_RX_DN<3> PERN0||SATA-B+ @S9S_MB_2U_LIB.S9S_MB_2U(SCH_1):P3E_PCH_M2_RX_DN(3)
  43 P3E_PCH_M2_RX_DP<3> PERP0||SATA-B- @S9S_MB_2U_LIB.S9S_MB_2U(SCH_1):P3E_PCH_M2_RX_DP(3)
  47 P3E_PCH_M2_TX_C_DP<3> PETN0||SATA-A- @S9S_MB_2U_LIB.S9S_MB_2U(SCH_1):P3E_PCH_M2_TX_C_DP(3)
  49 P3E_PCH_M2_TX_C_DN<3> PETP0||SATA-A+ @S9S_MB_2U_LIB.S9S_MB_2U(SCH_1):P3E_PCH_M2_TX_C_DN(3)
  57    GND  GND11 @S9S_MB_2U_LIB.S9S_MB_2U(SCH_1):GND
  67 NC_M2_0_NC19   NC19 @S9S_MB_2U_LIB.S9S_MB_2U(SCH_1):NC_M2_0_NC19
  69 FM_M2_SSD_0_PEDET  PEDET @S9S_MB_2U_LIB.S9S_MB_2U(SCH_1):FM_M2_SSD_0_PEDET
  71    GND  GND12 @S9S_MB_2U_LIB.S9S_MB_2U(SCH_1):GND
  73    GND  GND13 @S9S_MB_2U_LIB.S9S_MB_2U(SCH_1):GND
  75    GND  GND14 @S9S_MB_2U_LIB.S9S_MB_2U(SCH_1):GND
  G1    GND     G1 @S9S_MB_2U_LIB.S9S_MB_2U(SCH_1):GND
  G2    GND     G2 @S9S_MB_2U_LIB.S9S_MB_2U(SCH_1):GND
   6 NC_M2_0_NC1    NC1 @S9S_MB_2U_LIB.S9S_MB_2U(SCH_1):NC_M2_0_NC1
   8 NC_M2_0_NC2    NC2 @S9S_MB_2U_LIB.S9S_MB_2U(SCH_1):NC_M2_0_NC2
  20 NC_M2_0_NC3    NC3 @S9S_MB_2U_LIB.S9S_MB_2U(SCH_1):NC_M2_0_NC3
  34 NC_M2_0_NC10   NC10 @S9S_MB_2U_LIB.S9S_MB_2U(SCH_1):NC_M2_0_NC10
  56 NC_M2_0_NC17   NC17 @S9S_MB_2U_LIB.S9S_MB_2U(SCH_1):NC_M2_0_NC17
  48 NC_M2_0_NC16   NC16 @S9S_MB_2U_LIB.S9S_MB_2U(SCH_1):NC_M2_0_NC16
  46 NC_M2_0_NC15   NC15 @S9S_MB_2U_LIB.S9S_MB_2U(SCH_1):NC_M2_0_NC15
  44 NC_M2_0_NC14   NC14 @S9S_MB_2U_LIB.S9S_MB_2U(SCH_1):NC_M2_0_NC14
  42 SMB_M2_P0_1V8AUX_SDA   NC13 @S9S_MB_2U_LIB.S9S_MB_2U(SCH_1):SMB_M2_P0_1V8AUX_SDA
  40 SMB_M2_P0_1V8AUX_SCL   NC12 @S9S_MB_2U_LIB.S9S_MB_2U(SCH_1):SMB_M2_P0_1V8AUX_SCL
  36 NC_M2_0_NC11   NC11 @S9S_MB_2U_LIB.S9S_MB_2U(SCH_1):NC_M2_0_NC11
  32 NC_M2_0_NC9    NC9 @S9S_MB_2U_LIB.S9S_MB_2U(SCH_1):NC_M2_0_NC9
  30 NC_M2_0_NC8    NC8 @S9S_MB_2U_LIB.S9S_MB_2U(SCH_1):NC_M2_0_NC8
  28 NC_M2_0_NC7    NC7 @S9S_MB_2U_LIB.S9S_MB_2U(SCH_1):NC_M2_0_NC7
  26 NC_M2_0_NC6    NC6 @S9S_MB_2U_LIB.S9S_MB_2U(SCH_1):NC_M2_0_NC6
  24 NC_M2_0_NC5    NC5 @S9S_MB_2U_LIB.S9S_MB_2U(SCH_1):NC_M2_0_NC5
  22 NC_M2_0_NC4    NC4 @S9S_MB_2U_LIB.S9S_MB_2U(SCH_1):NC_M2_0_NC4
   1 PCIE_M2_SSD0_PRSNT_N   GND1 @S9S_MB_2U_LIB.S9S_MB_2U(SCH_1):PCIE_M2_SSD0_PRSNT_N
   3    GND   GND2 @S9S_MB_2U_LIB.S9S_MB_2U(SCH_1):GND
   9    GND   GND3 @S9S_MB_2U_LIB.S9S_MB_2U(SCH_1):GND
  15    GND   GND4 @S9S_MB_2U_LIB.S9S_MB_2U(SCH_1):GND
  21    GND   GND5 @S9S_MB_2U_LIB.S9S_MB_2U(SCH_1):GND
  27    GND   GND6 @S9S_MB_2U_LIB.S9S_MB_2U(SCH_1):GND
  33    GND   GND7 @S9S_MB_2U_LIB.S9S_MB_2U(SCH_1):GND
  39    GND   GND8 @S9S_MB_2U_LIB.S9S_MB_2U(SCH_1):GND
  45    GND   GND9 @S9S_MB_2U_LIB.S9S_MB_2U(SCH_1):GND
  51    GND  GND10 @S9S_MB_2U_LIB.S9S_MB_2U(SCH_1):GND
   5 P3E_PCH_M2_RX_DN<0>  PERN3 @S9S_MB_2U_LIB.S9S_MB_2U(SCH_1):P3E_PCH_M2_RX_DN(0)
   7 P3E_PCH_M2_RX_DP<0>  PERP3 @S9S_MB_2U_LIB.S9S_MB_2U(SCH_1):P3E_PCH_M2_RX_DP(0)
  11 P3E_PCH_M2_TX_C_DP<0>  PETN3 @S9S_MB_2U_LIB.S9S_MB_2U(SCH_1):P3E_PCH_M2_TX_C_DP(0)
  13 P3E_PCH_M2_TX_C_DN<0>  PETP3 @S9S_MB_2U_LIB.S9S_MB_2U(SCH_1):P3E_PCH_M2_TX_C_DN(0)
  17 P3E_PCH_M2_RX_DN<1>  PERN2 @S9S_MB_2U_LIB.S9S_MB_2U(SCH_1):P3E_PCH_M2_RX_DN(1)
  19 P3E_PCH_M2_RX_DP<1>  PERP2 @S9S_MB_2U_LIB.S9S_MB_2U(SCH_1):P3E_PCH_M2_RX_DP(1)
  23 P3E_PCH_M2_TX_C_DP<1>  PETN2 @S9S_MB_2U_LIB.S9S_MB_2U(SCH_1):P3E_PCH_M2_TX_C_DP(1)
  25 P3E_PCH_M2_TX_C_DN<1>  PETP2 @S9S_MB_2U_LIB.S9S_MB_2U(SCH_1):P3E_PCH_M2_TX_C_DN(1)
  29 P3E_PCH_M2_RX_DN<2>  PERN1 @S9S_MB_2U_LIB.S9S_MB_2U(SCH_1):P3E_PCH_M2_RX_DN(2)
  31 P3E_PCH_M2_RX_DP<2>  PERP1 @S9S_MB_2U_LIB.S9S_MB_2U(SCH_1):P3E_PCH_M2_RX_DP(2)
  35 P3E_PCH_M2_TX_C_DP<2>  PETN1 @S9S_MB_2U_LIB.S9S_MB_2U(SCH_1):P3E_PCH_M2_TX_C_DP(2)
  37 P3E_PCH_M2_TX_C_DN<2>  PETP1 @S9S_MB_2U_LIB.S9S_MB_2U(SCH_1):P3E_PCH_M2_TX_C_DN(2)
  53 CLK_100M_PE_M2_0_DN REFCLKN @S9S_MB_2U_LIB.S9S_MB_2U(SCH_1):CLK_100M_PE_M2_0_DN
  55 CLK_100M_PE_M2_0_DP REFCLKP @S9S_MB_2U_LIB.S9S_MB_2U(SCH_1):CLK_100M_PE_M2_0_DP

Q_RES_0402LF-0,5%,1/16W,CHIP,CA  I247  R2526
   1 FM_M2_SSD_0_PEDET      A @S9S_MB_2U_LIB.S9S_MB_2U(SCH_1):FM_M2_SSD_0_PEDET
   2 FM_M2_SSD0_E7_PEDET      B @S9S_MB_2U_LIB.S9S_MB_2U(SCH_1):FM_M2_SSD0_E7_PEDET

Q_RES_0402LF-33.2,1%,1/16W,CHIA  I299  R3301
   1 IRQ_LVC3_WAKE_N      A @S9S_MB_2U_LIB.S9S_MB_2U(SCH_1):IRQ_LVC3_WAKE_N
   2 M2_0_PEWAKE_N      B @S9S_MB_2U_LIB.S9S_MB_2U(SCH_1):M2_0_PEWAKE_N

Q_RES_0402LF-10K,1%,1/16W,CHIPA  I303  R3297
   1 LED_HDD_ACTIVITY_B_N      A @S9S_MB_2U_LIB.S9S_MB_2U(SCH_1):LED_HDD_ACTIVITY_B_N
   2    GND      B @S9S_MB_2U_LIB.S9S_MB_2U(SCH_1):GND

Q_RES_0402LF-10K,1%,1/16W,CHIPA  I306  R3298
   1 P3V3_AUX      A @S9S_MB_2U_LIB.S9S_MB_2U(SCH_1):P3V3_AUX
   2 HDD_ACTIVITY_BUF_N      B @S9S_MB_2U_LIB.S9S_MB_2U(SCH_1):HDD_ACTIVITY_BUF_N

Q_CAP_0402-0.1UF,25V,10%,X7R,CA  I308  C1873
   1 P3V3_AUX      A @S9S_MB_2U_LIB.S9S_MB_2U(SCH_1):P3V3_AUX
   2    GND      B @S9S_MB_2U_LIB.S9S_MB_2U(SCH_1):GND

Q_RES_0402LF-0,5%,1/16W,CHIP,CA  I312  R5377
   1 HDD_ACTIVITY_BUF_N      A @S9S_MB_2U_LIB.S9S_MB_2U(SCH_1):HDD_ACTIVITY_BUF_N
   2 PU_BUFFER_HDD_ACTIVITY      B @S9S_MB_2U_LIB.S9S_MB_2U(SCH_1):PU_BUFFER_HDD_ACTIVITY

74LVC1G126SE7-74LVC1G126SE-7,SA  I315  U239
   2 LED_HDD_ACTIVITY_N      A @S9S_MB_2U_LIB.S9S_MB_2U(SCH_1):LED_HDD_ACTIVITY_N
   4 LED_HDD_ACTIVITY_B_N      Y @S9S_MB_2U_LIB.S9S_MB_2U(SCH_1):LED_HDD_ACTIVITY_B_N
   5 P3V3_AUX    VCC @S9S_MB_2U_LIB.S9S_MB_2U(SCH_1):P3V3_AUX
   3    GND    GND @S9S_MB_2U_LIB.S9S_MB_2U(SCH_1):GND
   1 PU_BUFFER_HDD_ACTIVITY     OE @S9S_MB_2U_LIB.S9S_MB_2U(SCH_1):PU_BUFFER_HDD_ACTIVITY

Q_RES_0402LF-4.7K,1%,1/16W,CHIA  I317  R3295
   1 P3V3_M2_0      A @S9S_MB_2U_LIB.S9S_MB_2U(SCH_1):P3V3_M2_0
   2 LED_HDD_ACTIVITY_N      B @S9S_MB_2U_LIB.S9S_MB_2U(SCH_1):LED_HDD_ACTIVITY_N

Q_RES_0402LF-0,5%,1/16W,CHIP,CA  I320  R3294
   1 LED_M2_SSD_0_ACT_N      A @S9S_MB_2U_LIB.S9S_MB_2U(SCH_1):LED_M2_SSD_0_ACT_N
   2 LED_HDD_ACTIVITY_N      B @S9S_MB_2U_LIB.S9S_MB_2U(SCH_1):LED_HDD_ACTIVITY_N

Q_RES_0402LF-4.7K,1%,1/16W,CHIA  I324  R3296
   1 P3V3_AUX      A @S9S_MB_2U_LIB.S9S_MB_2U(SCH_1):P3V3_AUX
   2 HDD_ACTIVITY_BUF      B @S9S_MB_2U_LIB.S9S_MB_2U(SCH_1):HDD_ACTIVITY_BUF

Q_CAP_C0402-1UF,25V,10%,X6S,CHA  I326  C2007
   1 P3V3_AUX      A @S9S_MB_2U_LIB.S9S_MB_2U(SCH_1):P3V3_AUX
   2    GND      B @S9S_MB_2U_LIB.S9S_MB_2U(SCH_1):GND

SN74LVC2G07DCKR_SMLF-SN74LVC2GA  I327  U259
   1 M2_SSD0_CLKREQ_EN_N     1A @S9S_MB_2U_LIB.S9S_MB_2U(SCH_1):M2_SSD0_CLKREQ_EN_N
   3 RST_PCIE_PCH_DEV_PERST_M2_R_N     2A @S9S_MB_2U_LIB.S9S_MB_2U(SCH_1):RST_PCIE_PCH_DEV_PERST_M2_R_N
   6 HDD_ACTIVITY_BUF     1Y @S9S_MB_2U_LIB.S9S_MB_2U(SCH_1):HDD_ACTIVITY_BUF
   4 RST_PCIE_PCH_DEV_BUF_M2_0_PERST     2Y @S9S_MB_2U_LIB.S9S_MB_2U(SCH_1):RST_PCIE_PCH_DEV_BUF_M2_0_PERST_N
   2    GND    GND @S9S_MB_2U_LIB.S9S_MB_2U(SCH_1):GND
   5 P3V3_AUX    VCC @S9S_MB_2U_LIB.S9S_MB_2U(SCH_1):P3V3_AUX

Q_RES_0402LF-4.7K,5%,1/16W,CHIA  I337  R2121
   1 P3V3_AUX      A @S9S_MB_2U_LIB.S9S_MB_2U(SCH_1):P3V3_AUX
   2 RST_PCIE_PCH_DEV_BUF_M2_0_PERST      B @S9S_MB_2U_LIB.S9S_MB_2U(SCH_1):RST_PCIE_PCH_DEV_BUF_M2_0_PERST_N

MOSFET_NCH_DUAL-PJT138K,SMLF,IA  I342  Q95
   1    GND     S1 @S9S_MB_2U_LIB.S9S_MB_2U(SCH_1):GND
   2 HDD_ACTIVITY_BUF     G1 @S9S_MB_2U_LIB.S9S_MB_2U(SCH_1):HDD_ACTIVITY_BUF
   6 HDD_ACTIVITY_BUF_N     D1 @S9S_MB_2U_LIB.S9S_MB_2U(SCH_1):HDD_ACTIVITY_BUF_N

MOSFET_NCH_DUAL-PJT138K,SMLF,IA  I343  Q95
   3 NC_Q95_D2     D2 @S9S_MB_2U_LIB.S9S_MB_2U(SCH_1):NC_Q95_D2
   5 NC_Q95_G2     G2 @S9S_MB_2U_LIB.S9S_MB_2U(SCH_1):NC_Q95_G2
   4 NC_Q95_S2     S2 @S9S_MB_2U_LIB.S9S_MB_2U(SCH_1):NC_Q95_S2

Q_RES_0402LF-33.2,1%,1/16W,CHIA  I344  R2113
   1 RST_PCIE_PCH_DEV_BUF_M2_0_PERST      A @S9S_MB_2U_LIB.S9S_MB_2U(SCH_1):RST_PCIE_PCH_DEV_BUF_M2_0_PERST_N
   2 RST_PCIE_PCH_DEV_0_N      B @S9S_MB_2U_LIB.S9S_MB_2U(SCH_1):RST_PCIE_PCH_DEV_0_N


DRAWING: @S9S_MB_2U_LIB.S9S_MB_2U(SCH_1):PAGE183 

Q_RES_0402LF-2.21K,1%,1/16W,EMA  I5  R1271
   1 P3V3_AUX      A @S9S_MB_2U_LIB.S9S_MB_2U(SCH_1):P3V3_AUX
   2 FM_PCH_SATA_RAID_KEY      B @S9S_MB_2U_LIB.S9S_MB_2U(SCH_1):FM_PCH_SATA_RAID_KEY

PCA9306DP1-PCA9306DP1,SMLF,IC,A  I27  U98
   2 P1V8_PCH_AUX  VREF1 @S9S_MB_2U_LIB.S9S_MB_2U(SCH_1):P1V8_PCH_AUX
   3 SMB_M2_P0_1V8AUX_SCL_R   SCL1 @S9S_MB_2U_LIB.S9S_MB_2U(SCH_1):SMB_M2_P0_1V8AUX_SCL_R
   4 SMB_M2_P0_1V8AUX_SDA_R   SDA1 @S9S_MB_2U_LIB.S9S_MB_2U(SCH_1):SMB_M2_P0_1V8AUX_SDA_R
   5 SMB_SENSOR_M2_P0_3V3AUX_SDA   SDA2 @S9S_MB_2U_LIB.S9S_MB_2U(SCH_1):SMB_SENSOR_M2_P0_3V3AUX_SDA
   6 SMB_SENSOR_M2_P0_3V3AUX_SCL   SCL2 @S9S_MB_2U_LIB.S9S_MB_2U(SCH_1):SMB_SENSOR_M2_P0_3V3AUX_SCL
   7 SMB_PCIE_M2_0_EN  VREF2 @S9S_MB_2U_LIB.S9S_MB_2U(SCH_1):SMB_PCIE_M2_0_EN
   8 SMB_PCIE_M2_0_EN     EN @S9S_MB_2U_LIB.S9S_MB_2U(SCH_1):SMB_PCIE_M2_0_EN
   1    GND    GND @S9S_MB_2U_LIB.S9S_MB_2U(SCH_1):GND

Q_CAP_0402-0.1UF,25V,10%,X7R,CA  I28  C1323
   1 P1V8_PCH_AUX      A @S9S_MB_2U_LIB.S9S_MB_2U(SCH_1):P1V8_PCH_AUX
   2    GND      B @S9S_MB_2U_LIB.S9S_MB_2U(SCH_1):GND

Q_RES_0402LF-4.7K,5%,1/16W,CHIA  I43  R1702
   1 P1V8_PCH_AUX      A @S9S_MB_2U_LIB.S9S_MB_2U(SCH_1):P1V8_PCH_AUX
   2 SMB_M2_P0_1V8AUX_SDA_R      B @S9S_MB_2U_LIB.S9S_MB_2U(SCH_1):SMB_M2_P0_1V8AUX_SDA_R

Q_RES_0402LF-4.7K,5%,1/16W,CHIA  I45  R1703
   1 P1V8_PCH_AUX      A @S9S_MB_2U_LIB.S9S_MB_2U(SCH_1):P1V8_PCH_AUX
   2 SMB_M2_P0_1V8AUX_SCL_R      B @S9S_MB_2U_LIB.S9S_MB_2U(SCH_1):SMB_M2_P0_1V8AUX_SCL_R

Q_CAP_0402-0.1UF,25V,10%,X7R,CA  I52  C1305
   1 P3V3_AUX      A @S9S_MB_2U_LIB.S9S_MB_2U(SCH_1):P3V3_AUX
   2    GND      B @S9S_MB_2U_LIB.S9S_MB_2U(SCH_1):GND

Q_RES_0402LF-33.2,1%,1/16W,CHIA  I65  R2410
   1 SMB_M2_P0_1V8AUX_SDA_R      A @S9S_MB_2U_LIB.S9S_MB_2U(SCH_1):SMB_M2_P0_1V8AUX_SDA_R
   2 SMB_M2_P0_1V8AUX_SDA      B @S9S_MB_2U_LIB.S9S_MB_2U(SCH_1):SMB_M2_P0_1V8AUX_SDA

Q_RES_0402LF-33.2,1%,1/16W,CHIA  I66  R2411
   1 SMB_M2_P0_1V8AUX_SCL_R      A @S9S_MB_2U_LIB.S9S_MB_2U(SCH_1):SMB_M2_P0_1V8AUX_SCL_R
   2 SMB_M2_P0_1V8AUX_SCL      B @S9S_MB_2U_LIB.S9S_MB_2U(SCH_1):SMB_M2_P0_1V8AUX_SCL

Q_RES_0402LF-200K,1%,1/16W,EMPA  I70  R2476
   1 SMB_PCIE_M2_0_EN      A @S9S_MB_2U_LIB.S9S_MB_2U(SCH_1):SMB_PCIE_M2_0_EN
   2 PWRGD_P1V8_PCH_AUX      B @S9S_MB_2U_LIB.S9S_MB_2U(SCH_1):PWRGD_P1V8_PCH_AUX

Q_RES_0402LF-200K,1%,1/16W,CHIA  I72  R1700
   1 P3V3_AUX      A @S9S_MB_2U_LIB.S9S_MB_2U(SCH_1):P3V3_AUX
   2 SMB_PCIE_M2_0_EN      B @S9S_MB_2U_LIB.S9S_MB_2U(SCH_1):SMB_PCIE_M2_0_EN

Q_RES_0402LF-33.2,1%,1/16W,CHIA  I76  R3533
   1 SMB_E1S_3V3AUX_ISO_SCL_R      A @S9S_MB_2U_LIB.S9S_MB_2U(SCH_1):SMB_E1S_3V3AUX_ISO_SCL_R
   2 SMB_E1S_3V3AUX_ISO_SCL      B @S9S_MB_2U_LIB.S9S_MB_2U(SCH_1):SMB_E1S_3V3AUX_ISO_SCL

Q_RES_0402LF-33.2,1%,1/16W,CHIA  I77  R3534
   1 SMB_E1S_3V3AUX_ISO_SDA_R      A @S9S_MB_2U_LIB.S9S_MB_2U(SCH_1):SMB_E1S_3V3AUX_ISO_SDA_R
   2 SMB_E1S_3V3AUX_ISO_SDA      B @S9S_MB_2U_LIB.S9S_MB_2U(SCH_1):SMB_E1S_3V3AUX_ISO_SDA

Q_RES_0402LF-4.7K,5%,1/16W,CHIA  I78  R3532
   1 P3V3_E1S_0      A @S9S_MB_2U_LIB.S9S_MB_2U(SCH_1):P3V3_E1S_0
   2 SMB_E1S_3V3AUX_ISO_SDA_R      B @S9S_MB_2U_LIB.S9S_MB_2U(SCH_1):SMB_E1S_3V3AUX_ISO_SDA_R

Q_RES_0402LF-4.7K,5%,1/16W,CHIA  I80  R3530
   1 P3V3_E1S_0      A @S9S_MB_2U_LIB.S9S_MB_2U(SCH_1):P3V3_E1S_0
   2 SMB_E1S_3V3AUX_ISO_SCL_R      B @S9S_MB_2U_LIB.S9S_MB_2U(SCH_1):SMB_E1S_3V3AUX_ISO_SCL_R

Q_CAP_0402-0.1UF,25V,10%,X7R,CA  I82  C1998
   1 P3V3_E1S_0      A @S9S_MB_2U_LIB.S9S_MB_2U(SCH_1):P3V3_E1S_0
   2    GND      B @S9S_MB_2U_LIB.S9S_MB_2U(SCH_1):GND

Q_CAP_0402-0.1UF,25V,10%,X7R,CA  I89  C1997
   1 P3V3_AUX      A @S9S_MB_2U_LIB.S9S_MB_2U(SCH_1):P3V3_AUX
   2    GND      B @S9S_MB_2U_LIB.S9S_MB_2U(SCH_1):GND

PCA9617ADP-PCA9617ADP,SMLF,IC,A  I93  U279
   5 SMB_PCIE_E1S_ISO_EN_R     EN @S9S_MB_2U_LIB.S9S_MB_2U(SCH_1):SMB_PCIE_E1S_ISO_EN_R
   1 P3V3_E1S_0   VCCA @S9S_MB_2U_LIB.S9S_MB_2U(SCH_1):P3V3_E1S_0
   8 P3V3_AUX   VCCB @S9S_MB_2U_LIB.S9S_MB_2U(SCH_1):P3V3_AUX
   2 SMB_E1S_3V3AUX_ISO_SCL_R   SCLA @S9S_MB_2U_LIB.S9S_MB_2U(SCH_1):SMB_E1S_3V3AUX_ISO_SCL_R
   3 SMB_E1S_3V3AUX_ISO_SDA_R   SDAA @S9S_MB_2U_LIB.S9S_MB_2U(SCH_1):SMB_E1S_3V3AUX_ISO_SDA_R
   6 SMB_SENSOR_E1S_3V3AUX_SDA   SDAB @S9S_MB_2U_LIB.S9S_MB_2U(SCH_1):SMB_SENSOR_E1S_3V3AUX_SDA
   7 SMB_SENSOR_E1S_3V3AUX_SCL   SCLB @S9S_MB_2U_LIB.S9S_MB_2U(SCH_1):SMB_SENSOR_E1S_3V3AUX_SCL
   4    GND    GND @S9S_MB_2U_LIB.S9S_MB_2U(SCH_1):GND

Q_RES_0402LF-200K,1%,1/16W,EMPA  I96  R3531
   1 SMB_PCIE_E1S_ISO_EN      A @S9S_MB_2U_LIB.S9S_MB_2U(SCH_1):SMB_PCIE_E1S_ISO_EN
   2 SMB_PCIE_E1S_ISO_EN_R      B @S9S_MB_2U_LIB.S9S_MB_2U(SCH_1):SMB_PCIE_E1S_ISO_EN_R

Q_RES_0402LF-10K,1%,1/16W,CHIPA  I99  R3529
   1 P3V3_AUX      A @S9S_MB_2U_LIB.S9S_MB_2U(SCH_1):P3V3_AUX
   2 SMB_PCIE_E1S_ISO_EN_R      B @S9S_MB_2U_LIB.S9S_MB_2U(SCH_1):SMB_PCIE_E1S_ISO_EN_R


DRAWING: @S9S_MB_2U_LIB.S9S_MB_2U(SCH_1):PAGE185 

Q_RES_0402LF-0,5%,1/16W,CHIP,CA  I24  R149
   1 PECI_PCH_R      A @S9S_MB_2U_LIB.S9S_MB_2U(SCH_1):PECI_PCH_R
   2 PECI_PCH_B1      B @S9S_MB_2U_LIB.S9S_MB_2U(SCH_1):PECI_PCH_B1

Q_RES_0402LF-4.75K,1%,1/16W,EMA  I26  R145
   1 PVNN_TERM_CPU0      A @S9S_MB_2U_LIB.S9S_MB_2U(SCH_1):PVNN_TERM_CPU0
   2 PECI_PCH_R      B @S9S_MB_2U_LIB.S9S_MB_2U(SCH_1):PECI_PCH_R

Q_RES_0402LF-4.75K,1%,1/16W,EMA  I30  R146
   1 PVNN_TERM_CPU0      A @S9S_MB_2U_LIB.S9S_MB_2U(SCH_1):PVNN_TERM_CPU0
   2 PECI_BMC_R      B @S9S_MB_2U_LIB.S9S_MB_2U(SCH_1):PECI_BMC_R

Q_RES_0402LF-0,5%,1/16W,CHIP,CA  I32  R1297
   1 PECI_BMC_R      A @S9S_MB_2U_LIB.S9S_MB_2U(SCH_1):PECI_BMC_R
   2 PECI_BMC_B1      B @S9S_MB_2U_LIB.S9S_MB_2U(SCH_1):PECI_BMC_B1

NC7SB3157_SMLF-NC7SB3157P6X,NCA  I35  U142
   1 PECI_BMC_B1     B1 @S9S_MB_2U_LIB.S9S_MB_2U(SCH_1):PECI_BMC_B1
   2    GND    GND @S9S_MB_2U_LIB.S9S_MB_2U(SCH_1):GND
   3 PECI_PCH_B1     B0 @S9S_MB_2U_LIB.S9S_MB_2U(SCH_1):PECI_PCH_B1
   6 PECI_MUX_SEL_R      S @S9S_MB_2U_LIB.S9S_MB_2U(SCH_1):PECI_MUX_SEL_R
   5 P3V3_AUX    VCC @S9S_MB_2U_LIB.S9S_MB_2U(SCH_1):P3V3_AUX
   4 PECI_CPU_GTL      A @S9S_MB_2U_LIB.S9S_MB_2U(SCH_1):PECI_CPU_GTL

Q_CAP_C0402-1UF,25V,10%,X6S,CHA  I36  C1612
   1 P3V3_AUX      A @S9S_MB_2U_LIB.S9S_MB_2U(SCH_1):P3V3_AUX
   2    GND      B @S9S_MB_2U_LIB.S9S_MB_2U(SCH_1):GND

Q_RES_0402LF-4.75K,1%,1/16W,CHA  I39  R2253
   1 P3V3_AUX      A @S9S_MB_2U_LIB.S9S_MB_2U(SCH_1):P3V3_AUX
   2 PECI_MUX_SEL_R      B @S9S_MB_2U_LIB.S9S_MB_2U(SCH_1):PECI_MUX_SEL_R

Q_RES_0402LF-0,5%,1/16W,CHIP,CA  I41  R2255
   1 PECI_MUX_SEL_R      A @S9S_MB_2U_LIB.S9S_MB_2U(SCH_1):PECI_MUX_SEL_R
   2 FM_PECI_MUX_SEL_N      B @S9S_MB_2U_LIB.S9S_MB_2U(SCH_1):FM_PECI_MUX_SEL_N

Q_RES_0402LF-100K,1%,1/16W,EMPA  I42  R2252
   1 PECI_MUX_SEL_R      A @S9S_MB_2U_LIB.S9S_MB_2U(SCH_1):PECI_MUX_SEL_R
   2    GND      B @S9S_MB_2U_LIB.S9S_MB_2U(SCH_1):GND

Q_RES_0402LF-0,5%,1/16W,EMPTY,A  I45  R3064
   1 PECI_CPU_GTL      A @S9S_MB_2U_LIB.S9S_MB_2U(SCH_1):PECI_CPU_GTL
   2 PECI_BMC_ME      B @S9S_MB_2U_LIB.S9S_MB_2U(SCH_1):PECI_BMC_ME

Q_RES_0402LF-49.9,1%,1/16W,CHIA  I47  R143
   1 PECI_PCH      A @S9S_MB_2U_LIB.S9S_MB_2U(SCH_1):PECI_PCH
   2 PECI_PCH_R      B @S9S_MB_2U_LIB.S9S_MB_2U(SCH_1):PECI_PCH_R

Q_RES_0402LF-10K,1%,1/16W,EMPTA  I49  R148
   1 PECI_BMC_R      A @S9S_MB_2U_LIB.S9S_MB_2U(SCH_1):PECI_BMC_R
   2    GND      B @S9S_MB_2U_LIB.S9S_MB_2U(SCH_1):GND

Q_RES_0402LF-10K,1%,1/16W,CHIPA  I50  R147
   1 PECI_PCH_R      A @S9S_MB_2U_LIB.S9S_MB_2U(SCH_1):PECI_PCH_R
   2    GND      B @S9S_MB_2U_LIB.S9S_MB_2U(SCH_1):GND

Q_RES_0402LF-0,5%,1/16W,CHIP,CA  I51  R144
   1 PECI_BMC      A @S9S_MB_2U_LIB.S9S_MB_2U(SCH_1):PECI_BMC
   2 PECI_BMC_R      B @S9S_MB_2U_LIB.S9S_MB_2U(SCH_1):PECI_BMC_R


DRAWING: @S9S_MB_2U_LIB.S9S_MB_2U(SCH_1):PAGE186 

Q_RES_0402LF-1K,1%,1/16W,EMPTYA  I11  R367
   1 P3V3_AUX      A @S9S_MB_2U_LIB.S9S_MB_2U(SCH_1):P3V3_AUX
   2 FM_PCH_SPKR      B @S9S_MB_2U_LIB.S9S_MB_2U(SCH_1):FM_PCH_SPKR

Q_RES_0402LF-1K,1%,1/16W,CHIP,A  I16  R369
   1 P3V3_AUX      A @S9S_MB_2U_LIB.S9S_MB_2U(SCH_1):P3V3_AUX
   2 FM_ADR_ACK      B @S9S_MB_2U_LIB.S9S_MB_2U(SCH_1):FM_ADR_ACK

Q_RES_0402LF-1K,1%,1/16W,EMPTYA  I45  R371
   1 P3V3_AUX      A @S9S_MB_2U_LIB.S9S_MB_2U(SCH_1):P3V3_AUX
   2 FM_PCH_BOOT_BIOS_STRAP      B @S9S_MB_2U_LIB.S9S_MB_2U(SCH_1):FM_PCH_BOOT_BIOS_STRAP

Q_RES_0402LF-10K,1%,1/16W,CHIPA  I46  R372
   1 FM_PCH_BOOT_BIOS_STRAP      A @S9S_MB_2U_LIB.S9S_MB_2U(SCH_1):FM_PCH_BOOT_BIOS_STRAP
   2    GND      B @S9S_MB_2U_LIB.S9S_MB_2U(SCH_1):GND

Q_RES_0402LF-1K,1%,1/16W,EMPTYA  I60  R374
   1 P3V3_AUX      A @S9S_MB_2U_LIB.S9S_MB_2U(SCH_1):P3V3_AUX
   2 FM_SPI_3V3_1V8_VOLTAGE      B @S9S_MB_2U_LIB.S9S_MB_2U(SCH_1):FM_SPI_3V3_1V8_VOLTAGE

Q_RES_0402LF-10K,1%,1/16W,CHIPA  I61  R375
   1 FM_SPI_3V3_1V8_VOLTAGE      A @S9S_MB_2U_LIB.S9S_MB_2U(SCH_1):FM_SPI_3V3_1V8_VOLTAGE
   2    GND      B @S9S_MB_2U_LIB.S9S_MB_2U(SCH_1):GND

Q_RES_0402LF-20K,1%,1/16W,CHIPA  I68  R502
   1 P3V3_AUX      A @S9S_MB_2U_LIB.S9S_MB_2U(SCH_1):P3V3_AUX
   2 FM_PCH_CONSENT_STRAP_N      B @S9S_MB_2U_LIB.S9S_MB_2U(SCH_1):FM_PCH_CONSENT_STRAP_N

Q_RES_0402LF-1K,1%,1/16W,CHIP,A  I76  R379
   1 FM_ADR_MODE1      A @S9S_MB_2U_LIB.S9S_MB_2U(SCH_1):FM_ADR_MODE1
   2    GND      B @S9S_MB_2U_LIB.S9S_MB_2U(SCH_1):GND

Q_RES_0402LF-1K,1%,1/16W,EMPTYA  I77  R378
   1 P3V3_AUX      A @S9S_MB_2U_LIB.S9S_MB_2U(SCH_1):P3V3_AUX
   2 FM_ADR_MODE1      B @S9S_MB_2U_LIB.S9S_MB_2U(SCH_1):FM_ADR_MODE1

Q_RES_0402LF-1K,1%,1/16W,EMPTYA  I78  R380
   1 P3V3_AUX      A @S9S_MB_2U_LIB.S9S_MB_2U(SCH_1):P3V3_AUX
   2 FM_FLASH_SECURITY_STRAP      B @S9S_MB_2U_LIB.S9S_MB_2U(SCH_1):FM_FLASH_SECURITY_STRAP

Q_RES_0402LF-10K,1%,1/16W,CHIPA  I81  R381
   1 FM_FLASH_SECURITY_STRAP      A @S9S_MB_2U_LIB.S9S_MB_2U(SCH_1):FM_FLASH_SECURITY_STRAP
   2    GND      B @S9S_MB_2U_LIB.S9S_MB_2U(SCH_1):GND

Q_RES_0402LF-1K,1%,1/16W,EMPTYA  I88  R1810
   1 FM_ADR_MODE0      A @S9S_MB_2U_LIB.S9S_MB_2U(SCH_1):FM_ADR_MODE0
   2    GND      B @S9S_MB_2U_LIB.S9S_MB_2U(SCH_1):GND

Q_RES_0402LF-20K,1%,1/16W,CHIPA  I89  R1809
   1 P3V3_AUX      A @S9S_MB_2U_LIB.S9S_MB_2U(SCH_1):P3V3_AUX
   2 FM_ADR_MODE0      B @S9S_MB_2U_LIB.S9S_MB_2U(SCH_1):FM_ADR_MODE0

Q_RES_0402LF-20K,1%,1/16W,EMPTA  I90  R1962
   1 FM_PCH_CONSENT_STRAP_N      A @S9S_MB_2U_LIB.S9S_MB_2U(SCH_1):FM_PCH_CONSENT_STRAP_N
   2    GND      B @S9S_MB_2U_LIB.S9S_MB_2U(SCH_1):GND

Q_RES_0402LF-10K,1%,1/16W,CHIPA  I92  R3325
   1 FM_PCH_SPKR      A @S9S_MB_2U_LIB.S9S_MB_2U(SCH_1):FM_PCH_SPKR
   2    GND      B @S9S_MB_2U_LIB.S9S_MB_2U(SCH_1):GND


DRAWING: @S9S_MB_2U_LIB.S9S_MB_2U(SCH_1):PAGE187 

Q_RES_0402LF-1K,1%,1/16W,EMPTYA  I13  R623
   1 P3V3_AUX      A @S9S_MB_2U_LIB.S9S_MB_2U(SCH_1):P3V3_AUX
   2 FM_PCH_XTALSEL      B @S9S_MB_2U_LIB.S9S_MB_2U(SCH_1):FM_PCH_XTALSEL

Q_RES_0402LF-10K,1%,1/16W,CHIPA  I14  R624
   1 FM_PCH_XTALSEL      A @S9S_MB_2U_LIB.S9S_MB_2U(SCH_1):FM_PCH_XTALSEL
   2    GND      B @S9S_MB_2U_LIB.S9S_MB_2U(SCH_1):GND

Q_RES_0402LF-10K,1%,1/16W,CHIPA  I18  R613
   1 P3V3_AUX      A @S9S_MB_2U_LIB.S9S_MB_2U(SCH_1):P3V3_AUX
   2 FM_JTAG_ODT_DISABLE      B @S9S_MB_2U_LIB.S9S_MB_2U(SCH_1):FM_JTAG_ODT_DISABLE

Q_RES_0402LF-1K,1%,1/16W,EMPTYA  I21  R607
   1 P3V3_AUX      A @S9S_MB_2U_LIB.S9S_MB_2U(SCH_1):P3V3_AUX
   2 FM_ESPI_FLASH_MODE      B @S9S_MB_2U_LIB.S9S_MB_2U(SCH_1):FM_ESPI_FLASH_MODE

Q_RES_0402LF-1K,1%,1/16W,EMPTYA  I23  R614
   1 FM_JTAG_ODT_DISABLE      A @S9S_MB_2U_LIB.S9S_MB_2U(SCH_1):FM_JTAG_ODT_DISABLE
   2    GND      B @S9S_MB_2U_LIB.S9S_MB_2U(SCH_1):GND

Q_RES_0402LF-10K,1%,1/16W,CHIPA  I36  R608
   1 FM_ESPI_FLASH_MODE      A @S9S_MB_2U_LIB.S9S_MB_2U(SCH_1):FM_ESPI_FLASH_MODE
   2    GND      B @S9S_MB_2U_LIB.S9S_MB_2U(SCH_1):GND

Q_RES_0402LF-1K,1%,1/16W,EMPTYA  I39  R609
   1 P3V3_AUX      A @S9S_MB_2U_LIB.S9S_MB_2U(SCH_1):P3V3_AUX
   2 FM_ESPI_CS_SWIZZLE      B @S9S_MB_2U_LIB.S9S_MB_2U(SCH_1):FM_ESPI_CS_SWIZZLE

Q_RES_0402LF-10K,1%,1/16W,CHIPA  I40  R610
   1 FM_ESPI_CS_SWIZZLE      A @S9S_MB_2U_LIB.S9S_MB_2U(SCH_1):FM_ESPI_CS_SWIZZLE
   2    GND      B @S9S_MB_2U_LIB.S9S_MB_2U(SCH_1):GND

Q_RES_0402LF-1K,1%,1/16W,CHIP,A  I43  R611
   1 P3V3_AUX      A @S9S_MB_2U_LIB.S9S_MB_2U(SCH_1):P3V3_AUX
   2 FM_PCH_EXTERNALCLKMODE      B @S9S_MB_2U_LIB.S9S_MB_2U(SCH_1):FM_PCH_EXTERNALCLKMODE

Q_RES_0402LF-10K,1%,1/16W,EMPTA  I44  R612
   1 FM_PCH_EXTERNALCLKMODE      A @S9S_MB_2U_LIB.S9S_MB_2U(SCH_1):FM_PCH_EXTERNALCLKMODE
   2    GND      B @S9S_MB_2U_LIB.S9S_MB_2U(SCH_1):GND

Q_RES_0402LF-10K,1%,1/16W,CHIPA  I48  R619
   1 P3V3_AUX      A @S9S_MB_2U_LIB.S9S_MB_2U(SCH_1):P3V3_AUX
   2 FM_LT_KEY_DOWNGRADE_N      B @S9S_MB_2U_LIB.S9S_MB_2U(SCH_1):FM_LT_KEY_DOWNGRADE_N

Q_RES_0402LF-1K,1%,1/16W,CHIP,A  I51  R615
   1 P3V3_AUX      A @S9S_MB_2U_LIB.S9S_MB_2U(SCH_1):P3V3_AUX
   2 FM_PCH_VISA_DEFAULT      B @S9S_MB_2U_LIB.S9S_MB_2U(SCH_1):FM_PCH_VISA_DEFAULT

Q_RES_0402LF-10K,1%,1/16W,CHIPA  I53  R618
   1 FM_PCH_IO_EXPANDER      A @S9S_MB_2U_LIB.S9S_MB_2U(SCH_1):FM_PCH_IO_EXPANDER
   2    GND      B @S9S_MB_2U_LIB.S9S_MB_2U(SCH_1):GND

Q_RES_0402LF-1K,1%,1/16W,EMPTYA  I54  R617
   1 P3V3_AUX      A @S9S_MB_2U_LIB.S9S_MB_2U(SCH_1):P3V3_AUX
   2 FM_PCH_IO_EXPANDER      B @S9S_MB_2U_LIB.S9S_MB_2U(SCH_1):FM_PCH_IO_EXPANDER

Q_RES_0402LF-1K,1%,1/16W,EMPTYA  I55  R621
   1 P3V3_AUX      A @S9S_MB_2U_LIB.S9S_MB_2U(SCH_1):P3V3_AUX
   2 FM_PCH_SKIP_RTC_CLOCK      B @S9S_MB_2U_LIB.S9S_MB_2U(SCH_1):FM_PCH_SKIP_RTC_CLOCK

Q_RES_0402LF-1K,1%,1/16W,CHIP,A  I56  R622
   1 FM_PCH_SKIP_RTC_CLOCK      A @S9S_MB_2U_LIB.S9S_MB_2U(SCH_1):FM_PCH_SKIP_RTC_CLOCK
   2    GND      B @S9S_MB_2U_LIB.S9S_MB_2U(SCH_1):GND


DRAWING: @S9S_MB_2U_LIB.S9S_MB_2U(SCH_1):PAGE188 

Q_RES_0402LF-10K,1%,1/16W,CHIPA  I21  R1299
   1 FM_MFG_MODE      A @S9S_MB_2U_LIB.S9S_MB_2U(SCH_1):FM_MFG_MODE
   2    GND      B @S9S_MB_2U_LIB.S9S_MB_2U(SCH_1):GND

Q_RES_0402LF-1K,1%,1/16W,EMPTYA  I22  R1298
   1 P1V05_PCH_AUX      A @S9S_MB_2U_LIB.S9S_MB_2U(SCH_1):P1V05_PCH_AUX
   2 FM_MFG_MODE      B @S9S_MB_2U_LIB.S9S_MB_2U(SCH_1):FM_MFG_MODE

Q_RES_0402LF-10K,1%,1/16W,CHIPA  I31  R1311
   1 FM_XTAL_INPUT_FREQUENCY_0_MGPIO      A @S9S_MB_2U_LIB.S9S_MB_2U(SCH_1):FM_XTAL_INPUT_FREQUENCY_0_MGPIO_TEST4
   2    GND      B @S9S_MB_2U_LIB.S9S_MB_2U(SCH_1):GND

Q_RES_0402LF-10K,1%,1/16W,CHIPA  I36  R1457
   1 FM_XTAL_INPUT_FREQUENCY_1_MGPIO      A @S9S_MB_2U_LIB.S9S_MB_2U(SCH_1):FM_XTAL_INPUT_FREQUENCY_1_MGPIO_TEST5
   2    GND      B @S9S_MB_2U_LIB.S9S_MB_2U(SCH_1):GND

Q_RES_0402LF-1K,1%,1/16W,CHIP,A  I43  R1476
   1 FM_PCH_RING_OSC_BYPASS_MGPIO_TE      A @S9S_MB_2U_LIB.S9S_MB_2U(SCH_1):FM_PCH_RING_OSC_BYPASS_MGPIO_TEST2
   2    GND      B @S9S_MB_2U_LIB.S9S_MB_2U(SCH_1):GND

Q_RES_0402LF-1K,1%,1/16W,EMPTYA  I44  R1475
   1 P3V3_AUX      A @S9S_MB_2U_LIB.S9S_MB_2U(SCH_1):P3V3_AUX
   2 FM_PCH_RING_OSC_BYPASS_MGPIO_TE      B @S9S_MB_2U_LIB.S9S_MB_2U(SCH_1):FM_PCH_RING_OSC_BYPASS_MGPIO_TEST2

Q_RES_0402LF-1K,1%,1/16W,EMPTYA  I47  R1477
   1 P3V3_AUX      A @S9S_MB_2U_LIB.S9S_MB_2U(SCH_1):P3V3_AUX
   2 FM_PCH_XTAL_INPUT_MODE_MGPIO_TE      B @S9S_MB_2U_LIB.S9S_MB_2U(SCH_1):FM_PCH_XTAL_INPUT_MODE_MGPIO_TEST3

Q_RES_0402LF-10K,1%,1/16W,CHIPA  I50  R1478
   1 FM_PCH_XTAL_INPUT_MODE_MGPIO_TE      A @S9S_MB_2U_LIB.S9S_MB_2U(SCH_1):FM_PCH_XTAL_INPUT_MODE_MGPIO_TEST3
   2    GND      B @S9S_MB_2U_LIB.S9S_MB_2U(SCH_1):GND

Q_RES_0402LF-5.11K,1%,1/16W,CHA  I57  R3038
   1 P3V3_AUX      A @S9S_MB_2U_LIB.S9S_MB_2U(SCH_1):P3V3_AUX
   2 FM_PCH_SPARE0      B @S9S_MB_2U_LIB.S9S_MB_2U(SCH_1):FM_PCH_SPARE0

Q_RES_0402LF-1K,1%,1/16W,EMPTYA  I63  R1220
   1 P3V3_AUX      A @S9S_MB_2U_LIB.S9S_MB_2U(SCH_1):P3V3_AUX
   2 FM_PCH_MCRO_LDO      B @S9S_MB_2U_LIB.S9S_MB_2U(SCH_1):FM_PCH_MCRO_LDO

Q_RES_0402LF-1K,1%,1/16W,CHIP,A  I64  R1221
   1 FM_PCH_MCRO_LDO      A @S9S_MB_2U_LIB.S9S_MB_2U(SCH_1):FM_PCH_MCRO_LDO
   2    GND      B @S9S_MB_2U_LIB.S9S_MB_2U(SCH_1):GND

Q_RES_0402LF-12K,1%,1/16W,EMPTA  I70  R1497
   1 FM_PCH_DFXTESTMODE      A @S9S_MB_2U_LIB.S9S_MB_2U(SCH_1):FM_PCH_DFXTESTMODE
   2    GND      B @S9S_MB_2U_LIB.S9S_MB_2U(SCH_1):GND

Q_RES_0402LF-10K,1%,1/16W,CHIPA  I71  R1496
   1 P3V3_AUX      A @S9S_MB_2U_LIB.S9S_MB_2U(SCH_1):P3V3_AUX
   2 FM_PCH_DFXTESTMODE      B @S9S_MB_2U_LIB.S9S_MB_2U(SCH_1):FM_PCH_DFXTESTMODE

Q_RES_0402LF-1K,1%,1/16W,EMPTYA  I76  R1498
   1 P1V05_PCH_AUX      A @S9S_MB_2U_LIB.S9S_MB_2U(SCH_1):P1V05_PCH_AUX
   2 FM_BIOS_ADV_FUNCTIONS      B @S9S_MB_2U_LIB.S9S_MB_2U(SCH_1):FM_BIOS_ADV_FUNCTIONS

Q_RES_0402LF-1K,1%,1/16W,CHIP,A  I77  R1499
   1 FM_BIOS_ADV_FUNCTIONS      A @S9S_MB_2U_LIB.S9S_MB_2U(SCH_1):FM_BIOS_ADV_FUNCTIONS
   2    GND      B @S9S_MB_2U_LIB.S9S_MB_2U(SCH_1):GND


DRAWING: @S9S_MB_2U_LIB.S9S_MB_2U(SCH_1):PAGE190 

Q_RES_0402LF-0,5%,1/16W,CHIP,CA  I33  R1214
   1 IRQ_LPC_PIRQA_N_ESPI_ALERT0_N      A @S9S_MB_2U_LIB.S9S_MB_2U(SCH_1):IRQ_LPC_PIRQA_N_ESPI_ALERT0_N
   2 IRQ_LPC_PIRQA_N_ESPI_ALERT0_R_N      B @S9S_MB_2U_LIB.S9S_MB_2U(SCH_1):IRQ_LPC_PIRQA_N_ESPI_ALERT0_R_N

NC7SB3157_SMLF-NC7SB3157P6X,NCA  I34  U60
   1 IRQ_LPC_PIRQA_N_ESPI_ALERT0_R_N     B1 @S9S_MB_2U_LIB.S9S_MB_2U(SCH_1):IRQ_LPC_PIRQA_N_ESPI_ALERT0_R_N
   2    GND    GND @S9S_MB_2U_LIB.S9S_MB_2U(SCH_1):GND
   3 IRQ_LPC_SERIRQ_ESPI_CS1_R_N     B0 @S9S_MB_2U_LIB.S9S_MB_2U(SCH_1):IRQ_LPC_SERIRQ_ESPI_CS1_R_N
   6 FM_ESPI_PLD_EN      S @S9S_MB_2U_LIB.S9S_MB_2U(SCH_1):FM_ESPI_PLD_EN
   5 PGPPA_AUX    VCC @S9S_MB_2U_LIB.S9S_MB_2U(SCH_1):PGPPA_AUX
   4 IRQ_ESPI_LPC_SERIRQ_ALERT_N      A @S9S_MB_2U_LIB.S9S_MB_2U(SCH_1):IRQ_ESPI_LPC_SERIRQ_ALERT_N

Q_CAP_0402-0.1UF,25V,10%,X7R,CA  I36  C607
   1 PGPPA_AUX      A @S9S_MB_2U_LIB.S9S_MB_2U(SCH_1):PGPPA_AUX
   2    GND      B @S9S_MB_2U_LIB.S9S_MB_2U(SCH_1):GND

Q_CAP_C0402-1UF,25V,10%,X6S,CHA  I37  C605
   1 PGPPA_AUX      A @S9S_MB_2U_LIB.S9S_MB_2U(SCH_1):PGPPA_AUX
   2    GND      B @S9S_MB_2U_LIB.S9S_MB_2U(SCH_1):GND

Q_RES_0402LF-49.9,1%,1/16W,CHIA  I38  R1215
   1 IRQ_ESPI_LPC_SERIRQ_ALERT_N      A @S9S_MB_2U_LIB.S9S_MB_2U(SCH_1):IRQ_ESPI_LPC_SERIRQ_ALERT_N
   2 IRQ_ESPI_LPC_SERIRQ_ALERT_R_N      B @S9S_MB_2U_LIB.S9S_MB_2U(SCH_1):IRQ_ESPI_LPC_SERIRQ_ALERT_R_N

NC7SB3157_SMLF-NC7SB3157P6X,NCA  I39  U61
   1 RST_ESPI_RESET_N_R     B1 @S9S_MB_2U_LIB.S9S_MB_2U(SCH_1):RST_ESPI_RESET_N_R
   2    GND    GND @S9S_MB_2U_LIB.S9S_MB_2U(SCH_1):GND
   3 RST_PLTRST_B_MUX_N     B0 @S9S_MB_2U_LIB.S9S_MB_2U(SCH_1):RST_PLTRST_B_MUX_N
   6 FM_ESPI_PLD_EN      S @S9S_MB_2U_LIB.S9S_MB_2U(SCH_1):FM_ESPI_PLD_EN
   5 PGPPA_AUX    VCC @S9S_MB_2U_LIB.S9S_MB_2U(SCH_1):PGPPA_AUX
   4 ESPI_BMC_LPC_RST_N      A @S9S_MB_2U_LIB.S9S_MB_2U(SCH_1):ESPI_BMC_LPC_RST_N

Q_CAP_0402-0.1UF,25V,10%,X7R,CA  I43  C608
   1 PGPPA_AUX      A @S9S_MB_2U_LIB.S9S_MB_2U(SCH_1):PGPPA_AUX
   2    GND      B @S9S_MB_2U_LIB.S9S_MB_2U(SCH_1):GND

Q_CAP_C0402-1UF,25V,10%,X6S,CHA  I45  C606
   1 PGPPA_AUX      A @S9S_MB_2U_LIB.S9S_MB_2U(SCH_1):PGPPA_AUX
   2    GND      B @S9S_MB_2U_LIB.S9S_MB_2U(SCH_1):GND

Q_RES_0402LF-0,5%,1/16W,CHIP,CA  I54  R1748
   1 FM_ESPI_PLD_EN      A @S9S_MB_2U_LIB.S9S_MB_2U(SCH_1):FM_ESPI_PLD_EN
   2 FM_ESPI_PLD_R_EN_BUF      B @S9S_MB_2U_LIB.S9S_MB_2U(SCH_1):FM_ESPI_PLD_R_EN_BUF

Q_RES_0402LF-10K,1%,1/16W,CHIPA  I70  R1961
   1 PGPPA_AUX      A @S9S_MB_2U_LIB.S9S_MB_2U(SCH_1):PGPPA_AUX
   2 ESPI_LFRAME_N_BMC_CS0_N      B @S9S_MB_2U_LIB.S9S_MB_2U(SCH_1):ESPI_LFRAME_N_BMC_CS0_N

Q_CAP_0402-0.1UF,25V,10%,X7R,CA  I84  C1647
   1 P3V3_AUX      A @S9S_MB_2U_LIB.S9S_MB_2U(SCH_1):P3V3_AUX
   2    GND      B @S9S_MB_2U_LIB.S9S_MB_2U(SCH_1):GND

Q_RES_0402LF-1K,1%,1/16W,CHIP,A  I87  R1750
   1 PGPPA_AUX      A @S9S_MB_2U_LIB.S9S_MB_2U(SCH_1):PGPPA_AUX
   2 FM_ESPI_PLD_R_EN_BUF      B @S9S_MB_2U_LIB.S9S_MB_2U(SCH_1):FM_ESPI_PLD_R_EN_BUF

Q_RES_0402LF-10K,1%,1/16W,EMPTA  I89  R1749
   1 FM_ESPI_PLD_R1_EN      A @S9S_MB_2U_LIB.S9S_MB_2U(SCH_1):FM_ESPI_PLD_R1_EN
   2    GND      B @S9S_MB_2U_LIB.S9S_MB_2U(SCH_1):GND

Q_RES_0402LF-0,5%,1/16W,EMPTY,A  I91  R2132
   1 JTAG_TRC_PCH_PTI<6>      A @S9S_MB_2U_LIB.S9S_MB_2U(SCH_1):JTAG_TRC_PCH_PTI(6)
   2 FM_ESPI_PLD_R1_EN      B @S9S_MB_2U_LIB.S9S_MB_2U(SCH_1):FM_ESPI_PLD_R1_EN

Q_RES_0402LF-10K,1%,1/16W,EMPTA  I94  R2451
   1 P3V3_AUX      A @S9S_MB_2U_LIB.S9S_MB_2U(SCH_1):P3V3_AUX
   2 FM_ESPI_PLD_R1_EN      B @S9S_MB_2U_LIB.S9S_MB_2U(SCH_1):FM_ESPI_PLD_R1_EN

74LVC1G07SE7-74LVC1G07SE-7,SMLA  I95  U154
   5 P3V3_AUX    VCC @S9S_MB_2U_LIB.S9S_MB_2U(SCH_1):P3V3_AUX
   2 FM_ESPI_PLD_R1_EN      A @S9S_MB_2U_LIB.S9S_MB_2U(SCH_1):FM_ESPI_PLD_R1_EN
   3    GND    GND @S9S_MB_2U_LIB.S9S_MB_2U(SCH_1):GND
   4 FM_ESPI_PLD_R_EN_BUF      Y @S9S_MB_2U_LIB.S9S_MB_2U(SCH_1):FM_ESPI_PLD_R_EN_BUF
   1 NC_ESPI_PLD_R_EN_BUF    NC1 @S9S_MB_2U_LIB.S9S_MB_2U(SCH_1):NC_ESPI_PLD_R_EN_BUF

Q_RES_0402LF-10,1%,1/16W,CHIP,A  I96  R1868
   1 ESPI_LAD0_DATA_IO3      A @S9S_MB_2U_LIB.S9S_MB_2U(SCH_1):ESPI_LAD0_DATA_IO3
   2 ESPI_LPC_LAD0_IO3      B @S9S_MB_2U_LIB.S9S_MB_2U(SCH_1):ESPI_LPC_LAD0_IO3

Q_RES_0402LF-10,1%,1/16W,CHIP,A  I97  R1869
   1 ESPI_LAD0_DATA_IO2      A @S9S_MB_2U_LIB.S9S_MB_2U(SCH_1):ESPI_LAD0_DATA_IO2
   2 ESPI_LPC_LAD0_IO2      B @S9S_MB_2U_LIB.S9S_MB_2U(SCH_1):ESPI_LPC_LAD0_IO2

Q_RES_0402LF-10,1%,1/16W,CHIP,A  I98  R1870
   1 ESPI_LAD0_DATA_IO1      A @S9S_MB_2U_LIB.S9S_MB_2U(SCH_1):ESPI_LAD0_DATA_IO1
   2 ESPI_LPC_LAD0_IO1      B @S9S_MB_2U_LIB.S9S_MB_2U(SCH_1):ESPI_LPC_LAD0_IO1

Q_RES_0402LF-10,1%,1/16W,CHIP,A  I99  R1871
   1 ESPI_LAD0_DATA_IO0      A @S9S_MB_2U_LIB.S9S_MB_2U(SCH_1):ESPI_LAD0_DATA_IO0
   2 ESPI_LPC_LAD0_IO0      B @S9S_MB_2U_LIB.S9S_MB_2U(SCH_1):ESPI_LPC_LAD0_IO0

Q_RES_0402LF-10,1%,1/16W,CHIP,A  I100  R1872
   1 CLK_24M_66M_LPC0_ESPI      A @S9S_MB_2U_LIB.S9S_MB_2U(SCH_1):CLK_24M_66M_LPC0_ESPI
   2 ESPI_HOST_LPC_BMC_CLK      B @S9S_MB_2U_LIB.S9S_MB_2U(SCH_1):ESPI_HOST_LPC_BMC_CLK

Q_RES_0402LF-10,1%,1/16W,CHIP,A  I101  R2363
   1 RST_ESPI_RESET_N      A @S9S_MB_2U_LIB.S9S_MB_2U(SCH_1):RST_ESPI_RESET_N
   2 RST_ESPI_RESET_N_R      B @S9S_MB_2U_LIB.S9S_MB_2U(SCH_1):RST_ESPI_RESET_N_R

Q_RES_0402LF-10,1%,1/16W,CHIP,A  I102  R1479
   1 ESPI_LFRAME_N_BMC_CS0_N      A @S9S_MB_2U_LIB.S9S_MB_2U(SCH_1):ESPI_LFRAME_N_BMC_CS0_N
   2 ESPI_HOST_LPC_BMC_LFRAME_N      B @S9S_MB_2U_LIB.S9S_MB_2U(SCH_1):ESPI_HOST_LPC_BMC_LFRAME_N

Q_RES_0402LF-10,1%,1/16W,CHIP,A  I105  R4118
   1 IRQ_LPC_SERIRQ_ESPI_CS1_N      A @S9S_MB_2U_LIB.S9S_MB_2U(SCH_1):IRQ_LPC_SERIRQ_ESPI_CS1_N
   2 IRQ_LPC_SERIRQ_ESPI_CS1_R_N      B @S9S_MB_2U_LIB.S9S_MB_2U(SCH_1):IRQ_LPC_SERIRQ_ESPI_CS1_R_N


DRAWING: @S9S_MB_2U_LIB.S9S_MB_2U(SCH_1):PAGE191 

Q_RES_0402LF-0,5%,1/16W,CHIP,CA  I2  R1249
   1 FM_THERMTRIP_DLY_LVC1_N      A @S9S_MB_2U_LIB.S9S_MB_2U(SCH_1):FM_THERMTRIP_DLY_LVC1_N
   2 H_THERMTRIP_LVC1_N      B @S9S_MB_2U_LIB.S9S_MB_2U(SCH_1):H_THERMTRIP_LVC1_N

Q_RES_0402LF-0,5%,1/16W,CHIP,CA  I14  R1247
   1 FM_PCH_CPU_PWR_DEBUG_N      A @S9S_MB_2U_LIB.S9S_MB_2U(SCH_1):FM_PCH_CPU_PWR_DEBUG_N
   2 FM_CPU_FBRK_DEBUG_N      B @S9S_MB_2U_LIB.S9S_MB_2U(SCH_1):FM_CPU_FBRK_DEBUG_N

Q_RES_0402LF-33.2,1%,1/16W,CHIA  I29  R1263
   1 FM_PLT_BMC_THERMTRIP_R_N      A @S9S_MB_2U_LIB.S9S_MB_2U(SCH_1):FM_PLT_BMC_THERMTRIP_R_N
   2 FM_PCH_BMC_THERMTRIP_N      B @S9S_MB_2U_LIB.S9S_MB_2U(SCH_1):FM_PCH_BMC_THERMTRIP_N

Q_RES_0402LF-10K,1%,1/16W,CHIPA  I35  R1820
   1 P3V3_AUX      A @S9S_MB_2U_LIB.S9S_MB_2U(SCH_1):P3V3_AUX
   2 FM_PLT_BMC_THERMTRIP_R_N      B @S9S_MB_2U_LIB.S9S_MB_2U(SCH_1):FM_PLT_BMC_THERMTRIP_R_N

Q_RES_0402LF-75,1%,1/16W,CHIP,A  I38  R1266
   1 P1V05_PCH_AUX      A @S9S_MB_2U_LIB.S9S_MB_2U(SCH_1):P1V05_PCH_AUX
   2 H_THERMTRIP_LVC1_N      B @S9S_MB_2U_LIB.S9S_MB_2U(SCH_1):H_THERMTRIP_LVC1_N


DRAWING: @S9S_MB_2U_LIB.S9S_MB_2U(SCH_1):PAGE192 

Q_RES_0402LF-1K,1%,1/16W,CHIP,A  I1  R3040
   1 P3V3_AUX      A @S9S_MB_2U_LIB.S9S_MB_2U(SCH_1):P3V3_AUX
   2 IRQ_PCH_SCI_WHEA_N      B @S9S_MB_2U_LIB.S9S_MB_2U(SCH_1):IRQ_PCH_SCI_WHEA_N

Q_RES_0402LF-10K,1%,1/16W,CHIPA  I4  R1257
   1 P3V3_AUX      A @S9S_MB_2U_LIB.S9S_MB_2U(SCH_1):P3V3_AUX
   2 PU_PCH_VRALERT_N      B @S9S_MB_2U_LIB.S9S_MB_2U(SCH_1):PU_PCH_VRALERT_N

Q_RES_0402LF-10K,1%,1/16W,CHIPA  I6  R3041
   1 P3V3_AUX      A @S9S_MB_2U_LIB.S9S_MB_2U(SCH_1):P3V3_AUX
   2 FM_PCH_GLB_RST_WARN_N      B @S9S_MB_2U_LIB.S9S_MB_2U(SCH_1):FM_PCH_GLB_RST_WARN_N

Q_RES_0402LF-10K,1%,1/16W,CHIPA  I8  R1259
   1 P3V3_AUX      A @S9S_MB_2U_LIB.S9S_MB_2U(SCH_1):P3V3_AUX
   2 PU_LPC_PME_N      B @S9S_MB_2U_LIB.S9S_MB_2U(SCH_1):PU_LPC_PME_N

Q_RES_0402LF-10K,1%,1/16W,EMPTA  I11  R1262
   1 P1V05_PCH_AUX      A @S9S_MB_2U_LIB.S9S_MB_2U(SCH_1):P1V05_PCH_AUX
   2 H_CPU_ERR2_PCH_R_N      B @S9S_MB_2U_LIB.S9S_MB_2U(SCH_1):H_CPU_ERR2_PCH_R_N

Q_RES_0402LF-10K,1%,1/16W,EMPTA  I17  R1260
   1 P1V05_PCH_AUX      A @S9S_MB_2U_LIB.S9S_MB_2U(SCH_1):P1V05_PCH_AUX
   2 H_CPU_ERR0_PCH_R_N      B @S9S_MB_2U_LIB.S9S_MB_2U(SCH_1):H_CPU_ERR0_PCH_R_N

Q_RES_0402LF-10K,1%,1/16W,EMPTA  I18  R3042
   1 P1V05_PCH_AUX      A @S9S_MB_2U_LIB.S9S_MB_2U(SCH_1):P1V05_PCH_AUX
   2 H_CPU_ERR1_PCH_R_N      B @S9S_MB_2U_LIB.S9S_MB_2U(SCH_1):H_CPU_ERR1_PCH_R_N

Q_RES_0402LF-1K,1%,1/16W,CHIP,A  I23  R1253
   1 PGPPA_AUX      A @S9S_MB_2U_LIB.S9S_MB_2U(SCH_1):PGPPA_AUX
   2 IRQ_LPC_PIRQA_N_ESPI_ALERT0_N      B @S9S_MB_2U_LIB.S9S_MB_2U(SCH_1):IRQ_LPC_PIRQA_N_ESPI_ALERT0_N

Q_RES_0402LF-10K,1%,1/16W,CHIPA  I24  R1254
   1 PGPPA_AUX      A @S9S_MB_2U_LIB.S9S_MB_2U(SCH_1):PGPPA_AUX
   2 IRQ_LPC_SERIRQ_ESPI_CS1_N      B @S9S_MB_2U_LIB.S9S_MB_2U(SCH_1):IRQ_LPC_SERIRQ_ESPI_CS1_N

Q_RES_0402LF-1K,1%,1/16W,CHIP,A  I26  R1255
   1 PGPPA_AUX      A @S9S_MB_2U_LIB.S9S_MB_2U(SCH_1):PGPPA_AUX
   2 ESPI_ALERT1_N_LPC_RCIN_N      B @S9S_MB_2U_LIB.S9S_MB_2U(SCH_1):ESPI_ALERT1_N_LPC_RCIN_N

Q_RES_0402LF-10K,1%,1/16W,CHIPA  I41  R1449
   1 P3V3_AUX      A @S9S_MB_2U_LIB.S9S_MB_2U(SCH_1):P3V3_AUX
   2 FM_BIOS_POST_CMPLT_N      B @S9S_MB_2U_LIB.S9S_MB_2U(SCH_1):FM_BIOS_POST_CMPLT_N

Q_RES_0402LF-10K,1%,1/16W,CHIPA  I42  R1450
   1 P3V3_AUX      A @S9S_MB_2U_LIB.S9S_MB_2U(SCH_1):P3V3_AUX
   2 FM_THROTTLE_N      B @S9S_MB_2U_LIB.S9S_MB_2U(SCH_1):FM_THROTTLE_N

Q_RES_0402LF-10K,1%,1/16W,CHIPA  I50  R1458
   1 P3V3_AUX      A @S9S_MB_2U_LIB.S9S_MB_2U(SCH_1):P3V3_AUX
   2 IRQ_SMI_ACTIVE_N      B @S9S_MB_2U_LIB.S9S_MB_2U(SCH_1):IRQ_SMI_ACTIVE_N

Q_RES_0402LF-10K,1%,1/16W,CHIPA  I51  R1459
   1 P3V3_AUX      A @S9S_MB_2U_LIB.S9S_MB_2U(SCH_1):P3V3_AUX
   2 IRQ_PCH_CPU_NMI_EVENT_R_N      B @S9S_MB_2U_LIB.S9S_MB_2U(SCH_1):IRQ_PCH_CPU_NMI_EVENT_R_N

Q_RES_0402LF-10K,1%,1/16W,CHIPA  I59  R8
   1 P3V3_AUX      A @S9S_MB_2U_LIB.S9S_MB_2U(SCH_1):P3V3_AUX
   2 FM_PS_PWROK_DLY_R_SEL      B @S9S_MB_2U_LIB.S9S_MB_2U(SCH_1):FM_PS_PWROK_DLY_R_SEL

Q_RES_0402LF-10K,1%,1/16W,CHIPA  I60  R71
   1 P3V3_AUX      A @S9S_MB_2U_LIB.S9S_MB_2U(SCH_1):P3V3_AUX
   2 FM_ME_BT_DONE      B @S9S_MB_2U_LIB.S9S_MB_2U(SCH_1):FM_ME_BT_DONE

Q_RES_0402LF-10K,1%,1/16W,CHIPA  I62  R1554
   1 P3V3_AUX      A @S9S_MB_2U_LIB.S9S_MB_2U(SCH_1):P3V3_AUX
   2 FM_ME_AUTHN_FAIL      B @S9S_MB_2U_LIB.S9S_MB_2U(SCH_1):FM_ME_AUTHN_FAIL

Q_RES_0402LF-10K,1%,1/16W,CHIPA  I66  R456
   1 P3V3_AUX      A @S9S_MB_2U_LIB.S9S_MB_2U(SCH_1):P3V3_AUX
   2 PU_PCH_PMCALERT_N      B @S9S_MB_2U_LIB.S9S_MB_2U(SCH_1):PU_PCH_PMCALERT_N

Q_RES_0402LF-10K,1%,1/16W,EMPTA  I69  R401
   1 P3V3_AUX      A @S9S_MB_2U_LIB.S9S_MB_2U(SCH_1):P3V3_AUX
   2 IRQ_TPM_SPI_N      B @S9S_MB_2U_LIB.S9S_MB_2U(SCH_1):IRQ_TPM_SPI_N

Q_RES_0402LF-10K,1%,1/16W,CHIPA  I72  R1955
   1 P3V3_AUX      A @S9S_MB_2U_LIB.S9S_MB_2U(SCH_1):P3V3_AUX
   2 FM_PCHHOT_N      B @S9S_MB_2U_LIB.S9S_MB_2U(SCH_1):FM_PCHHOT_N

Q_RES_0402LF-10K,1%,1/16W,CHIPA  I75  R2342
   1 P3V3_AUX      A @S9S_MB_2U_LIB.S9S_MB_2U(SCH_1):P3V3_AUX
   2 FM_DEBUG_PORT_PRSNT_R_N      B @S9S_MB_2U_LIB.S9S_MB_2U(SCH_1):FM_DEBUG_PORT_PRSNT_R_N


DRAWING: @S9S_MB_2U_LIB.S9S_MB_2U(SCH_1):PAGE193 

Q_RES_0402LF-33.2,1%,1/16W,CHIA  I3  R1307
   1 FM_THROTTLE_N      A @S9S_MB_2U_LIB.S9S_MB_2U(SCH_1):FM_THROTTLE_N
   2 FM_THROTTLE_R_N      B @S9S_MB_2U_LIB.S9S_MB_2U(SCH_1):FM_THROTTLE_R_N

Q_RES_0402LF-33.2,1%,1/16W,CHIA  I5  R1300
   1 FM_BIOS_POST_CMPLT_N      A @S9S_MB_2U_LIB.S9S_MB_2U(SCH_1):FM_BIOS_POST_CMPLT_N
   2 FM_BIOS_POST_CMPLT_BMC_N      B @S9S_MB_2U_LIB.S9S_MB_2U(SCH_1):FM_BIOS_POST_CMPLT_BMC_N

Q_RES_0402LF-33.2,1%,1/16W,CHIA  I10  R1309
   1 IRQ_SMI_ACTIVE_N      A @S9S_MB_2U_LIB.S9S_MB_2U(SCH_1):IRQ_SMI_ACTIVE_N
   2 IRQ_SMI_ACTIVE_BMC_N      B @S9S_MB_2U_LIB.S9S_MB_2U(SCH_1):IRQ_SMI_ACTIVE_BMC_N

Q_RES_0402LF-33.2,1%,1/16W,CHIA  I13  R1306
   1 FM_PS_PWROK_DLY_R_SEL      A @S9S_MB_2U_LIB.S9S_MB_2U(SCH_1):FM_PS_PWROK_DLY_R_SEL
   2 FM_PS_PWROK_DLY_SEL      B @S9S_MB_2U_LIB.S9S_MB_2U(SCH_1):FM_PS_PWROK_DLY_SEL

Q_RES_0402LF-33.2,1%,1/16W,CHIA  I20  R1310
   1 IRQ_PCH_CPU_NMI_EVENT_R_N      A @S9S_MB_2U_LIB.S9S_MB_2U(SCH_1):IRQ_PCH_CPU_NMI_EVENT_R_N
   2 IRQ_PCH_CPU_NMI_EVENT_N      B @S9S_MB_2U_LIB.S9S_MB_2U(SCH_1):IRQ_PCH_CPU_NMI_EVENT_N

Q_RES_0402LF-33.2,1%,1/16W,CHIA  I21  R1313
   1 FM_PCH_GLB_RST_WARN_N      A @S9S_MB_2U_LIB.S9S_MB_2U(SCH_1):FM_PCH_GLB_RST_WARN_N
   2 FM_PCH_PLD_GLB_RST_WARN_N      B @S9S_MB_2U_LIB.S9S_MB_2U(SCH_1):FM_PCH_PLD_GLB_RST_WARN_N

Q_RES_0402LF-49.9,1%,1/16W,CHIA  I27  R1455
   1 FM_ADR_MODE0_R      A @S9S_MB_2U_LIB.S9S_MB_2U(SCH_1):FM_ADR_MODE0_R
   2 FM_ADR_MODE0      B @S9S_MB_2U_LIB.S9S_MB_2U(SCH_1):FM_ADR_MODE0

Q_RES_0402LF-49.9,1%,1/16W,CHIA  I28  R1456
   1 FM_CPU_RMCA_CATERR_DLY_LVT3_R_N      A @S9S_MB_2U_LIB.S9S_MB_2U(SCH_1):FM_CPU_RMCA_CATERR_DLY_LVT3_R_N
   2 FM_CPU_RMCA_CATERR_DLY_N      B @S9S_MB_2U_LIB.S9S_MB_2U(SCH_1):FM_CPU_RMCA_CATERR_DLY_N

Q_RES_0402LF-49.9,1%,1/16W,CHIA  I32  R698
   1 FM_ADR_TRIGGER_R_N      A @S9S_MB_2U_LIB.S9S_MB_2U(SCH_1):FM_ADR_TRIGGER_R_N
   2 FM_ADR_TRIGGER_N      B @S9S_MB_2U_LIB.S9S_MB_2U(SCH_1):FM_ADR_TRIGGER_N

Q_RES_0402LF-33.2,1%,1/16W,CHIA  I40  R3065
   1 FM_BIOS_POST_CMPLT_N      A @S9S_MB_2U_LIB.S9S_MB_2U(SCH_1):FM_BIOS_POST_CMPLT_N
   2 FM_BIOS_POST_CMPLT_HDR_N      B @S9S_MB_2U_LIB.S9S_MB_2U(SCH_1):FM_BIOS_POST_CMPLT_HDR_N


DRAWING: @S9S_MB_2U_LIB.S9S_MB_2U(SCH_1):PAGE195 

9QXL2001BNHGI8-9QXL2001BNHGI8,A  I119  U38
  H1 CLK_100M_DB2000_DN DIF_IN# @S9S_MB_2U_LIB.S9S_MB_2U(SCH_1):CLK_100M_DB2000_DN
  J2 NC_CLK_100M_DB2000_NC12   NC12 @S9S_MB_2U_LIB.S9S_MB_2U(SCH_1):NC_CLK_100M_DB2000_NC12
  B3 NC_CLK_100M_DB2000_NC1    NC1 @S9S_MB_2U_LIB.S9S_MB_2U(SCH_1):NC_CLK_100M_DB2000_NC1
  G2 NC_CLK_100M_DB2000_NC10   NC10 @S9S_MB_2U_LIB.S9S_MB_2U(SCH_1):NC_CLK_100M_DB2000_NC10
  A5 CLK_100M_OCP_V3_2_B_R_DP  DIF15 @S9S_MB_2U_LIB.S9S_MB_2U(SCH_1):CLK_100M_OCP_V3_2_B_R_DP
  A1 CLK_100M_OCP_V3_2_D_R_DP  DIF17 @S9S_MB_2U_LIB.S9S_MB_2U(SCH_1):CLK_100M_OCP_V3_2_D_R_DP
  D1 TP_CLK_100M_DIF18_DN DIF18# @S9S_MB_2U_LIB.S9S_MB_2U(SCH_1):TP_CLK_100M_DIF18_DN
  M6 FM_DB2000_DEV_EN VCKPWRGD_PD# @S9S_MB_2U_LIB.S9S_MB_2U(SCH_1):FM_DB2000_DEV_EN
  TH    GND   EPAD @S9S_MB_2U_LIB.S9S_MB_2U(SCH_1):GND
  F2 NC_CLK_100M_DB2000_NC8    NC8 @S9S_MB_2U_LIB.S9S_MB_2U(SCH_1):NC_CLK_100M_DB2000_NC8
 G11 NC_CLK_100M_DB2000_NC11   NC11 @S9S_MB_2U_LIB.S9S_MB_2U(SCH_1):NC_CLK_100M_DB2000_NC11
  K2 NC_CLK_100M_DB2000_NC14   NC14 @S9S_MB_2U_LIB.S9S_MB_2U(SCH_1):NC_CLK_100M_DB2000_NC14
  L6 NC_CLK_100M_DB2000_NC15   NC15 @S9S_MB_2U_LIB.S9S_MB_2U(SCH_1):NC_CLK_100M_DB2000_NC15
 J11 NC_CLK_100M_DB2000_NC13   NC13 @S9S_MB_2U_LIB.S9S_MB_2U(SCH_1):NC_CLK_100M_DB2000_NC13
  J1 CLK_100M_DB2000_CPU0_BCLK0_DP   DIF0 @S9S_MB_2U_LIB.S9S_MB_2U(SCH_1):CLK_100M_DB2000_CPU0_BCLK0_DP
  K1 CLK_100M_DB2000_CPU0_BCLK0_DN  DIF0# @S9S_MB_2U_LIB.S9S_MB_2U(SCH_1):CLK_100M_DB2000_CPU0_BCLK0_DN
  L1 CLK_100M_DB2000_CPU0_BCLK1_DP   DIF1 @S9S_MB_2U_LIB.S9S_MB_2U(SCH_1):CLK_100M_DB2000_CPU0_BCLK1_DP
  M1 CLK_100M_DB2000_CPU0_BCLK1_DN  DIF1# @S9S_MB_2U_LIB.S9S_MB_2U(SCH_1):CLK_100M_DB2000_CPU0_BCLK1_DN
 D12 CLK_100M_OCP_SFF_1_R_DP  DIF10 @S9S_MB_2U_LIB.S9S_MB_2U(SCH_1):CLK_100M_OCP_SFF_1_R_DP
 C12 CLK_100M_OCP_SFF_1_R_DN DIF10# @S9S_MB_2U_LIB.S9S_MB_2U(SCH_1):CLK_100M_OCP_SFF_1_R_DN
 B12 CLK_100M_OCP_SFF_2_R_DP  DIF11 @S9S_MB_2U_LIB.S9S_MB_2U(SCH_1):CLK_100M_OCP_SFF_2_R_DP
 A10 CLK_100M_OCP_SFF_3_R_DN DIF12# @S9S_MB_2U_LIB.S9S_MB_2U(SCH_1):CLK_100M_OCP_SFF_3_R_DN
 A11 CLK_100M_OCP_SFF_3_R_DP  DIF12 @S9S_MB_2U_LIB.S9S_MB_2U(SCH_1):CLK_100M_OCP_SFF_3_R_DP
  A8 TP_CLK_100M_DIF13_DN DIF13# @S9S_MB_2U_LIB.S9S_MB_2U(SCH_1):TP_CLK_100M_DIF13_DN
  A7 CLK_100M_OCP_V3_2_A_R_DP  DIF14 @S9S_MB_2U_LIB.S9S_MB_2U(SCH_1):CLK_100M_OCP_V3_2_A_R_DP
  A6 CLK_100M_OCP_V3_2_A_R_DN DIF14# @S9S_MB_2U_LIB.S9S_MB_2U(SCH_1):CLK_100M_OCP_V3_2_A_R_DN
  A4 CLK_100M_OCP_V3_2_B_R_DN DIF15# @S9S_MB_2U_LIB.S9S_MB_2U(SCH_1):CLK_100M_OCP_V3_2_B_R_DN
  A3 CLK_100M_OCP_V3_2_C_R_DP  DIF16 @S9S_MB_2U_LIB.S9S_MB_2U(SCH_1):CLK_100M_OCP_V3_2_C_R_DP
  A2 CLK_100M_OCP_V3_2_C_R_DN DIF16# @S9S_MB_2U_LIB.S9S_MB_2U(SCH_1):CLK_100M_OCP_V3_2_C_R_DN
  C1 TP_CLK_100M_DIF18_DP  DIF18 @S9S_MB_2U_LIB.S9S_MB_2U(SCH_1):TP_CLK_100M_DIF18_DP
  G1 CLK_100M_DB2000_DP DIF_IN @S9S_MB_2U_LIB.S9S_MB_2U(SCH_1):CLK_100M_DB2000_DP
 A12 CLK_100M_OCP_SFF_2_R_DN DIF11# @S9S_MB_2U_LIB.S9S_MB_2U(SCH_1):CLK_100M_OCP_SFF_2_R_DN
  A9 TP_CLK_100M_DIF13_DP  DIF13 @S9S_MB_2U_LIB.S9S_MB_2U(SCH_1):TP_CLK_100M_DIF13_DP
  B1 CLK_100M_OCP_V3_2_D_R_DN DIF17# @S9S_MB_2U_LIB.S9S_MB_2U(SCH_1):CLK_100M_OCP_V3_2_D_R_DN
 F11 NC_CLK_100M_DB2000_NC9    NC9 @S9S_MB_2U_LIB.S9S_MB_2U(SCH_1):NC_CLK_100M_DB2000_NC9
 D11 NC_CLK_100M_DB2000_NC7    NC7 @S9S_MB_2U_LIB.S9S_MB_2U(SCH_1):NC_CLK_100M_DB2000_NC7
  L7 NC_CLK_100M_DB2000_NC16   NC16 @S9S_MB_2U_LIB.S9S_MB_2U(SCH_1):NC_CLK_100M_DB2000_NC16
  L3 NC_CLK_100M_DB2000_NC17   NC17 @S9S_MB_2U_LIB.S9S_MB_2U(SCH_1):NC_CLK_100M_DB2000_NC17
  L9 NC_CLK_100M_DB2000_NC18   NC18 @S9S_MB_2U_LIB.S9S_MB_2U(SCH_1):NC_CLK_100M_DB2000_NC18
  B5 NC_CLK_100M_DB2000_NC2    NC2 @S9S_MB_2U_LIB.S9S_MB_2U(SCH_1):NC_CLK_100M_DB2000_NC2
  B7 NC_CLK_100M_DB2000_NC3    NC3 @S9S_MB_2U_LIB.S9S_MB_2U(SCH_1):NC_CLK_100M_DB2000_NC3
  B9 NC_CLK_100M_DB2000_NC4    NC4 @S9S_MB_2U_LIB.S9S_MB_2U(SCH_1):NC_CLK_100M_DB2000_NC4
  C2 NC_CLK_100M_DB2000_NC5    NC5 @S9S_MB_2U_LIB.S9S_MB_2U(SCH_1):NC_CLK_100M_DB2000_NC5
  D2 NC_CLK_100M_DB2000_NC6    NC6 @S9S_MB_2U_LIB.S9S_MB_2U(SCH_1):NC_CLK_100M_DB2000_NC6
  M2 CLK_100M_DB2000_CPU0_BCLK2_DP   DIF2 @S9S_MB_2U_LIB.S9S_MB_2U(SCH_1):CLK_100M_DB2000_CPU0_BCLK2_DP
  M3 CLK_100M_DB2000_CPU0_BCLK2_DN  DIF2# @S9S_MB_2U_LIB.S9S_MB_2U(SCH_1):CLK_100M_DB2000_CPU0_BCLK2_DN
  M4 CLK_100M_DB2000_CPU0_BCLK3_DP   DIF3 @S9S_MB_2U_LIB.S9S_MB_2U(SCH_1):CLK_100M_DB2000_CPU0_BCLK3_DP
  M5 CLK_100M_DB2000_CPU0_BCLK3_DN  DIF3# @S9S_MB_2U_LIB.S9S_MB_2U(SCH_1):CLK_100M_DB2000_CPU0_BCLK3_DN
  M7 CLK_100M_DB2000_CPU1_BCLK0_DP   DIF4 @S9S_MB_2U_LIB.S9S_MB_2U(SCH_1):CLK_100M_DB2000_CPU1_BCLK0_DP
  M8 CLK_100M_DB2000_CPU1_BCLK0_DN  DIF4# @S9S_MB_2U_LIB.S9S_MB_2U(SCH_1):CLK_100M_DB2000_CPU1_BCLK0_DN
  M9 CLK_100M_DB2000_CPU1_BCLK1_DP   DIF5 @S9S_MB_2U_LIB.S9S_MB_2U(SCH_1):CLK_100M_DB2000_CPU1_BCLK1_DP
 M10 CLK_100M_DB2000_CPU1_BCLK1_DN  DIF5# @S9S_MB_2U_LIB.S9S_MB_2U(SCH_1):CLK_100M_DB2000_CPU1_BCLK1_DN
 M11 CLK_100M_DB2000_CPU1_BCLK2_DP   DIF6 @S9S_MB_2U_LIB.S9S_MB_2U(SCH_1):CLK_100M_DB2000_CPU1_BCLK2_DP
 M12 CLK_100M_DB2000_CPU1_BCLK2_DN  DIF6# @S9S_MB_2U_LIB.S9S_MB_2U(SCH_1):CLK_100M_DB2000_CPU1_BCLK2_DN
 L12 CLK_100M_DB2000_CPU1_BCLK3_DP   DIF7 @S9S_MB_2U_LIB.S9S_MB_2U(SCH_1):CLK_100M_DB2000_CPU1_BCLK3_DP
 K12 CLK_100M_DB2000_CPU1_BCLK3_DN  DIF7# @S9S_MB_2U_LIB.S9S_MB_2U(SCH_1):CLK_100M_DB2000_CPU1_BCLK3_DN
 J12 CLK_100M_GPU_SWB_REF_DP   DIF8 @S9S_MB_2U_LIB.S9S_MB_2U(SCH_1):CLK_100M_GPU_SWB_REF_DP
 H12 CLK_100M_GPU_SWB_REF_DN  DIF8# @S9S_MB_2U_LIB.S9S_MB_2U(SCH_1):CLK_100M_GPU_SWB_REF_DN
 G12 CLK_100M_OCP_SFF_0_R_DP   DIF9 @S9S_MB_2U_LIB.S9S_MB_2U(SCH_1):CLK_100M_OCP_SFF_0_R_DP
 F12 CLK_100M_OCP_SFF_0_R_DN  DIF9# @S9S_MB_2U_LIB.S9S_MB_2U(SCH_1):CLK_100M_OCP_SFF_0_R_DN
  E2 FM_DB2000_VSBEN  VSBEN @S9S_MB_2U_LIB.S9S_MB_2U(SCH_1):FM_DB2000_VSBEN
  L8 FM_DB2000_1_OE_N VOE5#||DATA @S9S_MB_2U_LIB.S9S_MB_2U(SCH_1):FM_DB2000_1_OE_N
 L10 FM_DB2000_1_OE_N VOE6#||CLK @S9S_MB_2U_LIB.S9S_MB_2U(SCH_1):FM_DB2000_1_OE_N
 K11 FM_DB2000_1_OE_N  VOE7# @S9S_MB_2U_LIB.S9S_MB_2U(SCH_1):FM_DB2000_1_OE_N
 H11 FM_DB2000_8_OE_N  VOE8# @S9S_MB_2U_LIB.S9S_MB_2U(SCH_1):FM_DB2000_8_OE_N
 E12 FM_DB2000_9_OE_N  VOE9# @S9S_MB_2U_LIB.S9S_MB_2U(SCH_1):FM_DB2000_9_OE_N
 E11 FM_DB2000_10_OE_N VOE10#||SHFT_LD# @S9S_MB_2U_LIB.S9S_MB_2U(SCH_1):FM_DB2000_10_OE_N
 C11 FM_DB2000_11_OE_N VOE11# @S9S_MB_2U_LIB.S9S_MB_2U(SCH_1):FM_DB2000_11_OE_N
 B10 FM_DB2000_12_OE_N VOE12# @S9S_MB_2U_LIB.S9S_MB_2U(SCH_1):FM_DB2000_12_OE_N
  L5 SMB_HOST_DB2000_3V3AUX_SCL SMBCLK @S9S_MB_2U_LIB.S9S_MB_2U(SCH_1):SMB_HOST_DB2000_3V3AUX_SCL
  L4 SMB_HOST_DB2000_3V3AUX_SDA SMBDAT @S9S_MB_2U_LIB.S9S_MB_2U(SCH_1):SMB_HOST_DB2000_3V3AUX_SDA
  B6 P3V3_DB2000_VDDA VDDA3.3 @S9S_MB_2U_LIB.S9S_MB_2U(SCH_1):P3V3_DB2000_VDDA
  B2 P3V3_DB2000_VDD VDDO3.3_B2 @S9S_MB_2U_LIB.S9S_MB_2U(SCH_1):P3V3_DB2000_VDD
 B11 P3V3_DB2000_VDD VDDO3.3_B11 @S9S_MB_2U_LIB.S9S_MB_2U(SCH_1):P3V3_DB2000_VDD
  L2 P3V3_DB2000_VDD VDDO3.3_L2 @S9S_MB_2U_LIB.S9S_MB_2U(SCH_1):P3V3_DB2000_VDD
 L11 P3V3_DB2000_VDD VDDO3.3_L11 @S9S_MB_2U_LIB.S9S_MB_2U(SCH_1):P3V3_DB2000_VDD
  H2 P3V3_DB2000_VDDR VDDR3.3 @S9S_MB_2U_LIB.S9S_MB_2U(SCH_1):P3V3_DB2000_VDDR
  B4 PD_DB2000_SMB_SA0 ^VSADR0_TRI @S9S_MB_2U_LIB.S9S_MB_2U(SCH_1):PD_DB2000_SMB_SA0
  B8 PD_DB2000_SMB_SA1 ^VSADR1_TRI @S9S_MB_2U_LIB.S9S_MB_2U(SCH_1):PD_DB2000_SMB_SA1
  E1 TP_CLK_100M_DIF19_DP  DIF19 @S9S_MB_2U_LIB.S9S_MB_2U(SCH_1):TP_CLK_100M_DIF19_DP
  F1 TP_CLK_100M_DIF19_DN DIF19# @S9S_MB_2U_LIB.S9S_MB_2U(SCH_1):TP_CLK_100M_DIF19_DN

Q_RES_0402LF-49.9,1%,1/16W,CHIA  I156  R576
   1 FM_DB2000_OE_N      A @S9S_MB_2U_LIB.S9S_MB_2U(SCH_1):FM_DB2000_OE_N
   2 FM_DB2000_1_OE_N      B @S9S_MB_2U_LIB.S9S_MB_2U(SCH_1):FM_DB2000_1_OE_N

Q_RES_0603LF-2.2,1%,1/10W,CHIPA  I162  R572
   1 P3V3_DB2000_FB_VDD      A @S9S_MB_2U_LIB.S9S_MB_2U(SCH_1):P3V3_DB2000_FB_VDD
   2 P3V3_DB2000_VDDA      B @S9S_MB_2U_LIB.S9S_MB_2U(SCH_1):P3V3_DB2000_VDDA

Q_RES_0603LF-2.2,1%,1/10W,CHIPA  I163  R571
   1 P3V3_DB2000_FB_VDD      A @S9S_MB_2U_LIB.S9S_MB_2U(SCH_1):P3V3_DB2000_FB_VDD
   2 P3V3_DB2000_VDDR      B @S9S_MB_2U_LIB.S9S_MB_2U(SCH_1):P3V3_DB2000_VDDR

Q_CAP_C0603-10UF,6.3V,20%,X6S,A  I164  C209
   1 P3V3_DB2000_VDDA      A @S9S_MB_2U_LIB.S9S_MB_2U(SCH_1):P3V3_DB2000_VDDA
   2    GND      B @S9S_MB_2U_LIB.S9S_MB_2U(SCH_1):GND

Q_CAP_0402-0.1UF,25V,10%,X7R,CA  I165  C211
   1 P3V3_DB2000_VDDA      A @S9S_MB_2U_LIB.S9S_MB_2U(SCH_1):P3V3_DB2000_VDDA
   2    GND      B @S9S_MB_2U_LIB.S9S_MB_2U(SCH_1):GND

Q_CAP_C0603-10UF,6.3V,20%,X6S,A  I167  C208
   1 P3V3_DB2000_VDDR      A @S9S_MB_2U_LIB.S9S_MB_2U(SCH_1):P3V3_DB2000_VDDR
   2    GND      B @S9S_MB_2U_LIB.S9S_MB_2U(SCH_1):GND

Q_CAP_0402-0.1UF,25V,10%,X7R,CA  I168  C210
   1 P3V3_DB2000_VDDR      A @S9S_MB_2U_LIB.S9S_MB_2U(SCH_1):P3V3_DB2000_VDDR
   2    GND      B @S9S_MB_2U_LIB.S9S_MB_2U(SCH_1):GND

Q_INDUCTOR_SMLF-BLM18SG331TN1DA  I170  L3
   2 P3V3_DB2000_VDD      2 @S9S_MB_2U_LIB.S9S_MB_2U(SCH_1):P3V3_DB2000_VDD
   1   P3V3      1 @S9S_MB_2U_LIB.S9S_MB_2U(SCH_1):P3V3

Q_CAP_0402-0.1UF,25V,10%,X7R,CA  I171  C204
   1 P3V3_DB2000_VDD      A @S9S_MB_2U_LIB.S9S_MB_2U(SCH_1):P3V3_DB2000_VDD
   2    GND      B @S9S_MB_2U_LIB.S9S_MB_2U(SCH_1):GND

Q_CAP_0402-0.1UF,25V,10%,X7R,CA  I172  C205
   1 P3V3_DB2000_VDD      A @S9S_MB_2U_LIB.S9S_MB_2U(SCH_1):P3V3_DB2000_VDD
   2    GND      B @S9S_MB_2U_LIB.S9S_MB_2U(SCH_1):GND

Q_CAP_0402-0.1UF,25V,10%,X7R,CA  I173  C206
   1 P3V3_DB2000_VDD      A @S9S_MB_2U_LIB.S9S_MB_2U(SCH_1):P3V3_DB2000_VDD
   2    GND      B @S9S_MB_2U_LIB.S9S_MB_2U(SCH_1):GND

Q_CAP_0402-0.1UF,25V,10%,X7R,CA  I174  C207
   1 P3V3_DB2000_VDD      A @S9S_MB_2U_LIB.S9S_MB_2U(SCH_1):P3V3_DB2000_VDD
   2    GND      B @S9S_MB_2U_LIB.S9S_MB_2U(SCH_1):GND

Q_INDUCTOR_SMLF-BLM18SG331TN1DA  I177  L4
   2 P3V3_DB2000_FB_VDD      2 @S9S_MB_2U_LIB.S9S_MB_2U(SCH_1):P3V3_DB2000_FB_VDD
   1   P3V3      1 @S9S_MB_2U_LIB.S9S_MB_2U(SCH_1):P3V3

Q_RES_0402LF-4.7K,1%,1/16W,CHIA  I178  R568
   1 PD_DB2000_SMB_SA1      A @S9S_MB_2U_LIB.S9S_MB_2U(SCH_1):PD_DB2000_SMB_SA1
   2    GND      B @S9S_MB_2U_LIB.S9S_MB_2U(SCH_1):GND

Q_RES_0402LF-4.7K,1%,1/16W,EMPA  I179  R567
   1   P3V3      A @S9S_MB_2U_LIB.S9S_MB_2U(SCH_1):P3V3
   2 PD_DB2000_SMB_SA1      B @S9S_MB_2U_LIB.S9S_MB_2U(SCH_1):PD_DB2000_SMB_SA1

Q_RES_0402LF-4.7K,1%,1/16W,EMPA  I185  R569
   1   P3V3      A @S9S_MB_2U_LIB.S9S_MB_2U(SCH_1):P3V3
   2 PD_DB2000_SMB_SA0      B @S9S_MB_2U_LIB.S9S_MB_2U(SCH_1):PD_DB2000_SMB_SA0

Q_RES_0402LF-4.7K,1%,1/16W,CHIA  I187  R570
   1 PD_DB2000_SMB_SA0      A @S9S_MB_2U_LIB.S9S_MB_2U(SCH_1):PD_DB2000_SMB_SA0
   2    GND      B @S9S_MB_2U_LIB.S9S_MB_2U(SCH_1):GND

Q_RES_0402LF-4.7K,1%,1/16W,EMPA  I194  R573
   1   P3V3      A @S9S_MB_2U_LIB.S9S_MB_2U(SCH_1):P3V3
   2 FM_DB2000_VSBEN      B @S9S_MB_2U_LIB.S9S_MB_2U(SCH_1):FM_DB2000_VSBEN

Q_RES_0402LF-4.7K,1%,1/16W,CHIA  I197  R574
   1 FM_DB2000_VSBEN      A @S9S_MB_2U_LIB.S9S_MB_2U(SCH_1):FM_DB2000_VSBEN
   2    GND      B @S9S_MB_2U_LIB.S9S_MB_2U(SCH_1):GND

Q_RES_0402LF-49.9,1%,1/16W,CHIA  I199  R575
   1 FM_PLD_CLKS_DEV_EN      A @S9S_MB_2U_LIB.S9S_MB_2U(SCH_1):FM_PLD_CLKS_DEV_EN
   2 FM_DB2000_DEV_EN      B @S9S_MB_2U_LIB.S9S_MB_2U(SCH_1):FM_DB2000_DEV_EN

Q_RES_0402LF-2K,1%,1/16W,CHIP,A  I304  R106
   1    GND      A @S9S_MB_2U_LIB.S9S_MB_2U(SCH_1):GND
   2 FM_PLD_CLKS_DEV_EN      B @S9S_MB_2U_LIB.S9S_MB_2U(SCH_1):FM_PLD_CLKS_DEV_EN

Q_CAP_C0603-10UF,6.3V,20%,X6S,A  I419  C1409
   1 P3V3_DB2000_VDD      A @S9S_MB_2U_LIB.S9S_MB_2U(SCH_1):P3V3_DB2000_VDD
   2    GND      B @S9S_MB_2U_LIB.S9S_MB_2U(SCH_1):GND

Q_RES_0402LF-0,5%,1/16W,CHIP,CA  I487  R4534
   1 CLK_SWB_OE_N      A @S9S_MB_2U_LIB.S9S_MB_2U(SCH_1):CLK_SWB_OE_N
   2 FM_DB2000_8_OE_N      B @S9S_MB_2U_LIB.S9S_MB_2U(SCH_1):FM_DB2000_8_OE_N

Q_RES_0402LF-0,5%,1/16W,CHIP,CA  I534  R1543
   1 OCP_SFF_CLK_OE_N      A @S9S_MB_2U_LIB.S9S_MB_2U(SCH_1):OCP_SFF_CLK_OE_N
   2 FM_DB2000_9_OE_N      B @S9S_MB_2U_LIB.S9S_MB_2U(SCH_1):FM_DB2000_9_OE_N

Q_RES_0402LF-0,5%,1/16W,CHIP,CA  I535  R2562
   1 OCP_SFF_CLK_OE_N      A @S9S_MB_2U_LIB.S9S_MB_2U(SCH_1):OCP_SFF_CLK_OE_N
   2 FM_DB2000_10_OE_N      B @S9S_MB_2U_LIB.S9S_MB_2U(SCH_1):FM_DB2000_10_OE_N

Q_RES_0402LF-0,5%,1/16W,CHIP,CA  I536  R3636
   1 OCP_SFF_CLK_OE_N      A @S9S_MB_2U_LIB.S9S_MB_2U(SCH_1):OCP_SFF_CLK_OE_N
   2 FM_DB2000_11_OE_N      B @S9S_MB_2U_LIB.S9S_MB_2U(SCH_1):FM_DB2000_11_OE_N

Q_RES_0402LF-0,5%,1/16W,CHIP,CA  I537  R3637
   1 OCP_SFF_CLK_OE_N      A @S9S_MB_2U_LIB.S9S_MB_2U(SCH_1):OCP_SFF_CLK_OE_N
   2 FM_DB2000_12_OE_N      B @S9S_MB_2U_LIB.S9S_MB_2U(SCH_1):FM_DB2000_12_OE_N

Q_RES_0402LF-10K,1%,1/16W,CHIPA  I539  R4516
   1   P3V3      A @S9S_MB_2U_LIB.S9S_MB_2U(SCH_1):P3V3
   2 CLK_SWB_OE_N      B @S9S_MB_2U_LIB.S9S_MB_2U(SCH_1):CLK_SWB_OE_N

Q_RES_0402LF-10K,1%,1/16W,CHIPA  I540  R4517
   1   P3V3      A @S9S_MB_2U_LIB.S9S_MB_2U(SCH_1):P3V3
   2 OCP_SFF_CLK_OE_N      B @S9S_MB_2U_LIB.S9S_MB_2U(SCH_1):OCP_SFF_CLK_OE_N


DRAWING: @S9S_MB_2U_LIB.S9S_MB_2U(SCH_1):PAGE197 

9SQ440NQQI8-9SQ440NQQI8,SMLF,IA  I180  U13
  A2 CLK_25M_CK440_CPU1_DN  25M1# @S9S_MB_2U_LIB.S9S_MB_2U(SCH_1):CLK_25M_CK440_CPU1_DN
  C1    GND   EPAD @S9S_MB_2U_LIB.S9S_MB_2U(SCH_1):GND
 A14    GND GNDXTAL @S9S_MB_2U_LIB.S9S_MB_2U(SCH_1):GND
  B9 CLK_CK440_SMB_ADDR1 SMB_ADR1_TRI @S9S_MB_2U_LIB.S9S_MB_2U(SCH_1):CLK_CK440_SMB_ADDR1
 A54 PD_CK440_SBI_CLK SBI_CLK @S9S_MB_2U_LIB.S9S_MB_2U(SCH_1):PD_CK440_SBI_CLK
 B42 PU_CK440_SHFT_LD_N SHFT_LD# @S9S_MB_2U_LIB.S9S_MB_2U(SCH_1):PU_CK440_SHFT_LD_N
 A29 CK440Q_OE_2   OE2# @S9S_MB_2U_LIB.S9S_MB_2U(SCH_1):CK440Q_OE_2
 A26 CK440Q_OE_3   OE3# @S9S_MB_2U_LIB.S9S_MB_2U(SCH_1):CK440Q_OE_3
 B19 CK440Q_OE_4   OE4# @S9S_MB_2U_LIB.S9S_MB_2U(SCH_1):CK440Q_OE_4
 A30 CK440Q_OE_1   OE1# @S9S_MB_2U_LIB.S9S_MB_2U(SCH_1):CK440Q_OE_1
 B15 CK440Q_OE_5   OE5# @S9S_MB_2U_LIB.S9S_MB_2U(SCH_1):CK440Q_OE_5
  A4 CLK_25M_CK440_CPU0_DN  25M0# @S9S_MB_2U_LIB.S9S_MB_2U(SCH_1):CLK_25M_CK440_CPU0_DN
  A5 CLK_25M_CK440_CPU0_DP   25M0 @S9S_MB_2U_LIB.S9S_MB_2U(SCH_1):CLK_25M_CK440_CPU0_DP
  A3 CLK_25M_CK440_CPU1_DP   25M1 @S9S_MB_2U_LIB.S9S_MB_2U(SCH_1):CLK_25M_CK440_CPU1_DP
 A55 CLK_25M_CK440_ISCLK_REF_DN  25M2# @S9S_MB_2U_LIB.S9S_MB_2U(SCH_1):CLK_25M_CK440_ISCLK_REF_DN
 A56 CLK_25M_CK440_ISCLK_REF_DP   25M2 @S9S_MB_2U_LIB.S9S_MB_2U(SCH_1):CLK_25M_CK440_ISCLK_REF_DP
  A1 FM_CK440Q_DEV_25M_EN  25MPG @S9S_MB_2U_LIB.S9S_MB_2U(SCH_1):FM_CK440Q_DEV_25M_EN
 A33 CLK_100M_DB2000_DN 100M0# @S9S_MB_2U_LIB.S9S_MB_2U(SCH_1):CLK_100M_DB2000_DN
 A34 CLK_100M_DB2000_DP  100M0 @S9S_MB_2U_LIB.S9S_MB_2U(SCH_1):CLK_100M_DB2000_DP
 A31 NC_CLK_CK440_100M1_DN 100M1# @S9S_MB_2U_LIB.S9S_MB_2U(SCH_1):NC_CLK_CK440_100M1_DN
 A32 NC_CLK_CK440_100M1_DP  100M1 @S9S_MB_2U_LIB.S9S_MB_2U(SCH_1):NC_CLK_CK440_100M1_DP
 A27 NC_CLK_CK440_100M2_DN 100M2# @S9S_MB_2U_LIB.S9S_MB_2U(SCH_1):NC_CLK_CK440_100M2_DN
 A28 NC_CLK_CK440_100M2_DP  100M2 @S9S_MB_2U_LIB.S9S_MB_2U(SCH_1):NC_CLK_CK440_100M2_DP
 A24 NC_CLK_CK440_100M3_DN 100M3# @S9S_MB_2U_LIB.S9S_MB_2U(SCH_1):NC_CLK_CK440_100M3_DN
 A25 NC_CLK_CK440_100M3_DP  100M3 @S9S_MB_2U_LIB.S9S_MB_2U(SCH_1):NC_CLK_CK440_100M3_DP
 A22 NC_CLK_CK440_100M4_DN 100M4# @S9S_MB_2U_LIB.S9S_MB_2U(SCH_1):NC_CLK_CK440_100M4_DN
 A23 NC_CLK_CK440_100M4_DP  100M4 @S9S_MB_2U_LIB.S9S_MB_2U(SCH_1):NC_CLK_CK440_100M4_DP
 A20 NC_CLK_CK440_100M5_DN 100M5# @S9S_MB_2U_LIB.S9S_MB_2U(SCH_1):NC_CLK_CK440_100M5_DN
 A21 NC_CLK_CK440_100M5_DP  100M5 @S9S_MB_2U_LIB.S9S_MB_2U(SCH_1):NC_CLK_CK440_100M5_DP
 A18 NC_CLK_CK440_100M6_DN 100M6# @S9S_MB_2U_LIB.S9S_MB_2U(SCH_1):NC_CLK_CK440_100M6_DN
 A19 NC_CLK_CK440_100M6_DP  100M6 @S9S_MB_2U_LIB.S9S_MB_2U(SCH_1):NC_CLK_CK440_100M6_DP
 B10    GND   GNDS @S9S_MB_2U_LIB.S9S_MB_2U(SCH_1):GND
 A51 NC_CLK_CK440_MXCK0_DN MXCK0# @S9S_MB_2U_LIB.S9S_MB_2U(SCH_1):NC_CLK_CK440_MXCK0_DN
 A52 NC_CLK_CK440_MXCK0_DP  MXCK0 @S9S_MB_2U_LIB.S9S_MB_2U(SCH_1):NC_CLK_CK440_MXCK0_DP
 A49 NC_CLK_CK440_MXCK1_DN MXCK1# @S9S_MB_2U_LIB.S9S_MB_2U(SCH_1):NC_CLK_CK440_MXCK1_DN
 A50 NC_CLK_CK440_MXCK1_DP  MXCK1 @S9S_MB_2U_LIB.S9S_MB_2U(SCH_1):NC_CLK_CK440_MXCK1_DP
 A47 CLK_100M_CK440_PCH_EXTCLK_R_DN MXCK2# @S9S_MB_2U_LIB.S9S_MB_2U(SCH_1):CLK_100M_CK440_PCH_EXTCLK_R_DN
 A48 CLK_100M_CK440_PCH_EXTCLK_R_DP  MXCK2 @S9S_MB_2U_LIB.S9S_MB_2U(SCH_1):CLK_100M_CK440_PCH_EXTCLK_R_DP
 A45 NC_CLK_CK440_MXCK3_DN MXCK3# @S9S_MB_2U_LIB.S9S_MB_2U(SCH_1):NC_CLK_CK440_MXCK3_DN
 A46 NC_CLK_CK440_MXCK3_DP  MXCK3 @S9S_MB_2U_LIB.S9S_MB_2U(SCH_1):NC_CLK_CK440_MXCK3_DP
 A43 NC_CLK_CK440_MXCK4_DN MXCK4# @S9S_MB_2U_LIB.S9S_MB_2U(SCH_1):NC_CLK_CK440_MXCK4_DN
 A44 NC_CLK_CK440_MXCK4_DP  MXCK4 @S9S_MB_2U_LIB.S9S_MB_2U(SCH_1):NC_CLK_CK440_MXCK4_DP
 A41 NC_CLK_CK440_MXCK5_DN MXCK5# @S9S_MB_2U_LIB.S9S_MB_2U(SCH_1):NC_CLK_CK440_MXCK5_DN
 A42 NC_CLK_CK440_MXCK5_DP  MXCK5 @S9S_MB_2U_LIB.S9S_MB_2U(SCH_1):NC_CLK_CK440_MXCK5_DP
 A39 NC_CLK_CK440_MXCK6_DN MXCK6# @S9S_MB_2U_LIB.S9S_MB_2U(SCH_1):NC_CLK_CK440_MXCK6_DN
 A40 NC_CLK_CK440_MXCK6_DP  MXCK6 @S9S_MB_2U_LIB.S9S_MB_2U(SCH_1):NC_CLK_CK440_MXCK6_DP
 A37 NC_CLK_CK440_MXCK7_DN MXCK7# @S9S_MB_2U_LIB.S9S_MB_2U(SCH_1):NC_CLK_CK440_MXCK7_DN
 A38 NC_CLK_CK440_MXCK7_DP  MXCK7 @S9S_MB_2U_LIB.S9S_MB_2U(SCH_1):NC_CLK_CK440_MXCK7_DP
 A35 NC_CLK_CK440_MXCK8_DN MXCK8# @S9S_MB_2U_LIB.S9S_MB_2U(SCH_1):NC_CLK_CK440_MXCK8_DN
 A36 NC_CLK_CK440_MXCK8_DP  MXCK8 @S9S_MB_2U_LIB.S9S_MB_2U(SCH_1):NC_CLK_CK440_MXCK8_DP
 B38 FM_CK440_MXCK_25M_100M MXCK_SEL_100M# @S9S_MB_2U_LIB.S9S_MB_2U(SCH_1):FM_CK440_MXCK_25M_100M
 B12    GND  NVGND @S9S_MB_2U_LIB.S9S_MB_2U(SCH_1):GND
 B27 FM_CLK_GEN1_OE0_N   OE0# @S9S_MB_2U_LIB.S9S_MB_2U(SCH_1):FM_CLK_GEN1_OE0_N
 B14 CK440Q_OE_6   OE6# @S9S_MB_2U_LIB.S9S_MB_2U(SCH_1):CK440Q_OE_6
  A9 TP_CLK_PFT_IN_DN PFT_IN# @S9S_MB_2U_LIB.S9S_MB_2U(SCH_1):TP_CLK_PFT_IN_DN
  A8 TP_CLK_PFT_IN_DP PFT_IN @S9S_MB_2U_LIB.S9S_MB_2U(SCH_1):TP_CLK_PFT_IN_DP
  B4 PU_CLK_PFT_LOST_N PFT_LOST# @S9S_MB_2U_LIB.S9S_MB_2U(SCH_1):PU_CLK_PFT_LOST_N
  A7 TP_CLK_CK440_PFT_OUT_DN PFT_OUT# @S9S_MB_2U_LIB.S9S_MB_2U(SCH_1):TP_CLK_CK440_PFT_OUT_DN
  A6 TP_CLK_CK440_PFT_OUT_DP PFT_OUT @S9S_MB_2U_LIB.S9S_MB_2U(SCH_1):TP_CLK_CK440_PFT_OUT_DP
 A17 FM_PLD_CLKS_DEV_EN PWRGD||PWRDN# @S9S_MB_2U_LIB.S9S_MB_2U(SCH_1):FM_PLD_CLKS_DEV_EN
 B43 PD_CK440_SBI_DATA_IN SBI_IN @S9S_MB_2U_LIB.S9S_MB_2U(SCH_1):PD_CK440_SBI_DATA_IN
 A53 TP_CK440_SBI_DATA_OUT SBI_OUT @S9S_MB_2U_LIB.S9S_MB_2U(SCH_1):TP_CK440_SBI_DATA_OUT
 A10 SMB_HOST_CLK_3V3AUX_SCL   SCLK @S9S_MB_2U_LIB.S9S_MB_2U(SCH_1):SMB_HOST_CLK_3V3AUX_SCL
  B8 SMB_HOST_CLK_3V3AUX_SDA SMBDATTA @S9S_MB_2U_LIB.S9S_MB_2U(SCH_1):SMB_HOST_CLK_3V3AUX_SDA
 A11 CLK_CK440_SMB_ADDR0 SMB_ADR0_TRI @S9S_MB_2U_LIB.S9S_MB_2U(SCH_1):CLK_CK440_SMB_ADDR0
 A16 FM_CLK_CK440_SS_EN SS_EN_TRI @S9S_MB_2U_LIB.S9S_MB_2U(SCH_1):FM_CLK_CK440_SS_EN
  B1 P3V3_AUX_CLK_GEN_VDDA25M_CK440 VDDA25M @S9S_MB_2U_LIB.S9S_MB_2U(SCH_1):P3V3_AUX_CLK_GEN_VDDA25M_CK440
 B17 P3V3_AUX_CLK_GEN_VDDA100M_CK440 VDDA100M @S9S_MB_2U_LIB.S9S_MB_2U(SCH_1):P3V3_AUX_CLK_GEN_VDDA100M_CK440
  B6 P3V3_AUX_CLK_GEN_VDDPT_CK440  VDDPT @S9S_MB_2U_LIB.S9S_MB_2U(SCH_1):P3V3_AUX_CLK_GEN_VDDPT_CK440
 A12 P3V3_AUX_CLK_GEN_VDDXTAL_CK440 VDDXTAL @S9S_MB_2U_LIB.S9S_MB_2U(SCH_1):P3V3_AUX_CLK_GEN_VDDXTAL_CK440
 A13 XTAL_CLK_GEN1_25M_X1 XIN_CLKIN @S9S_MB_2U_LIB.S9S_MB_2U(SCH_1):XTAL_CLK_GEN1_25M_X1
 B11 XTAL_CLK_GEN1_25M_X2   XOUT @S9S_MB_2U_LIB.S9S_MB_2U(SCH_1):XTAL_CLK_GEN1_25M_X2
 B29 P3V3_AUX_CLK_GEN_VDDMXCK_CK440 VDDMXCK_B29 @S9S_MB_2U_LIB.S9S_MB_2U(SCH_1):P3V3_AUX_CLK_GEN_VDDMXCK_CK440
 B32 P3V3_AUX_CLK_GEN_VDDMXCK_CK440 VDDMXCK_B32 @S9S_MB_2U_LIB.S9S_MB_2U(SCH_1):P3V3_AUX_CLK_GEN_VDDMXCK_CK440
 B35 P3V3_AUX_CLK_GEN_VDDMXCK_CK440 VDDMXCK_B35 @S9S_MB_2U_LIB.S9S_MB_2U(SCH_1):P3V3_AUX_CLK_GEN_VDDMXCK_CK440
 B40 P3V3_AUX_CLK_GEN_VDDMXCK_CK440 VDDMXCK_B40 @S9S_MB_2U_LIB.S9S_MB_2U(SCH_1):P3V3_AUX_CLK_GEN_VDDMXCK_CK440
 B21 P3V3_AUX_CLK_GEN_VDD_CK440 VDD100M_B21 @S9S_MB_2U_LIB.S9S_MB_2U(SCH_1):P3V3_AUX_CLK_GEN_VDD_CK440
 B23 P3V3_AUX_CLK_GEN_VDD_CK440 VDD100M_B23 @S9S_MB_2U_LIB.S9S_MB_2U(SCH_1):P3V3_AUX_CLK_GEN_VDD_CK440

Q_RES_0402LF-0,5%,1/16W,CHIP,CA  I252  R1680
   1 FM_PLD_CLK_25M_EN      A @S9S_MB_2U_LIB.S9S_MB_2U(SCH_1):FM_PLD_CLK_25M_EN
   2 FM_CK440Q_DEV_25M_EN      B @S9S_MB_2U_LIB.S9S_MB_2U(SCH_1):FM_CK440Q_DEV_25M_EN

Q_RES_0402LF-10K,1%,1/16W,EMPTA  I265  R1483
   1 P3V3_AUX      A @S9S_MB_2U_LIB.S9S_MB_2U(SCH_1):P3V3_AUX
   2 FM_CK440Q_DEV_25M_EN      B @S9S_MB_2U_LIB.S9S_MB_2U(SCH_1):FM_CK440Q_DEV_25M_EN

Q_RES_0402LF-4.75K,1%,1/16W,CHA  I267  R1471
   1 P3V3_AUX      A @S9S_MB_2U_LIB.S9S_MB_2U(SCH_1):P3V3_AUX
   2 FM_CLK_CK440_SS_EN      B @S9S_MB_2U_LIB.S9S_MB_2U(SCH_1):FM_CLK_CK440_SS_EN

Q_RES_0402LF-1K,1%,1/16W,EMPTYA  I268  R1484
   1 FM_CK440Q_DEV_25M_EN      A @S9S_MB_2U_LIB.S9S_MB_2U(SCH_1):FM_CK440Q_DEV_25M_EN
   2    GND      B @S9S_MB_2U_LIB.S9S_MB_2U(SCH_1):GND

Q_RES_0402LF-1K,1%,1/16W,CHIP,A  I269  R1527
   1 FM_CLK_GEN1_OE0_N      A @S9S_MB_2U_LIB.S9S_MB_2U(SCH_1):FM_CLK_GEN1_OE0_N
   2    GND      B @S9S_MB_2U_LIB.S9S_MB_2U(SCH_1):GND

Q_RES_0402LF-4.75K,1%,1/16W,CHA  I270  R1502
   1 FM_CLK_CK440_SS_EN      A @S9S_MB_2U_LIB.S9S_MB_2U(SCH_1):FM_CLK_CK440_SS_EN
   2    GND      B @S9S_MB_2U_LIB.S9S_MB_2U(SCH_1):GND

Q_RES_0402LF-4.75K,1%,1/16W,CHA  I271  R1500
   1 PD_CK440_SBI_DATA_IN      A @S9S_MB_2U_LIB.S9S_MB_2U(SCH_1):PD_CK440_SBI_DATA_IN
   2    GND      B @S9S_MB_2U_LIB.S9S_MB_2U(SCH_1):GND

Q_RES_0402LF-10K,1%,1/16W,EMPTA  I272  R1305
   1 P3V3_AUX      A @S9S_MB_2U_LIB.S9S_MB_2U(SCH_1):P3V3_AUX
   2 FM_PLD_CLKS_DEV_EN      B @S9S_MB_2U_LIB.S9S_MB_2U(SCH_1):FM_PLD_CLKS_DEV_EN

Q_RES_0402LF-10K,1%,1/16W,EMPTA  I273  R1204
   1 P3V3_AUX      A @S9S_MB_2U_LIB.S9S_MB_2U(SCH_1):P3V3_AUX
   2 PU_CK440_SHFT_LD_N      B @S9S_MB_2U_LIB.S9S_MB_2U(SCH_1):PU_CK440_SHFT_LD_N

Q_RES_0402LF-1K,1%,1/16W,CHIP,A  I274  R1462
   1 PD_CK440_SBI_CLK      A @S9S_MB_2U_LIB.S9S_MB_2U(SCH_1):PD_CK440_SBI_CLK
   2    GND      B @S9S_MB_2U_LIB.S9S_MB_2U(SCH_1):GND

Q_RES_0402LF-1K,1%,1/16W,EMPTYA  I275  R1390
   1 FM_PLD_CLKS_DEV_EN      A @S9S_MB_2U_LIB.S9S_MB_2U(SCH_1):FM_PLD_CLKS_DEV_EN
   2    GND      B @S9S_MB_2U_LIB.S9S_MB_2U(SCH_1):GND

Q_RES_0402LF-1K,1%,1/16W,CHIP,A  I276  R1267
   1 PU_CK440_SHFT_LD_N      A @S9S_MB_2U_LIB.S9S_MB_2U(SCH_1):PU_CK440_SHFT_LD_N
   2    GND      B @S9S_MB_2U_LIB.S9S_MB_2U(SCH_1):GND

Q_RES_0402LF-4.75K,1%,1/16W,EMA  I277  R1194
   1 P3V3_AUX      A @S9S_MB_2U_LIB.S9S_MB_2U(SCH_1):P3V3_AUX
   2 FM_CK440_MXCK_25M_100M      B @S9S_MB_2U_LIB.S9S_MB_2U(SCH_1):FM_CK440_MXCK_25M_100M

Q_RES_0402LF-4.75K,1%,1/16W,EMA  I278  R912
   1 P3V3_AUX      A @S9S_MB_2U_LIB.S9S_MB_2U(SCH_1):P3V3_AUX
   2 CLK_CK440_SMB_ADDR0      B @S9S_MB_2U_LIB.S9S_MB_2U(SCH_1):CLK_CK440_SMB_ADDR0

Q_RES_0402LF-4.75K,1%,1/16W,EMA  I280  R2481
   1 P3V3_AUX      A @S9S_MB_2U_LIB.S9S_MB_2U(SCH_1):P3V3_AUX
   2 CLK_CK440_SMB_ADDR1      B @S9S_MB_2U_LIB.S9S_MB_2U(SCH_1):CLK_CK440_SMB_ADDR1

Q_RES_0402LF-4.75K,1%,1/16W,CHA  I281  R1196
   1 FM_CK440_MXCK_25M_100M      A @S9S_MB_2U_LIB.S9S_MB_2U(SCH_1):FM_CK440_MXCK_25M_100M
   2    GND      B @S9S_MB_2U_LIB.S9S_MB_2U(SCH_1):GND

Q_RES_0402LF-4.75K,1%,1/16W,CHA  I282  R953
   1 CLK_CK440_SMB_ADDR0      A @S9S_MB_2U_LIB.S9S_MB_2U(SCH_1):CLK_CK440_SMB_ADDR0
   2    GND      B @S9S_MB_2U_LIB.S9S_MB_2U(SCH_1):GND

Q_RES_0402LF-4.75K,1%,1/16W,CHA  I283  R734
   1 CLK_CK440_SMB_ADDR1      A @S9S_MB_2U_LIB.S9S_MB_2U(SCH_1):CLK_CK440_SMB_ADDR1
   2    GND      B @S9S_MB_2U_LIB.S9S_MB_2U(SCH_1):GND

Q_CAP_0402-0.1UF,25V,10%,EMPTYA  I286  C1324
   1 FM_CK440Q_DEV_25M_EN      A @S9S_MB_2U_LIB.S9S_MB_2U(SCH_1):FM_CK440Q_DEV_25M_EN
   2    GND      B @S9S_MB_2U_LIB.S9S_MB_2U(SCH_1):GND

9SQ440NQQI8-9SQ440NQQI8,SMLF,IA  I288  U13
 B22 NC_CK440_B22 NC_B22 @S9S_MB_2U_LIB.S9S_MB_2U(SCH_1):NC_CK440_B22
 B20 NC_CK440_B20 NC_B20 @S9S_MB_2U_LIB.S9S_MB_2U(SCH_1):NC_CK440_B20
 B18 NC_CK440_B18 NC_B18 @S9S_MB_2U_LIB.S9S_MB_2U(SCH_1):NC_CK440_B18
 B16 NC_CK440_B16 NC_B16 @S9S_MB_2U_LIB.S9S_MB_2U(SCH_1):NC_CK440_B16
 B13 NC_CK440_B13 NC_B13 @S9S_MB_2U_LIB.S9S_MB_2U(SCH_1):NC_CK440_B13
  B7 NC_CK440_B7  NC_B7 @S9S_MB_2U_LIB.S9S_MB_2U(SCH_1):NC_CK440_B7
  B5 NC_CK440_B5  NC_B5 @S9S_MB_2U_LIB.S9S_MB_2U(SCH_1):NC_CK440_B5
  B3 NC_CK440_B3  NC_B3 @S9S_MB_2U_LIB.S9S_MB_2U(SCH_1):NC_CK440_B3
  B2 NC_CK440_B2  NC_B2 @S9S_MB_2U_LIB.S9S_MB_2U(SCH_1):NC_CK440_B2
 A15 NC_CK440_A15 NC_A15 @S9S_MB_2U_LIB.S9S_MB_2U(SCH_1):NC_CK440_A15
 B24 NC_CK440_B24 NC_B24 @S9S_MB_2U_LIB.S9S_MB_2U(SCH_1):NC_CK440_B24
 B25 NC_CK440_B25 NC_B25 @S9S_MB_2U_LIB.S9S_MB_2U(SCH_1):NC_CK440_B25
 B26 NC_CK440_B26 NC_B26 @S9S_MB_2U_LIB.S9S_MB_2U(SCH_1):NC_CK440_B26
 B28 NC_CK440_B28 NC_B28 @S9S_MB_2U_LIB.S9S_MB_2U(SCH_1):NC_CK440_B28
 B30 NC_CK440_B30 NC_B30 @S9S_MB_2U_LIB.S9S_MB_2U(SCH_1):NC_CK440_B30
 B31 NC_CK440_B31 NC_B31 @S9S_MB_2U_LIB.S9S_MB_2U(SCH_1):NC_CK440_B31
 B33 NC_CK440_B33 NC_B33 @S9S_MB_2U_LIB.S9S_MB_2U(SCH_1):NC_CK440_B33
 B34 NC_CK440_B34 NC_B34 @S9S_MB_2U_LIB.S9S_MB_2U(SCH_1):NC_CK440_B34
 B36 NC_CK440_B36 NC_B36 @S9S_MB_2U_LIB.S9S_MB_2U(SCH_1):NC_CK440_B36
 B37 NC_CK440_B37 NC_B37 @S9S_MB_2U_LIB.S9S_MB_2U(SCH_1):NC_CK440_B37
 B39 NC_CK440_B39 NC_B39 @S9S_MB_2U_LIB.S9S_MB_2U(SCH_1):NC_CK440_B39
 B41 NC_CK440_B41 NC_B41 @S9S_MB_2U_LIB.S9S_MB_2U(SCH_1):NC_CK440_B41
 B44 NC_CK440_B44 NC_B44 @S9S_MB_2U_LIB.S9S_MB_2U(SCH_1):NC_CK440_B44

Q_RES_0402LF-10K,1%,1/16W,CHIPA  I303  R1958
   1 P3V3_AUX      A @S9S_MB_2U_LIB.S9S_MB_2U(SCH_1):P3V3_AUX
   2 PU_CLK_PFT_LOST_N      B @S9S_MB_2U_LIB.S9S_MB_2U(SCH_1):PU_CLK_PFT_LOST_N

Q_RES_0402LF-10K,1%,1/16W,CHIPA  I378  R3638
   1 P3V3_AUX      A @S9S_MB_2U_LIB.S9S_MB_2U(SCH_1):P3V3_AUX
   2 CK440Q_OE_1      B @S9S_MB_2U_LIB.S9S_MB_2U(SCH_1):CK440Q_OE_1

Q_RES_0402LF-10K,1%,1/16W,CHIPA  I379  R3639
   1 P3V3_AUX      A @S9S_MB_2U_LIB.S9S_MB_2U(SCH_1):P3V3_AUX
   2 CK440Q_OE_2      B @S9S_MB_2U_LIB.S9S_MB_2U(SCH_1):CK440Q_OE_2

Q_RES_0402LF-10K,1%,1/16W,CHIPA  I380  R3640
   1 P3V3_AUX      A @S9S_MB_2U_LIB.S9S_MB_2U(SCH_1):P3V3_AUX
   2 CK440Q_OE_3      B @S9S_MB_2U_LIB.S9S_MB_2U(SCH_1):CK440Q_OE_3

Q_RES_0402LF-10K,1%,1/16W,CHIPA  I381  R3641
   1 P3V3_AUX      A @S9S_MB_2U_LIB.S9S_MB_2U(SCH_1):P3V3_AUX
   2 CK440Q_OE_4      B @S9S_MB_2U_LIB.S9S_MB_2U(SCH_1):CK440Q_OE_4

Q_RES_0402LF-10K,1%,1/16W,CHIPA  I382  R3642
   1 P3V3_AUX      A @S9S_MB_2U_LIB.S9S_MB_2U(SCH_1):P3V3_AUX
   2 CK440Q_OE_5      B @S9S_MB_2U_LIB.S9S_MB_2U(SCH_1):CK440Q_OE_5

Q_RES_0402LF-10K,1%,1/16W,CHIPA  I383  R3643
   1 P3V3_AUX      A @S9S_MB_2U_LIB.S9S_MB_2U(SCH_1):P3V3_AUX
   2 CK440Q_OE_6      B @S9S_MB_2U_LIB.S9S_MB_2U(SCH_1):CK440Q_OE_6

Q_XTAL_4P_13BI_24GND-25MHZ,SMLB  I391  Y2
   1 XTAL_CLK_GEN1_25M_X1_R     X1 @S9S_MB_2U_LIB.S9S_MB_2U(SCH_1):XTAL_CLK_GEN1_25M_X1_R
   2    GND     G1 @S9S_MB_2U_LIB.S9S_MB_2U(SCH_1):GND
   4    GND     G2 @S9S_MB_2U_LIB.S9S_MB_2U(SCH_1):GND
   3 XTAL_CLK_GEN1_25M_X2     X2 @S9S_MB_2U_LIB.S9S_MB_2U(SCH_1):XTAL_CLK_GEN1_25M_X2

Q_RES_0402LF-0,5%,1/16W,CHIP,CA  I392  R1724
   1 XTAL_CLK_GEN1_25M_X1_R      A @S9S_MB_2U_LIB.S9S_MB_2U(SCH_1):XTAL_CLK_GEN1_25M_X1_R
   2 XTAL_CLK_GEN1_25M_X1      B @S9S_MB_2U_LIB.S9S_MB_2U(SCH_1):XTAL_CLK_GEN1_25M_X1

Q_CAP_C0402-8.2PF,50V,0.1P,NP0A  I393  C2036
   1 XTAL_CLK_GEN1_25M_X1_R      A @S9S_MB_2U_LIB.S9S_MB_2U(SCH_1):XTAL_CLK_GEN1_25M_X1_R
   2    GND      B @S9S_MB_2U_LIB.S9S_MB_2U(SCH_1):GND

Q_CAP_C0402-8.2PF,50V,0.1P,NP0A  I394  C2037
   1 XTAL_CLK_GEN1_25M_X2      A @S9S_MB_2U_LIB.S9S_MB_2U(SCH_1):XTAL_CLK_GEN1_25M_X2
   2    GND      B @S9S_MB_2U_LIB.S9S_MB_2U(SCH_1):GND


DRAWING: @S9S_MB_2U_LIB.S9S_MB_2U(SCH_1):PAGE199 

Q_CAP_C0603-10UF,6.3V,20%,X6S,A  I6  C172
   1 P3V3_AUX_CLK_GEN_VDDA100M_CK440      A @S9S_MB_2U_LIB.S9S_MB_2U(SCH_1):P3V3_AUX_CLK_GEN_VDDA100M_CK440
   2    GND      B @S9S_MB_2U_LIB.S9S_MB_2U(SCH_1):GND

Q_RES_0603LF-1,1%,1/10W,CHIP,CA  I7  R519
   1 P3V3_AUX_CLK_GEN_VDD_CK440      A @S9S_MB_2U_LIB.S9S_MB_2U(SCH_1):P3V3_AUX_CLK_GEN_VDD_CK440
   2 P3V3_AUX_CLK_GEN_VDDA100M_CK440      B @S9S_MB_2U_LIB.S9S_MB_2U(SCH_1):P3V3_AUX_CLK_GEN_VDDA100M_CK440

Q_CAP_C0603-10UF,6.3V,20%,X6S,A  I19  C108
   1 P3V3_AUX_CLK_GEN_VDD_CK440      A @S9S_MB_2U_LIB.S9S_MB_2U(SCH_1):P3V3_AUX_CLK_GEN_VDD_CK440
   2    GND      B @S9S_MB_2U_LIB.S9S_MB_2U(SCH_1):GND

Q_INDUCTOR_SMLF-FCM2012KF-601TA  I20  L1
   2 P3V3_AUX_CLK_GEN_VDD_CK440      2 @S9S_MB_2U_LIB.S9S_MB_2U(SCH_1):P3V3_AUX_CLK_GEN_VDD_CK440
   1 P3V3_AUX      1 @S9S_MB_2U_LIB.S9S_MB_2U(SCH_1):P3V3_AUX

Q_RES_0603LF-1,1%,1/10W,CHIP,CA  I36  R442
   1 P3V3_AUX_CLK_GEN_VDDXTAL_CK440      A @S9S_MB_2U_LIB.S9S_MB_2U(SCH_1):P3V3_AUX_CLK_GEN_VDDXTAL_CK440
   2 P3V3_AUX_CLK_GEN_VDDA25M_CK440      B @S9S_MB_2U_LIB.S9S_MB_2U(SCH_1):P3V3_AUX_CLK_GEN_VDDA25M_CK440

Q_INDUCTOR_SMLF-FCM2012KF-601TA  I41  L13
   2 P3V3_AUX_CLK_GEN_VDDXTAL_CK440      2 @S9S_MB_2U_LIB.S9S_MB_2U(SCH_1):P3V3_AUX_CLK_GEN_VDDXTAL_CK440
   1 P3V3_AUX      1 @S9S_MB_2U_LIB.S9S_MB_2U(SCH_1):P3V3_AUX

Q_CAP_C0402-1UF,25V,10%,X6S,CHA  I43  C1311
   1 P3V3_AUX_CLK_GEN_VDDXTAL_CK440      A @S9S_MB_2U_LIB.S9S_MB_2U(SCH_1):P3V3_AUX_CLK_GEN_VDDXTAL_CK440
   2    GND      B @S9S_MB_2U_LIB.S9S_MB_2U(SCH_1):GND

Q_CAP_C0603-10UF,6.3V,20%,X6S,A  I44  C1309
   1 P3V3_AUX_CLK_GEN_VDDXTAL_CK440      A @S9S_MB_2U_LIB.S9S_MB_2U(SCH_1):P3V3_AUX_CLK_GEN_VDDXTAL_CK440
   2    GND      B @S9S_MB_2U_LIB.S9S_MB_2U(SCH_1):GND

Q_CAP_C0603-10UF,6.3V,20%,X6S,A  I48  C1313
   1 P3V3_AUX_CLK_GEN_VDDA25M_CK440      A @S9S_MB_2U_LIB.S9S_MB_2U(SCH_1):P3V3_AUX_CLK_GEN_VDDA25M_CK440
   2    GND      B @S9S_MB_2U_LIB.S9S_MB_2U(SCH_1):GND

Q_CAP_C0603-10UF,6.3V,20%,X6S,A  I53  C1314
   1 P3V3_AUX_CLK_GEN_VDDPT_CK440      A @S9S_MB_2U_LIB.S9S_MB_2U(SCH_1):P3V3_AUX_CLK_GEN_VDDPT_CK440
   2    GND      B @S9S_MB_2U_LIB.S9S_MB_2U(SCH_1):GND

Q_RES_0603LF-1,1%,1/10W,CHIP,CA  I55  R447
   1 P3V3_AUX_CLK_GEN_VDDMXCK_CK440      A @S9S_MB_2U_LIB.S9S_MB_2U(SCH_1):P3V3_AUX_CLK_GEN_VDDMXCK_CK440
   2 P3V3_AUX_CLK_GEN_VDDPT_CK440      B @S9S_MB_2U_LIB.S9S_MB_2U(SCH_1):P3V3_AUX_CLK_GEN_VDDPT_CK440

Q_CAP_C0402-1UF,25V,10%,X6S,CHA  I58  C1312
   1 P3V3_AUX_CLK_GEN_VDDMXCK_CK440      A @S9S_MB_2U_LIB.S9S_MB_2U(SCH_1):P3V3_AUX_CLK_GEN_VDDMXCK_CK440
   2    GND      B @S9S_MB_2U_LIB.S9S_MB_2U(SCH_1):GND

Q_CAP_C0603-10UF,6.3V,20%,X6S,A  I59  C1310
   1 P3V3_AUX_CLK_GEN_VDDMXCK_CK440      A @S9S_MB_2U_LIB.S9S_MB_2U(SCH_1):P3V3_AUX_CLK_GEN_VDDMXCK_CK440
   2    GND      B @S9S_MB_2U_LIB.S9S_MB_2U(SCH_1):GND

Q_INDUCTOR_SMLF-FCM2012KF-601TA  I60  L14
   2 P3V3_AUX_CLK_GEN_VDDMXCK_CK440      2 @S9S_MB_2U_LIB.S9S_MB_2U(SCH_1):P3V3_AUX_CLK_GEN_VDDMXCK_CK440
   1 P3V3_AUX      1 @S9S_MB_2U_LIB.S9S_MB_2U(SCH_1):P3V3_AUX

Q_CAP_C0402-0.047UF,25V,10%,X7A  I76  C110
   1 P3V3_AUX_CLK_GEN_VDD_CK440      A @S9S_MB_2U_LIB.S9S_MB_2U(SCH_1):P3V3_AUX_CLK_GEN_VDD_CK440
   2    GND      B @S9S_MB_2U_LIB.S9S_MB_2U(SCH_1):GND

Q_CAP_C0402-0.047UF,25V,10%,X7A  I77  C171
   1 P3V3_AUX_CLK_GEN_VDD_CK440      A @S9S_MB_2U_LIB.S9S_MB_2U(SCH_1):P3V3_AUX_CLK_GEN_VDD_CK440
   2    GND      B @S9S_MB_2U_LIB.S9S_MB_2U(SCH_1):GND

Q_CAP_C0402-0.047UF,25V,10%,X7A  I78  C173
   1 P3V3_AUX_CLK_GEN_VDDA100M_CK440      A @S9S_MB_2U_LIB.S9S_MB_2U(SCH_1):P3V3_AUX_CLK_GEN_VDDA100M_CK440
   2    GND      B @S9S_MB_2U_LIB.S9S_MB_2U(SCH_1):GND

Q_CAP_C0402-0.047UF,25V,10%,X7A  I79  C114
   1 P3V3_AUX_CLK_GEN_VDDA25M_CK440      A @S9S_MB_2U_LIB.S9S_MB_2U(SCH_1):P3V3_AUX_CLK_GEN_VDDA25M_CK440
   2    GND      B @S9S_MB_2U_LIB.S9S_MB_2U(SCH_1):GND

Q_CAP_C0402-0.047UF,25V,10%,X7A  I80  C112
   1 P3V3_AUX_CLK_GEN_VDDXTAL_CK440      A @S9S_MB_2U_LIB.S9S_MB_2U(SCH_1):P3V3_AUX_CLK_GEN_VDDXTAL_CK440
   2    GND      B @S9S_MB_2U_LIB.S9S_MB_2U(SCH_1):GND

Q_CAP_C0402-0.047UF,25V,10%,X7A  I81  C111
   1 P3V3_AUX_CLK_GEN_VDDXTAL_CK440      A @S9S_MB_2U_LIB.S9S_MB_2U(SCH_1):P3V3_AUX_CLK_GEN_VDDXTAL_CK440
   2    GND      B @S9S_MB_2U_LIB.S9S_MB_2U(SCH_1):GND

Q_CAP_C0402-1UF,25V,10%,X6S,CHA  I82  C107
   1 P3V3_AUX_CLK_GEN_VDD_CK440      A @S9S_MB_2U_LIB.S9S_MB_2U(SCH_1):P3V3_AUX_CLK_GEN_VDD_CK440
   2    GND      B @S9S_MB_2U_LIB.S9S_MB_2U(SCH_1):GND

Q_CAP_C0402-0.047UF,25V,10%,X7A  I85  C120
   1 P3V3_AUX_CLK_GEN_VDDPT_CK440      A @S9S_MB_2U_LIB.S9S_MB_2U(SCH_1):P3V3_AUX_CLK_GEN_VDDPT_CK440
   2    GND      B @S9S_MB_2U_LIB.S9S_MB_2U(SCH_1):GND

Q_CAP_C0402-0.047UF,25V,10%,X7A  I86  C119
   1 P3V3_AUX_CLK_GEN_VDDMXCK_CK440      A @S9S_MB_2U_LIB.S9S_MB_2U(SCH_1):P3V3_AUX_CLK_GEN_VDDMXCK_CK440
   2    GND      B @S9S_MB_2U_LIB.S9S_MB_2U(SCH_1):GND

Q_CAP_C0402-0.047UF,25V,10%,X7A  I87  C117
   1 P3V3_AUX_CLK_GEN_VDDMXCK_CK440      A @S9S_MB_2U_LIB.S9S_MB_2U(SCH_1):P3V3_AUX_CLK_GEN_VDDMXCK_CK440
   2    GND      B @S9S_MB_2U_LIB.S9S_MB_2U(SCH_1):GND

Q_CAP_C0402-0.047UF,25V,10%,X7A  I88  C116
   1 P3V3_AUX_CLK_GEN_VDDMXCK_CK440      A @S9S_MB_2U_LIB.S9S_MB_2U(SCH_1):P3V3_AUX_CLK_GEN_VDDMXCK_CK440
   2    GND      B @S9S_MB_2U_LIB.S9S_MB_2U(SCH_1):GND

Q_CAP_C0402-0.047UF,25V,10%,X7A  I89  C115
   1 P3V3_AUX_CLK_GEN_VDDMXCK_CK440      A @S9S_MB_2U_LIB.S9S_MB_2U(SCH_1):P3V3_AUX_CLK_GEN_VDDMXCK_CK440
   2    GND      B @S9S_MB_2U_LIB.S9S_MB_2U(SCH_1):GND


DRAWING: @S9S_MB_2U_LIB.S9S_MB_2U(SCH_1):PAGE200 

Q_CAP_C0603-10UF,6.3V,20%,X6S,A  I5  C2331
   1 P3V3_9ZXL045_VDDA      A @S9S_MB_2U_LIB.S9S_MB_2U(SCH_1):P3V3_9ZXL045_VDDA
   2    GND      B @S9S_MB_2U_LIB.S9S_MB_2U(SCH_1):GND

Q_CAP_C0603-10UF,6.3V,20%,X6S,A  I10  C2332
   1 P3V3_9ZXL045_VDDR      A @S9S_MB_2U_LIB.S9S_MB_2U(SCH_1):P3V3_9ZXL045_VDDR
   2    GND      B @S9S_MB_2U_LIB.S9S_MB_2U(SCH_1):GND

Q_RES_0603LF-1,1%,1/10W,CHIP,CA  I11  R4475
   1 P3V3_9ZXL045      A @S9S_MB_2U_LIB.S9S_MB_2U(SCH_1):P3V3_9ZXL045
   2 P3V3_9ZXL045_VDDR      B @S9S_MB_2U_LIB.S9S_MB_2U(SCH_1):P3V3_9ZXL045_VDDR

9ZXL0451EKILFT-9ZXL0451EKILFT,A  I1  U314
   3 CLK_100M_GPU_SWB_REF_DP DIF_IN @S9S_MB_2U_LIB.S9S_MB_2U(SCH_1):CLK_100M_GPU_SWB_REF_DP
   4 CLK_100M_GPU_SWB_REF_DN DIF_IN# @S9S_MB_2U_LIB.S9S_MB_2U(SCH_1):CLK_100M_GPU_SWB_REF_DN
   2 P3V3_9ZXL045_VDDR   VDDR @S9S_MB_2U_LIB.S9S_MB_2U(SCH_1):P3V3_9ZXL045_VDDR
  25 P3V3_9ZXL045_VDD   VDD3 @S9S_MB_2U_LIB.S9S_MB_2U(SCH_1):P3V3_9ZXL045_VDD
  29 P3V3_9ZXL045_VDD   VDD4 @S9S_MB_2U_LIB.S9S_MB_2U(SCH_1):P3V3_9ZXL045_VDD
   9 NC_U314_FBOUT FBOUT_NC @S9S_MB_2U_LIB.S9S_MB_2U(SCH_1):NC_U314_FBOUT
  15 FM_9ZXL045_0_OE_N  VOE0# @S9S_MB_2U_LIB.S9S_MB_2U(SCH_1):FM_9ZXL045_0_OE_N
  26 FM_9ZXL045_3_OE_N  VOE3# @S9S_MB_2U_LIB.S9S_MB_2U(SCH_1):FM_9ZXL045_3_OE_N
   6 SMB_HOST_9ZXL045_3V3AUX_SDA SMBDAT @S9S_MB_2U_LIB.S9S_MB_2U(SCH_1):SMB_HOST_9ZXL045_3V3AUX_SDA
  11 NC_U314_NC1    NC1 @S9S_MB_2U_LIB.S9S_MB_2U(SCH_1):NC_U314_NC1
   8 NC_U314_FBOUT_N FBOUT_NC# @S9S_MB_2U_LIB.S9S_MB_2U(SCH_1):NC_U314_FBOUT_N
   7 SMB_HOST_9ZXL045_3V3AUX_SCL SMBCLK @S9S_MB_2U_LIB.S9S_MB_2U(SCH_1):SMB_HOST_9ZXL045_3V3AUX_SCL
  21 P3V3_9ZXL045_VDD   VDD2 @S9S_MB_2U_LIB.S9S_MB_2U(SCH_1):P3V3_9ZXL045_VDD
   1 FM_9ZXL045_DEV_EN ^CKPWRGD_PD# @S9S_MB_2U_LIB.S9S_MB_2U(SCH_1):FM_9ZXL045_DEV_EN
  14 CLK_100M_SWB_R_DN  DIF0# @S9S_MB_2U_LIB.S9S_MB_2U(SCH_1):CLK_100M_SWB_R_DN
  13 CLK_100M_SWB_R_DP   DIF0 @S9S_MB_2U_LIB.S9S_MB_2U(SCH_1):CLK_100M_SWB_R_DP
  18 FM_9ZXL045_1_OE_N  VOE1# @S9S_MB_2U_LIB.S9S_MB_2U(SCH_1):FM_9ZXL045_1_OE_N
  20 CLK_100M_GPU_1_R_DN  DIF1# @S9S_MB_2U_LIB.S9S_MB_2U(SCH_1):CLK_100M_GPU_1_R_DN
  22 CLK_100M_GPU_2_R_DP   DIF2 @S9S_MB_2U_LIB.S9S_MB_2U(SCH_1):CLK_100M_GPU_2_R_DP
  24 FM_9ZXL045_2_OE_N  VOE2# @S9S_MB_2U_LIB.S9S_MB_2U(SCH_1):FM_9ZXL045_2_OE_N
  23 CLK_100M_GPU_2_R_DN  DIF2# @S9S_MB_2U_LIB.S9S_MB_2U(SCH_1):CLK_100M_GPU_2_R_DN
  28 TP_CLK_100M_BUF_DIF3_DN  DIF3# @S9S_MB_2U_LIB.S9S_MB_2U(SCH_1):TP_CLK_100M_BUF_DIF3_DN
  10 NC_U314_NC0    NC0 @S9S_MB_2U_LIB.S9S_MB_2U(SCH_1):NC_U314_NC0
  31 P3V3_9ZXL045_VDDA   VDDA @S9S_MB_2U_LIB.S9S_MB_2U(SCH_1):P3V3_9ZXL045_VDDA
  16 P3V3_9ZXL045_VDD   VDD1 @S9S_MB_2U_LIB.S9S_MB_2U(SCH_1):P3V3_9ZXL045_VDD
  32 CLK_9ZXL045_HIBW ^HIBW_BYPM_LOBW# @S9S_MB_2U_LIB.S9S_MB_2U(SCH_1):CLK_9ZXL045_HIBW
  33    GND EPAD_GND @S9S_MB_2U_LIB.S9S_MB_2U(SCH_1):GND
  19 CLK_100M_GPU_1_R_DP   DIF1 @S9S_MB_2U_LIB.S9S_MB_2U(SCH_1):CLK_100M_GPU_1_R_DP
  27 TP_CLK_100M_BUF_DIF3_DP   DIF3 @S9S_MB_2U_LIB.S9S_MB_2U(SCH_1):TP_CLK_100M_BUF_DIF3_DP
  12 P3V3_9ZXL045_VDD   VDD0 @S9S_MB_2U_LIB.S9S_MB_2U(SCH_1):P3V3_9ZXL045_VDD
  30 NC_U314_NC3    NC3 @S9S_MB_2U_LIB.S9S_MB_2U(SCH_1):NC_U314_NC3
  17 NC_U314_NC2    NC2 @S9S_MB_2U_LIB.S9S_MB_2U(SCH_1):NC_U314_NC2
   5 CLK_9ZXL045_SADR0 VSADR0_TRI @S9S_MB_2U_LIB.S9S_MB_2U(SCH_1):CLK_9ZXL045_SADR0

Q_RES_0603LF-1,1%,1/10W,CHIP,CA  I4  R4493
   1 P3V3_9ZXL045      A @S9S_MB_2U_LIB.S9S_MB_2U(SCH_1):P3V3_9ZXL045
   2 P3V3_9ZXL045_VDDA      B @S9S_MB_2U_LIB.S9S_MB_2U(SCH_1):P3V3_9ZXL045_VDDA

Q_CAP_C0603-10UF,6.3V,20%,X6S,A  I17  C2328
   1 P3V3_9ZXL045_VDD      A @S9S_MB_2U_LIB.S9S_MB_2U(SCH_1):P3V3_9ZXL045_VDD
   2    GND      B @S9S_MB_2U_LIB.S9S_MB_2U(SCH_1):GND

Q_RES_0402LF-4.75K,1%,1/16W,CHA  I30  R4489
   1   P3V3      A @S9S_MB_2U_LIB.S9S_MB_2U(SCH_1):P3V3
   2 CLK_9ZXL045_SADR0      B @S9S_MB_2U_LIB.S9S_MB_2U(SCH_1):CLK_9ZXL045_SADR0

Q_RES_0402LF-4.75K,1%,1/16W,EMA  I31  R4490
   1 CLK_9ZXL045_SADR0      A @S9S_MB_2U_LIB.S9S_MB_2U(SCH_1):CLK_9ZXL045_SADR0
   2    GND      B @S9S_MB_2U_LIB.S9S_MB_2U(SCH_1):GND

Q_RES_0402LF-49.9,1%,1/16W,CHIA  I39  R4476
   1 FM_PLD_CLKS_DEV_EN      A @S9S_MB_2U_LIB.S9S_MB_2U(SCH_1):FM_PLD_CLKS_DEV_EN
   2 FM_9ZXL045_DEV_EN      B @S9S_MB_2U_LIB.S9S_MB_2U(SCH_1):FM_9ZXL045_DEV_EN

Q_RES_0402LF-10K,1%,1/16W,CHIPA  I48  R4491
   1   P3V3      A @S9S_MB_2U_LIB.S9S_MB_2U(SCH_1):P3V3
   2 CLK_9ZXL045_HIBW      B @S9S_MB_2U_LIB.S9S_MB_2U(SCH_1):CLK_9ZXL045_HIBW

Q_RES_0402LF-10K,1%,1/16W,CHIPA  I49  R4492
   1 CLK_9ZXL045_HIBW      A @S9S_MB_2U_LIB.S9S_MB_2U(SCH_1):CLK_9ZXL045_HIBW
   2    GND      B @S9S_MB_2U_LIB.S9S_MB_2U(SCH_1):GND

Q_CAP_0402-0.1UF,25V,10%,X7R,CA  I54  C2329
   1 P3V3_9ZXL045_VDD      A @S9S_MB_2U_LIB.S9S_MB_2U(SCH_1):P3V3_9ZXL045_VDD
   2    GND      B @S9S_MB_2U_LIB.S9S_MB_2U(SCH_1):GND

Q_CAP_0402-0.1UF,25V,10%,X7R,CA  I55  C2330
   1 P3V3_9ZXL045_VDD      A @S9S_MB_2U_LIB.S9S_MB_2U(SCH_1):P3V3_9ZXL045_VDD
   2    GND      B @S9S_MB_2U_LIB.S9S_MB_2U(SCH_1):GND

Q_CAP_0402-0.1UF,25V,10%,X7R,CA  I56  C2333
   1 P3V3_9ZXL045_VDD      A @S9S_MB_2U_LIB.S9S_MB_2U(SCH_1):P3V3_9ZXL045_VDD
   2    GND      B @S9S_MB_2U_LIB.S9S_MB_2U(SCH_1):GND

Q_CAP_0402-0.1UF,25V,10%,X7R,CA  I57  C2336
   1 P3V3_9ZXL045_VDD      A @S9S_MB_2U_LIB.S9S_MB_2U(SCH_1):P3V3_9ZXL045_VDD
   2    GND      B @S9S_MB_2U_LIB.S9S_MB_2U(SCH_1):GND

Q_CAP_0402-0.1UF,25V,10%,X7R,CA  I58  C2334
   1 P3V3_9ZXL045_VDDA      A @S9S_MB_2U_LIB.S9S_MB_2U(SCH_1):P3V3_9ZXL045_VDDA
   2    GND      B @S9S_MB_2U_LIB.S9S_MB_2U(SCH_1):GND

Q_CAP_0402-0.1UF,25V,10%,X7R,CA  I59  C2335
   1 P3V3_9ZXL045_VDDR      A @S9S_MB_2U_LIB.S9S_MB_2U(SCH_1):P3V3_9ZXL045_VDDR
   2    GND      B @S9S_MB_2U_LIB.S9S_MB_2U(SCH_1):GND

Q_RES_0402LF-10K,1%,1/16W,CHIPA  I69  R4494
   1 FM_9ZXL045_3_OE_N      A @S9S_MB_2U_LIB.S9S_MB_2U(SCH_1):FM_9ZXL045_3_OE_N
   2   P3V3      B @S9S_MB_2U_LIB.S9S_MB_2U(SCH_1):P3V3

Q_CAP_0402-0.1UF,25V,10%,X7R,CA  I71  C2339
   1 P3V3_9ZXL045_VDD      A @S9S_MB_2U_LIB.S9S_MB_2U(SCH_1):P3V3_9ZXL045_VDD
   2    GND      B @S9S_MB_2U_LIB.S9S_MB_2U(SCH_1):GND

Q_RES_0402LF-33.2,1%,1/16W,CHIA  I74  R4477
   1 FM_9ZXL045_0_OE_N      A @S9S_MB_2U_LIB.S9S_MB_2U(SCH_1):FM_9ZXL045_0_OE_N
   2 CLK_SWB_BUF2_OE_N      B @S9S_MB_2U_LIB.S9S_MB_2U(SCH_1):CLK_SWB_BUF2_OE_N

Q_RES_0402LF-33.2,1%,1/16W,CHIA  I75  R4478
   1 FM_9ZXL045_1_OE_N      A @S9S_MB_2U_LIB.S9S_MB_2U(SCH_1):FM_9ZXL045_1_OE_N
   2 CLK_GPU_1_OE_N      B @S9S_MB_2U_LIB.S9S_MB_2U(SCH_1):CLK_GPU_1_OE_N

Q_RES_0402LF-33.2,1%,1/16W,CHIA  I76  R4479
   1 FM_9ZXL045_2_OE_N      A @S9S_MB_2U_LIB.S9S_MB_2U(SCH_1):FM_9ZXL045_2_OE_N
   2 CLK_GPU_2_OE_N      B @S9S_MB_2U_LIB.S9S_MB_2U(SCH_1):CLK_GPU_2_OE_N

Q_RES_0402LF-10K,1%,1/16W,CHIPA  I77  R4518
   1   P3V3      A @S9S_MB_2U_LIB.S9S_MB_2U(SCH_1):P3V3
   2 CLK_GPU_2_OE_N      B @S9S_MB_2U_LIB.S9S_MB_2U(SCH_1):CLK_GPU_2_OE_N

Q_RES_0402LF-10K,1%,1/16W,CHIPA  I78  R4519
   1   P3V3      A @S9S_MB_2U_LIB.S9S_MB_2U(SCH_1):P3V3
   2 CLK_GPU_1_OE_N      B @S9S_MB_2U_LIB.S9S_MB_2U(SCH_1):CLK_GPU_1_OE_N

Q_RES_0402LF-10K,1%,1/16W,CHIPA  I79  R4520
   1   P3V3      A @S9S_MB_2U_LIB.S9S_MB_2U(SCH_1):P3V3
   2 CLK_SWB_BUF2_OE_N      B @S9S_MB_2U_LIB.S9S_MB_2U(SCH_1):CLK_SWB_BUF2_OE_N

Q_INDUCTOR_SMLF-FCM2012KF-601TA  I81  L19
   2 P3V3_9ZXL045      2 @S9S_MB_2U_LIB.S9S_MB_2U(SCH_1):P3V3_9ZXL045
   1   P3V3      1 @S9S_MB_2U_LIB.S9S_MB_2U(SCH_1):P3V3

Q_INDUCTOR_SMLF-FCM2012KF-601TA  I82  L20
   2 P3V3_9ZXL045_VDD      2 @S9S_MB_2U_LIB.S9S_MB_2U(SCH_1):P3V3_9ZXL045_VDD
   1   P3V3      1 @S9S_MB_2U_LIB.S9S_MB_2U(SCH_1):P3V3


DRAWING: @S9S_MB_2U_LIB.S9S_MB_2U(SCH_1):PAGE207 

MOSFET_N_SMLF-BSS138K,BSS138K,A  I236  U89
   G FM_PLD_HEARTBEAT_LVC3   GATE @S9S_MB_2U_LIB.S9S_MB_2U(SCH_1):FM_PLD_HEARTBEAT_LVC3
   D FM_PLD_HEARTBEAT_LVC3_D  DRAIN @S9S_MB_2U_LIB.S9S_MB_2U(SCH_1):FM_PLD_HEARTBEAT_LVC3_D
   S    GND SOURCE @S9S_MB_2U_LIB.S9S_MB_2U(SCH_1):GND

Q_RES_0402LF-22,5%,1/16W,CHIP,A  I268  R2339
   1 LED_CPU_RMCA_CATERR_R      A @S9S_MB_2U_LIB.S9S_MB_2U(SCH_1):LED_CPU_RMCA_CATERR_R
   2    GND      B @S9S_MB_2U_LIB.S9S_MB_2U(SCH_1):GND

MOSFET_NCH_GDS_ESD_PROTECTED-2A  I272  Q33
   D LED_CPU_RMCA_CATERR      D @S9S_MB_2U_LIB.S9S_MB_2U(SCH_1):LED_CPU_RMCA_CATERR
   G CPU_RMCA_CATERR_LVT3_N      G @S9S_MB_2U_LIB.S9S_MB_2U(SCH_1):CPU_RMCA_CATERR_LVT3_N
   S LED_CPU_RMCA_CATERR_R      S @S9S_MB_2U_LIB.S9S_MB_2U(SCH_1):LED_CPU_RMCA_CATERR_R

Q_RES_0402LF-0,5%,1/16W,CHIP,CA  I273  R365
   1 FM_CPU_RMCA_CATERR_LVT3_R_N      A @S9S_MB_2U_LIB.S9S_MB_2U(SCH_1):FM_CPU_RMCA_CATERR_LVT3_R_N
   2 CPU_RMCA_CATERR_LVT3_N      B @S9S_MB_2U_LIB.S9S_MB_2U(SCH_1):CPU_RMCA_CATERR_LVT3_N

Q_RES_0402LF-10K,1%,1/16W,CHIPA  I275  R1841
   1 P3V3_AUX      A @S9S_MB_2U_LIB.S9S_MB_2U(SCH_1):P3V3_AUX
   2 FM_CPU_RMCA_CATERR_LVT3_R_N      B @S9S_MB_2U_LIB.S9S_MB_2U(SCH_1):FM_CPU_RMCA_CATERR_LVT3_R_N

Q_LED_SMLF-LED_BLUE,LTST-C281TA  I277  D0
   A PU_PLD_HEARTBEAT_LVC3      A @S9S_MB_2U_LIB.S9S_MB_2U(SCH_1):PU_PLD_HEARTBEAT_LVC3
   C FM_PLD_HEARTBEAT_LVC3_D      C @S9S_MB_2U_LIB.S9S_MB_2U(SCH_1):FM_PLD_HEARTBEAT_LVC3_D

Q_RES_0402LF-130,1%,1/16W,CHIPA  I278  R1195
   1 P3V3_AUX      A @S9S_MB_2U_LIB.S9S_MB_2U(SCH_1):P3V3_AUX
   2 PU_PLD_HEARTBEAT_LVC3      B @S9S_MB_2U_LIB.S9S_MB_2U(SCH_1):PU_PLD_HEARTBEAT_LVC3

Q_LED_SMLF-LED_YELLOW,LTST-C19A  I279  D6
   A LED_CPU_RMCA_CATERR      A @S9S_MB_2U_LIB.S9S_MB_2U(SCH_1):LED_CPU_RMCA_CATERR
   C    GND      C @S9S_MB_2U_LIB.S9S_MB_2U(SCH_1):GND

Q_RES_0402LF-249,1%,1/16W,CHIPA  I280  R366
   1 P3V3_AUX      A @S9S_MB_2U_LIB.S9S_MB_2U(SCH_1):P3V3_AUX
   2 LED_CPU_RMCA_CATERR      B @S9S_MB_2U_LIB.S9S_MB_2U(SCH_1):LED_CPU_RMCA_CATERR


DRAWING: @S9S_MB_2U_LIB.S9S_MB_2U(SCH_1):PAGE208 

Q_RES_0402LF-2K,1%,1/16W,EMPTYA  I4  R1415
   1 RST_CPU0_LVC1_R_N      A @S9S_MB_2U_LIB.S9S_MB_2U(SCH_1):RST_CPU0_LVC1_R_N
   2    GND      B @S9S_MB_2U_LIB.S9S_MB_2U(SCH_1):GND

Q_RES_0402LF-2K,1%,1/16W,EMPTYA  I5  R1416
   1 RST_CPU1_LVC1_R_N      A @S9S_MB_2U_LIB.S9S_MB_2U(SCH_1):RST_CPU1_LVC1_R_N
   2    GND      B @S9S_MB_2U_LIB.S9S_MB_2U(SCH_1):GND

Q_RES_0402LF-2K,1%,1/16W,CHIP,A  I6  R1418
   1 RST_PCIE_CPU1_DEV_PERST_N      A @S9S_MB_2U_LIB.S9S_MB_2U(SCH_1):RST_PCIE_CPU1_DEV_PERST_N
   2    GND      B @S9S_MB_2U_LIB.S9S_MB_2U(SCH_1):GND

Q_RES_0402LF-2K,1%,1/16W,CHIP,A  I7  R1417
   1 RST_PCIE_CPU0_DEV_PERST_N      A @S9S_MB_2U_LIB.S9S_MB_2U(SCH_1):RST_PCIE_CPU0_DEV_PERST_N
   2    GND      B @S9S_MB_2U_LIB.S9S_MB_2U(SCH_1):GND

Q_RES_0402LF-2K,1%,1/16W,CHIP,A  I8  R1419
   1 RST_PCIE_PCH_DEV_PERST_N      A @S9S_MB_2U_LIB.S9S_MB_2U(SCH_1):RST_PCIE_PCH_DEV_PERST_N
   2    GND      B @S9S_MB_2U_LIB.S9S_MB_2U(SCH_1):GND

Q_RES_0402LF-2K,1%,1/16W,CHIP,A  I9  R1420
   1 RST_PLTRST_PLD_B_N      A @S9S_MB_2U_LIB.S9S_MB_2U(SCH_1):RST_PLTRST_PLD_B_N
   2    GND      B @S9S_MB_2U_LIB.S9S_MB_2U(SCH_1):GND

Q_RES_0402LF-2K,1%,1/16W,CHIP,A  I10  R1421
   1 RST_RSMRST_PLD_R_N      A @S9S_MB_2U_LIB.S9S_MB_2U(SCH_1):RST_RSMRST_PLD_R_N
   2    GND      B @S9S_MB_2U_LIB.S9S_MB_2U(SCH_1):GND

Q_RES_0402LF-2K,1%,1/16W,EMPTYA  I11  R1326
   1 PWRGD_DRAMPWRGD_CPU0_CD_R_LVC1      A @S9S_MB_2U_LIB.S9S_MB_2U(SCH_1):PWRGD_DRAMPWRGD_CPU0_CD_R_LVC1
   2    GND      B @S9S_MB_2U_LIB.S9S_MB_2U(SCH_1):GND

Q_RES_0402LF-2K,1%,1/16W,EMPTYA  I12  R1302
   1 PWRGD_DRAMPWRGD_CPU0_AB_R_LVC1      A @S9S_MB_2U_LIB.S9S_MB_2U(SCH_1):PWRGD_DRAMPWRGD_CPU0_AB_R_LVC1
   2    GND      B @S9S_MB_2U_LIB.S9S_MB_2U(SCH_1):GND

Q_RES_0402LF-2K,1%,1/16W,EMPTYA  I13  R1328
   1 PWRGD_DRAMPWRGD_CPU0_GH_R_LVC1      A @S9S_MB_2U_LIB.S9S_MB_2U(SCH_1):PWRGD_DRAMPWRGD_CPU0_GH_R_LVC1
   2    GND      B @S9S_MB_2U_LIB.S9S_MB_2U(SCH_1):GND

Q_RES_0402LF-2K,1%,1/16W,EMPTYA  I14  R1327
   1 PWRGD_DRAMPWRGD_CPU0_EF_R_LVC1      A @S9S_MB_2U_LIB.S9S_MB_2U(SCH_1):PWRGD_DRAMPWRGD_CPU0_EF_R_LVC1
   2    GND      B @S9S_MB_2U_LIB.S9S_MB_2U(SCH_1):GND

Q_RES_0402LF-2K,1%,1/16W,EMPTYA  I15  R1329
   1 PWRGD_DRAMPWRGD_CPU1_AB_R_LVC1      A @S9S_MB_2U_LIB.S9S_MB_2U(SCH_1):PWRGD_DRAMPWRGD_CPU1_AB_R_LVC1
   2    GND      B @S9S_MB_2U_LIB.S9S_MB_2U(SCH_1):GND

Q_RES_0402LF-2K,1%,1/16W,EMPTYA  I16  R1330
   1 PWRGD_DRAMPWRGD_CPU1_CD_R_LVC1      A @S9S_MB_2U_LIB.S9S_MB_2U(SCH_1):PWRGD_DRAMPWRGD_CPU1_CD_R_LVC1
   2    GND      B @S9S_MB_2U_LIB.S9S_MB_2U(SCH_1):GND

Q_RES_0402LF-2K,1%,1/16W,EMPTYA  I17  R1388
   1 PWRGD_DRAMPWRGD_CPU1_EF_R_LVC1      A @S9S_MB_2U_LIB.S9S_MB_2U(SCH_1):PWRGD_DRAMPWRGD_CPU1_EF_R_LVC1
   2    GND      B @S9S_MB_2U_LIB.S9S_MB_2U(SCH_1):GND

Q_RES_0402LF-2K,1%,1/16W,CHIP,A  I18  R990
   1 FM_PLD_CLK_25M_R_EN      A @S9S_MB_2U_LIB.S9S_MB_2U(SCH_1):FM_PLD_CLK_25M_R_EN
   2    GND      B @S9S_MB_2U_LIB.S9S_MB_2U(SCH_1):GND

Q_RES_0402LF-2K,1%,1/16W,EMPTYA  I19  R4533
   1 PWRGD_DRAMPWRGD_CPU1_GH_R_LVC1      A @S9S_MB_2U_LIB.S9S_MB_2U(SCH_1):PWRGD_DRAMPWRGD_CPU1_GH_R_LVC1
   2    GND      B @S9S_MB_2U_LIB.S9S_MB_2U(SCH_1):GND

Q_RES_0402LF-2K,1%,1/16W,CHIP,A  I20  R991
   1 FM_AUX_SW_EN      A @S9S_MB_2U_LIB.S9S_MB_2U(SCH_1):FM_AUX_SW_EN
   2    GND      B @S9S_MB_2U_LIB.S9S_MB_2U(SCH_1):GND

Q_RES_0402LF-2K,1%,1/16W,EMPTYA  I21  R992
   1 PWRGD_CPU0_LVC1_R      A @S9S_MB_2U_LIB.S9S_MB_2U(SCH_1):PWRGD_CPU0_LVC1_R
   2    GND      B @S9S_MB_2U_LIB.S9S_MB_2U(SCH_1):GND

Q_RES_0402LF-2K,1%,1/16W,EMPTYA  I22  R1398
   1 PWRGD_CPU1_LVC1_R      A @S9S_MB_2U_LIB.S9S_MB_2U(SCH_1):PWRGD_CPU1_LVC1_R
   2    GND      B @S9S_MB_2U_LIB.S9S_MB_2U(SCH_1):GND

Q_RES_0402LF-2K,1%,1/16W,CHIP,A  I23  R1402
   1 PWRGD_SYS_PWROK      A @S9S_MB_2U_LIB.S9S_MB_2U(SCH_1):PWRGD_SYS_PWROK
   2    GND      B @S9S_MB_2U_LIB.S9S_MB_2U(SCH_1):GND

Q_RES_0402LF-2K,1%,1/16W,CHIP,A  I24  R1403
   1 PWRGD_PCH_PWROK      A @S9S_MB_2U_LIB.S9S_MB_2U(SCH_1):PWRGD_PCH_PWROK
   2    GND      B @S9S_MB_2U_LIB.S9S_MB_2U(SCH_1):GND

Q_RES_0402LF-2K,1%,1/16W,CHIP,A  I25  R1404
   1 FM_PCH_P1V8_AUX_EN      A @S9S_MB_2U_LIB.S9S_MB_2U(SCH_1):FM_PCH_P1V8_AUX_EN
   2    GND      B @S9S_MB_2U_LIB.S9S_MB_2U(SCH_1):GND

Q_RES_0402LF-2K,1%,1/16W,CHIP,A  I26  R1405
   1 FM_PVCCIN_CPU0_R_EN      A @S9S_MB_2U_LIB.S9S_MB_2U(SCH_1):FM_PVCCIN_CPU0_R_EN
   2    GND      B @S9S_MB_2U_LIB.S9S_MB_2U(SCH_1):GND

Q_RES_0402LF-2K,1%,1/16W,CHIP,A  I51  R1406
   1 FM_PVCCIN_CPU1_R_EN      A @S9S_MB_2U_LIB.S9S_MB_2U(SCH_1):FM_PVCCIN_CPU1_R_EN
   2    GND      B @S9S_MB_2U_LIB.S9S_MB_2U(SCH_1):GND

Q_RES_0402LF-2K,1%,1/16W,CHIP,A  I52  R1407
   1 FM_PVCCINFAON_CPU0_R_EN      A @S9S_MB_2U_LIB.S9S_MB_2U(SCH_1):FM_PVCCINFAON_CPU0_R_EN
   2    GND      B @S9S_MB_2U_LIB.S9S_MB_2U(SCH_1):GND

Q_RES_0402LF-2K,1%,1/16W,CHIP,A  I53  R1408
   1 FM_PVCCINFAON_CPU1_R_EN      A @S9S_MB_2U_LIB.S9S_MB_2U(SCH_1):FM_PVCCINFAON_CPU1_R_EN
   2    GND      B @S9S_MB_2U_LIB.S9S_MB_2U(SCH_1):GND

Q_RES_0402LF-2K,1%,1/16W,CHIP,A  I54  R1410
   1 FM_PVCCFA_EHV_CPU1_R_EN      A @S9S_MB_2U_LIB.S9S_MB_2U(SCH_1):FM_PVCCFA_EHV_CPU1_R_EN
   2    GND      B @S9S_MB_2U_LIB.S9S_MB_2U(SCH_1):GND

Q_RES_0402LF-2K,1%,1/16W,CHIP,A  I55  R1409
   1 FM_PVCCFA_EHV_CPU0_R_EN      A @S9S_MB_2U_LIB.S9S_MB_2U(SCH_1):FM_PVCCFA_EHV_CPU0_R_EN
   2    GND      B @S9S_MB_2U_LIB.S9S_MB_2U(SCH_1):GND

Q_RES_0402LF-2K,1%,1/16W,CHIP,A  I56  R1411
   1 FM_PVCCFA_EHV_FIVRA_CPU0_R_EN      A @S9S_MB_2U_LIB.S9S_MB_2U(SCH_1):FM_PVCCFA_EHV_FIVRA_CPU0_R_EN
   2    GND      B @S9S_MB_2U_LIB.S9S_MB_2U(SCH_1):GND

Q_RES_0402LF-2K,1%,1/16W,CHIP,A  I57  R1412
   1 FM_PVCCFA_EHV_FIVRA_CPU1_R_EN      A @S9S_MB_2U_LIB.S9S_MB_2U(SCH_1):FM_PVCCFA_EHV_FIVRA_CPU1_R_EN
   2    GND      B @S9S_MB_2U_LIB.S9S_MB_2U(SCH_1):GND

Q_RES_0402LF-2K,1%,1/16W,CHIP,A  I58  R1414
   1 FM_PVCCD_HV_CPU1_EN      A @S9S_MB_2U_LIB.S9S_MB_2U(SCH_1):FM_PVCCD_HV_CPU1_EN
   2    GND      B @S9S_MB_2U_LIB.S9S_MB_2U(SCH_1):GND

Q_RES_0402LF-2K,1%,1/16W,CHIP,A  I59  R1413
   1 FM_PVCCD_HV_CPU0_EN      A @S9S_MB_2U_LIB.S9S_MB_2U(SCH_1):FM_PVCCD_HV_CPU0_EN
   2    GND      B @S9S_MB_2U_LIB.S9S_MB_2U(SCH_1):GND

Q_RES_0402LF-2K,1%,1/16W,CHIP,A  I66  R4622
   1 RST_PERST_SWB_N      A @S9S_MB_2U_LIB.S9S_MB_2U(SCH_1):RST_PERST_SWB_N
   2    GND      B @S9S_MB_2U_LIB.S9S_MB_2U(SCH_1):GND


DRAWING: @S9S_MB_2U_LIB.S9S_MB_2U(SCH_1):PAGE210 

Q_RES_0402LF-33.2,1%,1/16W,CHIA  I19  R803
   1 JTAG_PLD_TDI_R      A @S9S_MB_2U_LIB.S9S_MB_2U(SCH_1):JTAG_PLD_TDI_R
   2 JTAG_BMC_PLD_TDI      B @S9S_MB_2U_LIB.S9S_MB_2U(SCH_1):JTAG_BMC_PLD_TDI

Q_RES_0402LF-33.2,1%,1/16W,CHIA  I20  R804
   1 JTAG_PLD_TDO_R      A @S9S_MB_2U_LIB.S9S_MB_2U(SCH_1):JTAG_PLD_TDO_R
   2 JTAG_BMC_PLD_TDO      B @S9S_MB_2U_LIB.S9S_MB_2U(SCH_1):JTAG_BMC_PLD_TDO

Q_RES_0402LF-33.2,1%,1/16W,CHIA  I25  R805
   1 JTAG_PLD_TMS_R      A @S9S_MB_2U_LIB.S9S_MB_2U(SCH_1):JTAG_PLD_TMS_R
   2 JTAG_BMC_PLD_TMS      B @S9S_MB_2U_LIB.S9S_MB_2U(SCH_1):JTAG_BMC_PLD_TMS

Q_RES_0402LF-33.2,1%,1/16W,CHIA  I54  R806
   1 JTAG_PLD_TCK_R      A @S9S_MB_2U_LIB.S9S_MB_2U(SCH_1):JTAG_PLD_TCK_R
   2 JTAG_BMC_PLD_TCK      B @S9S_MB_2U_LIB.S9S_MB_2U(SCH_1):JTAG_BMC_PLD_TCK

Q_RES_0402LF-10K,1%,1/16W,CHIPA  I59  R929
   1 P3V3_AUX      A @S9S_MB_2U_LIB.S9S_MB_2U(SCH_1):P3V3_AUX
   2 JTAG_BMC_PLD_TMS      B @S9S_MB_2U_LIB.S9S_MB_2U(SCH_1):JTAG_BMC_PLD_TMS

Q_RES_0402LF-10K,1%,1/16W,CHIPA  I60  R928
   1 P3V3_AUX      A @S9S_MB_2U_LIB.S9S_MB_2U(SCH_1):P3V3_AUX
   2 JTAG_BMC_PLD_TDO      B @S9S_MB_2U_LIB.S9S_MB_2U(SCH_1):JTAG_BMC_PLD_TDO

Q_RES_0402LF-10K,1%,1/16W,CHIPA  I61  R927
   1 P3V3_AUX      A @S9S_MB_2U_LIB.S9S_MB_2U(SCH_1):P3V3_AUX
   2 JTAG_BMC_PLD_TDI      B @S9S_MB_2U_LIB.S9S_MB_2U(SCH_1):JTAG_BMC_PLD_TDI

Q_RES_0402LF-4.7K,1%,1/16W,CHIA  I63  R930
   1 JTAG_BMC_PLD_TCK      A @S9S_MB_2U_LIB.S9S_MB_2U(SCH_1):JTAG_BMC_PLD_TCK
   2    GND      B @S9S_MB_2U_LIB.S9S_MB_2U(SCH_1):GND

Q_RES_0402LF-10K,1%,1/16W,CHIPA  I75  R919
   1 P3V3_AUX      A @S9S_MB_2U_LIB.S9S_MB_2U(SCH_1):P3V3_AUX
   2 JTAG_PLD_JTAGEN      B @S9S_MB_2U_LIB.S9S_MB_2U(SCH_1):JTAG_PLD_JTAGEN

Q_RES_0402LF-1K,1%,1/16W,EMPTYA  I76  R920
   1 JTAG_PLD_JTAGEN      A @S9S_MB_2U_LIB.S9S_MB_2U(SCH_1):JTAG_PLD_JTAGEN
   2    GND      B @S9S_MB_2U_LIB.S9S_MB_2U(SCH_1):GND

CONN8_210HP1080BR1-CONN8_210-HA  I79  J43
   1 P3V3_AUX_BMC_D      1 @S9S_MB_2U_LIB.S9S_MB_2U(SCH_1):P3V3_AUX_BMC_D
   2 JTAG_BMC_PLD_TDO      2 @S9S_MB_2U_LIB.S9S_MB_2U(SCH_1):JTAG_BMC_PLD_TDO
   3 JTAG_BMC_PLD_TDI      3 @S9S_MB_2U_LIB.S9S_MB_2U(SCH_1):JTAG_BMC_PLD_TDI
   4 TP_PLD_CONN_P4      4 @S9S_MB_2U_LIB.S9S_MB_2U(SCH_1):TP_PLD_CONN_P4
   5 TP_PLD_CONN_P5      5 @S9S_MB_2U_LIB.S9S_MB_2U(SCH_1):TP_PLD_CONN_P5
   6 JTAG_BMC_PLD_TMS      6 @S9S_MB_2U_LIB.S9S_MB_2U(SCH_1):JTAG_BMC_PLD_TMS
   7    GND      7 @S9S_MB_2U_LIB.S9S_MB_2U(SCH_1):GND
   8 JTAG_BMC_PLD_TCK      8 @S9S_MB_2U_LIB.S9S_MB_2U(SCH_1):JTAG_BMC_PLD_TCK

Q_CAP_0402-0.1UF,25V,10%,X7R,CA  I86  C554
   1 P3V3_AUX_BMC_D      A @S9S_MB_2U_LIB.S9S_MB_2U(SCH_1):P3V3_AUX_BMC_D
   2    GND      B @S9S_MB_2U_LIB.S9S_MB_2U(SCH_1):GND

Q_CAP_C0805-10UF,25V,10%,X6S,CA  I88  C563
   1 P3V3_AUX_BMC_D      A @S9S_MB_2U_LIB.S9S_MB_2U(SCH_1):P3V3_AUX_BMC_D
   2    GND      B @S9S_MB_2U_LIB.S9S_MB_2U(SCH_1):GND

SCHOTTKY_12-1N5819HW,SMLF,IC,BA  I91  D141
   1 P3V3_AUX      A @S9S_MB_2U_LIB.S9S_MB_2U(SCH_1):P3V3_AUX
   2 P3V3_AUX_BMC_D      C @S9S_MB_2U_LIB.S9S_MB_2U(SCH_1):P3V3_AUX_BMC_D


DRAWING: @S9S_MB_2U_LIB.S9S_MB_2U(SCH_1):PAGE211 

Q_RES_0402LF-33.2,1%,1/16W,CHIA  I9  R981
   1 FM_PVCCIN_CPU0_R_EN      A @S9S_MB_2U_LIB.S9S_MB_2U(SCH_1):FM_PVCCIN_CPU0_R_EN
   2 FM_PVCCIN_CPU0_EN      B @S9S_MB_2U_LIB.S9S_MB_2U(SCH_1):FM_PVCCIN_CPU0_EN

Q_RES_0402LF-33.2,1%,1/16W,CHIA  I10  R982
   1 FM_PVCCFA_EHV_CPU0_R_EN      A @S9S_MB_2U_LIB.S9S_MB_2U(SCH_1):FM_PVCCFA_EHV_CPU0_R_EN
   2 FM_PVCCFA_EHV_CPU0_EN      B @S9S_MB_2U_LIB.S9S_MB_2U(SCH_1):FM_PVCCFA_EHV_CPU0_EN

Q_RES_0402LF-33.2,1%,1/16W,CHIA  I13  R983
   1 FM_PVCCINFAON_CPU0_R_EN      A @S9S_MB_2U_LIB.S9S_MB_2U(SCH_1):FM_PVCCINFAON_CPU0_R_EN
   2 FM_PVCCINFAON_CPU0_EN      B @S9S_MB_2U_LIB.S9S_MB_2U(SCH_1):FM_PVCCINFAON_CPU0_EN

Q_RES_0402LF-33.2,1%,1/16W,CHIA  I15  R984
   1 FM_PVCCFA_EHV_FIVRA_CPU0_R_EN      A @S9S_MB_2U_LIB.S9S_MB_2U(SCH_1):FM_PVCCFA_EHV_FIVRA_CPU0_R_EN
   2 FM_PVCCFA_EHV_FIVRA_CPU0_EN      B @S9S_MB_2U_LIB.S9S_MB_2U(SCH_1):FM_PVCCFA_EHV_FIVRA_CPU0_EN

Q_RES_0402LF-33.2,1%,1/16W,CHIA  I21  R985
   1 FM_PVCCIN_CPU1_R_EN      A @S9S_MB_2U_LIB.S9S_MB_2U(SCH_1):FM_PVCCIN_CPU1_R_EN
   2 FM_PVCCIN_CPU1_EN      B @S9S_MB_2U_LIB.S9S_MB_2U(SCH_1):FM_PVCCIN_CPU1_EN

Q_RES_0402LF-33.2,1%,1/16W,CHIA  I23  R988
   1 FM_PVCCFA_EHV_FIVRA_CPU1_R_EN      A @S9S_MB_2U_LIB.S9S_MB_2U(SCH_1):FM_PVCCFA_EHV_FIVRA_CPU1_R_EN
   2 FM_PVCCFA_EHV_FIVRA_CPU1_EN      B @S9S_MB_2U_LIB.S9S_MB_2U(SCH_1):FM_PVCCFA_EHV_FIVRA_CPU1_EN

Q_RES_0402LF-33.2,1%,1/16W,CHIA  I24  R987
   1 FM_PVCCINFAON_CPU1_R_EN      A @S9S_MB_2U_LIB.S9S_MB_2U(SCH_1):FM_PVCCINFAON_CPU1_R_EN
   2 FM_PVCCINFAON_CPU1_EN      B @S9S_MB_2U_LIB.S9S_MB_2U(SCH_1):FM_PVCCINFAON_CPU1_EN

Q_RES_0402LF-33.2,1%,1/16W,CHIA  I25  R986
   1 FM_PVCCFA_EHV_CPU1_R_EN      A @S9S_MB_2U_LIB.S9S_MB_2U(SCH_1):FM_PVCCFA_EHV_CPU1_R_EN
   2 FM_PVCCFA_EHV_CPU1_EN      B @S9S_MB_2U_LIB.S9S_MB_2U(SCH_1):FM_PVCCFA_EHV_CPU1_EN

Q_RES_0402LF-33.2,1%,1/16W,CHIA  I44  R1423
   1 PWRGD_SYS_PWROK_R      A @S9S_MB_2U_LIB.S9S_MB_2U(SCH_1):PWRGD_SYS_PWROK_R
   2 PWRGD_SYS_PWROK      B @S9S_MB_2U_LIB.S9S_MB_2U(SCH_1):PWRGD_SYS_PWROK

Q_RES_0402LF-33.2,1%,1/16W,CHIA  I48  R1442
   1 PWRGD_PCH_PWROK_R      A @S9S_MB_2U_LIB.S9S_MB_2U(SCH_1):PWRGD_PCH_PWROK_R
   2 PWRGD_PCH_PWROK      B @S9S_MB_2U_LIB.S9S_MB_2U(SCH_1):PWRGD_PCH_PWROK

Q_RES_0402LF-33.2,1%,1/16W,CHIA  I49  R1443
   1 PWRGD_CPUPWRGD_LVC1      A @S9S_MB_2U_LIB.S9S_MB_2U(SCH_1):PWRGD_CPUPWRGD_LVC1
   2 PWRGD_CPUPWRGD_LVC1_R      B @S9S_MB_2U_LIB.S9S_MB_2U(SCH_1):PWRGD_CPUPWRGD_LVC1_R

Q_RES_0402LF-33.2,1%,1/16W,CHIA  I54  R1444
   1 PWRGD_P1V8_PCH_AUX      A @S9S_MB_2U_LIB.S9S_MB_2U(SCH_1):PWRGD_P1V8_PCH_AUX
   2 PWRGD_P1V8_PCH_AUX_PLD      B @S9S_MB_2U_LIB.S9S_MB_2U(SCH_1):PWRGD_P1V8_PCH_AUX_PLD

Q_RES_0402LF-33.2,1%,1/16W,CHIA  I62  R1448
   1 FM_CPU1_SKTOCC_LVT3_N      A @S9S_MB_2U_LIB.S9S_MB_2U(SCH_1):FM_CPU1_SKTOCC_LVT3_N
   2 FM_CPU1_SKTOCC_LVT3_PLD_N      B @S9S_MB_2U_LIB.S9S_MB_2U(SCH_1):FM_CPU1_SKTOCC_LVT3_PLD_N

Q_RES_0402LF-33.2,1%,1/16W,CHIA  I68  R1447
   1 FM_CPU0_SKTOCC_LVT3_N      A @S9S_MB_2U_LIB.S9S_MB_2U(SCH_1):FM_CPU0_SKTOCC_LVT3_N
   2 FM_CPU0_SKTOCC_LVT3_PLD_N      B @S9S_MB_2U_LIB.S9S_MB_2U(SCH_1):FM_CPU0_SKTOCC_LVT3_PLD_N

Q_RES_0402LF-33.2,1%,1/16W,CHIA  I81  R1751
   1 SGPIO_DO_0      A @S9S_MB_2U_LIB.S9S_MB_2U(SCH_1):SGPIO_DO_0
   2 SGPIO_DEBUG_PLD_DOUT      B @S9S_MB_2U_LIB.S9S_MB_2U(SCH_1):SGPIO_DEBUG_PLD_DOUT

Q_RES_0402LF-33.2,1%,1/16W,CHIA  I82  R1752
   1 SGPIO_CLK_0      A @S9S_MB_2U_LIB.S9S_MB_2U(SCH_1):SGPIO_CLK_0
   2 SGPIO_DEBUG_PLD_CLK      B @S9S_MB_2U_LIB.S9S_MB_2U(SCH_1):SGPIO_DEBUG_PLD_CLK

Q_RES_0402LF-33.2,1%,1/16W,CHIA  I84  R1753
   1 SGPIO_DI_0      A @S9S_MB_2U_LIB.S9S_MB_2U(SCH_1):SGPIO_DI_0
   2 SGPIO_DEBUG_PLD_DIN      B @S9S_MB_2U_LIB.S9S_MB_2U(SCH_1):SGPIO_DEBUG_PLD_DIN

Q_RES_0402LF-33.2,1%,1/16W,CHIA  I88  R1754
   1 SGPIO_LD_0      A @S9S_MB_2U_LIB.S9S_MB_2U(SCH_1):SGPIO_LD_0
   2 SGPIO_DEBUG_PLD_LD_N      B @S9S_MB_2U_LIB.S9S_MB_2U(SCH_1):SGPIO_DEBUG_PLD_LD_N

Q_RES_0402LF-33.2,1%,1/16W,CHIA  I91  R1758
   1 SGPIO_LD_1      A @S9S_MB_2U_LIB.S9S_MB_2U(SCH_1):SGPIO_LD_1
   2 SGPIO_BMC_LD_N      B @S9S_MB_2U_LIB.S9S_MB_2U(SCH_1):SGPIO_BMC_LD_N

Q_RES_0402LF-33.2,1%,1/16W,CHIA  I96  R1755
   1 SGPIO_DO_1      A @S9S_MB_2U_LIB.S9S_MB_2U(SCH_1):SGPIO_DO_1
   2 SGPIO_BMC_DOUT      B @S9S_MB_2U_LIB.S9S_MB_2U(SCH_1):SGPIO_BMC_DOUT

Q_RES_0402LF-33.2,1%,1/16W,CHIA  I98  R1756
   1 SGPIO_CLK_1      A @S9S_MB_2U_LIB.S9S_MB_2U(SCH_1):SGPIO_CLK_1
   2 SGPIO_BMC_CLK      B @S9S_MB_2U_LIB.S9S_MB_2U(SCH_1):SGPIO_BMC_CLK

Q_RES_0402LF-33.2,1%,1/16W,CHIA  I99  R1757
   1 SGPIO_DI_1      A @S9S_MB_2U_LIB.S9S_MB_2U(SCH_1):SGPIO_DI_1
   2 SGPIO_BMC_DIN_R      B @S9S_MB_2U_LIB.S9S_MB_2U(SCH_1):SGPIO_BMC_DIN_R

Q_RES_0402LF-33.2,1%,1/16W,CHIA  I110  R1811
   1 RST_SGPIO_RESET_N      A @S9S_MB_2U_LIB.S9S_MB_2U(SCH_1):RST_SGPIO_RESET_N
   2 RST_SGPIO_RESET_N_R      B @S9S_MB_2U_LIB.S9S_MB_2U(SCH_1):RST_SGPIO_RESET_N_R

Q_RES_0402LF-33.2,1%,1/16W,CHIA  I111  R1812
   1 IRQ_SGPIO_INTR_N      A @S9S_MB_2U_LIB.S9S_MB_2U(SCH_1):IRQ_SGPIO_INTR_N
   2 IRQ_SGPIO_INTR_N_R      B @S9S_MB_2U_LIB.S9S_MB_2U(SCH_1):IRQ_SGPIO_INTR_N_R

Q_RES_0402LF-33.2,1%,1/16W,CHIA  I122  R1843
   1 RST_PFR_OVR_RTC_R      A @S9S_MB_2U_LIB.S9S_MB_2U(SCH_1):RST_PFR_OVR_RTC_R
   2 RST_PFR_OVR_RTC      B @S9S_MB_2U_LIB.S9S_MB_2U(SCH_1):RST_PFR_OVR_RTC

Q_RES_0402LF-33.2,1%,1/16W,CHIA  I123  R1844
   1 RST_PFR_OVR_SRTC_R      A @S9S_MB_2U_LIB.S9S_MB_2U(SCH_1):RST_PFR_OVR_SRTC_R
   2 RST_PFR_OVR_SRTC      B @S9S_MB_2U_LIB.S9S_MB_2U(SCH_1):RST_PFR_OVR_SRTC

Q_RES_0402LF-33.2,1%,1/16W,CHIA  I127  R1919
   1 PWRGD_P3V3_AUX      A @S9S_MB_2U_LIB.S9S_MB_2U(SCH_1):PWRGD_P3V3_AUX
   2 PWRGD_P3V3_AUX_PLD      B @S9S_MB_2U_LIB.S9S_MB_2U(SCH_1):PWRGD_P3V3_AUX_PLD

Q_RES_0402LF-33.2,1%,1/16W,CHIA  I129  R4267
   1 PWRGD_P3V3_AUX      A @S9S_MB_2U_LIB.S9S_MB_2U(SCH_1):PWRGD_P3V3_AUX
   2 PWRGD_P3V3_AUX_PDB      B @S9S_MB_2U_LIB.S9S_MB_2U(SCH_1):PWRGD_P3V3_AUX_PDB


DRAWING: @S9S_MB_2U_LIB.S9S_MB_2U(SCH_1):PAGE212 

Q_RES_0402LF-33.2,1%,1/16W,CHIA  I7  R1205
   1 RST_PLTRST_N      A @S9S_MB_2U_LIB.S9S_MB_2U(SCH_1):RST_PLTRST_N
   2 RST_PLTRST_PLD_N      B @S9S_MB_2U_LIB.S9S_MB_2U(SCH_1):RST_PLTRST_PLD_N

Q_RES_0402LF-33.2,1%,1/16W,CHIA  I10  R1206
   1 RST_MB_STBY_R_N      A @S9S_MB_2U_LIB.S9S_MB_2U(SCH_1):RST_MB_STBY_R_N
   2 RST_MB_STBY_N      B @S9S_MB_2U_LIB.S9S_MB_2U(SCH_1):RST_MB_STBY_N

Q_RES_0402LF-33.2,1%,1/16W,CHIA  I15  R1207
   1 RST_RSMRST_PLD_R_N      A @S9S_MB_2U_LIB.S9S_MB_2U(SCH_1):RST_RSMRST_PLD_R_N
   2 RST_RSMRST_PCH_N      B @S9S_MB_2U_LIB.S9S_MB_2U(SCH_1):RST_RSMRST_PCH_N

Q_RES_0402LF-33.2,1%,1/16W,CHIA  I17  R110
   1 FM_PLD_CLKS_DEV_R_EN      A @S9S_MB_2U_LIB.S9S_MB_2U(SCH_1):FM_PLD_CLKS_DEV_R_EN
   2 FM_PLD_CLKS_DEV_EN      B @S9S_MB_2U_LIB.S9S_MB_2U(SCH_1):FM_PLD_CLKS_DEV_EN

MOSFET_N_SMLF-BSS138K,BSS138K,A  I19  U70
   G FM_PLD_CLKS_DEV_EN   GATE @S9S_MB_2U_LIB.S9S_MB_2U(SCH_1):FM_PLD_CLKS_DEV_EN
   D FM_PLD_CLKS_OE_R_N  DRAIN @S9S_MB_2U_LIB.S9S_MB_2U(SCH_1):FM_PLD_CLKS_OE_R_N
   S    GND SOURCE @S9S_MB_2U_LIB.S9S_MB_2U(SCH_1):GND

Q_RES_0402LF-10K,1%,1/16W,CHIPA  I24  R111
   1   P3V3      A @S9S_MB_2U_LIB.S9S_MB_2U(SCH_1):P3V3
   2 FM_PLD_CLKS_OE_R_N      B @S9S_MB_2U_LIB.S9S_MB_2U(SCH_1):FM_PLD_CLKS_OE_R_N

Q_RES_0402LF-33.2,1%,1/16W,CHIA  I27  R113
   1 FM_PLD_CLKS_OE_R_N      A @S9S_MB_2U_LIB.S9S_MB_2U(SCH_1):FM_PLD_CLKS_OE_R_N
   2 FM_DB2000_OE_N      B @S9S_MB_2U_LIB.S9S_MB_2U(SCH_1):FM_DB2000_OE_N

Q_RES_0402LF-33.2,1%,1/16W,CHIA  I44  R109
   1 FM_PLD_CLK_25M_R_EN      A @S9S_MB_2U_LIB.S9S_MB_2U(SCH_1):FM_PLD_CLK_25M_R_EN
   2 FM_PLD_CLK_25M_EN      B @S9S_MB_2U_LIB.S9S_MB_2U(SCH_1):FM_PLD_CLK_25M_EN

Q_RES_0402LF-33.2,1%,1/16W,CHIA  I55  R1469
   1 RST_PLTRST_PLD_B_N      A @S9S_MB_2U_LIB.S9S_MB_2U(SCH_1):RST_PLTRST_PLD_B_N
   2 RST_PLTRST_B_N      B @S9S_MB_2U_LIB.S9S_MB_2U(SCH_1):RST_PLTRST_B_N

Q_RES_0402LF-33.2,1%,1/16W,CHIA  I56  R1470
   1 RST_PLTRST_PLD_B_N      A @S9S_MB_2U_LIB.S9S_MB_2U(SCH_1):RST_PLTRST_PLD_B_N
   2 RST_PLTRST_B_MUX_N      B @S9S_MB_2U_LIB.S9S_MB_2U(SCH_1):RST_PLTRST_B_MUX_N

Q_RES_0402LF-33.2,1%,1/16W,CHIA  I86  R1995
   1 FM_PCH_SLP_S3_N      A @S9S_MB_2U_LIB.S9S_MB_2U(SCH_1):FM_PCH_SLP_S3_N
   2 FM_SLPS3_PLD_N      B @S9S_MB_2U_LIB.S9S_MB_2U(SCH_1):FM_SLPS3_PLD_N

Q_RES_0402LF-33.2,1%,1/16W,CHIA  I87  R1996
   1 FM_PCH_SLP_S4_N      A @S9S_MB_2U_LIB.S9S_MB_2U(SCH_1):FM_PCH_SLP_S4_N
   2 FM_SLPS4_PLD_N      B @S9S_MB_2U_LIB.S9S_MB_2U(SCH_1):FM_SLPS4_PLD_N

Q_RES_0402LF-33.2,1%,1/16W,CHIA  I91  R269
   1 FM_ADR_MODE1      A @S9S_MB_2U_LIB.S9S_MB_2U(SCH_1):FM_ADR_MODE1
   2 FM_ADR_MODE1_R      B @S9S_MB_2U_LIB.S9S_MB_2U(SCH_1):FM_ADR_MODE1_R

Q_RES_0402LF-100K,1%,1/16W,CHIA  I92  R1541
   1    GND      A @S9S_MB_2U_LIB.S9S_MB_2U(SCH_1):GND
   2 RST_PLTRST_N      B @S9S_MB_2U_LIB.S9S_MB_2U(SCH_1):RST_PLTRST_N

Q_RES_0402LF-0,5%,1/16W,CHIP,CA  I94  R1744
   1 FM_BMC_PWRBTN_OUT_N      A @S9S_MB_2U_LIB.S9S_MB_2U(SCH_1):FM_BMC_PWRBTN_OUT_N
   2 FM_BMC_PWRBTN_N      B @S9S_MB_2U_LIB.S9S_MB_2U(SCH_1):FM_BMC_PWRBTN_N

Q_RES_0402LF-33.2,1%,1/16W,CHIA  I105  R1514
   1 RST_PCIE_CPU0_DEV_PERST_N      A @S9S_MB_2U_LIB.S9S_MB_2U(SCH_1):RST_PCIE_CPU0_DEV_PERST_N
   2 RST_OCP_V3_1_N      B @S9S_MB_2U_LIB.S9S_MB_2U(SCH_1):RST_OCP_V3_1_N

Q_RES_0402LF-33.2,1%,1/16W,CHIA  I113  R1520
   1 RST_PCIE_CPU1_DEV_PERST_N      A @S9S_MB_2U_LIB.S9S_MB_2U(SCH_1):RST_PCIE_CPU1_DEV_PERST_N
   2 RST_OCP_V3_2_N      B @S9S_MB_2U_LIB.S9S_MB_2U(SCH_1):RST_OCP_V3_2_N

Q_RES_0402LF-33.2,1%,1/16W,CHIA  I127  R2738
   1 RST_PERST_SWB_N      A @S9S_MB_2U_LIB.S9S_MB_2U(SCH_1):RST_PERST_SWB_N
   2 RST_PERST_SWB_R_N      B @S9S_MB_2U_LIB.S9S_MB_2U(SCH_1):RST_PERST_SWB_R_N

Q_RES_0402LF-33.2,1%,1/16W,CHIA  I129  R3050
   1 RST_RSMRST_PLD_R_N      A @S9S_MB_2U_LIB.S9S_MB_2U(SCH_1):RST_RSMRST_PLD_R_N
   2 RST_RSMRST_NM_HDR_N      B @S9S_MB_2U_LIB.S9S_MB_2U(SCH_1):RST_RSMRST_NM_HDR_N

Q_RES_0402LF-0,5%,1/16W,CHIP,CA  I130  R1318
   1 FM_THERMTRIP_DLY_LVC1_R_N      A @S9S_MB_2U_LIB.S9S_MB_2U(SCH_1):FM_THERMTRIP_DLY_LVC1_R_N
   2 FM_THERMTRIP_DLY_LVC1_N      B @S9S_MB_2U_LIB.S9S_MB_2U(SCH_1):FM_THERMTRIP_DLY_LVC1_N


DRAWING: @S9S_MB_2U_LIB.S9S_MB_2U(SCH_1):PAGE217 

Q_RES_0402LF-499,1%,1/16W,CHIPA  I29  R679
   1 PVNN_TERM_CPU0      A @S9S_MB_2U_LIB.S9S_MB_2U(SCH_1):PVNN_TERM_CPU0
   2 I3C_SPD_DDRABCD_CPU0_SCL      B @S9S_MB_2U_LIB.S9S_MB_2U(SCH_1):I3C_SPD_DDRABCD_CPU0_SCL

Q_RES_0402LF-1K,1%,1/16W,CHIP,A  I13  R678
   1 PD_I3C_SPD_DDR_CPU0_OE_N      A @S9S_MB_2U_LIB.S9S_MB_2U(SCH_1):PD_I3C_SPD_DDR_CPU0_OE_N
   2    GND      B @S9S_MB_2U_LIB.S9S_MB_2U(SCH_1):GND

Q_RES_0402LF-0,5%,1/16W,EMPTY,A  I16  R685
   1 I3C_SPD_DDREFGH_CPU0_R_SDA      A @S9S_MB_2U_LIB.S9S_MB_2U(SCH_1):I3C_SPD_DDREFGH_CPU0_R_SDA
   2 I3C_SPD_DDREFGH_CPU0_LVC1_R_SDA      B @S9S_MB_2U_LIB.S9S_MB_2U(SCH_1):I3C_SPD_DDREFGH_CPU0_LVC1_R_SDA

Q_RES_0402LF-0,5%,1/16W,EMPTY,A  I17  R684
   1 I3C_SPD_DDREFGH_CPU0_R_SCL      A @S9S_MB_2U_LIB.S9S_MB_2U(SCH_1):I3C_SPD_DDREFGH_CPU0_R_SCL
   2 I3C_SPD_DDREFGH_CPU0_LVC1_R_SCL      B @S9S_MB_2U_LIB.S9S_MB_2U(SCH_1):I3C_SPD_DDREFGH_CPU0_LVC1_R_SCL

Q_RES_0402LF-0,5%,1/16W,EMPTY,A  I18  R683
   1 I3C_SPD_DDRABCD_CPU0_R_SDA      A @S9S_MB_2U_LIB.S9S_MB_2U(SCH_1):I3C_SPD_DDRABCD_CPU0_R_SDA
   2 I3C_SPD_DDRABCD_CPU0_LVC1_R_SDA      B @S9S_MB_2U_LIB.S9S_MB_2U(SCH_1):I3C_SPD_DDRABCD_CPU0_LVC1_R_SDA

QS3VH257QG8_SMLF-QS3VH257QG8,IA  I19  U15
   1 FM_SPD_REMOTE_EN      S @S9S_MB_2U_LIB.S9S_MB_2U(SCH_1):FM_SPD_REMOTE_EN
  15 PD_I3C_SPD_DDR_CPU0_OE_N     E* @S9S_MB_2U_LIB.S9S_MB_2U(SCH_1):PD_I3C_SPD_DDR_CPU0_OE_N
   4 I3C_SPD_DDRABCD_CPU0_LVC1_R_SCL     YA @S9S_MB_2U_LIB.S9S_MB_2U(SCH_1):I3C_SPD_DDRABCD_CPU0_LVC1_R_SCL
   2 I3C_SPD_DDRABCD_CPU0_R_SCL    I0A @S9S_MB_2U_LIB.S9S_MB_2U(SCH_1):I3C_SPD_DDRABCD_CPU0_R_SCL
   3 I3C_SPD_DDRABCD_CPU0_BMC_SCL    I1A @S9S_MB_2U_LIB.S9S_MB_2U(SCH_1):I3C_SPD_DDRABCD_CPU0_BMC_SCL
   5 I3C_SPD_DDRABCD_CPU0_R_SDA    I0B @S9S_MB_2U_LIB.S9S_MB_2U(SCH_1):I3C_SPD_DDRABCD_CPU0_R_SDA
   6 I3C_SPD_DDRABCD_CPU0_BMC_SDA    I1B @S9S_MB_2U_LIB.S9S_MB_2U(SCH_1):I3C_SPD_DDRABCD_CPU0_BMC_SDA
   7 I3C_SPD_DDRABCD_CPU0_LVC1_R_SDA     YB @S9S_MB_2U_LIB.S9S_MB_2U(SCH_1):I3C_SPD_DDRABCD_CPU0_LVC1_R_SDA
  11 I3C_SPD_DDREFGH_CPU0_R_SCL    I0C @S9S_MB_2U_LIB.S9S_MB_2U(SCH_1):I3C_SPD_DDREFGH_CPU0_R_SCL
  10 I3C_SPD_DDREFGH_CPU0_BMC_SCL    I1C @S9S_MB_2U_LIB.S9S_MB_2U(SCH_1):I3C_SPD_DDREFGH_CPU0_BMC_SCL
   9 I3C_SPD_DDREFGH_CPU0_LVC1_R_SCL     YC @S9S_MB_2U_LIB.S9S_MB_2U(SCH_1):I3C_SPD_DDREFGH_CPU0_LVC1_R_SCL
  12 I3C_SPD_DDREFGH_CPU0_LVC1_R_SDA     YD @S9S_MB_2U_LIB.S9S_MB_2U(SCH_1):I3C_SPD_DDREFGH_CPU0_LVC1_R_SDA
  14 I3C_SPD_DDREFGH_CPU0_R_SDA    I0D @S9S_MB_2U_LIB.S9S_MB_2U(SCH_1):I3C_SPD_DDREFGH_CPU0_R_SDA
  13 I3C_SPD_DDREFGH_CPU0_BMC_SDA    I1D @S9S_MB_2U_LIB.S9S_MB_2U(SCH_1):I3C_SPD_DDREFGH_CPU0_BMC_SDA
   8    GND    GND @S9S_MB_2U_LIB.S9S_MB_2U(SCH_1):GND
  16 P3V3_AUX    VCC @S9S_MB_2U_LIB.S9S_MB_2U(SCH_1):P3V3_AUX

Q_RES_0402LF-0,5%,1/16W,EMPTY,A  I20  R682
   1 I3C_SPD_DDRABCD_CPU0_R_SCL      A @S9S_MB_2U_LIB.S9S_MB_2U(SCH_1):I3C_SPD_DDRABCD_CPU0_R_SCL
   2 I3C_SPD_DDRABCD_CPU0_LVC1_R_SCL      B @S9S_MB_2U_LIB.S9S_MB_2U(SCH_1):I3C_SPD_DDRABCD_CPU0_LVC1_R_SCL

Q_CAP_0402-0.1UF,25V,10%,X7R,CA  I24  C538
   1 P3V3_AUX      A @S9S_MB_2U_LIB.S9S_MB_2U(SCH_1):P3V3_AUX
   2    GND      B @S9S_MB_2U_LIB.S9S_MB_2U(SCH_1):GND

Q_RES_0402LF-0,5%,1/16W,CHIP,CA  I25  R689
   1 I3C_SPD_DDREFGH_CPU0_SCL      A @S9S_MB_2U_LIB.S9S_MB_2U(SCH_1):I3C_SPD_DDREFGH_CPU0_SCL
   2 I3C_SPD_DDREFGH_CPU0_R_SCL      B @S9S_MB_2U_LIB.S9S_MB_2U(SCH_1):I3C_SPD_DDREFGH_CPU0_R_SCL

Q_RES_0402LF-33.2,1%,1/16W,CHIA  I26  R690
   1 I3C_SPD_DDREFGH_CPU0_SDA      A @S9S_MB_2U_LIB.S9S_MB_2U(SCH_1):I3C_SPD_DDREFGH_CPU0_SDA
   2 I3C_SPD_DDREFGH_CPU0_R_SDA      B @S9S_MB_2U_LIB.S9S_MB_2U(SCH_1):I3C_SPD_DDREFGH_CPU0_R_SDA

Q_RES_0402LF-499,1%,1/16W,CHIPA  I30  R680
   1 PVNN_TERM_CPU0      A @S9S_MB_2U_LIB.S9S_MB_2U(SCH_1):PVNN_TERM_CPU0
   2 I3C_SPD_DDRABCD_CPU0_SDA      B @S9S_MB_2U_LIB.S9S_MB_2U(SCH_1):I3C_SPD_DDRABCD_CPU0_SDA

Q_RES_0402LF-499,1%,1/16W,CHIPA  I32  R681
   1 PVNN_TERM_CPU0      A @S9S_MB_2U_LIB.S9S_MB_2U(SCH_1):PVNN_TERM_CPU0
   2 I3C_SPD_DDREFGH_CPU0_SCL      B @S9S_MB_2U_LIB.S9S_MB_2U(SCH_1):I3C_SPD_DDREFGH_CPU0_SCL

Q_RES_0402LF-499,1%,1/16W,CHIPA  I33  R686
   1 PVNN_TERM_CPU0      A @S9S_MB_2U_LIB.S9S_MB_2U(SCH_1):PVNN_TERM_CPU0
   2 I3C_SPD_DDREFGH_CPU0_SDA      B @S9S_MB_2U_LIB.S9S_MB_2U(SCH_1):I3C_SPD_DDREFGH_CPU0_SDA

Q_RES_0402LF-0,5%,1/16W,CHIP,CA  I34  R687
   1 I3C_SPD_DDRABCD_CPU0_SCL      A @S9S_MB_2U_LIB.S9S_MB_2U(SCH_1):I3C_SPD_DDRABCD_CPU0_SCL
   2 I3C_SPD_DDRABCD_CPU0_R_SCL      B @S9S_MB_2U_LIB.S9S_MB_2U(SCH_1):I3C_SPD_DDRABCD_CPU0_R_SCL

Q_RES_0402LF-33.2,1%,1/16W,CHIA  I35  R688
   1 I3C_SPD_DDRABCD_CPU0_SDA      A @S9S_MB_2U_LIB.S9S_MB_2U(SCH_1):I3C_SPD_DDRABCD_CPU0_SDA
   2 I3C_SPD_DDRABCD_CPU0_R_SDA      B @S9S_MB_2U_LIB.S9S_MB_2U(SCH_1):I3C_SPD_DDRABCD_CPU0_R_SDA

Q_RES_0402LF-33.2,1%,1/16W,CHIA  I37  R694
   1 I3C_SPD_DDREFGH_CPU0_LVC1_R_SDA      A @S9S_MB_2U_LIB.S9S_MB_2U(SCH_1):I3C_SPD_DDREFGH_CPU0_LVC1_R_SDA
   2 I3C_SPD_DDREFGH_CPU0_LVC1_SDA      B @S9S_MB_2U_LIB.S9S_MB_2U(SCH_1):I3C_SPD_DDREFGH_CPU0_LVC1_SDA

Q_RES_0402LF-0,5%,1/16W,CHIP,CA  I38  R693
   1 I3C_SPD_DDREFGH_CPU0_LVC1_R_SCL      A @S9S_MB_2U_LIB.S9S_MB_2U(SCH_1):I3C_SPD_DDREFGH_CPU0_LVC1_R_SCL
   2 I3C_SPD_DDREFGH_CPU0_LVC1_SCL      B @S9S_MB_2U_LIB.S9S_MB_2U(SCH_1):I3C_SPD_DDREFGH_CPU0_LVC1_SCL

Q_RES_0402LF-0,5%,1/16W,CHIP,CA  I39  R691
   1 I3C_SPD_DDRABCD_CPU0_LVC1_R_SCL      A @S9S_MB_2U_LIB.S9S_MB_2U(SCH_1):I3C_SPD_DDRABCD_CPU0_LVC1_R_SCL
   2 I3C_SPD_DDRABCD_CPU0_LVC1_SCL      B @S9S_MB_2U_LIB.S9S_MB_2U(SCH_1):I3C_SPD_DDRABCD_CPU0_LVC1_SCL

Q_RES_0402LF-33.2,1%,1/16W,CHIA  I40  R692
   1 I3C_SPD_DDRABCD_CPU0_LVC1_R_SDA      A @S9S_MB_2U_LIB.S9S_MB_2U(SCH_1):I3C_SPD_DDRABCD_CPU0_LVC1_R_SDA
   2 I3C_SPD_DDRABCD_CPU0_LVC1_SDA      B @S9S_MB_2U_LIB.S9S_MB_2U(SCH_1):I3C_SPD_DDRABCD_CPU0_LVC1_SDA

Q_RES_0402LF-10K,1%,1/16W,CHIPA  I42  R318
   1 FM_SPD_REMOTE_EN      A @S9S_MB_2U_LIB.S9S_MB_2U(SCH_1):FM_SPD_REMOTE_EN
   2    GND      B @S9S_MB_2U_LIB.S9S_MB_2U(SCH_1):GND

Q_RES_0402LF-1K,1%,1/16W,EMPTYA  I43  R87
   1 P3V3_AUX      A @S9S_MB_2U_LIB.S9S_MB_2U(SCH_1):P3V3_AUX
   2 FM_SPD_REMOTE_EN      B @S9S_MB_2U_LIB.S9S_MB_2U(SCH_1):FM_SPD_REMOTE_EN

Q_RES_0402LF-200,1%,1/16W,CHIPA  I53  R1821
   1 FM_SPD_REMOTE_EN_R      A @S9S_MB_2U_LIB.S9S_MB_2U(SCH_1):FM_SPD_REMOTE_EN_R
   2 FM_SPD_REMOTE_EN      B @S9S_MB_2U_LIB.S9S_MB_2U(SCH_1):FM_SPD_REMOTE_EN


DRAWING: @S9S_MB_2U_LIB.S9S_MB_2U(SCH_1):PAGE218 

Q_RES_0402LF-499,1%,1/16W,CHIPA  I18  R663
   1 PVNN_TERM_CPU1      A @S9S_MB_2U_LIB.S9S_MB_2U(SCH_1):PVNN_TERM_CPU1
   2 I3C_SPD_DDRABCD_CPU1_SDA      B @S9S_MB_2U_LIB.S9S_MB_2U(SCH_1):I3C_SPD_DDRABCD_CPU1_SDA

Q_RES_0402LF-0,5%,1/16W,EMPTY,A  I22  R666
   1 I3C_SPD_DDRABCD_CPU1_R_SDA      A @S9S_MB_2U_LIB.S9S_MB_2U(SCH_1):I3C_SPD_DDRABCD_CPU1_R_SDA
   2 I3C_SPD_DDRABCD_CPU1_LVC1_R_SDA      B @S9S_MB_2U_LIB.S9S_MB_2U(SCH_1):I3C_SPD_DDRABCD_CPU1_LVC1_R_SDA

Q_RES_0402LF-499,1%,1/16W,CHIPA  I28  R664
   1 PVNN_TERM_CPU1      A @S9S_MB_2U_LIB.S9S_MB_2U(SCH_1):PVNN_TERM_CPU1
   2 I3C_SPD_DDREFGH_CPU1_SCL      B @S9S_MB_2U_LIB.S9S_MB_2U(SCH_1):I3C_SPD_DDREFGH_CPU1_SCL

Q_RES_0402LF-0,5%,1/16W,CHIP,CA  I30  R672
   1 I3C_SPD_DDREFGH_CPU1_SCL      A @S9S_MB_2U_LIB.S9S_MB_2U(SCH_1):I3C_SPD_DDREFGH_CPU1_SCL
   2 I3C_SPD_DDREFGH_CPU1_R_SCL      B @S9S_MB_2U_LIB.S9S_MB_2U(SCH_1):I3C_SPD_DDREFGH_CPU1_R_SCL

Q_RES_0402LF-33.2,1%,1/16W,CHIA  I31  R673
   1 I3C_SPD_DDREFGH_CPU1_SDA      A @S9S_MB_2U_LIB.S9S_MB_2U(SCH_1):I3C_SPD_DDREFGH_CPU1_SDA
   2 I3C_SPD_DDREFGH_CPU1_R_SDA      B @S9S_MB_2U_LIB.S9S_MB_2U(SCH_1):I3C_SPD_DDREFGH_CPU1_R_SDA

Q_RES_0402LF-0,5%,1/16W,CHIP,CA  I32  R670
   1 I3C_SPD_DDRABCD_CPU1_SCL      A @S9S_MB_2U_LIB.S9S_MB_2U(SCH_1):I3C_SPD_DDRABCD_CPU1_SCL
   2 I3C_SPD_DDRABCD_CPU1_R_SCL      B @S9S_MB_2U_LIB.S9S_MB_2U(SCH_1):I3C_SPD_DDRABCD_CPU1_R_SCL

Q_RES_0402LF-33.2,1%,1/16W,CHIA  I33  R671
   1 I3C_SPD_DDRABCD_CPU1_SDA      A @S9S_MB_2U_LIB.S9S_MB_2U(SCH_1):I3C_SPD_DDRABCD_CPU1_SDA
   2 I3C_SPD_DDRABCD_CPU1_R_SDA      B @S9S_MB_2U_LIB.S9S_MB_2U(SCH_1):I3C_SPD_DDRABCD_CPU1_R_SDA

Q_RES_0402LF-1K,1%,1/16W,CHIP,A  I4  R661
   1 PD_I3C_SPD_DDR_CPU1_OE_N      A @S9S_MB_2U_LIB.S9S_MB_2U(SCH_1):PD_I3C_SPD_DDR_CPU1_OE_N
   2    GND      B @S9S_MB_2U_LIB.S9S_MB_2U(SCH_1):GND

QS3VH257QG8_SMLF-QS3VH257QG8,IA  I12  U14
   1 FM_SPD_REMOTE_EN      S @S9S_MB_2U_LIB.S9S_MB_2U(SCH_1):FM_SPD_REMOTE_EN
  15 PD_I3C_SPD_DDR_CPU1_OE_N     E* @S9S_MB_2U_LIB.S9S_MB_2U(SCH_1):PD_I3C_SPD_DDR_CPU1_OE_N
   4 I3C_SPD_DDRABCD_CPU1_LVC1_R_SCL     YA @S9S_MB_2U_LIB.S9S_MB_2U(SCH_1):I3C_SPD_DDRABCD_CPU1_LVC1_R_SCL
   2 I3C_SPD_DDRABCD_CPU1_R_SCL    I0A @S9S_MB_2U_LIB.S9S_MB_2U(SCH_1):I3C_SPD_DDRABCD_CPU1_R_SCL
   3 I3C_SPD_DDRABCD_CPU1_BMC_SCL    I1A @S9S_MB_2U_LIB.S9S_MB_2U(SCH_1):I3C_SPD_DDRABCD_CPU1_BMC_SCL
   5 I3C_SPD_DDRABCD_CPU1_R_SDA    I0B @S9S_MB_2U_LIB.S9S_MB_2U(SCH_1):I3C_SPD_DDRABCD_CPU1_R_SDA
   6 I3C_SPD_DDRABCD_CPU1_BMC_SDA    I1B @S9S_MB_2U_LIB.S9S_MB_2U(SCH_1):I3C_SPD_DDRABCD_CPU1_BMC_SDA
   7 I3C_SPD_DDRABCD_CPU1_LVC1_R_SDA     YB @S9S_MB_2U_LIB.S9S_MB_2U(SCH_1):I3C_SPD_DDRABCD_CPU1_LVC1_R_SDA
  11 I3C_SPD_DDREFGH_CPU1_R_SCL    I0C @S9S_MB_2U_LIB.S9S_MB_2U(SCH_1):I3C_SPD_DDREFGH_CPU1_R_SCL
  10 I3C_SPD_DDREFGH_CPU1_BMC_SCL    I1C @S9S_MB_2U_LIB.S9S_MB_2U(SCH_1):I3C_SPD_DDREFGH_CPU1_BMC_SCL
   9 I3C_SPD_DDREFGH_CPU1_LVC1_R_SCL     YC @S9S_MB_2U_LIB.S9S_MB_2U(SCH_1):I3C_SPD_DDREFGH_CPU1_LVC1_R_SCL
  12 I3C_SPD_DDREFGH_CPU1_LVC1_R_SDA     YD @S9S_MB_2U_LIB.S9S_MB_2U(SCH_1):I3C_SPD_DDREFGH_CPU1_LVC1_R_SDA
  14 I3C_SPD_DDREFGH_CPU1_R_SDA    I0D @S9S_MB_2U_LIB.S9S_MB_2U(SCH_1):I3C_SPD_DDREFGH_CPU1_R_SDA
  13 I3C_SPD_DDREFGH_CPU1_BMC_SDA    I1D @S9S_MB_2U_LIB.S9S_MB_2U(SCH_1):I3C_SPD_DDREFGH_CPU1_BMC_SDA
   8    GND    GND @S9S_MB_2U_LIB.S9S_MB_2U(SCH_1):GND
  16 P3V3_AUX    VCC @S9S_MB_2U_LIB.S9S_MB_2U(SCH_1):P3V3_AUX

Q_RES_0402LF-499,1%,1/16W,CHIPA  I17  R662
   1 PVNN_TERM_CPU1      A @S9S_MB_2U_LIB.S9S_MB_2U(SCH_1):PVNN_TERM_CPU1
   2 I3C_SPD_DDRABCD_CPU1_SCL      B @S9S_MB_2U_LIB.S9S_MB_2U(SCH_1):I3C_SPD_DDRABCD_CPU1_SCL

Q_RES_0402LF-0,5%,1/16W,EMPTY,A  I20  R668
   1 I3C_SPD_DDREFGH_CPU1_R_SDA      A @S9S_MB_2U_LIB.S9S_MB_2U(SCH_1):I3C_SPD_DDREFGH_CPU1_R_SDA
   2 I3C_SPD_DDREFGH_CPU1_LVC1_R_SDA      B @S9S_MB_2U_LIB.S9S_MB_2U(SCH_1):I3C_SPD_DDREFGH_CPU1_LVC1_R_SDA

Q_RES_0402LF-0,5%,1/16W,EMPTY,A  I21  R667
   1 I3C_SPD_DDREFGH_CPU1_R_SCL      A @S9S_MB_2U_LIB.S9S_MB_2U(SCH_1):I3C_SPD_DDREFGH_CPU1_R_SCL
   2 I3C_SPD_DDREFGH_CPU1_LVC1_R_SCL      B @S9S_MB_2U_LIB.S9S_MB_2U(SCH_1):I3C_SPD_DDREFGH_CPU1_LVC1_R_SCL

Q_RES_0402LF-0,5%,1/16W,EMPTY,A  I23  R665
   1 I3C_SPD_DDRABCD_CPU1_R_SCL      A @S9S_MB_2U_LIB.S9S_MB_2U(SCH_1):I3C_SPD_DDRABCD_CPU1_R_SCL
   2 I3C_SPD_DDRABCD_CPU1_LVC1_R_SCL      B @S9S_MB_2U_LIB.S9S_MB_2U(SCH_1):I3C_SPD_DDRABCD_CPU1_LVC1_R_SCL

Q_CAP_0402-0.1UF,25V,10%,X7R,CA  I25  C537
   1 P3V3_AUX      A @S9S_MB_2U_LIB.S9S_MB_2U(SCH_1):P3V3_AUX
   2    GND      B @S9S_MB_2U_LIB.S9S_MB_2U(SCH_1):GND

Q_RES_0402LF-499,1%,1/16W,CHIPA  I29  R669
   1 PVNN_TERM_CPU1      A @S9S_MB_2U_LIB.S9S_MB_2U(SCH_1):PVNN_TERM_CPU1
   2 I3C_SPD_DDREFGH_CPU1_SDA      B @S9S_MB_2U_LIB.S9S_MB_2U(SCH_1):I3C_SPD_DDREFGH_CPU1_SDA

Q_RES_0402LF-33.2,1%,1/16W,CHIA  I34  R677
   1 I3C_SPD_DDREFGH_CPU1_LVC1_R_SDA      A @S9S_MB_2U_LIB.S9S_MB_2U(SCH_1):I3C_SPD_DDREFGH_CPU1_LVC1_R_SDA
   2 I3C_SPD_DDREFGH_CPU1_LVC1_SDA      B @S9S_MB_2U_LIB.S9S_MB_2U(SCH_1):I3C_SPD_DDREFGH_CPU1_LVC1_SDA

Q_RES_0402LF-0,5%,1/16W,CHIP,CA  I35  R676
   1 I3C_SPD_DDREFGH_CPU1_LVC1_R_SCL      A @S9S_MB_2U_LIB.S9S_MB_2U(SCH_1):I3C_SPD_DDREFGH_CPU1_LVC1_R_SCL
   2 I3C_SPD_DDREFGH_CPU1_LVC1_SCL      B @S9S_MB_2U_LIB.S9S_MB_2U(SCH_1):I3C_SPD_DDREFGH_CPU1_LVC1_SCL

Q_RES_0402LF-33.2,1%,1/16W,CHIA  I36  R675
   1 I3C_SPD_DDRABCD_CPU1_LVC1_R_SDA      A @S9S_MB_2U_LIB.S9S_MB_2U(SCH_1):I3C_SPD_DDRABCD_CPU1_LVC1_R_SDA
   2 I3C_SPD_DDRABCD_CPU1_LVC1_SDA      B @S9S_MB_2U_LIB.S9S_MB_2U(SCH_1):I3C_SPD_DDRABCD_CPU1_LVC1_SDA

Q_RES_0402LF-0,5%,1/16W,CHIP,CA  I37  R674
   1 I3C_SPD_DDRABCD_CPU1_LVC1_R_SCL      A @S9S_MB_2U_LIB.S9S_MB_2U(SCH_1):I3C_SPD_DDRABCD_CPU1_LVC1_R_SCL
   2 I3C_SPD_DDRABCD_CPU1_LVC1_SCL      B @S9S_MB_2U_LIB.S9S_MB_2U(SCH_1):I3C_SPD_DDRABCD_CPU1_LVC1_SCL


DRAWING: @S9S_MB_2U_LIB.S9S_MB_2U(SCH_1):PAGE219 

Q_RES_0402LF-1K,1%,1/16W,CHIP,A  I2  R537
   1 PCA9548_PCIE3_ADDR2      A @S9S_MB_2U_LIB.S9S_MB_2U(SCH_1):PCA9548_PCIE3_ADDR2
   2    GND      B @S9S_MB_2U_LIB.S9S_MB_2U(SCH_1):GND

Q_RES_0402LF-1K,1%,1/16W,CHIP,A  I6  R539
   1 PCA9548_PCIE3_ADDR1      A @S9S_MB_2U_LIB.S9S_MB_2U(SCH_1):PCA9548_PCIE3_ADDR1
   2    GND      B @S9S_MB_2U_LIB.S9S_MB_2U(SCH_1):GND

Q_RES_0402LF-10K,1%,1/16W,EMPTA  I9  R538
   1 P3V3_AUX      A @S9S_MB_2U_LIB.S9S_MB_2U(SCH_1):P3V3_AUX
   2 PCA9548_PCIE3_ADDR1      B @S9S_MB_2U_LIB.S9S_MB_2U(SCH_1):PCA9548_PCIE3_ADDR1

Q_RES_0402LF-10K,1%,1/16W,EMPTA  I10  R540
   1 P3V3_AUX      A @S9S_MB_2U_LIB.S9S_MB_2U(SCH_1):P3V3_AUX
   2 PCA9548_PCIE3_ADDR0      B @S9S_MB_2U_LIB.S9S_MB_2U(SCH_1):PCA9548_PCIE3_ADDR0

Q_RES_0402LF-10K,1%,1/16W,EMPTA  I3  R536
   1 P3V3_AUX      A @S9S_MB_2U_LIB.S9S_MB_2U(SCH_1):P3V3_AUX
   2 PCA9548_PCIE3_ADDR2      B @S9S_MB_2U_LIB.S9S_MB_2U(SCH_1):PCA9548_PCIE3_ADDR2

Q_RES_0402LF-1K,1%,1/16W,CHIP,A  I8  R587
   1 PCA9548_PCIE3_ADDR0      A @S9S_MB_2U_LIB.S9S_MB_2U(SCH_1):PCA9548_PCIE3_ADDR0
   2    GND      B @S9S_MB_2U_LIB.S9S_MB_2U(SCH_1):GND

Q_RES_0402LF-10K,1%,1/16W,CHIPA  I18  R1822
   1 P3V3_AUX      A @S9S_MB_2U_LIB.S9S_MB_2U(SCH_1):P3V3_AUX
   2 RST_SMB_SWITCH_N      B @S9S_MB_2U_LIB.S9S_MB_2U(SCH_1):RST_SMB_SWITCH_N

Q_RES_0402LF-2.2K,5%,1/16W,CHIA  I20  R1090
   1 P3V3_AUX      A @S9S_MB_2U_LIB.S9S_MB_2U(SCH_1):P3V3_AUX
   2 SMB_SENSOR_M2_P0_3V3AUX_SDA      B @S9S_MB_2U_LIB.S9S_MB_2U(SCH_1):SMB_SENSOR_M2_P0_3V3AUX_SDA

Q_RES_0402LF-2.2K,5%,1/16W,CHIA  I21  R1089
   1 P3V3_AUX      A @S9S_MB_2U_LIB.S9S_MB_2U(SCH_1):P3V3_AUX
   2 SMB_SENSOR_M2_P0_3V3AUX_SCL      B @S9S_MB_2U_LIB.S9S_MB_2U(SCH_1):SMB_SENSOR_M2_P0_3V3AUX_SCL

Q_RES_0402LF-2.2K,5%,1/16W,CHIA  I22  R651
   1 P3V3_AUX      A @S9S_MB_2U_LIB.S9S_MB_2U(SCH_1):P3V3_AUX
   2 SMB_FRU_3V3AUX_SCL      B @S9S_MB_2U_LIB.S9S_MB_2U(SCH_1):SMB_FRU_3V3AUX_SCL

Q_RES_0402LF-2.2K,5%,1/16W,CHIA  I23  R652
   1 P3V3_AUX      A @S9S_MB_2U_LIB.S9S_MB_2U(SCH_1):P3V3_AUX
   2 SMB_FRU_3V3AUX_SDA      B @S9S_MB_2U_LIB.S9S_MB_2U(SCH_1):SMB_FRU_3V3AUX_SDA

Q_RES_0402LF-10K,1%,1/16W,CHIPA  I24  R2985
   1 P3V3_AUX      A @S9S_MB_2U_LIB.S9S_MB_2U(SCH_1):P3V3_AUX
   2 SMB_BMC_SWB_SDA      B @S9S_MB_2U_LIB.S9S_MB_2U(SCH_1):SMB_BMC_SWB_SDA

Q_RES_0402LF-10K,1%,1/16W,CHIPA  I25  R2984
   1 P3V3_AUX      A @S9S_MB_2U_LIB.S9S_MB_2U(SCH_1):P3V3_AUX
   2 SMB_BMC_SWB_SCL      B @S9S_MB_2U_LIB.S9S_MB_2U(SCH_1):SMB_BMC_SWB_SCL

Q_RES_0402LF-0,5%,1/16W,CHIP,CA  I35  R3526
   1 SMB_PCIE0_3V3AUX_SCL_R5      A @S9S_MB_2U_LIB.S9S_MB_2U(SCH_1):SMB_PCIE0_3V3AUX_SCL_R5
   2 SMB_SENSOR_E1S_3V3AUX_SCL      B @S9S_MB_2U_LIB.S9S_MB_2U(SCH_1):SMB_SENSOR_E1S_3V3AUX_SCL

Q_RES_0402LF-0,5%,1/16W,CHIP,CA  I36  R2967
   1 SMB_PCIE0_3V3AUX_SCL_R3      A @S9S_MB_2U_LIB.S9S_MB_2U(SCH_1):SMB_PCIE0_3V3AUX_SCL_R3
   2 SMB_SENSOR_M2_P0_3V3AUX_SCL      B @S9S_MB_2U_LIB.S9S_MB_2U(SCH_1):SMB_SENSOR_M2_P0_3V3AUX_SCL

Q_RES_0402LF-0,5%,1/16W,CHIP,CA  I37  R3527
   1 SMB_PCIE0_3V3AUX_SDA_R5      A @S9S_MB_2U_LIB.S9S_MB_2U(SCH_1):SMB_PCIE0_3V3AUX_SDA_R5
   2 SMB_SENSOR_E1S_3V3AUX_SDA      B @S9S_MB_2U_LIB.S9S_MB_2U(SCH_1):SMB_SENSOR_E1S_3V3AUX_SDA

Q_RES_0402LF-0,5%,1/16W,CHIP,CA  I38  R3393
   1 SMB_IOEXP_3V3AUX_SCL_R      A @S9S_MB_2U_LIB.S9S_MB_2U(SCH_1):SMB_IOEXP_3V3AUX_SCL_R
   2 SMB_IOEXP_3V3AUX_SCL      B @S9S_MB_2U_LIB.S9S_MB_2U(SCH_1):SMB_IOEXP_3V3AUX_SCL

Q_RES_0402LF-0,5%,1/16W,CHIP,CA  I39  R2968
   1 SMB_PCIE0_3V3AUX_SDA_R3      A @S9S_MB_2U_LIB.S9S_MB_2U(SCH_1):SMB_PCIE0_3V3AUX_SDA_R3
   2 SMB_SENSOR_M2_P0_3V3AUX_SDA      B @S9S_MB_2U_LIB.S9S_MB_2U(SCH_1):SMB_SENSOR_M2_P0_3V3AUX_SDA

Q_RES_0402LF-0,5%,1/16W,CHIP,CA  I40  R3394
   1 SMB_IOEXP_3V3AUX_SDA_R      A @S9S_MB_2U_LIB.S9S_MB_2U(SCH_1):SMB_IOEXP_3V3AUX_SDA_R
   2 SMB_IOEXP_3V3AUX_SDA      B @S9S_MB_2U_LIB.S9S_MB_2U(SCH_1):SMB_IOEXP_3V3AUX_SDA

Q_RES_0402LF-0,5%,1/16W,CHIP,CA  I41  R2268
   1 RST_SMB_SWITCH_N      A @S9S_MB_2U_LIB.S9S_MB_2U(SCH_1):RST_SMB_SWITCH_N
   2 PU_RST_SMB_PCIE0_N      B @S9S_MB_2U_LIB.S9S_MB_2U(SCH_1):PU_RST_SMB_PCIE0_N

TCA9548APWR-TCA9548APWR,SMLF,IA  I45  U36
   1 PCA9548_PCIE3_ADDR0     A0 @S9S_MB_2U_LIB.S9S_MB_2U(SCH_1):PCA9548_PCIE3_ADDR0
   2 PCA9548_PCIE3_ADDR1     A1 @S9S_MB_2U_LIB.S9S_MB_2U(SCH_1):PCA9548_PCIE3_ADDR1
   3 PU_RST_SMB_PCIE0_N RESET# @S9S_MB_2U_LIB.S9S_MB_2U(SCH_1):PU_RST_SMB_PCIE0_N
   4     NC    SD0     NC
   5     NC    SC0     NC
   6 SMB_IOEXP_3V3AUX_SDA_R    SD1 @S9S_MB_2U_LIB.S9S_MB_2U(SCH_1):SMB_IOEXP_3V3AUX_SDA_R
   7 SMB_IOEXP_3V3AUX_SCL_R    SC1 @S9S_MB_2U_LIB.S9S_MB_2U(SCH_1):SMB_IOEXP_3V3AUX_SCL_R
   8 SMB_PCIE0_3V3AUX_SDA_R3    SD2 @S9S_MB_2U_LIB.S9S_MB_2U(SCH_1):SMB_PCIE0_3V3AUX_SDA_R3
   9 SMB_PCIE0_3V3AUX_SCL_R3    SC2 @S9S_MB_2U_LIB.S9S_MB_2U(SCH_1):SMB_PCIE0_3V3AUX_SCL_R3
  10 SMB_PCIE0_3V3AUX_SDA_R5    SD3 @S9S_MB_2U_LIB.S9S_MB_2U(SCH_1):SMB_PCIE0_3V3AUX_SDA_R5
  11 SMB_PCIE0_3V3AUX_SCL_R5    SC3 @S9S_MB_2U_LIB.S9S_MB_2U(SCH_1):SMB_PCIE0_3V3AUX_SCL_R5
  12    GND    GND @S9S_MB_2U_LIB.S9S_MB_2U(SCH_1):GND
  24 P3V3_AUX    VCC @S9S_MB_2U_LIB.S9S_MB_2U(SCH_1):P3V3_AUX
  23 SMB_PCIE0_3V3AUX_SDA_R    SDA @S9S_MB_2U_LIB.S9S_MB_2U(SCH_1):SMB_PCIE0_3V3AUX_SDA_R
  22 SMB_PCIE0_3V3AUX_SCL_R    SCL @S9S_MB_2U_LIB.S9S_MB_2U(SCH_1):SMB_PCIE0_3V3AUX_SCL_R
  21 PCA9548_PCIE3_ADDR2     A2 @S9S_MB_2U_LIB.S9S_MB_2U(SCH_1):PCA9548_PCIE3_ADDR2
  20     NC    SC7     NC
  19     NC    SD7     NC
  18 SMB_INA230_3V3AUX_SCL_R    SC6 @S9S_MB_2U_LIB.S9S_MB_2U(SCH_1):SMB_INA230_3V3AUX_SCL_R
  17 SMB_INA230_3V3AUX_SDA_R    SD6 @S9S_MB_2U_LIB.S9S_MB_2U(SCH_1):SMB_INA230_3V3AUX_SDA_R
  16 SMB_FRU_3V3AUX_SCL_R    SC5 @S9S_MB_2U_LIB.S9S_MB_2U(SCH_1):SMB_FRU_3V3AUX_SCL_R
  15 SMB_FRU_3V3AUX_SDA_R    SD5 @S9S_MB_2U_LIB.S9S_MB_2U(SCH_1):SMB_FRU_3V3AUX_SDA_R
  14 SMB_BMC_SWB_SCL_R4    SC4 @S9S_MB_2U_LIB.S9S_MB_2U(SCH_1):SMB_BMC_SWB_SCL_R4
  13 SMB_BMC_SWB_SDA_R4    SD4 @S9S_MB_2U_LIB.S9S_MB_2U(SCH_1):SMB_BMC_SWB_SDA_R4

Q_CAP_0402-0.1UF,25V,10%,X7R,CA  I47  C174
   1 P3V3_AUX      A @S9S_MB_2U_LIB.S9S_MB_2U(SCH_1):P3V3_AUX
   2    GND      B @S9S_MB_2U_LIB.S9S_MB_2U(SCH_1):GND

Q_RES_0402LF-2.2K,5%,1/16W,CHIA  I49  R3535
   1 P3V3_AUX      A @S9S_MB_2U_LIB.S9S_MB_2U(SCH_1):P3V3_AUX
   2 SMB_SENSOR_E1S_3V3AUX_SCL      B @S9S_MB_2U_LIB.S9S_MB_2U(SCH_1):SMB_SENSOR_E1S_3V3AUX_SCL

Q_RES_0402LF-2.2K,5%,1/16W,CHIA  I50  R3536
   1 P3V3_AUX      A @S9S_MB_2U_LIB.S9S_MB_2U(SCH_1):P3V3_AUX
   2 SMB_SENSOR_E1S_3V3AUX_SDA      B @S9S_MB_2U_LIB.S9S_MB_2U(SCH_1):SMB_SENSOR_E1S_3V3AUX_SDA

Q_RES_0402LF-2.2K,5%,1/16W,CHIA  I51  R3583
   1 P3V3_AUX      A @S9S_MB_2U_LIB.S9S_MB_2U(SCH_1):P3V3_AUX
   2 SMB_IOEXP_3V3AUX_SDA      B @S9S_MB_2U_LIB.S9S_MB_2U(SCH_1):SMB_IOEXP_3V3AUX_SDA

Q_RES_0402LF-2.2K,5%,1/16W,CHIA  I52  R3582
   1 P3V3_AUX      A @S9S_MB_2U_LIB.S9S_MB_2U(SCH_1):P3V3_AUX
   2 SMB_IOEXP_3V3AUX_SCL      B @S9S_MB_2U_LIB.S9S_MB_2U(SCH_1):SMB_IOEXP_3V3AUX_SCL

Q_RES_0402LF-2.2K,5%,1/16W,CHIA  I53  R3396
   1 P3V3_AUX      A @S9S_MB_2U_LIB.S9S_MB_2U(SCH_1):P3V3_AUX
   2 SMB_INA230_3V3AUX_SDA      B @S9S_MB_2U_LIB.S9S_MB_2U(SCH_1):SMB_INA230_3V3AUX_SDA

Q_RES_0402LF-2.2K,5%,1/16W,CHIA  I54  R3395
   1 P3V3_AUX      A @S9S_MB_2U_LIB.S9S_MB_2U(SCH_1):P3V3_AUX
   2 SMB_INA230_3V3AUX_SCL      B @S9S_MB_2U_LIB.S9S_MB_2U(SCH_1):SMB_INA230_3V3AUX_SCL

Q_RES_0402LF-2.2K,5%,1/16W,EMPA  I56  R2205
   1 P3V3_AUX      A @S9S_MB_2U_LIB.S9S_MB_2U(SCH_1):P3V3_AUX
   2 SMB_PCIE0_3V3AUX_SDA      B @S9S_MB_2U_LIB.S9S_MB_2U(SCH_1):SMB_PCIE0_3V3AUX_SDA

Q_RES_0402LF-2.2K,5%,1/16W,EMPA  I57  R2204
   1 P3V3_AUX      A @S9S_MB_2U_LIB.S9S_MB_2U(SCH_1):P3V3_AUX
   2 SMB_PCIE0_3V3AUX_SCL      B @S9S_MB_2U_LIB.S9S_MB_2U(SCH_1):SMB_PCIE0_3V3AUX_SCL

Q_RES_0402LF-0,5%,1/16W,CHIP,CA  I59  R3580
   1 SMB_INA230_3V3AUX_SCL_R      A @S9S_MB_2U_LIB.S9S_MB_2U(SCH_1):SMB_INA230_3V3AUX_SCL_R
   2 SMB_INA230_3V3AUX_SCL      B @S9S_MB_2U_LIB.S9S_MB_2U(SCH_1):SMB_INA230_3V3AUX_SCL

Q_RES_0402LF-0,5%,1/16W,CHIP,CA  I60  R3581
   1 SMB_INA230_3V3AUX_SDA_R      A @S9S_MB_2U_LIB.S9S_MB_2U(SCH_1):SMB_INA230_3V3AUX_SDA_R
   2 SMB_INA230_3V3AUX_SDA      B @S9S_MB_2U_LIB.S9S_MB_2U(SCH_1):SMB_INA230_3V3AUX_SDA

Q_RES_0402LF-0,5%,1/16W,CHIP,CA  I61  R2565
   1 SMB_FRU_3V3AUX_SCL_R      A @S9S_MB_2U_LIB.S9S_MB_2U(SCH_1):SMB_FRU_3V3AUX_SCL_R
   2 SMB_FRU_3V3AUX_SCL      B @S9S_MB_2U_LIB.S9S_MB_2U(SCH_1):SMB_FRU_3V3AUX_SCL

Q_RES_0402LF-0,5%,1/16W,CHIP,CA  I62  R2566
   1 SMB_FRU_3V3AUX_SDA_R      A @S9S_MB_2U_LIB.S9S_MB_2U(SCH_1):SMB_FRU_3V3AUX_SDA_R
   2 SMB_FRU_3V3AUX_SDA      B @S9S_MB_2U_LIB.S9S_MB_2U(SCH_1):SMB_FRU_3V3AUX_SDA

Q_RES_0402LF-0,5%,1/16W,CHIP,CA  I63  R2703
   1 SMB_BMC_SWB_SCL_R4      A @S9S_MB_2U_LIB.S9S_MB_2U(SCH_1):SMB_BMC_SWB_SCL_R4
   2 SMB_BMC_SWB_SCL      B @S9S_MB_2U_LIB.S9S_MB_2U(SCH_1):SMB_BMC_SWB_SCL

Q_RES_0402LF-0,5%,1/16W,CHIP,CA  I64  R2704
   1 SMB_BMC_SWB_SDA_R4      A @S9S_MB_2U_LIB.S9S_MB_2U(SCH_1):SMB_BMC_SWB_SDA_R4
   2 SMB_BMC_SWB_SDA      B @S9S_MB_2U_LIB.S9S_MB_2U(SCH_1):SMB_BMC_SWB_SDA

Q_RES_0402LF-33.2,1%,1/16W,CHIA  I65  R588
   1 SMB_PCIE0_3V3AUX_SCL      A @S9S_MB_2U_LIB.S9S_MB_2U(SCH_1):SMB_PCIE0_3V3AUX_SCL
   2 SMB_PCIE0_3V3AUX_SCL_R      B @S9S_MB_2U_LIB.S9S_MB_2U(SCH_1):SMB_PCIE0_3V3AUX_SCL_R

Q_RES_0402LF-33.2,1%,1/16W,CHIA  I66  R589
   1 SMB_PCIE0_3V3AUX_SDA      A @S9S_MB_2U_LIB.S9S_MB_2U(SCH_1):SMB_PCIE0_3V3AUX_SDA
   2 SMB_PCIE0_3V3AUX_SDA_R      B @S9S_MB_2U_LIB.S9S_MB_2U(SCH_1):SMB_PCIE0_3V3AUX_SDA_R


DRAWING: @S9S_MB_2U_LIB.S9S_MB_2U(SCH_1):PAGE223 

Q_RES_0402LF-4.7K,5%,1/16W,CHIA  I8  R1006
   1 PVNN_TERM_CPU0      A @S9S_MB_2U_LIB.S9S_MB_2U(SCH_1):PVNN_TERM_CPU0
   2 FM_PEHPCPU0_ALERT_N      B @S9S_MB_2U_LIB.S9S_MB_2U(SCH_1):FM_PEHPCPU0_ALERT_N

Q_RES_0402LF-4.7K,5%,1/16W,CHIA  I12  R1007
   1 PVNN_TERM_CPU1      A @S9S_MB_2U_LIB.S9S_MB_2U(SCH_1):PVNN_TERM_CPU1
   2 FM_PEHPCPU1_ALERT_N      B @S9S_MB_2U_LIB.S9S_MB_2U(SCH_1):FM_PEHPCPU1_ALERT_N

Q_CAP_0402-0.1UF,25V,10%,X7R,CA  I18  C561
   1 P3V3_AUX      A @S9S_MB_2U_LIB.S9S_MB_2U(SCH_1):P3V3_AUX
   2    GND      B @S9S_MB_2U_LIB.S9S_MB_2U(SCH_1):GND

Q_CAP_0402-0.1UF,25V,10%,X7R,CA  I20  C559
   1 PVNN_TERM_CPU0      A @S9S_MB_2U_LIB.S9S_MB_2U(SCH_1):PVNN_TERM_CPU0
   2    GND      B @S9S_MB_2U_LIB.S9S_MB_2U(SCH_1):GND

Q_RES_0402LF-240,1%,1/16W,CHIPA  I22  R911
   1 PVNN_TERM_CPU0      A @S9S_MB_2U_LIB.S9S_MB_2U(SCH_1):PVNN_TERM_CPU0
   2 SMB_PEHPCPU0_GTL_R_SDA      B @S9S_MB_2U_LIB.S9S_MB_2U(SCH_1):SMB_PEHPCPU0_GTL_R_SDA

Q_RES_0402LF-240,1%,1/16W,CHIPA  I24  R910
   1 PVNN_TERM_CPU0      A @S9S_MB_2U_LIB.S9S_MB_2U(SCH_1):PVNN_TERM_CPU0
   2 SMB_PEHPCPU0_GTL_R_SCL      B @S9S_MB_2U_LIB.S9S_MB_2U(SCH_1):SMB_PEHPCPU0_GTL_R_SCL

Q_CAP_0402-0.1UF,25V,10%,X7R,CA  I31  C562
   1 P3V3_AUX      A @S9S_MB_2U_LIB.S9S_MB_2U(SCH_1):P3V3_AUX
   2    GND      B @S9S_MB_2U_LIB.S9S_MB_2U(SCH_1):GND

Q_RES_0402LF-4.7K,5%,1/16W,CHIA  I34  R1002
   1   P3V3      A @S9S_MB_2U_LIB.S9S_MB_2U(SCH_1):P3V3
   2 FM_SMB_CPU0_ALERT_R1      B @S9S_MB_2U_LIB.S9S_MB_2U(SCH_1):FM_SMB_CPU0_ALERT_R1

Q_RES_0402LF-4.7K,5%,1/16W,CHIA  I38  R1003
   1   P3V3      A @S9S_MB_2U_LIB.S9S_MB_2U(SCH_1):P3V3
   2 FM_SMB_CPU1_ALERT_R1      B @S9S_MB_2U_LIB.S9S_MB_2U(SCH_1):FM_SMB_CPU1_ALERT_R1

PCA9617ADP-PCA9617ADP,SMLF,IC,A  I39  U28
   5 TP_SMB_PEHPCPU0_EN     EN @S9S_MB_2U_LIB.S9S_MB_2U(SCH_1):TP_SMB_PEHPCPU0_EN
   1 PVNN_TERM_CPU0   VCCA @S9S_MB_2U_LIB.S9S_MB_2U(SCH_1):PVNN_TERM_CPU0
   8 P3V3_AUX   VCCB @S9S_MB_2U_LIB.S9S_MB_2U(SCH_1):P3V3_AUX
   2 SMB_PEHPCPU0_GTL_R_SCL   SCLA @S9S_MB_2U_LIB.S9S_MB_2U(SCH_1):SMB_PEHPCPU0_GTL_R_SCL
   3 SMB_PEHPCPU0_GTL_R_SDA   SDAA @S9S_MB_2U_LIB.S9S_MB_2U(SCH_1):SMB_PEHPCPU0_GTL_R_SDA
   6 SMB_PEHPCPU0_LVC3_SDA_R0   SDAB @S9S_MB_2U_LIB.S9S_MB_2U(SCH_1):SMB_PEHPCPU0_LVC3_SDA_R0
   7 SMB_PEHPCPU0_LVC3_SCL_R0   SCLB @S9S_MB_2U_LIB.S9S_MB_2U(SCH_1):SMB_PEHPCPU0_LVC3_SCL_R0
   4    GND    GND @S9S_MB_2U_LIB.S9S_MB_2U(SCH_1):GND

Q_CAP_0402-0.1UF,25V,10%,X7R,CA  I42  C560
   1 PVNN_TERM_CPU1      A @S9S_MB_2U_LIB.S9S_MB_2U(SCH_1):PVNN_TERM_CPU1
   2    GND      B @S9S_MB_2U_LIB.S9S_MB_2U(SCH_1):GND

PCA9617ADP-PCA9617ADP,SMLF,IC,A  I43  U29
   5 TP_SMB_PEHPCPU1_EN     EN @S9S_MB_2U_LIB.S9S_MB_2U(SCH_1):TP_SMB_PEHPCPU1_EN
   1 PVNN_TERM_CPU1   VCCA @S9S_MB_2U_LIB.S9S_MB_2U(SCH_1):PVNN_TERM_CPU1
   8 P3V3_AUX   VCCB @S9S_MB_2U_LIB.S9S_MB_2U(SCH_1):P3V3_AUX
   2 SMB_PEHPCPU1_GTL_R_SCL   SCLA @S9S_MB_2U_LIB.S9S_MB_2U(SCH_1):SMB_PEHPCPU1_GTL_R_SCL
   3 SMB_PEHPCPU1_GTL_R_SDA   SDAA @S9S_MB_2U_LIB.S9S_MB_2U(SCH_1):SMB_PEHPCPU1_GTL_R_SDA
   6 SMB_PEHPCPU1_LVC3_SDA_R0   SDAB @S9S_MB_2U_LIB.S9S_MB_2U(SCH_1):SMB_PEHPCPU1_LVC3_SDA_R0
   7 SMB_PEHPCPU1_LVC3_SCL_R0   SCLB @S9S_MB_2U_LIB.S9S_MB_2U(SCH_1):SMB_PEHPCPU1_LVC3_SCL_R0
   4    GND    GND @S9S_MB_2U_LIB.S9S_MB_2U(SCH_1):GND

Q_RES_0402LF-240,1%,1/16W,CHIPA  I46  R964
   1 PVNN_TERM_CPU1      A @S9S_MB_2U_LIB.S9S_MB_2U(SCH_1):PVNN_TERM_CPU1
   2 SMB_PEHPCPU1_GTL_R_SDA      B @S9S_MB_2U_LIB.S9S_MB_2U(SCH_1):SMB_PEHPCPU1_GTL_R_SDA

Q_RES_0402LF-240,1%,1/16W,CHIPA  I48  R963
   1 PVNN_TERM_CPU1      A @S9S_MB_2U_LIB.S9S_MB_2U(SCH_1):PVNN_TERM_CPU1
   2 SMB_PEHPCPU1_GTL_R_SCL      B @S9S_MB_2U_LIB.S9S_MB_2U(SCH_1):SMB_PEHPCPU1_GTL_R_SCL

Q_RES_0402LF-4.7K,5%,1/16W,CHIA  I52  R1000
   1   P3V3      A @S9S_MB_2U_LIB.S9S_MB_2U(SCH_1):P3V3
   2 FM_SMB_PEHPCPU0_PCIE_ALERT_R_N      B @S9S_MB_2U_LIB.S9S_MB_2U(SCH_1):FM_SMB_PEHPCPU0_PCIE_ALERT_R_N

Q_RES_0402LF-0,5%,1/16W,CHIP,CA  I53  R998
   1 FM_SMB_PEHPCPU0_PCIE_ALERT_N      A @S9S_MB_2U_LIB.S9S_MB_2U(SCH_1):FM_SMB_PEHPCPU0_PCIE_ALERT_N
   2 FM_SMB_PEHPCPU0_PCIE_ALERT_R_N      B @S9S_MB_2U_LIB.S9S_MB_2U(SCH_1):FM_SMB_PEHPCPU0_PCIE_ALERT_R_N

Q_RES_0402LF-4.7K,5%,1/16W,CHIA  I55  R1001
   1   P3V3      A @S9S_MB_2U_LIB.S9S_MB_2U(SCH_1):P3V3
   2 FM_SMB_PEHPCPU1_PCIE_ALERT_R_N      B @S9S_MB_2U_LIB.S9S_MB_2U(SCH_1):FM_SMB_PEHPCPU1_PCIE_ALERT_R_N

CONN3_210HP1030BR1-CONN3_210-HB  I64  JP7
   3 FM_SMB_PEHPCPU1_PCIE_ALERT_N      3 @S9S_MB_2U_LIB.S9S_MB_2U(SCH_1):FM_SMB_PEHPCPU1_PCIE_ALERT_N
   2    GND      2 @S9S_MB_2U_LIB.S9S_MB_2U(SCH_1):GND
   1 FM_SMB_PEHPCPU0_PCIE_ALERT_N      1 @S9S_MB_2U_LIB.S9S_MB_2U(SCH_1):FM_SMB_PEHPCPU0_PCIE_ALERT_N

Q_RES_0402LF-0,5%,1/16W,CHIP,CA  I69  R999
   1 FM_SMB_PEHPCPU1_PCIE_ALERT_N      A @S9S_MB_2U_LIB.S9S_MB_2U(SCH_1):FM_SMB_PEHPCPU1_PCIE_ALERT_N
   2 FM_SMB_PEHPCPU1_PCIE_ALERT_R_N      B @S9S_MB_2U_LIB.S9S_MB_2U(SCH_1):FM_SMB_PEHPCPU1_PCIE_ALERT_R_N

Q_RES_0402LF-33.2,1%,1/16W,CHIA  I76  R2479
   1 SMB_PEHPCPU1_LVC3_SCL_R0      A @S9S_MB_2U_LIB.S9S_MB_2U(SCH_1):SMB_PEHPCPU1_LVC3_SCL_R0
   2 SMB_PEHPCPU1_LVC3_SCL      B @S9S_MB_2U_LIB.S9S_MB_2U(SCH_1):SMB_PEHPCPU1_LVC3_SCL

Q_RES_0402LF-33.2,1%,1/16W,CHIA  I77  R2480
   1 SMB_PEHPCPU1_LVC3_SDA_R0      A @S9S_MB_2U_LIB.S9S_MB_2U(SCH_1):SMB_PEHPCPU1_LVC3_SDA_R0
   2 SMB_PEHPCPU1_LVC3_SDA      B @S9S_MB_2U_LIB.S9S_MB_2U(SCH_1):SMB_PEHPCPU1_LVC3_SDA

Q_RES_0402LF-1K,1%,1/16W,CHIP,A  I81  R968
   1 P3V3_AUX      A @S9S_MB_2U_LIB.S9S_MB_2U(SCH_1):P3V3_AUX
   2 SMB_PEHPCPU1_LVC3_SDA      B @S9S_MB_2U_LIB.S9S_MB_2U(SCH_1):SMB_PEHPCPU1_LVC3_SDA

Q_RES_0402LF-1K,1%,1/16W,CHIP,A  I82  R966
   1 P3V3_AUX      A @S9S_MB_2U_LIB.S9S_MB_2U(SCH_1):P3V3_AUX
   2 SMB_PEHPCPU1_LVC3_SCL      B @S9S_MB_2U_LIB.S9S_MB_2U(SCH_1):SMB_PEHPCPU1_LVC3_SCL

Q_RES_0402LF-33.2,1%,1/16W,CHIA  I88  R2477
   1 SMB_PEHPCPU0_LVC3_SCL_R0      A @S9S_MB_2U_LIB.S9S_MB_2U(SCH_1):SMB_PEHPCPU0_LVC3_SCL_R0
   2 SMB_PEHPCPU0_LVC3_SCL      B @S9S_MB_2U_LIB.S9S_MB_2U(SCH_1):SMB_PEHPCPU0_LVC3_SCL

Q_RES_0402LF-33.2,1%,1/16W,CHIA  I89  R2478
   1 SMB_PEHPCPU0_LVC3_SDA_R0      A @S9S_MB_2U_LIB.S9S_MB_2U(SCH_1):SMB_PEHPCPU0_LVC3_SDA_R0
   2 SMB_PEHPCPU0_LVC3_SDA      B @S9S_MB_2U_LIB.S9S_MB_2U(SCH_1):SMB_PEHPCPU0_LVC3_SDA

Q_RES_0402LF-1K,1%,1/16W,CHIP,A  I93  R965
   1 P3V3_AUX      A @S9S_MB_2U_LIB.S9S_MB_2U(SCH_1):P3V3_AUX
   2 SMB_PEHPCPU0_LVC3_SCL      B @S9S_MB_2U_LIB.S9S_MB_2U(SCH_1):SMB_PEHPCPU0_LVC3_SCL

Q_RES_0402LF-1K,1%,1/16W,CHIP,A  I94  R967
   1 P3V3_AUX      A @S9S_MB_2U_LIB.S9S_MB_2U(SCH_1):P3V3_AUX
   2 SMB_PEHPCPU0_LVC3_SDA      B @S9S_MB_2U_LIB.S9S_MB_2U(SCH_1):SMB_PEHPCPU0_LVC3_SDA

Q_RES_0402LF-33.2,1%,1/16W,CHIA  I99  R961
   1 SMB_PEHPCPU1_GTL_SCL      A @S9S_MB_2U_LIB.S9S_MB_2U(SCH_1):SMB_PEHPCPU1_GTL_SCL
   2 SMB_PEHPCPU1_GTL_R_SCL      B @S9S_MB_2U_LIB.S9S_MB_2U(SCH_1):SMB_PEHPCPU1_GTL_R_SCL

Q_RES_0402LF-33.2,1%,1/16W,CHIA  I100  R962
   1 SMB_PEHPCPU1_GTL_SDA      A @S9S_MB_2U_LIB.S9S_MB_2U(SCH_1):SMB_PEHPCPU1_GTL_SDA
   2 SMB_PEHPCPU1_GTL_R_SDA      B @S9S_MB_2U_LIB.S9S_MB_2U(SCH_1):SMB_PEHPCPU1_GTL_R_SDA

Q_RES_0402LF-33.2,1%,1/16W,CHIA  I101  R960
   1 SMB_PEHPCPU0_GTL_SCL      A @S9S_MB_2U_LIB.S9S_MB_2U(SCH_1):SMB_PEHPCPU0_GTL_SCL
   2 SMB_PEHPCPU0_GTL_R_SCL      B @S9S_MB_2U_LIB.S9S_MB_2U(SCH_1):SMB_PEHPCPU0_GTL_R_SCL

Q_RES_0402LF-33.2,1%,1/16W,CHIA  I102  R909
   1 SMB_PEHPCPU0_GTL_SDA      A @S9S_MB_2U_LIB.S9S_MB_2U(SCH_1):SMB_PEHPCPU0_GTL_SDA
   2 SMB_PEHPCPU0_GTL_R_SDA      B @S9S_MB_2U_LIB.S9S_MB_2U(SCH_1):SMB_PEHPCPU0_GTL_R_SDA

MOSFET_NCH_DUAL-PJT138K,SMLF,IA  I104  Q15
   1    GND     S1 @S9S_MB_2U_LIB.S9S_MB_2U(SCH_1):GND
   2 FM_SMB_PEHPCPU0_PCIE_ALERT_R_N     G1 @S9S_MB_2U_LIB.S9S_MB_2U(SCH_1):FM_SMB_PEHPCPU0_PCIE_ALERT_R_N
   6 FM_SMB_CPU0_ALERT_R1     D1 @S9S_MB_2U_LIB.S9S_MB_2U(SCH_1):FM_SMB_CPU0_ALERT_R1

MOSFET_NCH_DUAL-PJT138K,SMLF,IA  I106  Q16
   1    GND     S1 @S9S_MB_2U_LIB.S9S_MB_2U(SCH_1):GND
   2 FM_SMB_PEHPCPU1_PCIE_ALERT_R_N     G1 @S9S_MB_2U_LIB.S9S_MB_2U(SCH_1):FM_SMB_PEHPCPU1_PCIE_ALERT_R_N
   6 FM_SMB_CPU1_ALERT_R1     D1 @S9S_MB_2U_LIB.S9S_MB_2U(SCH_1):FM_SMB_CPU1_ALERT_R1

MOSFET_NCH_DUAL-PJT138K,SMLF,IA  I108  Q15
   3 FM_PEHPCPU0_ALERT_N     D2 @S9S_MB_2U_LIB.S9S_MB_2U(SCH_1):FM_PEHPCPU0_ALERT_N
   5 FM_SMB_CPU0_ALERT_R1     G2 @S9S_MB_2U_LIB.S9S_MB_2U(SCH_1):FM_SMB_CPU0_ALERT_R1
   4    GND     S2 @S9S_MB_2U_LIB.S9S_MB_2U(SCH_1):GND

MOSFET_NCH_DUAL-PJT138K,SMLF,IA  I109  Q16
   3 FM_PEHPCPU1_ALERT_N     D2 @S9S_MB_2U_LIB.S9S_MB_2U(SCH_1):FM_PEHPCPU1_ALERT_N
   5 FM_SMB_CPU1_ALERT_R1     G2 @S9S_MB_2U_LIB.S9S_MB_2U(SCH_1):FM_SMB_CPU1_ALERT_R1
   4    GND     S2 @S9S_MB_2U_LIB.S9S_MB_2U(SCH_1):GND


DRAWING: @S9S_MB_2U_LIB.S9S_MB_2U(SCH_1):PAGE224 

Q_RES_0402LF-0,5%,1/16W,EMPTY,A  I3  R1648
   1 SMB_S3M_CPU0_3V3AUX_SDA      A @S9S_MB_2U_LIB.S9S_MB_2U(SCH_1):SMB_S3M_CPU0_3V3AUX_SDA
   2 SMB_S3M_CPU1_3V3AUX_SDA      B @S9S_MB_2U_LIB.S9S_MB_2U(SCH_1):SMB_S3M_CPU1_3V3AUX_SDA

Q_RES_0402LF-560,1%,1/16W,CHIPA  I6  R979
   1 P3V3_AUX      A @S9S_MB_2U_LIB.S9S_MB_2U(SCH_1):P3V3_AUX
   2 SMB_S3M_CPU0_3V3AUX_SDA      B @S9S_MB_2U_LIB.S9S_MB_2U(SCH_1):SMB_S3M_CPU0_3V3AUX_SDA

Q_RES_0402LF-560,1%,1/16W,CHIPA  I8  R977
   1 P3V3_AUX      A @S9S_MB_2U_LIB.S9S_MB_2U(SCH_1):P3V3_AUX
   2 SMB_S3M_CPU0_3V3AUX_SCL      B @S9S_MB_2U_LIB.S9S_MB_2U(SCH_1):SMB_S3M_CPU0_3V3AUX_SCL

Q_RES_0402LF-0,5%,1/16W,EMPTY,A  I13  R448
   1 SMB_S3M_CPU0_3V3AUX_SCL      A @S9S_MB_2U_LIB.S9S_MB_2U(SCH_1):SMB_S3M_CPU0_3V3AUX_SCL
   2 SMB_S3M_CPU1_3V3AUX_SCL      B @S9S_MB_2U_LIB.S9S_MB_2U(SCH_1):SMB_S3M_CPU1_3V3AUX_SCL

Q_RES_0402LF-560,1%,1/16W,CHIPA  I14  R980
   1 P3V3_AUX      A @S9S_MB_2U_LIB.S9S_MB_2U(SCH_1):P3V3_AUX
   2 SMB_S3M_CPU1_3V3AUX_SDA      B @S9S_MB_2U_LIB.S9S_MB_2U(SCH_1):SMB_S3M_CPU1_3V3AUX_SDA

Q_RES_0402LF-560,1%,1/16W,CHIPA  I16  R978
   1 P3V3_AUX      A @S9S_MB_2U_LIB.S9S_MB_2U(SCH_1):P3V3_AUX
   2 SMB_S3M_CPU1_3V3AUX_SCL      B @S9S_MB_2U_LIB.S9S_MB_2U(SCH_1):SMB_S3M_CPU1_3V3AUX_SCL

Q_CAP_0402-0.1UF,25V,10%,X7R,CA  I22  C569
   1 P3V3_AUX      A @S9S_MB_2U_LIB.S9S_MB_2U(SCH_1):P3V3_AUX
   2    GND      B @S9S_MB_2U_LIB.S9S_MB_2U(SCH_1):GND

Q_CAP_0402-0.1UF,25V,10%,X7R,CA  I25  C567
   1 PVNN_TERM_CPU0      A @S9S_MB_2U_LIB.S9S_MB_2U(SCH_1):PVNN_TERM_CPU0
   2    GND      B @S9S_MB_2U_LIB.S9S_MB_2U(SCH_1):GND

PCA9517AD-PCA9517AD,SMLF,IC,ALA  I28  U30
   5 TP_SMB_S3M_CPU0_EN ENABLE @S9S_MB_2U_LIB.S9S_MB_2U(SCH_1):TP_SMB_S3M_CPU0_EN
   1 PVNN_TERM_CPU0   VCCA @S9S_MB_2U_LIB.S9S_MB_2U(SCH_1):PVNN_TERM_CPU0
   8 P3V3_AUX   VCCB @S9S_MB_2U_LIB.S9S_MB_2U(SCH_1):P3V3_AUX
   2 SMB_S3M_CPU0_R_SCL   SCLA @S9S_MB_2U_LIB.S9S_MB_2U(SCH_1):SMB_S3M_CPU0_R_SCL
   3 SMB_S3M_CPU0_R_SDA   SDAA @S9S_MB_2U_LIB.S9S_MB_2U(SCH_1):SMB_S3M_CPU0_R_SDA
   6 SMB_S3M_CPU0_3V3AUX_SDA   SDAB @S9S_MB_2U_LIB.S9S_MB_2U(SCH_1):SMB_S3M_CPU0_3V3AUX_SDA
   7 SMB_S3M_CPU0_3V3AUX_SCL   SCLB @S9S_MB_2U_LIB.S9S_MB_2U(SCH_1):SMB_S3M_CPU0_3V3AUX_SCL
   4    GND    GND @S9S_MB_2U_LIB.S9S_MB_2U(SCH_1):GND

Q_CAP_0402-0.1UF,25V,10%,X7R,CA  I33  C570
   1 P3V3_AUX      A @S9S_MB_2U_LIB.S9S_MB_2U(SCH_1):P3V3_AUX
   2    GND      B @S9S_MB_2U_LIB.S9S_MB_2U(SCH_1):GND

Q_CAP_0402-0.1UF,25V,10%,X7R,CA  I35  C568
   1 PVNN_TERM_CPU1      A @S9S_MB_2U_LIB.S9S_MB_2U(SCH_1):PVNN_TERM_CPU1
   2    GND      B @S9S_MB_2U_LIB.S9S_MB_2U(SCH_1):GND

PCA9517AD-PCA9517AD,SMLF,IC,ALA  I37  U31
   5 TP_SMB_S3M_CPU1_EN ENABLE @S9S_MB_2U_LIB.S9S_MB_2U(SCH_1):TP_SMB_S3M_CPU1_EN
   1 PVNN_TERM_CPU1   VCCA @S9S_MB_2U_LIB.S9S_MB_2U(SCH_1):PVNN_TERM_CPU1
   8 P3V3_AUX   VCCB @S9S_MB_2U_LIB.S9S_MB_2U(SCH_1):P3V3_AUX
   2 SMB_S3M_CPU1_R_SCL   SCLA @S9S_MB_2U_LIB.S9S_MB_2U(SCH_1):SMB_S3M_CPU1_R_SCL
   3 SMB_S3M_CPU1_R_SDA   SDAA @S9S_MB_2U_LIB.S9S_MB_2U(SCH_1):SMB_S3M_CPU1_R_SDA
   6 SMB_S3M_CPU1_3V3AUX_SDA   SDAB @S9S_MB_2U_LIB.S9S_MB_2U(SCH_1):SMB_S3M_CPU1_3V3AUX_SDA
   7 SMB_S3M_CPU1_3V3AUX_SCL   SCLB @S9S_MB_2U_LIB.S9S_MB_2U(SCH_1):SMB_S3M_CPU1_3V3AUX_SCL
   4    GND    GND @S9S_MB_2U_LIB.S9S_MB_2U(SCH_1):GND

Q_RES_0402LF-240,1%,1/16W,CHIPA  I42  R971
   1 PVNN_TERM_CPU0      A @S9S_MB_2U_LIB.S9S_MB_2U(SCH_1):PVNN_TERM_CPU0
   2 SMB_S3M_CPU0_R_SDA      B @S9S_MB_2U_LIB.S9S_MB_2U(SCH_1):SMB_S3M_CPU0_R_SDA

Q_RES_0402LF-240,1%,1/16W,CHIPA  I43  R969
   1 PVNN_TERM_CPU0      A @S9S_MB_2U_LIB.S9S_MB_2U(SCH_1):PVNN_TERM_CPU0
   2 SMB_S3M_CPU0_R_SCL      B @S9S_MB_2U_LIB.S9S_MB_2U(SCH_1):SMB_S3M_CPU0_R_SCL

Q_RES_0402LF-33.2,1%,1/16W,CHIA  I44  R993
   1 SMB_S3M_CPU0_SCL      A @S9S_MB_2U_LIB.S9S_MB_2U(SCH_1):SMB_S3M_CPU0_SCL
   2 SMB_S3M_CPU0_R_SCL      B @S9S_MB_2U_LIB.S9S_MB_2U(SCH_1):SMB_S3M_CPU0_R_SCL

Q_RES_0402LF-240,1%,1/16W,CHIPA  I49  R972
   1 PVNN_TERM_CPU1      A @S9S_MB_2U_LIB.S9S_MB_2U(SCH_1):PVNN_TERM_CPU1
   2 SMB_S3M_CPU1_R_SDA      B @S9S_MB_2U_LIB.S9S_MB_2U(SCH_1):SMB_S3M_CPU1_R_SDA

Q_RES_0402LF-240,1%,1/16W,CHIPA  I50  R970
   1 PVNN_TERM_CPU1      A @S9S_MB_2U_LIB.S9S_MB_2U(SCH_1):PVNN_TERM_CPU1
   2 SMB_S3M_CPU1_R_SCL      B @S9S_MB_2U_LIB.S9S_MB_2U(SCH_1):SMB_S3M_CPU1_R_SCL

Q_RES_0402LF-33.2,1%,1/16W,CHIA  I51  R995
   1 SMB_S3M_CPU1_SCL      A @S9S_MB_2U_LIB.S9S_MB_2U(SCH_1):SMB_S3M_CPU1_SCL
   2 SMB_S3M_CPU1_R_SCL      B @S9S_MB_2U_LIB.S9S_MB_2U(SCH_1):SMB_S3M_CPU1_R_SCL

Q_RES_0402LF-0,5%,1/16W,CHIP,CA  I62  R2208
   1 SMB_S3M_CPU0_3V3AUX_SDA_R      A @S9S_MB_2U_LIB.S9S_MB_2U(SCH_1):SMB_S3M_CPU0_3V3AUX_SDA_R
   2 SMB_S3M_CPU0_3V3AUX_SDA      B @S9S_MB_2U_LIB.S9S_MB_2U(SCH_1):SMB_S3M_CPU0_3V3AUX_SDA

Q_RES_0402LF-0,5%,1/16W,CHIP,CA  I63  R2209
   1 SMB_S3M_CPU0_3V3AUX_SCL_R      A @S9S_MB_2U_LIB.S9S_MB_2U(SCH_1):SMB_S3M_CPU0_3V3AUX_SCL_R
   2 SMB_S3M_CPU0_3V3AUX_SCL      B @S9S_MB_2U_LIB.S9S_MB_2U(SCH_1):SMB_S3M_CPU0_3V3AUX_SCL

Q_RES_0402LF-0,5%,1/16W,CHIP,CA  I64  R2210
   1 SMB_S3M_CPU1_3V3AUX_SDA_R      A @S9S_MB_2U_LIB.S9S_MB_2U(SCH_1):SMB_S3M_CPU1_3V3AUX_SDA_R
   2 SMB_S3M_CPU1_3V3AUX_SDA      B @S9S_MB_2U_LIB.S9S_MB_2U(SCH_1):SMB_S3M_CPU1_3V3AUX_SDA

Q_RES_0402LF-0,5%,1/16W,CHIP,CA  I65  R2211
   1 SMB_S3M_CPU1_3V3AUX_SCL_R      A @S9S_MB_2U_LIB.S9S_MB_2U(SCH_1):SMB_S3M_CPU1_3V3AUX_SCL_R
   2 SMB_S3M_CPU1_3V3AUX_SCL      B @S9S_MB_2U_LIB.S9S_MB_2U(SCH_1):SMB_S3M_CPU1_3V3AUX_SCL

Q_CAP_0402-0.1UF,25V,10%,X7R,CA  I68  C1613
   1 P3V3_AUX      A @S9S_MB_2U_LIB.S9S_MB_2U(SCH_1):P3V3_AUX
   2    GND      B @S9S_MB_2U_LIB.S9S_MB_2U(SCH_1):GND

Q_RES_0402LF-10K,1%,1/16W,EMPTA  I83  R2310
   1 P3V3_AUX      A @S9S_MB_2U_LIB.S9S_MB_2U(SCH_1):P3V3_AUX
   2 PCA9543_S3M_ADDR0      B @S9S_MB_2U_LIB.S9S_MB_2U(SCH_1):PCA9543_S3M_ADDR0

Q_RES_0402LF-10K,1%,1/16W,EMPTA  I84  R2308
   1 P3V3_AUX      A @S9S_MB_2U_LIB.S9S_MB_2U(SCH_1):P3V3_AUX
   2 PCA9543_S3M_ADDR1      B @S9S_MB_2U_LIB.S9S_MB_2U(SCH_1):PCA9543_S3M_ADDR1

Q_RES_0402LF-1K,1%,1/16W,CHIP,A  I85  R2309
   1 PCA9543_S3M_ADDR1      A @S9S_MB_2U_LIB.S9S_MB_2U(SCH_1):PCA9543_S3M_ADDR1
   2    GND      B @S9S_MB_2U_LIB.S9S_MB_2U(SCH_1):GND

Q_RES_0402LF-1K,1%,1/16W,CHIP,A  I86  R2311
   1 PCA9543_S3M_ADDR0      A @S9S_MB_2U_LIB.S9S_MB_2U(SCH_1):PCA9543_S3M_ADDR0
   2    GND      B @S9S_MB_2U_LIB.S9S_MB_2U(SCH_1):GND

Q_RES_0402LF-0,5%,1/16W,CHIP,CA  I97  R2313
   1 RST_SMB_SWITCH_N      A @S9S_MB_2U_LIB.S9S_MB_2U(SCH_1):RST_SMB_SWITCH_N
   2 RST_SMB_S3M_N      B @S9S_MB_2U_LIB.S9S_MB_2U(SCH_1):RST_SMB_S3M_N

Q_RES_0402LF-10K,1%,1/16W,CHIPA  I101  R2312
   1 P3V3_AUX      A @S9S_MB_2U_LIB.S9S_MB_2U(SCH_1):P3V3_AUX
   2 PCA9545_S3M_INT_N      B @S9S_MB_2U_LIB.S9S_MB_2U(SCH_1):PCA9545_S3M_INT_N

Q_RES_0402LF-10K,1%,1/16W,CHIPA  I103  R2315
   1 P3V3_AUX      A @S9S_MB_2U_LIB.S9S_MB_2U(SCH_1):P3V3_AUX
   2 PCA9543_S3M_INT0_N      B @S9S_MB_2U_LIB.S9S_MB_2U(SCH_1):PCA9543_S3M_INT0_N

PCA9545APW-PCA9545APW,SMLF,IC,A  I106  U143
   1 PCA9543_S3M_ADDR0     A0 @S9S_MB_2U_LIB.S9S_MB_2U(SCH_1):PCA9543_S3M_ADDR0
   2 PCA9543_S3M_ADDR1     A1 @S9S_MB_2U_LIB.S9S_MB_2U(SCH_1):PCA9543_S3M_ADDR1
   3 RST_SMB_S3M_N RESET# @S9S_MB_2U_LIB.S9S_MB_2U(SCH_1):RST_SMB_S3M_N
  17 PCA9545_S3M_INT_N   INT# @S9S_MB_2U_LIB.S9S_MB_2U(SCH_1):PCA9545_S3M_INT_N
  18 SMB_S3M_CPU_3V3AUX_SCL    SCL @S9S_MB_2U_LIB.S9S_MB_2U(SCH_1):SMB_S3M_CPU_3V3AUX_SCL
  19 SMB_S3M_CPU_3V3AUX_SDA    SDA @S9S_MB_2U_LIB.S9S_MB_2U(SCH_1):SMB_S3M_CPU_3V3AUX_SDA
  10    GND    VSS @S9S_MB_2U_LIB.S9S_MB_2U(SCH_1):GND
  20 P3V3_AUX    VDD @S9S_MB_2U_LIB.S9S_MB_2U(SCH_1):P3V3_AUX
   5 SMB_S3M_CPU0_3V3AUX_SDA_R    SD0 @S9S_MB_2U_LIB.S9S_MB_2U(SCH_1):SMB_S3M_CPU0_3V3AUX_SDA_R
   6 SMB_S3M_CPU0_3V3AUX_SCL_R    SC0 @S9S_MB_2U_LIB.S9S_MB_2U(SCH_1):SMB_S3M_CPU0_3V3AUX_SCL_R
   4 PCA9543_S3M_INT0_N  INT0# @S9S_MB_2U_LIB.S9S_MB_2U(SCH_1):PCA9543_S3M_INT0_N
   8 SMB_S3M_CPU1_3V3AUX_SDA_R    SD1 @S9S_MB_2U_LIB.S9S_MB_2U(SCH_1):SMB_S3M_CPU1_3V3AUX_SDA_R
   9 SMB_S3M_CPU1_3V3AUX_SCL_R    SC1 @S9S_MB_2U_LIB.S9S_MB_2U(SCH_1):SMB_S3M_CPU1_3V3AUX_SCL_R
   7 PCA9543_S3M_INT1_N  INT1# @S9S_MB_2U_LIB.S9S_MB_2U(SCH_1):PCA9543_S3M_INT1_N
  12 SMB_S3M_CPU0_PIROM_3V3AUX_SDA_R    SD2 @S9S_MB_2U_LIB.S9S_MB_2U(SCH_1):SMB_S3M_CPU0_PIROM_3V3AUX_SDA_R
  13 SMB_S3M_CPU0_PIROM_3V3AUX_SCL_R    SC2 @S9S_MB_2U_LIB.S9S_MB_2U(SCH_1):SMB_S3M_CPU0_PIROM_3V3AUX_SCL_R
  11 PCA9543_S3M_INT2_N  INT2# @S9S_MB_2U_LIB.S9S_MB_2U(SCH_1):PCA9543_S3M_INT2_N
  15 SMB_S3M_CPU1_PIROM_3V3AUX_SDA_R    SD3 @S9S_MB_2U_LIB.S9S_MB_2U(SCH_1):SMB_S3M_CPU1_PIROM_3V3AUX_SDA_R
  16 SMB_S3M_CPU1_PIROM_3V3AUX_SCL_R    SC3 @S9S_MB_2U_LIB.S9S_MB_2U(SCH_1):SMB_S3M_CPU1_PIROM_3V3AUX_SCL_R
  14 PCA9543_S3M_INT3_N  INT3# @S9S_MB_2U_LIB.S9S_MB_2U(SCH_1):PCA9543_S3M_INT3_N

Q_RES_0402LF-10K,1%,1/16W,CHIPA  I109  R3127
   1 P3V3_AUX      A @S9S_MB_2U_LIB.S9S_MB_2U(SCH_1):P3V3_AUX
   2 PCA9543_S3M_INT1_N      B @S9S_MB_2U_LIB.S9S_MB_2U(SCH_1):PCA9543_S3M_INT1_N

Q_RES_0402LF-10K,1%,1/16W,CHIPA  I110  R3130
   1 P3V3_AUX      A @S9S_MB_2U_LIB.S9S_MB_2U(SCH_1):P3V3_AUX
   2 PCA9543_S3M_INT2_N      B @S9S_MB_2U_LIB.S9S_MB_2U(SCH_1):PCA9543_S3M_INT2_N

Q_RES_0402LF-10K,1%,1/16W,CHIPA  I111  R3131
   1 P3V3_AUX      A @S9S_MB_2U_LIB.S9S_MB_2U(SCH_1):P3V3_AUX
   2 PCA9543_S3M_INT3_N      B @S9S_MB_2U_LIB.S9S_MB_2U(SCH_1):PCA9543_S3M_INT3_N

Q_RES_0402LF-0,5%,1/16W,CHIP,CA  I114  R3124
   1 SMB_S3M_CPU0_PIROM_3V3AUX_SDA_R      A @S9S_MB_2U_LIB.S9S_MB_2U(SCH_1):SMB_S3M_CPU0_PIROM_3V3AUX_SDA_R
   2 SMB_S3M_CPU0_PIROM_3V3AUX_SDA      B @S9S_MB_2U_LIB.S9S_MB_2U(SCH_1):SMB_S3M_CPU0_PIROM_3V3AUX_SDA

Q_RES_0402LF-0,5%,1/16W,CHIP,CA  I115  R3123
   1 SMB_S3M_CPU0_PIROM_3V3AUX_SCL_R      A @S9S_MB_2U_LIB.S9S_MB_2U(SCH_1):SMB_S3M_CPU0_PIROM_3V3AUX_SCL_R
   2 SMB_S3M_CPU0_PIROM_3V3AUX_SCL      B @S9S_MB_2U_LIB.S9S_MB_2U(SCH_1):SMB_S3M_CPU0_PIROM_3V3AUX_SCL

Q_RES_0402LF-0,5%,1/16W,CHIP,CA  I116  R3125
   1 SMB_S3M_CPU1_PIROM_3V3AUX_SCL_R      A @S9S_MB_2U_LIB.S9S_MB_2U(SCH_1):SMB_S3M_CPU1_PIROM_3V3AUX_SCL_R
   2 SMB_S3M_CPU1_PIROM_3V3AUX_SCL      B @S9S_MB_2U_LIB.S9S_MB_2U(SCH_1):SMB_S3M_CPU1_PIROM_3V3AUX_SCL

Q_RES_0402LF-0,5%,1/16W,CHIP,CA  I117  R3126
   1 SMB_S3M_CPU1_PIROM_3V3AUX_SDA_R      A @S9S_MB_2U_LIB.S9S_MB_2U(SCH_1):SMB_S3M_CPU1_PIROM_3V3AUX_SDA_R
   2 SMB_S3M_CPU1_PIROM_3V3AUX_SDA      B @S9S_MB_2U_LIB.S9S_MB_2U(SCH_1):SMB_S3M_CPU1_PIROM_3V3AUX_SDA

Q_RES_0402LF-2K,1%,1/16W,CHIP,A  I130  R3225
   1 SMB_S3M_CPU1_PIROM_3V3AUX_SDA      A @S9S_MB_2U_LIB.S9S_MB_2U(SCH_1):SMB_S3M_CPU1_PIROM_3V3AUX_SDA
   2 P3V3_AUX      B @S9S_MB_2U_LIB.S9S_MB_2U(SCH_1):P3V3_AUX

Q_RES_0402LF-2K,1%,1/16W,CHIP,A  I131  R3224
   1 SMB_S3M_CPU1_PIROM_3V3AUX_SCL      A @S9S_MB_2U_LIB.S9S_MB_2U(SCH_1):SMB_S3M_CPU1_PIROM_3V3AUX_SCL
   2 P3V3_AUX      B @S9S_MB_2U_LIB.S9S_MB_2U(SCH_1):P3V3_AUX

Q_RES_0402LF-2K,1%,1/16W,CHIP,A  I132  R3222
   1 SMB_S3M_CPU0_PIROM_3V3AUX_SCL      A @S9S_MB_2U_LIB.S9S_MB_2U(SCH_1):SMB_S3M_CPU0_PIROM_3V3AUX_SCL
   2 P3V3_AUX      B @S9S_MB_2U_LIB.S9S_MB_2U(SCH_1):P3V3_AUX

Q_RES_0402LF-2K,1%,1/16W,CHIP,A  I133  R3223
   1 SMB_S3M_CPU0_PIROM_3V3AUX_SDA      A @S9S_MB_2U_LIB.S9S_MB_2U(SCH_1):SMB_S3M_CPU0_PIROM_3V3AUX_SDA
   2 P3V3_AUX      B @S9S_MB_2U_LIB.S9S_MB_2U(SCH_1):P3V3_AUX

Q_RES_0402LF-33.2,1%,1/16W,CHIA  I142  R994
   1 SMB_S3M_CPU0_SDA      A @S9S_MB_2U_LIB.S9S_MB_2U(SCH_1):SMB_S3M_CPU0_SDA
   2 SMB_S3M_CPU0_R_SDA      B @S9S_MB_2U_LIB.S9S_MB_2U(SCH_1):SMB_S3M_CPU0_R_SDA

Q_RES_0402LF-33.2,1%,1/16W,CHIA  I143  R996
   1 SMB_S3M_CPU1_SDA      A @S9S_MB_2U_LIB.S9S_MB_2U(SCH_1):SMB_S3M_CPU1_SDA
   2 SMB_S3M_CPU1_R_SDA      B @S9S_MB_2U_LIB.S9S_MB_2U(SCH_1):SMB_S3M_CPU1_R_SDA


DRAWING: @S9S_MB_2U_LIB.S9S_MB_2U(SCH_1):PAGE226 

Q_RES_0402LF-1K,1%,1/16W,CHIP,A  I1  R1383
   1 P3V3_AUX      A @S9S_MB_2U_LIB.S9S_MB_2U(SCH_1):P3V3_AUX
   2 JTAG_BMC_DBP_PREQ_N      B @S9S_MB_2U_LIB.S9S_MB_2U(SCH_1):JTAG_BMC_DBP_PREQ_N

Q_RES_0402LF-1K,1%,1/16W,CHIP,A  I7  R1381
   1 P3V3_AUX      A @S9S_MB_2U_LIB.S9S_MB_2U(SCH_1):P3V3_AUX
   2 FM_BMC_CPU_FBRK_OUT_N      B @S9S_MB_2U_LIB.S9S_MB_2U(SCH_1):FM_BMC_CPU_FBRK_OUT_N

Q_RES_0402LF-1K,1%,1/16W,CHIP,A  I10  R1347
   1 PD_GTL2014_BMC_JTAG_VREF_1      A @S9S_MB_2U_LIB.S9S_MB_2U(SCH_1):PD_GTL2014_BMC_JTAG_VREF_1
   2    GND      B @S9S_MB_2U_LIB.S9S_MB_2U(SCH_1):GND

Q_RES_0402LF-1K,1%,1/16W,CHIP,A  I11  R3055
   1 P3V3_AUX      A @S9S_MB_2U_LIB.S9S_MB_2U(SCH_1):P3V3_AUX
   2 PU_GTL2014_BMC_JTAG_DIR_1      B @S9S_MB_2U_LIB.S9S_MB_2U(SCH_1):PU_GTL2014_BMC_JTAG_DIR_1

Q_RES_0402LF-33.2,1%,1/16W,CHIA  I12  R3057
   1 JTAG_DBP_BMC_PREQ_R1_N      A @S9S_MB_2U_LIB.S9S_MB_2U(SCH_1):JTAG_DBP_BMC_PREQ_R1_N
   2 JTAG_BMC_DBP_PREQ_N      B @S9S_MB_2U_LIB.S9S_MB_2U(SCH_1):JTAG_BMC_DBP_PREQ_N

Q_RES_0402LF-0,5%,1/16W,CHIP,CA  I13  R1345
   1 JTAG_BMC_DBP_TDI_R      A @S9S_MB_2U_LIB.S9S_MB_2U(SCH_1):JTAG_BMC_DBP_TDI_R
   2 JTAG_BMC_DBP_TDI      B @S9S_MB_2U_LIB.S9S_MB_2U(SCH_1):JTAG_BMC_DBP_TDI

Q_RES_0402LF-0,5%,1/16W,CHIP,CA  I14  R1184
   1 JTAG_BMC_DBP_TMS_R      A @S9S_MB_2U_LIB.S9S_MB_2U(SCH_1):JTAG_BMC_DBP_TMS_R
   2 JTAG_BMC_DBP_TMS      B @S9S_MB_2U_LIB.S9S_MB_2U(SCH_1):JTAG_BMC_DBP_TMS

Q_CAP_C0402-1UF,25V,10%,X6S,CHA  I16  C1291
   1 P3V3_AUX      A @S9S_MB_2U_LIB.S9S_MB_2U(SCH_1):P3V3_AUX
   2    GND      B @S9S_MB_2U_LIB.S9S_MB_2U(SCH_1):GND

GTL2014PW-GTL2014PW,SMLF,IC,ALA  I18  U84
   2 JTAG_DBP_PREQ_R_N     B0 @S9S_MB_2U_LIB.S9S_MB_2U(SCH_1):JTAG_DBP_PREQ_R_N
   3 FM_CPU_FBRK_DEBUG_N     B1 @S9S_MB_2U_LIB.S9S_MB_2U(SCH_1):FM_CPU_FBRK_DEBUG_N
   5 JTAG_DBP_FB_TDI     B2 @S9S_MB_2U_LIB.S9S_MB_2U(SCH_1):JTAG_DBP_FB_TDI
   6 JTAG_DBP_FB_TMS     B3 @S9S_MB_2U_LIB.S9S_MB_2U(SCH_1):JTAG_DBP_FB_TMS
  11    GND  GND_2 @S9S_MB_2U_LIB.S9S_MB_2U(SCH_1):GND
   8    GND  GND_1 @S9S_MB_2U_LIB.S9S_MB_2U(SCH_1):GND
   7    GND  GND_0 @S9S_MB_2U_LIB.S9S_MB_2U(SCH_1):GND
   9 JTAG_BMC_DBP_TMS_R     A3 @S9S_MB_2U_LIB.S9S_MB_2U(SCH_1):JTAG_BMC_DBP_TMS_R
  10 JTAG_BMC_DBP_TDI_R     A2 @S9S_MB_2U_LIB.S9S_MB_2U(SCH_1):JTAG_BMC_DBP_TDI_R
  12 FM_BMC_CPU_FBRK_OUT_N     A1 @S9S_MB_2U_LIB.S9S_MB_2U(SCH_1):FM_BMC_CPU_FBRK_OUT_N
  13 JTAG_DBP_BMC_PREQ_R1_N     A0 @S9S_MB_2U_LIB.S9S_MB_2U(SCH_1):JTAG_DBP_BMC_PREQ_R1_N
   1 PU_GTL2014_BMC_JTAG_DIR_1    DIR @S9S_MB_2U_LIB.S9S_MB_2U(SCH_1):PU_GTL2014_BMC_JTAG_DIR_1
   4 PD_GTL2014_BMC_JTAG_VREF_1   VREF @S9S_MB_2U_LIB.S9S_MB_2U(SCH_1):PD_GTL2014_BMC_JTAG_VREF_1
  14 P3V3_AUX    VCC @S9S_MB_2U_LIB.S9S_MB_2U(SCH_1):P3V3_AUX

Q_RES_0402LF-1K,1%,1/16W,CHIP,A  I20  R1382
   1 P3V3_AUX      A @S9S_MB_2U_LIB.S9S_MB_2U(SCH_1):P3V3_AUX
   2 JTAG_DBP_BMC_PRDY_N      B @S9S_MB_2U_LIB.S9S_MB_2U(SCH_1):JTAG_DBP_BMC_PRDY_N

Q_CAP_0402-0.1UF,25V,10%,X7R,CA  I27  C1322
   1 P3V3_AUX      A @S9S_MB_2U_LIB.S9S_MB_2U(SCH_1):P3V3_AUX
   2    GND      B @S9S_MB_2U_LIB.S9S_MB_2U(SCH_1):GND

Q_RES_0402LF-1K,1%,1/16W,CHIP,A  I31  R1380
   1 P3V3_AUX      A @S9S_MB_2U_LIB.S9S_MB_2U(SCH_1):P3V3_AUX
   2 JTAG_BMC_DBP_TDO      B @S9S_MB_2U_LIB.S9S_MB_2U(SCH_1):JTAG_BMC_DBP_TDO

Q_RES_0402LF-100,1%,1/16W,CHIPA  I34  R1346
   1 P0V7_JTAG_VREF_2      A @S9S_MB_2U_LIB.S9S_MB_2U(SCH_1):P0V7_JTAG_VREF_2
   2    GND      B @S9S_MB_2U_LIB.S9S_MB_2U(SCH_1):GND

Q_RES_0402LF-33.2,1%,1/16W,CHIA  I36  R3056
   1 JTAG_DBP_BMC_PRDY_R1_N      A @S9S_MB_2U_LIB.S9S_MB_2U(SCH_1):JTAG_DBP_BMC_PRDY_R1_N
   2 JTAG_DBP_BMC_PRDY_N      B @S9S_MB_2U_LIB.S9S_MB_2U(SCH_1):JTAG_DBP_BMC_PRDY_N

Q_RES_0402LF-0,5%,1/16W,CHIP,CA  I37  R483
   1 JTAG_BMC_DBP_TDO_R      A @S9S_MB_2U_LIB.S9S_MB_2U(SCH_1):JTAG_BMC_DBP_TDO_R
   2 JTAG_BMC_DBP_TDO      B @S9S_MB_2U_LIB.S9S_MB_2U(SCH_1):JTAG_BMC_DBP_TDO

NX3L2267GM-NX3L2267GM,SMLF,IC,A  I38  U97
  10 P3V3_AUX    VCC @S9S_MB_2U_LIB.S9S_MB_2U(SCH_1):P3V3_AUX
   6 JTAG_BMC_SW_TCK     2Z @S9S_MB_2U_LIB.S9S_MB_2U(SCH_1):JTAG_BMC_SW_TCK
   1 JTAG_BMC_PLD_TMS    1Y0 @S9S_MB_2U_LIB.S9S_MB_2U(SCH_1):JTAG_BMC_PLD_TMS
   5    GND    GND @S9S_MB_2U_LIB.S9S_MB_2U(SCH_1):GND
   2 JTAG_BMC_DBP_TMS    1Y1 @S9S_MB_2U_LIB.S9S_MB_2U(SCH_1):JTAG_BMC_DBP_TMS
   7 FM_JTAG_BMC_MUX_SEL     2S @S9S_MB_2U_LIB.S9S_MB_2U(SCH_1):FM_JTAG_BMC_MUX_SEL
   4 JTAG_BMC_DBP_TCK    2Y1 @S9S_MB_2U_LIB.S9S_MB_2U(SCH_1):JTAG_BMC_DBP_TCK
   9 JTAG_BMC_SW_TMS     1Z @S9S_MB_2U_LIB.S9S_MB_2U(SCH_1):JTAG_BMC_SW_TMS
   8 FM_JTAG_BMC_MUX_SEL     1S @S9S_MB_2U_LIB.S9S_MB_2U(SCH_1):FM_JTAG_BMC_MUX_SEL
   3 JTAG_BMC_PLD_TCK    2Y0 @S9S_MB_2U_LIB.S9S_MB_2U(SCH_1):JTAG_BMC_PLD_TCK

Q_CAP_C0402-1UF,25V,10%,X6S,CHA  I43  C1290
   1 P3V3_AUX      A @S9S_MB_2U_LIB.S9S_MB_2U(SCH_1):P3V3_AUX
   2    GND      B @S9S_MB_2U_LIB.S9S_MB_2U(SCH_1):GND

GTL2014PW-GTL2014PW,SMLF,IC,ALA  I45  U83
   2 PD_JTAG_DBP_B0     B0 @S9S_MB_2U_LIB.S9S_MB_2U(SCH_1):PD_JTAG_DBP_B0
   3 JTAG_DBP_PRDY_R_N     B1 @S9S_MB_2U_LIB.S9S_MB_2U(SCH_1):JTAG_DBP_PRDY_R_N
   5 PD_JTAG_DBP_B2     B2 @S9S_MB_2U_LIB.S9S_MB_2U(SCH_1):PD_JTAG_DBP_B2
   6 JTAG_DBP_FB_TDO     B3 @S9S_MB_2U_LIB.S9S_MB_2U(SCH_1):JTAG_DBP_FB_TDO
  11    GND  GND_2 @S9S_MB_2U_LIB.S9S_MB_2U(SCH_1):GND
   8    GND  GND_1 @S9S_MB_2U_LIB.S9S_MB_2U(SCH_1):GND
   7    GND  GND_0 @S9S_MB_2U_LIB.S9S_MB_2U(SCH_1):GND
   9 JTAG_BMC_DBP_TDO_R     A3 @S9S_MB_2U_LIB.S9S_MB_2U(SCH_1):JTAG_BMC_DBP_TDO_R
  10 TP_JTAG_BMC_A2     A2 @S9S_MB_2U_LIB.S9S_MB_2U(SCH_1):TP_JTAG_BMC_A2
  12 JTAG_DBP_BMC_PRDY_R1_N     A1 @S9S_MB_2U_LIB.S9S_MB_2U(SCH_1):JTAG_DBP_BMC_PRDY_R1_N
  13 TP_JTAG_BMC_A0     A0 @S9S_MB_2U_LIB.S9S_MB_2U(SCH_1):TP_JTAG_BMC_A0
   1 PD_GTL2014_BMC_JTAG_DIR_2    DIR @S9S_MB_2U_LIB.S9S_MB_2U(SCH_1):PD_GTL2014_BMC_JTAG_DIR_2
   4 P0V7_JTAG_VREF_2   VREF @S9S_MB_2U_LIB.S9S_MB_2U(SCH_1):P0V7_JTAG_VREF_2
  14 P3V3_AUX    VCC @S9S_MB_2U_LIB.S9S_MB_2U(SCH_1):P3V3_AUX

Q_RES_0402LF-1K,1%,1/16W,CHIP,A  I47  R1369
   1 PD_JTAG_DBP_B0      A @S9S_MB_2U_LIB.S9S_MB_2U(SCH_1):PD_JTAG_DBP_B0
   2    GND      B @S9S_MB_2U_LIB.S9S_MB_2U(SCH_1):GND

Q_RES_0402LF-1K,1%,1/16W,CHIP,A  I48  R1368
   1 PD_JTAG_DBP_B2      A @S9S_MB_2U_LIB.S9S_MB_2U(SCH_1):PD_JTAG_DBP_B2
   2    GND      B @S9S_MB_2U_LIB.S9S_MB_2U(SCH_1):GND

Q_CAP_0402-0.1UF,25V,10%,X7R,CA  I55  C1321
   1 P3V3_AUX      A @S9S_MB_2U_LIB.S9S_MB_2U(SCH_1):P3V3_AUX
   2    GND      B @S9S_MB_2U_LIB.S9S_MB_2U(SCH_1):GND

Q_RES_0402LF-0,5%,1/16W,CHIP,CA  I57  R482
   1 JTAG_DBP_PREQ_N      A @S9S_MB_2U_LIB.S9S_MB_2U(SCH_1):JTAG_DBP_PREQ_N
   2 JTAG_DBP_PREQ_R_N      B @S9S_MB_2U_LIB.S9S_MB_2U(SCH_1):JTAG_DBP_PREQ_R_N

Q_RES_0402LF-0,5%,1/16W,CHIP,CA  I58  R481
   1 JTAG_DBP_TDI      A @S9S_MB_2U_LIB.S9S_MB_2U(SCH_1):JTAG_DBP_TDI
   2 JTAG_DBP_FB_TDI      B @S9S_MB_2U_LIB.S9S_MB_2U(SCH_1):JTAG_DBP_FB_TDI

Q_RES_0402LF-0,5%,1/16W,CHIP,CA  I59  R480
   1 JTAG_DBP_TMS      A @S9S_MB_2U_LIB.S9S_MB_2U(SCH_1):JTAG_DBP_TMS
   2 JTAG_DBP_FB_TMS      B @S9S_MB_2U_LIB.S9S_MB_2U(SCH_1):JTAG_DBP_FB_TMS

Q_RES_0402LF-100,1%,1/16W,CHIPA  I64  R1366
   1 JTAG_DBP_TDO      A @S9S_MB_2U_LIB.S9S_MB_2U(SCH_1):JTAG_DBP_TDO
   2 JTAG_DBP_FB_TDO      B @S9S_MB_2U_LIB.S9S_MB_2U(SCH_1):JTAG_DBP_FB_TDO

Q_RES_0402LF-100,1%,1/16W,CHIPA  I65  R1367
   1 JTAG_DBP_PRDY_N      A @S9S_MB_2U_LIB.S9S_MB_2U(SCH_1):JTAG_DBP_PRDY_N
   2 JTAG_DBP_PRDY_R_N      B @S9S_MB_2U_LIB.S9S_MB_2U(SCH_1):JTAG_DBP_PRDY_R_N

NX3L2267GM-NX3L2267GM,SMLF,IC,A  I68  U96
  10 P3V3_AUX    VCC @S9S_MB_2U_LIB.S9S_MB_2U(SCH_1):P3V3_AUX
   6 JTAG_BMC_SW_TDO     2Z @S9S_MB_2U_LIB.S9S_MB_2U(SCH_1):JTAG_BMC_SW_TDO
   1 JTAG_BMC_PLD_TDI    1Y0 @S9S_MB_2U_LIB.S9S_MB_2U(SCH_1):JTAG_BMC_PLD_TDI
   5    GND    GND @S9S_MB_2U_LIB.S9S_MB_2U(SCH_1):GND
   2 JTAG_BMC_DBP_TDI    1Y1 @S9S_MB_2U_LIB.S9S_MB_2U(SCH_1):JTAG_BMC_DBP_TDI
   7 FM_JTAG_BMC_MUX_SEL     2S @S9S_MB_2U_LIB.S9S_MB_2U(SCH_1):FM_JTAG_BMC_MUX_SEL
   4 JTAG_BMC_DBP_TDO    2Y1 @S9S_MB_2U_LIB.S9S_MB_2U(SCH_1):JTAG_BMC_DBP_TDO
   9 JTAG_BMC_SW_TDI     1Z @S9S_MB_2U_LIB.S9S_MB_2U(SCH_1):JTAG_BMC_SW_TDI
   8 FM_JTAG_BMC_MUX_SEL     1S @S9S_MB_2U_LIB.S9S_MB_2U(SCH_1):FM_JTAG_BMC_MUX_SEL
   3 JTAG_BMC_PLD_TDO    2Y0 @S9S_MB_2U_LIB.S9S_MB_2U(SCH_1):JTAG_BMC_PLD_TDO

Q_RES_0402LF-1K,1%,1/16W,EMPTYA  I77  R1814
   1 FM_JTAG_BMC_MUX_SEL      A @S9S_MB_2U_LIB.S9S_MB_2U(SCH_1):FM_JTAG_BMC_MUX_SEL
   2    GND      B @S9S_MB_2U_LIB.S9S_MB_2U(SCH_1):GND

Q_RES_0402LF-10K,1%,1/16W,EMPTA  I79  R1813
   1 P3V3_AUX      A @S9S_MB_2U_LIB.S9S_MB_2U(SCH_1):P3V3_AUX
   2 FM_JTAG_BMC_MUX_SEL      B @S9S_MB_2U_LIB.S9S_MB_2U(SCH_1):FM_JTAG_BMC_MUX_SEL

Q_RES_0402LF-0,5%,1/16W,EMPTY,A  I80  R1832
   1 JTAG_BMC_DBP_PREQ_N      A @S9S_MB_2U_LIB.S9S_MB_2U(SCH_1):JTAG_BMC_DBP_PREQ_N
   2 JTAG_DBP_BMC_PREQ_R_N      B @S9S_MB_2U_LIB.S9S_MB_2U(SCH_1):JTAG_DBP_BMC_PREQ_R_N

Q_RES_0402LF-0,5%,1/16W,EMPTY,A  I82  R1831
   1 JTAG_DBP_BMC_PRDY_N      A @S9S_MB_2U_LIB.S9S_MB_2U(SCH_1):JTAG_DBP_BMC_PRDY_N
   2 JTAG_DBP_BMC_PRDY_R_N      B @S9S_MB_2U_LIB.S9S_MB_2U(SCH_1):JTAG_DBP_BMC_PRDY_R_N

Q_RES_0402LF-1K,1%,1/16W,CHIP,A  I87  R2506
   1 P3V3_AUX      A @S9S_MB_2U_LIB.S9S_MB_2U(SCH_1):P3V3_AUX
   2 JTAG_BMC_DBP_TMS      B @S9S_MB_2U_LIB.S9S_MB_2U(SCH_1):JTAG_BMC_DBP_TMS

Q_RES_0402LF-1K,1%,1/16W,CHIP,A  I88  R2507
   1 P3V3_AUX      A @S9S_MB_2U_LIB.S9S_MB_2U(SCH_1):P3V3_AUX
   2 JTAG_BMC_DBP_TDI      B @S9S_MB_2U_LIB.S9S_MB_2U(SCH_1):JTAG_BMC_DBP_TDI

Q_RES_0402LF-1K,1%,1/16W,EMPTYA  I89  R2514
   1 PU_GTL2014_BMC_JTAG_DIR_1      A @S9S_MB_2U_LIB.S9S_MB_2U(SCH_1):PU_GTL2014_BMC_JTAG_DIR_1
   2    GND      B @S9S_MB_2U_LIB.S9S_MB_2U(SCH_1):GND

Q_RES_0402LF-0,5%,1/16W,CHIP,CA  I90  R2513
   1 PD_GTL2014_BMC_JTAG_DIR_2      A @S9S_MB_2U_LIB.S9S_MB_2U(SCH_1):PD_GTL2014_BMC_JTAG_DIR_2
   2    GND      B @S9S_MB_2U_LIB.S9S_MB_2U(SCH_1):GND

Q_RES_0402LF-49.9,1%,1/16W,CHIA  I91  R2512
   1 P1V05_PCH_AUX      A @S9S_MB_2U_LIB.S9S_MB_2U(SCH_1):P1V05_PCH_AUX
   2 P0V7_JTAG_VREF_2      B @S9S_MB_2U_LIB.S9S_MB_2U(SCH_1):P0V7_JTAG_VREF_2

Q_CAP_0402-0.1UF,25V,10%,X7R,CA  I93  C1664
   1 P0V7_JTAG_VREF_2      A @S9S_MB_2U_LIB.S9S_MB_2U(SCH_1):P0V7_JTAG_VREF_2
   2    GND      B @S9S_MB_2U_LIB.S9S_MB_2U(SCH_1):GND


DRAWING: @S9S_MB_2U_LIB.S9S_MB_2U(SCH_1):PAGE227 

Q_RES_0402LF-33.2,1%,1/16W,CHIA  I99  R2421
   1 SMB_VR_SENSOR_3V3AUX_SCL      A @S9S_MB_2U_LIB.S9S_MB_2U(SCH_1):SMB_VR_SENSOR_3V3AUX_SCL
   2 SMB_VR_3V3AUX_SCL_R0      B @S9S_MB_2U_LIB.S9S_MB_2U(SCH_1):SMB_VR_3V3AUX_SCL_R0

Q_RES_0402LF-0,5%,1/16W,CHIP,CA  I18  R506
   1 IRQ_SMI_ACTIVE_BMC_N      A @S9S_MB_2U_LIB.S9S_MB_2U(SCH_1):IRQ_SMI_ACTIVE_BMC_N
   2 IRQ0_A57      B @S9S_MB_2U_LIB.S9S_MB_2U(SCH_1):IRQ0_A57

Q_RES_0402LF-0,5%,1/16W,CHIP,CA  I19  R3777
   1 FM_UARTSW_LSB_N      A @S9S_MB_2U_LIB.S9S_MB_2U(SCH_1):FM_UARTSW_LSB_N
   2 FM_UARTSW_LSB_R      B @S9S_MB_2U_LIB.S9S_MB_2U(SCH_1):FM_UARTSW_LSB_R

Q_RES_0402LF-0,5%,1/16W,CHIP,CA  I20  R1798
   1 ROT_P1_RST_IND_N_R      A @S9S_MB_2U_LIB.S9S_MB_2U(SCH_1):ROT_P1_RST_IND_N_R
   2 ROT_P1_RST_IND_N      B @S9S_MB_2U_LIB.S9S_MB_2U(SCH_1):ROT_P1_RST_IND_N

Q_RES_0402LF-0,5%,1/16W,CHIP,CA  I21  R3776
   1 FM_UARTSW_MSB_N      A @S9S_MB_2U_LIB.S9S_MB_2U(SCH_1):FM_UARTSW_MSB_N
   2 FM_UARTSW_MSB_R      B @S9S_MB_2U_LIB.S9S_MB_2U(SCH_1):FM_UARTSW_MSB_R

Q_RES_0402LF-33.2,1%,1/16W,CHIA  I22  R2417
   1 SMB_S3M_CPU_3V3AUX_SCL      A @S9S_MB_2U_LIB.S9S_MB_2U(SCH_1):SMB_S3M_CPU_3V3AUX_SCL
   2 SMB_S3M_CPU_3V3AUX_SCL_R0      B @S9S_MB_2U_LIB.S9S_MB_2U(SCH_1):SMB_S3M_CPU_3V3AUX_SCL_R0

Q_RES_0402LF-33.2,1%,1/16W,CHIA  I23  R2418
   1 SMB_S3M_CPU_3V3AUX_SDA      A @S9S_MB_2U_LIB.S9S_MB_2U(SCH_1):SMB_S3M_CPU_3V3AUX_SDA
   2 SMB_S3M_CPU_3V3AUX_SDA_R0      B @S9S_MB_2U_LIB.S9S_MB_2U(SCH_1):SMB_S3M_CPU_3V3AUX_SDA_R0

Q_RES_0402LF-0,5%,1/16W,CHIP,CA  I24  R2416
   1 SMB_1_BMC_GPU_SDA      A @S9S_MB_2U_LIB.S9S_MB_2U(SCH_1):SMB_1_BMC_GPU_SDA
   2 SMB_PCIE3_3V3AUX_SDA_R      B @S9S_MB_2U_LIB.S9S_MB_2U(SCH_1):SMB_PCIE3_3V3AUX_SDA_R

Q_CAP_C0402-22UF,4V,20%,X6S,CHA  I82  C1302
   1 PVNN_TERM_CPU0      A @S9S_MB_2U_LIB.S9S_MB_2U(SCH_1):PVNN_TERM_CPU0
   2    GND      B @S9S_MB_2U_LIB.S9S_MB_2U(SCH_1):GND

Q_RES_0402LF-0,5%,1/16W,CHIP,CA  I84  R142
   1 PVNN_TERM_CPU0      A @S9S_MB_2U_LIB.S9S_MB_2U(SCH_1):PVNN_TERM_CPU0
   2 PVCCIO_PECI_BMC      B @S9S_MB_2U_LIB.S9S_MB_2U(SCH_1):PVCCIO_PECI_BMC

Q_RES_0402LF-0,5%,1/16W,CHIP,CA  I85  R2414
   1 SMB_2_BMC_GPU_SDA      A @S9S_MB_2U_LIB.S9S_MB_2U(SCH_1):SMB_2_BMC_GPU_SDA
   2 SMB_PCIE2_3V3AUX_SDA_R0      B @S9S_MB_2U_LIB.S9S_MB_2U(SCH_1):SMB_PCIE2_3V3AUX_SDA_R0

Q_RES_0402LF-0,5%,1/16W,CHIP,CA  I86  R2413
   1 SMB_2_BMC_GPU_SCL      A @S9S_MB_2U_LIB.S9S_MB_2U(SCH_1):SMB_2_BMC_GPU_SCL
   2 SMB_PCIE2_3V3AUX_SCL_R0      B @S9S_MB_2U_LIB.S9S_MB_2U(SCH_1):SMB_PCIE2_3V3AUX_SCL_R0

Q_RES_0402LF-33.2,1%,1/16W,CHIA  I87  R4508
   1 SMB_1_PLD_3V3AUX_SCL      A @S9S_MB_2U_LIB.S9S_MB_2U(SCH_1):SMB_1_PLD_3V3AUX_SCL
   2 SMB_1_PLD_3V3AUX_SCL_R3      B @S9S_MB_2U_LIB.S9S_MB_2U(SCH_1):SMB_1_PLD_3V3AUX_SCL_R3

Q_RES_0402LF-33.2,1%,1/16W,CHIA  I88  R4509
   1 SMB_1_PLD_3V3AUX_SDA      A @S9S_MB_2U_LIB.S9S_MB_2U(SCH_1):SMB_1_PLD_3V3AUX_SDA
   2 SMB_1_PLD_3V3AUX_SDA_R3      B @S9S_MB_2U_LIB.S9S_MB_2U(SCH_1):SMB_1_PLD_3V3AUX_SDA_R3

Q_RES_0402LF-33.2,1%,1/16W,CHIA  I89  R4507
   1 SMB_SML0_3V3AUX_SDA      A @S9S_MB_2U_LIB.S9S_MB_2U(SCH_1):SMB_SML0_3V3AUX_SDA
   2 SMB_SML0_3V3AUX_SDA_R1      B @S9S_MB_2U_LIB.S9S_MB_2U(SCH_1):SMB_SML0_3V3AUX_SDA_R1

Q_RES_0402LF-33.2,1%,1/16W,CHIA  I90  R4506
   1 SMB_SML0_3V3AUX_SCL      A @S9S_MB_2U_LIB.S9S_MB_2U(SCH_1):SMB_SML0_3V3AUX_SCL
   2 SMB_SML0_3V3AUX_SCL_R1      B @S9S_MB_2U_LIB.S9S_MB_2U(SCH_1):SMB_SML0_3V3AUX_SCL_R1

Q_RES_0402LF-10,1%,1/16W,CHIP,A  I91  R4535
   1 CLK_100M_BMC_P3E_DP      A @S9S_MB_2U_LIB.S9S_MB_2U(SCH_1):CLK_100M_BMC_P3E_DP
   2 CLK_100M_BMC_P3E_DP_R      B @S9S_MB_2U_LIB.S9S_MB_2U(SCH_1):CLK_100M_BMC_P3E_DP_R

Q_RES_0402LF-10,1%,1/16W,CHIP,A  I92  R4536
   1 CLK_100M_BMC_P3E_DN      A @S9S_MB_2U_LIB.S9S_MB_2U(SCH_1):CLK_100M_BMC_P3E_DN
   2 CLK_100M_BMC_P3E_DN_R      B @S9S_MB_2U_LIB.S9S_MB_2U(SCH_1):CLK_100M_BMC_P3E_DN_R

Q_RES_0402LF-33.2,1%,1/16W,CHIA  I93  R2425
   1 SMB_OCP_V3_2_3V3AUX_SCL      A @S9S_MB_2U_LIB.S9S_MB_2U(SCH_1):SMB_OCP_V3_2_3V3AUX_SCL
   2 SMB_OCP_V3_2_3V3AUX_SCL_R0      B @S9S_MB_2U_LIB.S9S_MB_2U(SCH_1):SMB_OCP_V3_2_3V3AUX_SCL_R0

Q_RES_0402LF-33.2,1%,1/16W,CHIA  I94  R3858
   1 SMB_OCP_V3_2_3V3AUX_SDA      A @S9S_MB_2U_LIB.S9S_MB_2U(SCH_1):SMB_OCP_V3_2_3V3AUX_SDA
   2 SMB_OCP_V3_2_3V3AUX_SDA_R0      B @S9S_MB_2U_LIB.S9S_MB_2U(SCH_1):SMB_OCP_V3_2_3V3AUX_SDA_R0

Q_RES_0402LF-33.2,1%,1/16W,CHIA  I95  R2422
   1 SMB_VR_SENSOR_3V3AUX_SDA      A @S9S_MB_2U_LIB.S9S_MB_2U(SCH_1):SMB_VR_SENSOR_3V3AUX_SDA
   2 SMB_VR_3V3AUX_SDA_R0      B @S9S_MB_2U_LIB.S9S_MB_2U(SCH_1):SMB_VR_3V3AUX_SDA_R0

Q_RES_0402LF-33.2,1%,1/16W,CHIA  I96  R2424
   1 SMB_SML1_PMBUS_3V3AUX_PCH_SDA      A @S9S_MB_2U_LIB.S9S_MB_2U(SCH_1):SMB_SML1_PMBUS_3V3AUX_PCH_SDA
   2 SMB_SML1_PMBUS_3V3AUX_PCH_SDA_R      B @S9S_MB_2U_LIB.S9S_MB_2U(SCH_1):SMB_SML1_PMBUS_3V3AUX_PCH_SDA_R0

Q_RES_0402LF-33.2,1%,1/16W,CHIA  I97  R2423
   1 SMB_SML1_PMBUS_3V3AUX_PCH_SCL      A @S9S_MB_2U_LIB.S9S_MB_2U(SCH_1):SMB_SML1_PMBUS_3V3AUX_PCH_SCL
   2 SMB_SML1_PMBUS_3V3AUX_PCH_SCL_R      B @S9S_MB_2U_LIB.S9S_MB_2U(SCH_1):SMB_SML1_PMBUS_3V3AUX_PCH_SCL_R0

Q_RES_0402LF-33.2,1%,1/16W,CHIA  I98  R2420
   1 SMB_HOST_3V3AUX_SDA      A @S9S_MB_2U_LIB.S9S_MB_2U(SCH_1):SMB_HOST_3V3AUX_SDA
   2 SMB_HOST_3V3AUX_SDA_R0      B @S9S_MB_2U_LIB.S9S_MB_2U(SCH_1):SMB_HOST_3V3AUX_SDA_R0

Q_RES_0402LF-0,5%,1/16W,EMPTY,A  I164  R2257
   1 USB2_7_R_DN      A @S9S_MB_2U_LIB.S9S_MB_2U(SCH_1):USB2_7_R_DN
   2 USB2_7_DN      B @S9S_MB_2U_LIB.S9S_MB_2U(SCH_1):USB2_7_DN

Q_RES_0402LF-0,5%,1/16W,CHIP,CA  I2  R4809
   1 FM_BMC_INTRUDER_N      A @S9S_MB_2U_LIB.S9S_MB_2U(SCH_1):FM_BMC_INTRUDER_N
   2    GND      B @S9S_MB_2U_LIB.S9S_MB_2U(SCH_1):GND

Q_RES_0402LF-0,5%,1/16W,CHIP,CA  I25  R2415
   1 SMB_1_BMC_GPU_SCL      A @S9S_MB_2U_LIB.S9S_MB_2U(SCH_1):SMB_1_BMC_GPU_SCL
   2 SMB_PCIE3_3V3AUX_SCL_R      B @S9S_MB_2U_LIB.S9S_MB_2U(SCH_1):SMB_PCIE3_3V3AUX_SCL_R

Q_RES_0402LF-0,5%,1/16W,CHIP,CA  I26  R1815
   1 FM_BMC_PWRBTN_OUT_N      A @S9S_MB_2U_LIB.S9S_MB_2U(SCH_1):FM_BMC_PWRBTN_OUT_N
   2 FM_BMC_PWRBTN_OUT_R_N      B @S9S_MB_2U_LIB.S9S_MB_2U(SCH_1):FM_BMC_PWRBTN_OUT_R_N

Q_RES_0402LF-0,5%,1/16W,CHIP,CA  I27  R1816
   1 PWRGD_PS_PWROK      A @S9S_MB_2U_LIB.S9S_MB_2U(SCH_1):PWRGD_PS_PWROK
   2 PWRGD_PS_PWROK_R      B @S9S_MB_2U_LIB.S9S_MB_2U(SCH_1):PWRGD_PS_PWROK_R

Q_RES_0402LF-33.2,1%,1/16W,CHIA  I28  R4087
   1 FM_JTAG_BMC_MUX_SEL_FROM_BMC_R      A @S9S_MB_2U_LIB.S9S_MB_2U(SCH_1):FM_JTAG_BMC_MUX_SEL_FROM_BMC_R
   2 FM_JTAG_BMC_MUX_SEL_FROM_BMC_R2      B @S9S_MB_2U_LIB.S9S_MB_2U(SCH_1):FM_JTAG_BMC_MUX_SEL_FROM_BMC_R2

Q_RES_0402LF-0,5%,1/16W,EMPTY,A  I48  R3302
   1 TP_PCIE_HPM_TXN<3>      A @S9S_MB_2U_LIB.S9S_MB_2U(SCH_1):TP_PCIE_HPM_TXN(3)
   2 FM_PCH_SPKR      B @S9S_MB_2U_LIB.S9S_MB_2U(SCH_1):FM_PCH_SPKR

Q_RES_0402LF-0,5%,1/16W,EMPTY,A  I49  R3254
   1 TP_PCIE_HPM_TXP<3>      A @S9S_MB_2U_LIB.S9S_MB_2U(SCH_1):TP_PCIE_HPM_TXP(3)
   2 LED_HDD_ACTIVITY_B_N      B @S9S_MB_2U_LIB.S9S_MB_2U(SCH_1):LED_HDD_ACTIVITY_B_N

Q_RES_0402LF-0,5%,1/16W,CHIP,CA  I57  R4720
   1 FM_AC_PWR_BTN_N      A @S9S_MB_2U_LIB.S9S_MB_2U(SCH_1):FM_AC_PWR_BTN_N
   2 FM_AC_PWR_BTN_R_N      B @S9S_MB_2U_LIB.S9S_MB_2U(SCH_1):FM_AC_PWR_BTN_R_N

Q_RES_0402LF-0,5%,1/16W,CHIP,CA  I58  R2994
   1 P3V_BAT_R1      A @S9S_MB_2U_LIB.S9S_MB_2U(SCH_1):P3V_BAT_R1
   2 P3V_BAT_R      B @S9S_MB_2U_LIB.S9S_MB_2U(SCH_1):P3V_BAT_R

Q_RES_0402LF-33.2,1%,1/16W,CHIA  I100  R2419
   1 SMB_HOST_3V3AUX_SCL      A @S9S_MB_2U_LIB.S9S_MB_2U(SCH_1):SMB_HOST_3V3AUX_SCL
   2 SMB_HOST_3V3AUX_SCL_R0      B @S9S_MB_2U_LIB.S9S_MB_2U(SCH_1):SMB_HOST_3V3AUX_SCL_R0

Q_RES_0402LF-33.2,1%,1/16W,CHIA  I101  R3238
   1 SMB_OCP_SFF_3V3AUX_SCL      A @S9S_MB_2U_LIB.S9S_MB_2U(SCH_1):SMB_OCP_SFF_3V3AUX_SCL
   2 SMB_OCP_SFF_3V3AUX_SCL_R0      B @S9S_MB_2U_LIB.S9S_MB_2U(SCH_1):SMB_OCP_SFF_3V3AUX_SCL_R0

Q_RES_0402LF-33.2,1%,1/16W,CHIA  I102  R3239
   1 SMB_OCP_SFF_3V3AUX_SDA      A @S9S_MB_2U_LIB.S9S_MB_2U(SCH_1):SMB_OCP_SFF_3V3AUX_SDA
   2 SMB_OCP_SFF_3V3AUX_SDA_R0      B @S9S_MB_2U_LIB.S9S_MB_2U(SCH_1):SMB_OCP_SFF_3V3AUX_SDA_R0

Q_RES_0402LF-0,5%,1/16W,CHIP,CA  I159  R3778
   1 FM_SOL_UART_CH_SEL_R      A @S9S_MB_2U_LIB.S9S_MB_2U(SCH_1):FM_SOL_UART_CH_SEL_R
   2 FM_SOL_UART_CH_SEL      B @S9S_MB_2U_LIB.S9S_MB_2U(SCH_1):FM_SOL_UART_CH_SEL

Q_RES_0402LF-0,5%,1/16W,EMPTY,A  I167  R2256
   1 USB2_7_R_DP      A @S9S_MB_2U_LIB.S9S_MB_2U(SCH_1):USB2_7_R_DP
   2 USB2_7_DP      B @S9S_MB_2U_LIB.S9S_MB_2U(SCH_1):USB2_7_DP

Q_RES_0402LF-0,5%,1/16W,CHIP,CA  I172  R1801
   1 PRSNT0_N      A @S9S_MB_2U_LIB.S9S_MB_2U(SCH_1):PRSNT0_N
   2    GND      B @S9S_MB_2U_LIB.S9S_MB_2U(SCH_1):GND

SCONN168_ME1016810202011-SCONNA  I173  J41
 OB1 P12V_SCM NIC_PWR_GOOD @S9S_MB_2U_LIB.S9S_MB_2U(SCH_1):P12V_SCM
 OB2 P12V_SCM MAIN_PWR_EN @S9S_MB_2U_LIB.S9S_MB_2U(SCH_1):P12V_SCM
 OB3 PRSNT0_N    LD# @S9S_MB_2U_LIB.S9S_MB_2U(SCH_1):PRSNT0_N
 OB4    GND DATA_IN @S9S_MB_2U_LIB.S9S_MB_2U(SCH_1):GND
 OB5 UART_BMC_BIC_TX DATA_OUT @S9S_MB_2U_LIB.S9S_MB_2U(SCH_1):UART_BMC_BIC_TX
 OB6 UART_BMC_BIC_BUF_RX    CLK @S9S_MB_2U_LIB.S9S_MB_2U(SCH_1):UART_BMC_BIC_BUF_RX
 OB7    GND SLOT_ID0 @S9S_MB_2U_LIB.S9S_MB_2U(SCH_1):GND
 OB8 USB2_7_R_DP RBT_RXD1 @S9S_MB_2U_LIB.S9S_MB_2U(SCH_1):USB2_7_R_DP
 OB9 USB2_7_R_DN RBT_RXD0 @S9S_MB_2U_LIB.S9S_MB_2U(SCH_1):USB2_7_R_DN
OB10    GND GND_OB10 @S9S_MB_2U_LIB.S9S_MB_2U(SCH_1):GND
OB11 RST_SRST_PLD_BMC_N REFCLKN2 @S9S_MB_2U_LIB.S9S_MB_2U(SCH_1):RST_SRST_PLD_BMC_N
OB12 SPI_TPM_CS_N REFCLKP2 @S9S_MB_2U_LIB.S9S_MB_2U(SCH_1):SPI_TPM_CS_N
OB13 H_CPU_CATERR_LVC2_BMC_N GND_OB13 @S9S_MB_2U_LIB.S9S_MB_2U(SCH_1):H_CPU_CATERR_LVC2_BMC_N
OB14 FM_SOL_UART_CH_SEL_R RBT_CRS_DV @S9S_MB_2U_LIB.S9S_MB_2U(SCH_1):FM_SOL_UART_CH_SEL_R
  B1 ESPI_HOST_LPC_BMC_CLK +12V_EDGE_B1 @S9S_MB_2U_LIB.S9S_MB_2U(SCH_1):ESPI_HOST_LPC_BMC_CLK
  B2 ESPI_HOST_LPC_BMC_LFRAME_N +12V_EDGE_B2 @S9S_MB_2U_LIB.S9S_MB_2U(SCH_1):ESPI_HOST_LPC_BMC_LFRAME_N
  B3 IRQ_ESPI_LPC_SERIRQ_ALERT_R_N +12V_EDGE_B3 @S9S_MB_2U_LIB.S9S_MB_2U(SCH_1):IRQ_ESPI_LPC_SERIRQ_ALERT_R_N
  B4 ESPI_BMC_LPC_RST_N +12V_EDGE_B4 @S9S_MB_2U_LIB.S9S_MB_2U(SCH_1):ESPI_BMC_LPC_RST_N
  B5 ESPI_LPC_LAD0_IO0 +12V_EDGE_B5 @S9S_MB_2U_LIB.S9S_MB_2U(SCH_1):ESPI_LPC_LAD0_IO0
  B6 ESPI_LPC_LAD0_IO1 +12V_EDGE_B6 @S9S_MB_2U_LIB.S9S_MB_2U(SCH_1):ESPI_LPC_LAD0_IO1
  B7 ESPI_LPC_LAD0_IO2  BIF0# @S9S_MB_2U_LIB.S9S_MB_2U(SCH_1):ESPI_LPC_LAD0_IO2
  B8 ESPI_LPC_LAD0_IO3  BIF1# @S9S_MB_2U_LIB.S9S_MB_2U(SCH_1):ESPI_LPC_LAD0_IO3
  B9 FM_LPC_ESPI_SEL  BIF2# @S9S_MB_2U_LIB.S9S_MB_2U(SCH_1):FM_LPC_ESPI_SEL
 B10    GND PERST0# @S9S_MB_2U_LIB.S9S_MB_2U(SCH_1):GND
 B11 SPI_SYS_CLK +3.3V_EDGE @S9S_MB_2U_LIB.S9S_MB_2U(SCH_1):SPI_SYS_CLK
 B12 SPI_SYS_CS0_N AUX_PWR_EN @S9S_MB_2U_LIB.S9S_MB_2U(SCH_1):SPI_SYS_CS0_N
 B13 SPI_SYS_MOSI GND_B13 @S9S_MB_2U_LIB.S9S_MB_2U(SCH_1):SPI_SYS_MOSI
 B14 SPI_SYS_MISO REFCLKN0 @S9S_MB_2U_LIB.S9S_MB_2U(SCH_1):SPI_SYS_MISO
 B15 SPI_SYS_WP_IO2 REFCLKP0 @S9S_MB_2U_LIB.S9S_MB_2U(SCH_1):SPI_SYS_WP_IO2
 B16 SPI_SYS_HOLD_IO3 GND_B16 @S9S_MB_2U_LIB.S9S_MB_2U(SCH_1):SPI_SYS_HOLD_IO3
 B17    GND  PETN0 @S9S_MB_2U_LIB.S9S_MB_2U(SCH_1):GND
 B18 CLK_50M_RMII_BMC_OCP  PETP0 @S9S_MB_2U_LIB.S9S_MB_2U(SCH_1):CLK_50M_RMII_BMC_OCP
 B19 RMII_OCP_BMC_CRSDV GND_B19 @S9S_MB_2U_LIB.S9S_MB_2U(SCH_1):RMII_OCP_BMC_CRSDV
 B20 RMII_BMC_OCP_TX_EN  PETN1 @S9S_MB_2U_LIB.S9S_MB_2U(SCH_1):RMII_BMC_OCP_TX_EN
 B21 RMII_BMC_OCP_TXD_0  PETP1 @S9S_MB_2U_LIB.S9S_MB_2U(SCH_1):RMII_BMC_OCP_TXD_0
 B22 RMII_BMC_OCP_TXD_1 GND_B22 @S9S_MB_2U_LIB.S9S_MB_2U(SCH_1):RMII_BMC_OCP_TXD_1
 B23 RMII_BMC_OCP_RX_ER  PETN2 @S9S_MB_2U_LIB.S9S_MB_2U(SCH_1):RMII_BMC_OCP_RX_ER
 B24 RMII_OCP_BMC_RXD_0  PETP2 @S9S_MB_2U_LIB.S9S_MB_2U(SCH_1):RMII_OCP_BMC_RXD_0
 B25 RMII_OCP_BMC_RXD_1 GND_B25 @S9S_MB_2U_LIB.S9S_MB_2U(SCH_1):RMII_OCP_BMC_RXD_1
 B26    GND  PETN3 @S9S_MB_2U_LIB.S9S_MB_2U(SCH_1):GND
 B27 PECI_BMC  PETP3 @S9S_MB_2U_LIB.S9S_MB_2U(SCH_1):PECI_BMC
 B28 PVCCIO_PECI_BMC GND_B28 @S9S_MB_2U_LIB.S9S_MB_2U(SCH_1):PVCCIO_PECI_BMC
 B29 SGPIO_DO_0 GND_B29 @S9S_MB_2U_LIB.S9S_MB_2U(SCH_1):SGPIO_DO_0
 B30 SGPIO_CLK_0  PETN4 @S9S_MB_2U_LIB.S9S_MB_2U(SCH_1):SGPIO_CLK_0
 B31 SGPIO_DI_0  PETP4 @S9S_MB_2U_LIB.S9S_MB_2U(SCH_1):SGPIO_DI_0
 B32 SGPIO_LD_0 GND_B32 @S9S_MB_2U_LIB.S9S_MB_2U(SCH_1):SGPIO_LD_0
 B33    GND  PETN5 @S9S_MB_2U_LIB.S9S_MB_2U(SCH_1):GND
 B34 SGPIO_DO_1  PETP5 @S9S_MB_2U_LIB.S9S_MB_2U(SCH_1):SGPIO_DO_1
 B35 SGPIO_CLK_1 GND_B35 @S9S_MB_2U_LIB.S9S_MB_2U(SCH_1):SGPIO_CLK_1
 B36 SGPIO_DI_1  PETN6 @S9S_MB_2U_LIB.S9S_MB_2U(SCH_1):SGPIO_DI_1
 B37 SGPIO_LD_1  PETP6 @S9S_MB_2U_LIB.S9S_MB_2U(SCH_1):SGPIO_LD_1
 B38    GND GND_B38 @S9S_MB_2U_LIB.S9S_MB_2U(SCH_1):GND
 B39 RST_SGPIO_RESET_N  PETN7 @S9S_MB_2U_LIB.S9S_MB_2U(SCH_1):RST_SGPIO_RESET_N
 B40 IRQ_SGPIO_INTR_N  PETP7 @S9S_MB_2U_LIB.S9S_MB_2U(SCH_1):IRQ_SGPIO_INTR_N
 B41 P3V_BAT_R1 GND_B41 @S9S_MB_2U_LIB.S9S_MB_2U(SCH_1):P3V_BAT_R1
 B42 FM_AC_PWR_BTN_N PRSNTB0# @S9S_MB_2U_LIB.S9S_MB_2U(SCH_1):FM_AC_PWR_BTN_N
 B43 TP_SPI_2_PLD_CLK GND_B43 @S9S_MB_2U_LIB.S9S_MB_2U(SCH_1):TP_SPI_2_PLD_CLK
 B44 TP_SPI_2_PLD_CS_N  PETN8 @S9S_MB_2U_LIB.S9S_MB_2U(SCH_1):TP_SPI_2_PLD_CS_N
 B45 TP_SPI_2_PLD_IO0  PETP8 @S9S_MB_2U_LIB.S9S_MB_2U(SCH_1):TP_SPI_2_PLD_IO0
 B46 TP_SPI_2_PLD_IO1 GND_B46 @S9S_MB_2U_LIB.S9S_MB_2U(SCH_1):TP_SPI_2_PLD_IO1
 B47 TP_SPI_2_PLD_IO2  PETN9 @S9S_MB_2U_LIB.S9S_MB_2U(SCH_1):TP_SPI_2_PLD_IO2
 B48 TP_SPI_2_PLD_IO3  PETP9 @S9S_MB_2U_LIB.S9S_MB_2U(SCH_1):TP_SPI_2_PLD_IO3
 B49    GND GND_B49 @S9S_MB_2U_LIB.S9S_MB_2U(SCH_1):GND
 B50 USB2_HOST_BMC_B_DP PETN10 @S9S_MB_2U_LIB.S9S_MB_2U(SCH_1):USB2_HOST_BMC_B_DP
 B51 USB2_HOST_BMC_B_DN PETP10 @S9S_MB_2U_LIB.S9S_MB_2U(SCH_1):USB2_HOST_BMC_B_DN
 B52    GND GND_B52 @S9S_MB_2U_LIB.S9S_MB_2U(SCH_1):GND
 B53 USB2_8_DP PETN11 @S9S_MB_2U_LIB.S9S_MB_2U(SCH_1):USB2_8_DP
 B54 USB2_8_DN PETP11 @S9S_MB_2U_LIB.S9S_MB_2U(SCH_1):USB2_8_DN
 B55    GND GND_B55 @S9S_MB_2U_LIB.S9S_MB_2U(SCH_1):GND
 B56 USB2_HUB_2_BUF_EXT_DP PETN12 @S9S_MB_2U_LIB.S9S_MB_2U(SCH_1):USB2_HUB_2_BUF_EXT_DP
 OA1 P12V_SCM PERST2# @S9S_MB_2U_LIB.S9S_MB_2U(SCH_1):P12V_SCM
 OA2 P12V_SCM PERST3# @S9S_MB_2U_LIB.S9S_MB_2U(SCH_1):P12V_SCM
 OA3    GND  WAKE# @S9S_MB_2U_LIB.S9S_MB_2U(SCH_1):GND
 OA4    GND RBT_ARB_IN @S9S_MB_2U_LIB.S9S_MB_2U(SCH_1):GND
 OA5 I3C_SPD_DDRABCD_CPU0_BMC_R_SCL RBT_ARB_OUT @S9S_MB_2U_LIB.S9S_MB_2U(SCH_1):I3C_SPD_DDRABCD_CPU0_BMC_R_SCL
 OA6 I3C_SPD_DDRABCD_CPU0_BMC_R_SDA SLOT_ID1 @S9S_MB_2U_LIB.S9S_MB_2U(SCH_1):I3C_SPD_DDRABCD_CPU0_BMC_R_SDA
 OA7 I3C_SPD_DDREFGH_CPU0_BMC_R_SCL RBT_TX_EN @S9S_MB_2U_LIB.S9S_MB_2U(SCH_1):I3C_SPD_DDREFGH_CPU0_BMC_R_SCL
 OA8 I3C_SPD_DDREFGH_CPU0_BMC_R_SDA RBT_TXD1 @S9S_MB_2U_LIB.S9S_MB_2U(SCH_1):I3C_SPD_DDREFGH_CPU0_BMC_R_SDA
 OA9 I3C_SPD_DDRABCD_CPU1_BMC_R_SCL RBT_TXD0 @S9S_MB_2U_LIB.S9S_MB_2U(SCH_1):I3C_SPD_DDRABCD_CPU1_BMC_R_SCL
OA10 I3C_SPD_DDRABCD_CPU1_BMC_R_SDA GND_OA10 @S9S_MB_2U_LIB.S9S_MB_2U(SCH_1):I3C_SPD_DDRABCD_CPU1_BMC_R_SDA
OA11 I3C_SPD_DDREFGH_CPU1_BMC_R_SCL REFCLKN3 @S9S_MB_2U_LIB.S9S_MB_2U(SCH_1):I3C_SPD_DDREFGH_CPU1_BMC_R_SCL
OA12 I3C_SPD_DDREFGH_CPU1_BMC_R_SDA REFCLKP3 @S9S_MB_2U_LIB.S9S_MB_2U(SCH_1):I3C_SPD_DDREFGH_CPU1_BMC_R_SDA
OA13    GND GND_OA13 @S9S_MB_2U_LIB.S9S_MB_2U(SCH_1):GND
OA14 VIRTUAL_RESEAT RBT_CLK_IN @S9S_MB_2U_LIB.S9S_MB_2U(SCH_1):VIRTUAL_RESEAT
  A1 SMB_OCP_SFF_3V3AUX_SCL_R0 GND_A1 @S9S_MB_2U_LIB.S9S_MB_2U(SCH_1):SMB_OCP_SFF_3V3AUX_SCL_R0
  A2 SMB_OCP_SFF_3V3AUX_SDA_R0 GND_A2 @S9S_MB_2U_LIB.S9S_MB_2U(SCH_1):SMB_OCP_SFF_3V3AUX_SDA_R0
  A3 SMB_HOST_3V3AUX_SCL_R0 GND_A3 @S9S_MB_2U_LIB.S9S_MB_2U(SCH_1):SMB_HOST_3V3AUX_SCL_R0
  A4 SMB_HOST_3V3AUX_SDA_R0 GND_A4 @S9S_MB_2U_LIB.S9S_MB_2U(SCH_1):SMB_HOST_3V3AUX_SDA_R0
  A5 SMB_VR_3V3AUX_SCL_R0 GND_A5 @S9S_MB_2U_LIB.S9S_MB_2U(SCH_1):SMB_VR_3V3AUX_SCL_R0
  A6 SMB_VR_3V3AUX_SDA_R0 GND_A6 @S9S_MB_2U_LIB.S9S_MB_2U(SCH_1):SMB_VR_3V3AUX_SDA_R0
  A7 SMB_SML1_PMBUS_3V3AUX_PCH_SCL_R  SMCLK @S9S_MB_2U_LIB.S9S_MB_2U(SCH_1):SMB_SML1_PMBUS_3V3AUX_PCH_SCL_R0
  A8 SMB_SML1_PMBUS_3V3AUX_PCH_SDA_R  SMDAT @S9S_MB_2U_LIB.S9S_MB_2U(SCH_1):SMB_SML1_PMBUS_3V3AUX_PCH_SDA_R0
  A9 I3C_BMC_SWB_SCL SMRST# @S9S_MB_2U_LIB.S9S_MB_2U(SCH_1):I3C_BMC_SWB_SCL
 A10 I3C_BMC_SWB_SDA PRSNTA# @S9S_MB_2U_LIB.S9S_MB_2U(SCH_1):I3C_BMC_SWB_SDA
 A11 SMB_OCP_V3_2_3V3AUX_SCL_R0 PERST1# @S9S_MB_2U_LIB.S9S_MB_2U(SCH_1):SMB_OCP_V3_2_3V3AUX_SCL_R0
 A12 SMB_OCP_V3_2_3V3AUX_SDA_R0 PRSNTB2# @S9S_MB_2U_LIB.S9S_MB_2U(SCH_1):SMB_OCP_V3_2_3V3AUX_SDA_R0
 A13    GND GND_A13 @S9S_MB_2U_LIB.S9S_MB_2U(SCH_1):GND
 A14 CLK_100M_BMC_P3E_DP_R REFCLKN1 @S9S_MB_2U_LIB.S9S_MB_2U(SCH_1):CLK_100M_BMC_P3E_DP_R
 A15 CLK_100M_BMC_P3E_DN_R REFCLKP1 @S9S_MB_2U_LIB.S9S_MB_2U(SCH_1):CLK_100M_BMC_P3E_DN_R
 A16    GND GND_A16 @S9S_MB_2U_LIB.S9S_MB_2U(SCH_1):GND
 A17 P3E_PCH_BMC_TX_C_DP  PERN0 @S9S_MB_2U_LIB.S9S_MB_2U(SCH_1):P3E_PCH_BMC_TX_C_DP
 A18 P3E_PCH_BMC_TX_C_DN  PERP0 @S9S_MB_2U_LIB.S9S_MB_2U(SCH_1):P3E_PCH_BMC_TX_C_DN
 A19    GND GND_A19 @S9S_MB_2U_LIB.S9S_MB_2U(SCH_1):GND
 A20 P3E_PCH_BMC_RX_DP  PERN1 @S9S_MB_2U_LIB.S9S_MB_2U(SCH_1):P3E_PCH_BMC_RX_DP
 A21 P3E_PCH_BMC_RX_DN  PERP1 @S9S_MB_2U_LIB.S9S_MB_2U(SCH_1):P3E_PCH_BMC_RX_DN
 A22    GND GND_A22 @S9S_MB_2U_LIB.S9S_MB_2U(SCH_1):GND
 A23 SMB_PCIE0_3V3AUX_SCL  PERN2 @S9S_MB_2U_LIB.S9S_MB_2U(SCH_1):SMB_PCIE0_3V3AUX_SCL
 A24 SMB_PCIE0_3V3AUX_SDA  PERP2 @S9S_MB_2U_LIB.S9S_MB_2U(SCH_1):SMB_PCIE0_3V3AUX_SDA
 A25 SMB_SML0_3V3AUX_SCL_R1 GND_A25 @S9S_MB_2U_LIB.S9S_MB_2U(SCH_1):SMB_SML0_3V3AUX_SCL_R1
 A26 SMB_SML0_3V3AUX_SDA_R1  PERN3 @S9S_MB_2U_LIB.S9S_MB_2U(SCH_1):SMB_SML0_3V3AUX_SDA_R1
 A27 SMB_1_PLD_3V3AUX_SCL_R3  PERP3 @S9S_MB_2U_LIB.S9S_MB_2U(SCH_1):SMB_1_PLD_3V3AUX_SCL_R3
 A28 SMB_1_PLD_3V3AUX_SDA_R3 GND_A28 @S9S_MB_2U_LIB.S9S_MB_2U(SCH_1):SMB_1_PLD_3V3AUX_SDA_R3
 A29 SMB_FAN_3V3AUX_SCL GND_A29 @S9S_MB_2U_LIB.S9S_MB_2U(SCH_1):SMB_FAN_3V3AUX_SCL
 A30 SMB_FAN_3V3AUX_SDA  PERN4 @S9S_MB_2U_LIB.S9S_MB_2U(SCH_1):SMB_FAN_3V3AUX_SDA
 A31 SMB_PCIE2_3V3AUX_SCL_R0  PERP4 @S9S_MB_2U_LIB.S9S_MB_2U(SCH_1):SMB_PCIE2_3V3AUX_SCL_R0
 A32 SMB_PCIE2_3V3AUX_SDA_R0 GND_A32 @S9S_MB_2U_LIB.S9S_MB_2U(SCH_1):SMB_PCIE2_3V3AUX_SDA_R0
 A33    GND  PERN5 @S9S_MB_2U_LIB.S9S_MB_2U(SCH_1):GND
 A34 JTAG_BMC_TCK  PERP5 @S9S_MB_2U_LIB.S9S_MB_2U(SCH_1):JTAG_BMC_TCK
 A35 JTAG_BMC_TMS GND_A35 @S9S_MB_2U_LIB.S9S_MB_2U(SCH_1):JTAG_BMC_TMS
 A36 JTAG_BMC_TDI  PERN6 @S9S_MB_2U_LIB.S9S_MB_2U(SCH_1):JTAG_BMC_TDI
 A37 JTAG_BMC_TDO  PERP6 @S9S_MB_2U_LIB.S9S_MB_2U(SCH_1):JTAG_BMC_TDO
 A38 SMB_PCIE3_3V3AUX_SCL_R GND_A38 @S9S_MB_2U_LIB.S9S_MB_2U(SCH_1):SMB_PCIE3_3V3AUX_SCL_R
 A39 SMB_PCIE3_3V3AUX_SDA_R  PERN7 @S9S_MB_2U_LIB.S9S_MB_2U(SCH_1):SMB_PCIE3_3V3AUX_SDA_R
 A40 SMB_S3M_CPU_3V3AUX_SCL_R0  PERP7 @S9S_MB_2U_LIB.S9S_MB_2U(SCH_1):SMB_S3M_CPU_3V3AUX_SCL_R0
 A41 SMB_S3M_CPU_3V3AUX_SDA_R0 GND_A41 @S9S_MB_2U_LIB.S9S_MB_2U(SCH_1):SMB_S3M_CPU_3V3AUX_SDA_R0
 A42    GND PRSNTB1# @S9S_MB_2U_LIB.S9S_MB_2U(SCH_1):GND
 A43 FM_JTAG_BMC_MUX_SEL_FROM_BMC_R2 GND_A43 @S9S_MB_2U_LIB.S9S_MB_2U(SCH_1):FM_JTAG_BMC_MUX_SEL_FROM_BMC_R2
 A44 PWRGD_PS_PWROK_R  PERN8 @S9S_MB_2U_LIB.S9S_MB_2U(SCH_1):PWRGD_PS_PWROK_R
 A45 TP_HPM_STBY_EN  PERP8 @S9S_MB_2U_LIB.S9S_MB_2U(SCH_1):TP_HPM_STBY_EN
 A46 RST_MB_STBY_N GND_A46 @S9S_MB_2U_LIB.S9S_MB_2U(SCH_1):RST_MB_STBY_N
 A47 FM_BMC_PWRBTN_OUT_R_N  PERN9 @S9S_MB_2U_LIB.S9S_MB_2U(SCH_1):FM_BMC_PWRBTN_OUT_R_N
 A48 PWRGD_SYS_PWROK  PERP9 @S9S_MB_2U_LIB.S9S_MB_2U(SCH_1):PWRGD_SYS_PWROK
 A49 JTAG_BMC_DBP_PREQ_N GND_A49 @S9S_MB_2U_LIB.S9S_MB_2U(SCH_1):JTAG_BMC_DBP_PREQ_N
 A50 JTAG_DBP_BMC_PRDY_N PERN10 @S9S_MB_2U_LIB.S9S_MB_2U(SCH_1):JTAG_DBP_BMC_PRDY_N
 A51 RST_PLTRST_B_N PERP10 @S9S_MB_2U_LIB.S9S_MB_2U(SCH_1):RST_PLTRST_B_N
 A52 FM_UARTSW_MSB_R GND_A52 @S9S_MB_2U_LIB.S9S_MB_2U(SCH_1):FM_UARTSW_MSB_R
 A53 ROT_P1_RST_IND_N PERN11 @S9S_MB_2U_LIB.S9S_MB_2U(SCH_1):ROT_P1_RST_IND_N
 A54 FM_BMC_INTRUDER_N PERP11 @S9S_MB_2U_LIB.S9S_MB_2U(SCH_1):FM_BMC_INTRUDER_N
 A55 FM_UARTSW_LSB_R GND_A55 @S9S_MB_2U_LIB.S9S_MB_2U(SCH_1):FM_UARTSW_LSB_R
 A56 IRQ0_A57 PERN12 @S9S_MB_2U_LIB.S9S_MB_2U(SCH_1):IRQ0_A57
 A57 FM_SCM_PRSNT1_N PERP12 @S9S_MB_2U_LIB.S9S_MB_2U(SCH_1):FM_SCM_PRSNT1_N
 A58    GND GND_A58 @S9S_MB_2U_LIB.S9S_MB_2U(SCH_1):GND
 A59 USB3_PCH_RX_DP<4> PERN13 @S9S_MB_2U_LIB.S9S_MB_2U(SCH_1):USB3_PCH_RX_DP(4)
 A60 USB3_PCH_RX_DN<4> PERP13 @S9S_MB_2U_LIB.S9S_MB_2U(SCH_1):USB3_PCH_RX_DN(4)
 A61    GND GND_A61 @S9S_MB_2U_LIB.S9S_MB_2U(SCH_1):GND
 A62 TP_PCIE_HPM_RXP<1> PERN14 @S9S_MB_2U_LIB.S9S_MB_2U(SCH_1):TP_PCIE_HPM_RXP(1)
 A63 TP_PCIE_HPM_RXN<1> PERP14 @S9S_MB_2U_LIB.S9S_MB_2U(SCH_1):TP_PCIE_HPM_RXN(1)
 A64    GND GND_A64 @S9S_MB_2U_LIB.S9S_MB_2U(SCH_1):GND
 A65 P2E_MB_BMC_RX_BUF_DP<0> PERN15 @S9S_MB_2U_LIB.S9S_MB_2U(SCH_1):P2E_MB_BMC_RX_BUF_DP(0)
 A66 P2E_MB_BMC_RX_BUF_DN<0> PERP15 @S9S_MB_2U_LIB.S9S_MB_2U(SCH_1):P2E_MB_BMC_RX_BUF_DN(0)
 A67    GND GND_A67 @S9S_MB_2U_LIB.S9S_MB_2U(SCH_1):GND
 A68 CLK_100M_BMC_RC_DP USB_DATN @S9S_MB_2U_LIB.S9S_MB_2U(SCH_1):CLK_100M_BMC_RC_DP
 A69 CLK_100M_BMC_RC_DN USB_DATP @S9S_MB_2U_LIB.S9S_MB_2U(SCH_1):CLK_100M_BMC_RC_DN
 A70    GND PWRBRK0# @S9S_MB_2U_LIB.S9S_MB_2U(SCH_1):GND
 B57 USB2_HUB_2_BUF_EXT_DN PETP12 @S9S_MB_2U_LIB.S9S_MB_2U(SCH_1):USB2_HUB_2_BUF_EXT_DN
 B58    GND GND_B58 @S9S_MB_2U_LIB.S9S_MB_2U(SCH_1):GND
 B59 USB3_PCH_TX_BUF_C_DP<4> PETN13 @S9S_MB_2U_LIB.S9S_MB_2U(SCH_1):USB3_PCH_TX_BUF_C_DP(4)
 B60 USB3_PCH_TX_BUF_C_DN<4> PETP13 @S9S_MB_2U_LIB.S9S_MB_2U(SCH_1):USB3_PCH_TX_BUF_C_DN(4)
 B61    GND GND_B61 @S9S_MB_2U_LIB.S9S_MB_2U(SCH_1):GND
 B62 TP_PCIE_HPM_TXP<1> PETN14 @S9S_MB_2U_LIB.S9S_MB_2U(SCH_1):TP_PCIE_HPM_TXP(1)
 B63 TP_PCIE_HPM_TXN<1> PETP14 @S9S_MB_2U_LIB.S9S_MB_2U(SCH_1):TP_PCIE_HPM_TXN(1)
 B64    GND GND_B64 @S9S_MB_2U_LIB.S9S_MB_2U(SCH_1):GND
 B65 P2E_MB_BMC_TX_C_DP<0> PETN15 @S9S_MB_2U_LIB.S9S_MB_2U(SCH_1):P2E_MB_BMC_TX_C_DP(0)
 B66 P2E_MB_BMC_TX_C_DN<0> PETP15 @S9S_MB_2U_LIB.S9S_MB_2U(SCH_1):P2E_MB_BMC_TX_C_DN(0)
 B67    GND GND_B67 @S9S_MB_2U_LIB.S9S_MB_2U(SCH_1):GND
 B68 TP_PCIE_HPM_TXP<3> RFU1_NC_B68 @S9S_MB_2U_LIB.S9S_MB_2U(SCH_1):TP_PCIE_HPM_TXP(3)
 B69 TP_PCIE_HPM_TXN<3> RFU1_NC_B69 @S9S_MB_2U_LIB.S9S_MB_2U(SCH_1):TP_PCIE_HPM_TXN(3)
 B70    GND PRSNTB3# @S9S_MB_2U_LIB.S9S_MB_2U(SCH_1):GND
  G1    GND     G1 @S9S_MB_2U_LIB.S9S_MB_2U(SCH_1):GND
  G2    GND     G2 @S9S_MB_2U_LIB.S9S_MB_2U(SCH_1):GND
  G3    GND     G3 @S9S_MB_2U_LIB.S9S_MB_2U(SCH_1):GND
  G4    GND     G4 @S9S_MB_2U_LIB.S9S_MB_2U(SCH_1):GND
  G5    GND     G5 @S9S_MB_2U_LIB.S9S_MB_2U(SCH_1):GND


DRAWING: @S9S_MB_2U_LIB.S9S_MB_2U(SCH_1):PAGE228 

Q_RES_0402LF-2K,1%,1/16W,EMPTYA  I2  R1319
   1 SMB_HOST_3V3AUX_SCL      A @S9S_MB_2U_LIB.S9S_MB_2U(SCH_1):SMB_HOST_3V3AUX_SCL
   2 P3V3_AUX      B @S9S_MB_2U_LIB.S9S_MB_2U(SCH_1):P3V3_AUX

Q_RES_0402LF-2K,1%,1/16W,EMPTYA  I3  R3062
   1 SMB_HOST_3V3AUX_SDA      A @S9S_MB_2U_LIB.S9S_MB_2U(SCH_1):SMB_HOST_3V3AUX_SDA
   2 P3V3_AUX      B @S9S_MB_2U_LIB.S9S_MB_2U(SCH_1):P3V3_AUX

Q_RES_0402LF-2K,1%,1/16W,EMPTYA  I4  R1384
   1 SMB_SML0_3V3AUX_SCL      A @S9S_MB_2U_LIB.S9S_MB_2U(SCH_1):SMB_SML0_3V3AUX_SCL
   2 P3V3_AUX      B @S9S_MB_2U_LIB.S9S_MB_2U(SCH_1):P3V3_AUX

Q_RES_0402LF-2K,1%,1/16W,EMPTYA  I5  R1385
   1 SMB_SML0_3V3AUX_SDA      A @S9S_MB_2U_LIB.S9S_MB_2U(SCH_1):SMB_SML0_3V3AUX_SDA
   2 P3V3_AUX      B @S9S_MB_2U_LIB.S9S_MB_2U(SCH_1):P3V3_AUX

Q_RES_0402LF-2K,1%,1/16W,EMPTYA  I6  R1386
   1 SMB_SML1_PMBUS_3V3AUX_PCH_SCL      A @S9S_MB_2U_LIB.S9S_MB_2U(SCH_1):SMB_SML1_PMBUS_3V3AUX_PCH_SCL
   2 P3V3_AUX      B @S9S_MB_2U_LIB.S9S_MB_2U(SCH_1):P3V3_AUX

Q_RES_0402LF-2K,1%,1/16W,EMPTYA  I7  R1387
   1 SMB_SML1_PMBUS_3V3AUX_PCH_SDA      A @S9S_MB_2U_LIB.S9S_MB_2U(SCH_1):SMB_SML1_PMBUS_3V3AUX_PCH_SDA
   2 P3V3_AUX      B @S9S_MB_2U_LIB.S9S_MB_2U(SCH_1):P3V3_AUX

Q_RES_0402LF-33.2,1%,1/16W,CHIA  I38  R579
   1 SMB_HOST_3V3AUX_SCL_R5      A @S9S_MB_2U_LIB.S9S_MB_2U(SCH_1):SMB_HOST_3V3AUX_SCL_R5
   2 SMB_HOST_BMC_3V3AUX_SCL      B @S9S_MB_2U_LIB.S9S_MB_2U(SCH_1):SMB_HOST_BMC_3V3AUX_SCL

Q_RES_0402LF-33.2,1%,1/16W,CHIA  I39  R580
   1 SMB_HOST_3V3AUX_SDA_R5      A @S9S_MB_2U_LIB.S9S_MB_2U(SCH_1):SMB_HOST_3V3AUX_SDA_R5
   2 SMB_HOST_BMC_3V3AUX_SDA      B @S9S_MB_2U_LIB.S9S_MB_2U(SCH_1):SMB_HOST_BMC_3V3AUX_SDA

Q_RES_0402LF-0,5%,1/16W,CHIP,CA  I40  R1525
   1 SMB_HOST_3V3AUX_SCL_R      A @S9S_MB_2U_LIB.S9S_MB_2U(SCH_1):SMB_HOST_3V3AUX_SCL_R
   2 SMB_HOST_CLK_3V3AUX_SCL      B @S9S_MB_2U_LIB.S9S_MB_2U(SCH_1):SMB_HOST_CLK_3V3AUX_SCL

Q_RES_0402LF-33.2,1%,1/16W,CHIA  I41  R1526
   1 SMB_HOST_3V3AUX_SDA_R      A @S9S_MB_2U_LIB.S9S_MB_2U(SCH_1):SMB_HOST_3V3AUX_SDA_R
   2 SMB_HOST_CLK_3V3AUX_SDA      B @S9S_MB_2U_LIB.S9S_MB_2U(SCH_1):SMB_HOST_CLK_3V3AUX_SDA

Q_RES_0402LF-33.2,1%,1/16W,CHIA  I42  R108
   1 SMB_HOST_3V3AUX_SDA_R      A @S9S_MB_2U_LIB.S9S_MB_2U(SCH_1):SMB_HOST_3V3AUX_SDA_R
   2 SMB_HOST_CLK_BUF_3V3AUX_SDA      B @S9S_MB_2U_LIB.S9S_MB_2U(SCH_1):SMB_HOST_CLK_BUF_3V3AUX_SDA

Q_RES_0402LF-33.2,1%,1/16W,CHIA  I43  R107
   1 SMB_HOST_3V3AUX_SCL_R      A @S9S_MB_2U_LIB.S9S_MB_2U(SCH_1):SMB_HOST_3V3AUX_SCL_R
   2 SMB_HOST_CLK_BUF_3V3AUX_SCL      B @S9S_MB_2U_LIB.S9S_MB_2U(SCH_1):SMB_HOST_CLK_BUF_3V3AUX_SCL

Q_RES_0402LF-33.2,1%,1/16W,CHIA  I44  R581
   1 SMB_SML0_3V3AUX_SCL      A @S9S_MB_2U_LIB.S9S_MB_2U(SCH_1):SMB_SML0_3V3AUX_SCL
   2 SMB_SML0_3V3AUX_PCH_SCL      B @S9S_MB_2U_LIB.S9S_MB_2U(SCH_1):SMB_SML0_3V3AUX_PCH_SCL

Q_RES_0402LF-33.2,1%,1/16W,CHIA  I45  R582
   1 SMB_SML0_3V3AUX_SDA      A @S9S_MB_2U_LIB.S9S_MB_2U(SCH_1):SMB_SML0_3V3AUX_SDA
   2 SMB_SML0_3V3AUX_PCH_SDA      B @S9S_MB_2U_LIB.S9S_MB_2U(SCH_1):SMB_SML0_3V3AUX_PCH_SDA

Q_RES_0402LF-33.2,1%,1/16W,CHIA  I89  R1661
   1 SMB_VR_3V3AUX_SCL      A @S9S_MB_2U_LIB.S9S_MB_2U(SCH_1):SMB_VR_3V3AUX_SCL
   2 SMB_VR_3V3AUX_SCL_R      B @S9S_MB_2U_LIB.S9S_MB_2U(SCH_1):SMB_VR_3V3AUX_SCL_R

Q_RES_0402LF-33.2,1%,1/16W,CHIA  I90  R1662
   1 SMB_VR_3V3AUX_SDA      A @S9S_MB_2U_LIB.S9S_MB_2U(SCH_1):SMB_VR_3V3AUX_SDA
   2 SMB_VR_3V3AUX_SDA_R      B @S9S_MB_2U_LIB.S9S_MB_2U(SCH_1):SMB_VR_3V3AUX_SDA_R

Q_RES_0402LF-2.2K,5%,1/16W,EMPA  I172  R601
   1 SMB_FAN_3V3AUX_SDA      A @S9S_MB_2U_LIB.S9S_MB_2U(SCH_1):SMB_FAN_3V3AUX_SDA
   2 P3V3_AUX      B @S9S_MB_2U_LIB.S9S_MB_2U(SCH_1):P3V3_AUX

Q_RES_0402LF-2.2K,5%,1/16W,EMPA  I173  R592
   1 SMB_FAN_3V3AUX_SCL      A @S9S_MB_2U_LIB.S9S_MB_2U(SCH_1):SMB_FAN_3V3AUX_SCL
   2 P3V3_AUX      B @S9S_MB_2U_LIB.S9S_MB_2U(SCH_1):P3V3_AUX

Q_RES_0402LF-2.2K,5%,1/16W,EMPA  I176  R1460
   1 I3C_BMC_SWB_SDA      A @S9S_MB_2U_LIB.S9S_MB_2U(SCH_1):I3C_BMC_SWB_SDA
   2 P3V3_AUX      B @S9S_MB_2U_LIB.S9S_MB_2U(SCH_1):P3V3_AUX

Q_RES_0402LF-2.2K,5%,1/16W,EMPA  I177  R1336
   1 I3C_BMC_SWB_SCL      A @S9S_MB_2U_LIB.S9S_MB_2U(SCH_1):I3C_BMC_SWB_SCL
   2 P3V3_AUX      B @S9S_MB_2U_LIB.S9S_MB_2U(SCH_1):P3V3_AUX

Q_RES_0402LF-2.2K,5%,1/16W,EMPA  I202  R2212
   1 SMB_S3M_CPU_3V3AUX_SCL      A @S9S_MB_2U_LIB.S9S_MB_2U(SCH_1):SMB_S3M_CPU_3V3AUX_SCL
   2 P3V3_AUX      B @S9S_MB_2U_LIB.S9S_MB_2U(SCH_1):P3V3_AUX

Q_RES_0402LF-2.2K,5%,1/16W,EMPA  I203  R2213
   1 SMB_S3M_CPU_3V3AUX_SDA      A @S9S_MB_2U_LIB.S9S_MB_2U(SCH_1):SMB_S3M_CPU_3V3AUX_SDA
   2 P3V3_AUX      B @S9S_MB_2U_LIB.S9S_MB_2U(SCH_1):P3V3_AUX

Q_RES_0402LF-33.2,1%,1/16W,CHIA  I206  R2449
   1 SMB_VR_3V3AUX_SCL      A @S9S_MB_2U_LIB.S9S_MB_2U(SCH_1):SMB_VR_3V3AUX_SCL
   2 SMB_VR_3V3AUX_SCL_R1      B @S9S_MB_2U_LIB.S9S_MB_2U(SCH_1):SMB_VR_3V3AUX_SCL_R1

Q_RES_0402LF-33.2,1%,1/16W,CHIA  I207  R2450
   1 SMB_VR_3V3AUX_SDA      A @S9S_MB_2U_LIB.S9S_MB_2U(SCH_1):SMB_VR_3V3AUX_SDA
   2 SMB_VR_3V3AUX_SDA_R1      B @S9S_MB_2U_LIB.S9S_MB_2U(SCH_1):SMB_VR_3V3AUX_SDA_R1

Q_RES_0402LF-33.2,1%,1/16W,CHIA  I216  R2456
   1 SMB_VR_3V3AUX_SDA_R      A @S9S_MB_2U_LIB.S9S_MB_2U(SCH_1):SMB_VR_3V3AUX_SDA_R
   2 SMB_VR_3V3AUX_SDA_R3      B @S9S_MB_2U_LIB.S9S_MB_2U(SCH_1):SMB_VR_3V3AUX_SDA_R3

Q_RES_0402LF-33.2,1%,1/16W,CHIA  I217  R2455
   1 SMB_VR_3V3AUX_SCL_R      A @S9S_MB_2U_LIB.S9S_MB_2U(SCH_1):SMB_VR_3V3AUX_SCL_R
   2 SMB_VR_3V3AUX_SCL_R3      B @S9S_MB_2U_LIB.S9S_MB_2U(SCH_1):SMB_VR_3V3AUX_SCL_R3

Q_RES_0402LF-33.2,1%,1/16W,CHIA  I218  R2454
   1 SMB_VR_3V3AUX_SDA_R      A @S9S_MB_2U_LIB.S9S_MB_2U(SCH_1):SMB_VR_3V3AUX_SDA_R
   2 SMB_VR_3V3AUX_SDA_R2      B @S9S_MB_2U_LIB.S9S_MB_2U(SCH_1):SMB_VR_3V3AUX_SDA_R2

Q_RES_0402LF-33.2,1%,1/16W,CHIA  I219  R2453
   1 SMB_VR_3V3AUX_SCL_R      A @S9S_MB_2U_LIB.S9S_MB_2U(SCH_1):SMB_VR_3V3AUX_SCL_R
   2 SMB_VR_3V3AUX_SCL_R2      B @S9S_MB_2U_LIB.S9S_MB_2U(SCH_1):SMB_VR_3V3AUX_SCL_R2

Q_RES_0402LF-33.2,1%,1/16W,CHIA  I228  R2995
   1 SMB_SML1_PMBUS_3V3AUX_PCH_SCL      A @S9S_MB_2U_LIB.S9S_MB_2U(SCH_1):SMB_SML1_PMBUS_3V3AUX_PCH_SCL
   2 SMB_SML1_PMBUS_HSC_SCL_R3      B @S9S_MB_2U_LIB.S9S_MB_2U(SCH_1):SMB_SML1_PMBUS_HSC_SCL_R3

Q_RES_0402LF-33.2,1%,1/16W,CHIA  I229  R2996
   1 SMB_SML1_PMBUS_3V3AUX_PCH_SDA      A @S9S_MB_2U_LIB.S9S_MB_2U(SCH_1):SMB_SML1_PMBUS_3V3AUX_PCH_SDA
   2 SMB_SML1_PMBUS_HSC_SDA_R3      B @S9S_MB_2U_LIB.S9S_MB_2U(SCH_1):SMB_SML1_PMBUS_HSC_SDA_R3

Q_RES_0402LF-2.2K,5%,1/16W,EMPA  I230  R3004
   1 SMB_2_BMC_GPU_SDA      A @S9S_MB_2U_LIB.S9S_MB_2U(SCH_1):SMB_2_BMC_GPU_SDA
   2 P3V3_AUX      B @S9S_MB_2U_LIB.S9S_MB_2U(SCH_1):P3V3_AUX

Q_RES_0402LF-2.2K,5%,1/16W,EMPA  I231  R2999
   1 SMB_2_BMC_GPU_SCL      A @S9S_MB_2U_LIB.S9S_MB_2U(SCH_1):SMB_2_BMC_GPU_SCL
   2 P3V3_AUX      B @S9S_MB_2U_LIB.S9S_MB_2U(SCH_1):P3V3_AUX

Q_RES_0402LF-33.2,1%,1/16W,CHIA  I234  R3061
   1 SMB_SML1_PMBUS_3V3AUX_PCH_SDA      A @S9S_MB_2U_LIB.S9S_MB_2U(SCH_1):SMB_SML1_PMBUS_3V3AUX_PCH_SDA
   2 SMB_PMBUS_SML1_ME_SDA      B @S9S_MB_2U_LIB.S9S_MB_2U(SCH_1):SMB_PMBUS_SML1_ME_SDA

Q_RES_0402LF-33.2,1%,1/16W,CHIA  I237  R3060
   1 SMB_SML1_PMBUS_3V3AUX_PCH_SCL      A @S9S_MB_2U_LIB.S9S_MB_2U(SCH_1):SMB_SML1_PMBUS_3V3AUX_PCH_SCL
   2 SMB_PMBUS_SML1_ME_SCL      B @S9S_MB_2U_LIB.S9S_MB_2U(SCH_1):SMB_PMBUS_SML1_ME_SCL

Q_RES_0402LF-33.2,1%,1/16W,CHIA  I242  R3058
   1 SMB_SML0_3V3AUX_SCL      A @S9S_MB_2U_LIB.S9S_MB_2U(SCH_1):SMB_SML0_3V3AUX_SCL
   2 SMB_SML0_ME_SCL      B @S9S_MB_2U_LIB.S9S_MB_2U(SCH_1):SMB_SML0_ME_SCL

Q_RES_0402LF-33.2,1%,1/16W,CHIA  I243  R3059
   1 SMB_SML0_3V3AUX_SDA      A @S9S_MB_2U_LIB.S9S_MB_2U(SCH_1):SMB_SML0_3V3AUX_SDA
   2 SMB_SML0_ME_SDA      B @S9S_MB_2U_LIB.S9S_MB_2U(SCH_1):SMB_SML0_ME_SDA

Q_RES_0402LF-2.2K,5%,1/16W,EMPA  I250  R3227
   1 SMB_1_BMC_GPU_SDA      A @S9S_MB_2U_LIB.S9S_MB_2U(SCH_1):SMB_1_BMC_GPU_SDA
   2 P3V3_AUX      B @S9S_MB_2U_LIB.S9S_MB_2U(SCH_1):P3V3_AUX

Q_RES_0402LF-2.2K,5%,1/16W,EMPA  I251  R3226
   1 SMB_1_BMC_GPU_SCL      A @S9S_MB_2U_LIB.S9S_MB_2U(SCH_1):SMB_1_BMC_GPU_SCL
   2 P3V3_AUX      B @S9S_MB_2U_LIB.S9S_MB_2U(SCH_1):P3V3_AUX

Q_RES_0402LF-2.2K,5%,1/16W,EMPA  I258  R3241
   1 SMB_OCP_SFF_3V3AUX_SDA      A @S9S_MB_2U_LIB.S9S_MB_2U(SCH_1):SMB_OCP_SFF_3V3AUX_SDA
   2 P3V3_AUX      B @S9S_MB_2U_LIB.S9S_MB_2U(SCH_1):P3V3_AUX

Q_RES_0402LF-2.2K,5%,1/16W,EMPA  I259  R3240
   1 SMB_OCP_SFF_3V3AUX_SCL      A @S9S_MB_2U_LIB.S9S_MB_2U(SCH_1):SMB_OCP_SFF_3V3AUX_SCL
   2 P3V3_AUX      B @S9S_MB_2U_LIB.S9S_MB_2U(SCH_1):P3V3_AUX

Q_RES_0402LF-2.2K,5%,1/16W,EMPA  I260  R3242
   1 SMB_OCP_V3_2_3V3AUX_SCL      A @S9S_MB_2U_LIB.S9S_MB_2U(SCH_1):SMB_OCP_V3_2_3V3AUX_SCL
   2 P3V3_AUX      B @S9S_MB_2U_LIB.S9S_MB_2U(SCH_1):P3V3_AUX

Q_RES_0402LF-2.2K,5%,1/16W,EMPA  I261  R3243
   1 SMB_OCP_V3_2_3V3AUX_SDA      A @S9S_MB_2U_LIB.S9S_MB_2U(SCH_1):SMB_OCP_V3_2_3V3AUX_SDA
   2 P3V3_AUX      B @S9S_MB_2U_LIB.S9S_MB_2U(SCH_1):P3V3_AUX

Q_RES_0402LF-33.2,1%,1/16W,CHIA  I264  R3341
   1 SMB_HOST_CLK_3V3AUX_SDA      A @S9S_MB_2U_LIB.S9S_MB_2U(SCH_1):SMB_HOST_CLK_3V3AUX_SDA
   2 SMB_HOST_CLK_GEN2_3V3AUX_SDA      B @S9S_MB_2U_LIB.S9S_MB_2U(SCH_1):SMB_HOST_CLK_GEN2_3V3AUX_SDA

Q_RES_0402LF-33.2,1%,1/16W,CHIA  I268  R3340
   1 SMB_HOST_CLK_3V3AUX_SCL      A @S9S_MB_2U_LIB.S9S_MB_2U(SCH_1):SMB_HOST_CLK_3V3AUX_SCL
   2 SMB_HOST_CLK_GEN2_3V3AUX_SCL      B @S9S_MB_2U_LIB.S9S_MB_2U(SCH_1):SMB_HOST_CLK_GEN2_3V3AUX_SCL

Q_RES_0402LF-33.2,1%,1/16W,CHIA  I271  R4150
   1 SMB_1_PLD_3V3AUX_SDA      A @S9S_MB_2U_LIB.S9S_MB_2U(SCH_1):SMB_1_PLD_3V3AUX_SDA
   2 SMB_1_PLD_3V3AUX_SDA_R1      B @S9S_MB_2U_LIB.S9S_MB_2U(SCH_1):SMB_1_PLD_3V3AUX_SDA_R1

Q_RES_0402LF-33.2,1%,1/16W,CHIA  I272  R4149
   1 SMB_1_PLD_3V3AUX_SCL      A @S9S_MB_2U_LIB.S9S_MB_2U(SCH_1):SMB_1_PLD_3V3AUX_SCL
   2 SMB_1_PLD_3V3AUX_SCL_R1      B @S9S_MB_2U_LIB.S9S_MB_2U(SCH_1):SMB_1_PLD_3V3AUX_SCL_R1

Q_RES_0402LF-33.2,1%,1/16W,CHIA  I273  R4152
   1 SMB_1_PLD_3V3AUX_SDA      A @S9S_MB_2U_LIB.S9S_MB_2U(SCH_1):SMB_1_PLD_3V3AUX_SDA
   2 SMB_2_PLD_3V3AUX_SDA_R1      B @S9S_MB_2U_LIB.S9S_MB_2U(SCH_1):SMB_2_PLD_3V3AUX_SDA_R1

Q_RES_0402LF-33.2,1%,1/16W,CHIA  I274  R4151
   1 SMB_1_PLD_3V3AUX_SCL      A @S9S_MB_2U_LIB.S9S_MB_2U(SCH_1):SMB_1_PLD_3V3AUX_SCL
   2 SMB_2_PLD_3V3AUX_SCL_R1      B @S9S_MB_2U_LIB.S9S_MB_2U(SCH_1):SMB_2_PLD_3V3AUX_SCL_R1

Q_RES_0402LF-0,5%,1/16W,CHIP,CA  I284  R4511
   1 SMB_HOST_3V3AUX_SDA      A @S9S_MB_2U_LIB.S9S_MB_2U(SCH_1):SMB_HOST_3V3AUX_SDA
   2 SMB_HOST_3V3AUX_SDA_R4      B @S9S_MB_2U_LIB.S9S_MB_2U(SCH_1):SMB_HOST_3V3AUX_SDA_R4

Q_RES_0402LF-33.2,1%,1/16W,CHIA  I285  R4510
   1 SMB_HOST_3V3AUX_SCL      A @S9S_MB_2U_LIB.S9S_MB_2U(SCH_1):SMB_HOST_3V3AUX_SCL
   2 SMB_HOST_3V3AUX_SCL_R4      B @S9S_MB_2U_LIB.S9S_MB_2U(SCH_1):SMB_HOST_3V3AUX_SCL_R4

Q_RES_0402LF-33.2,1%,1/16W,CHIA  I293  R4530
   1 SMB_SML1_PMBUS_HSC_SCL_R3      A @S9S_MB_2U_LIB.S9S_MB_2U(SCH_1):SMB_SML1_PMBUS_HSC_SCL_R3
   2 SMB_SML1_PMBUS_HSC_SCL      B @S9S_MB_2U_LIB.S9S_MB_2U(SCH_1):SMB_SML1_PMBUS_HSC_SCL

Q_RES_0402LF-0,5%,1/16W,CHIP,CA  I296  R4531
   1 SMB_SML1_PMBUS_HSC_SDA_R3      A @S9S_MB_2U_LIB.S9S_MB_2U(SCH_1):SMB_SML1_PMBUS_HSC_SDA_R3
   2 SMB_SML1_PMBUS_HSC_SDA      B @S9S_MB_2U_LIB.S9S_MB_2U(SCH_1):SMB_SML1_PMBUS_HSC_SDA

Q_RES_0402LF-33.2,1%,1/16W,CHIA  I303  R577
   1 SMB_HOST_3V3AUX_SCL_R4      A @S9S_MB_2U_LIB.S9S_MB_2U(SCH_1):SMB_HOST_3V3AUX_SCL_R4
   2 SMB_HOST_3V3AUX_SCL_R      B @S9S_MB_2U_LIB.S9S_MB_2U(SCH_1):SMB_HOST_3V3AUX_SCL_R

Q_RES_0402LF-33.2,1%,1/16W,CHIA  I304  R578
   1 SMB_HOST_3V3AUX_SDA_R4      A @S9S_MB_2U_LIB.S9S_MB_2U(SCH_1):SMB_HOST_3V3AUX_SDA_R4
   2 SMB_HOST_3V3AUX_SDA_R      B @S9S_MB_2U_LIB.S9S_MB_2U(SCH_1):SMB_HOST_3V3AUX_SDA_R

Q_RES_0402LF-33.2,1%,1/16W,CHIA  I305  R4512
   1 SMB_HOST_3V3AUX_SCL      A @S9S_MB_2U_LIB.S9S_MB_2U(SCH_1):SMB_HOST_3V3AUX_SCL
   2 SMB_HOST_3V3AUX_SCL_R5      B @S9S_MB_2U_LIB.S9S_MB_2U(SCH_1):SMB_HOST_3V3AUX_SCL_R5

Q_RES_0402LF-0,5%,1/16W,CHIP,CA  I306  R4513
   1 SMB_HOST_3V3AUX_SDA      A @S9S_MB_2U_LIB.S9S_MB_2U(SCH_1):SMB_HOST_3V3AUX_SDA
   2 SMB_HOST_3V3AUX_SDA_R5      B @S9S_MB_2U_LIB.S9S_MB_2U(SCH_1):SMB_HOST_3V3AUX_SDA_R5

Q_RES_0402LF-0,5%,1/16W,CHIP,CA  I311  R593
   1 I3C_SPD_DDRABCD_CPU0_BMC_R_SCL      A @S9S_MB_2U_LIB.S9S_MB_2U(SCH_1):I3C_SPD_DDRABCD_CPU0_BMC_R_SCL
   2 I3C_SPD_DDRABCD_CPU0_BMC_SCL      B @S9S_MB_2U_LIB.S9S_MB_2U(SCH_1):I3C_SPD_DDRABCD_CPU0_BMC_SCL

Q_RES_0402LF-0,5%,1/16W,CHIP,CA  I312  R594
   1 I3C_SPD_DDRABCD_CPU0_BMC_R_SDA      A @S9S_MB_2U_LIB.S9S_MB_2U(SCH_1):I3C_SPD_DDRABCD_CPU0_BMC_R_SDA
   2 I3C_SPD_DDRABCD_CPU0_BMC_SDA      B @S9S_MB_2U_LIB.S9S_MB_2U(SCH_1):I3C_SPD_DDRABCD_CPU0_BMC_SDA

Q_RES_0402LF-0,5%,1/16W,CHIP,CA  I313  R596
   1 I3C_SPD_DDREFGH_CPU0_BMC_R_SDA      A @S9S_MB_2U_LIB.S9S_MB_2U(SCH_1):I3C_SPD_DDREFGH_CPU0_BMC_R_SDA
   2 I3C_SPD_DDREFGH_CPU0_BMC_SDA      B @S9S_MB_2U_LIB.S9S_MB_2U(SCH_1):I3C_SPD_DDREFGH_CPU0_BMC_SDA

Q_RES_0402LF-0,5%,1/16W,CHIP,CA  I314  R595
   1 I3C_SPD_DDREFGH_CPU0_BMC_R_SCL      A @S9S_MB_2U_LIB.S9S_MB_2U(SCH_1):I3C_SPD_DDREFGH_CPU0_BMC_R_SCL
   2 I3C_SPD_DDREFGH_CPU0_BMC_SCL      B @S9S_MB_2U_LIB.S9S_MB_2U(SCH_1):I3C_SPD_DDREFGH_CPU0_BMC_SCL

Q_RES_0402LF-0,5%,1/16W,CHIP,CA  I315  R598
   1 I3C_SPD_DDRABCD_CPU1_BMC_R_SDA      A @S9S_MB_2U_LIB.S9S_MB_2U(SCH_1):I3C_SPD_DDRABCD_CPU1_BMC_R_SDA
   2 I3C_SPD_DDRABCD_CPU1_BMC_SDA      B @S9S_MB_2U_LIB.S9S_MB_2U(SCH_1):I3C_SPD_DDRABCD_CPU1_BMC_SDA

Q_RES_0402LF-0,5%,1/16W,CHIP,CA  I316  R597
   1 I3C_SPD_DDRABCD_CPU1_BMC_R_SCL      A @S9S_MB_2U_LIB.S9S_MB_2U(SCH_1):I3C_SPD_DDRABCD_CPU1_BMC_R_SCL
   2 I3C_SPD_DDRABCD_CPU1_BMC_SCL      B @S9S_MB_2U_LIB.S9S_MB_2U(SCH_1):I3C_SPD_DDRABCD_CPU1_BMC_SCL

Q_RES_0402LF-0,5%,1/16W,CHIP,CA  I317  R599
   1 I3C_SPD_DDREFGH_CPU1_BMC_R_SCL      A @S9S_MB_2U_LIB.S9S_MB_2U(SCH_1):I3C_SPD_DDREFGH_CPU1_BMC_R_SCL
   2 I3C_SPD_DDREFGH_CPU1_BMC_SCL      B @S9S_MB_2U_LIB.S9S_MB_2U(SCH_1):I3C_SPD_DDREFGH_CPU1_BMC_SCL

Q_RES_0402LF-0,5%,1/16W,CHIP,CA  I318  R600
   1 I3C_SPD_DDREFGH_CPU1_BMC_R_SDA      A @S9S_MB_2U_LIB.S9S_MB_2U(SCH_1):I3C_SPD_DDREFGH_CPU1_BMC_R_SDA
   2 I3C_SPD_DDREFGH_CPU1_BMC_SDA      B @S9S_MB_2U_LIB.S9S_MB_2U(SCH_1):I3C_SPD_DDREFGH_CPU1_BMC_SDA


DRAWING: @S9S_MB_2U_LIB.S9S_MB_2U(SCH_1):PAGE231 

M24128BWMN6TP-M24128-BWMN6TP,SA  I35  U64
   8 P3V3_AUX    VCC @S9S_MB_2U_LIB.S9S_MB_2U(SCH_1):P3V3_AUX
   7 PD_MB_FRU_WP    WC# @S9S_MB_2U_LIB.S9S_MB_2U(SCH_1):PD_MB_FRU_WP
   6 SMB_FRU_3V3AUX_SCL    SCL @S9S_MB_2U_LIB.S9S_MB_2U(SCH_1):SMB_FRU_3V3AUX_SCL
   5 SMB_FRU_3V3AUX_SDA    SDA @S9S_MB_2U_LIB.S9S_MB_2U(SCH_1):SMB_FRU_3V3AUX_SDA
   4    GND    VSS @S9S_MB_2U_LIB.S9S_MB_2U(SCH_1):GND
   3 MB_FRU_ADDR2     E2 @S9S_MB_2U_LIB.S9S_MB_2U(SCH_1):MB_FRU_ADDR2
   2 MB_FRU_ADDR1     E1 @S9S_MB_2U_LIB.S9S_MB_2U(SCH_1):MB_FRU_ADDR1
   1 MB_FRU_ADDR0     E0 @S9S_MB_2U_LIB.S9S_MB_2U(SCH_1):MB_FRU_ADDR0

Q_RES_0402LF-10K,1%,1/16W,EMPTA  I45  R717
   1 P3V3_AUX      A @S9S_MB_2U_LIB.S9S_MB_2U(SCH_1):P3V3_AUX
   2 MB_FRU_ADDR1      B @S9S_MB_2U_LIB.S9S_MB_2U(SCH_1):MB_FRU_ADDR1

Q_RES_0402LF-10K,1%,1/16W,EMPTA  I47  R713
   1 P3V3_AUX      A @S9S_MB_2U_LIB.S9S_MB_2U(SCH_1):P3V3_AUX
   2 MB_FRU_ADDR2      B @S9S_MB_2U_LIB.S9S_MB_2U(SCH_1):MB_FRU_ADDR2

Q_RES_0402LF-1K,1%,1/16W,CHIP,A  I50  R718
   1 MB_FRU_ADDR1      A @S9S_MB_2U_LIB.S9S_MB_2U(SCH_1):MB_FRU_ADDR1
   2    GND      B @S9S_MB_2U_LIB.S9S_MB_2U(SCH_1):GND

Q_RES_0402LF-1K,1%,1/16W,CHIP,A  I52  R714
   1 MB_FRU_ADDR2      A @S9S_MB_2U_LIB.S9S_MB_2U(SCH_1):MB_FRU_ADDR2
   2    GND      B @S9S_MB_2U_LIB.S9S_MB_2U(SCH_1):GND

Q_CAP_0402-0.1UF,25V,10%,X7R,CA  I55  C629
   1 P3V3_AUX      A @S9S_MB_2U_LIB.S9S_MB_2U(SCH_1):P3V3_AUX
   2    GND      B @S9S_MB_2U_LIB.S9S_MB_2U(SCH_1):GND

Q_RES_0402LF-1K,1%,1/16W,CHIP,A  I57  R710
   1 PD_MB_FRU_WP      A @S9S_MB_2U_LIB.S9S_MB_2U(SCH_1):PD_MB_FRU_WP
   2    GND      B @S9S_MB_2U_LIB.S9S_MB_2U(SCH_1):GND

Q_RES_0402LF-1K,1%,1/16W,EMPTYA  I61  R722
   1 MB_FRU_ADDR0      A @S9S_MB_2U_LIB.S9S_MB_2U(SCH_1):MB_FRU_ADDR0
   2    GND      B @S9S_MB_2U_LIB.S9S_MB_2U(SCH_1):GND

Q_RES_0402LF-10K,1%,1/16W,CHIPA  I62  R721
   1 P3V3_AUX      A @S9S_MB_2U_LIB.S9S_MB_2U(SCH_1):P3V3_AUX
   2 MB_FRU_ADDR0      B @S9S_MB_2U_LIB.S9S_MB_2U(SCH_1):MB_FRU_ADDR0

Q_RES_0402LF-4.7K,5%,1/16W,EMPA  I93  R1332
   1 P3V3_AUX      A @S9S_MB_2U_LIB.S9S_MB_2U(SCH_1):P3V3_AUX
   2 SMB_FRU_3V3AUX_SDA      B @S9S_MB_2U_LIB.S9S_MB_2U(SCH_1):SMB_FRU_3V3AUX_SDA

Q_RES_0402LF-4.7K,5%,1/16W,EMPA  I95  R1331
   1 P3V3_AUX      A @S9S_MB_2U_LIB.S9S_MB_2U(SCH_1):P3V3_AUX
   2 SMB_FRU_3V3AUX_SCL      B @S9S_MB_2U_LIB.S9S_MB_2U(SCH_1):SMB_FRU_3V3AUX_SCL


DRAWING: @S9S_MB_2U_LIB.S9S_MB_2U(SCH_1):PAGE232 

Q_RES_0402LF-10K,1%,1/16W,EMPTA  I4  R1691
   1 P3V3_AUX      A @S9S_MB_2U_LIB.S9S_MB_2U(SCH_1):P3V3_AUX
   2 PWRGD_DSW_PWROK_R1      B @S9S_MB_2U_LIB.S9S_MB_2U(SCH_1):PWRGD_DSW_PWROK_R1

Q_RES_0402LF-10K,1%,1/16W,CHIPA  I33  R1694
   1 P3V3_AUX      A @S9S_MB_2U_LIB.S9S_MB_2U(SCH_1):P3V3_AUX
   2 PWRGD_DSW_PWROK      B @S9S_MB_2U_LIB.S9S_MB_2U(SCH_1):PWRGD_DSW_PWROK

Q_CAP_C0402-1UF,25V,10%,X6S,CHA  I35  C1319
   1 PWRGD_DSW_PWROK      A @S9S_MB_2U_LIB.S9S_MB_2U(SCH_1):PWRGD_DSW_PWROK
   2    GND      B @S9S_MB_2U_LIB.S9S_MB_2U(SCH_1):GND

Q_CAP_C0402-0.047UF,25V,10%,X7A  I47  C1316
   1 FM_COMP_P3V3_STBY_CEXT      A @S9S_MB_2U_LIB.S9S_MB_2U(SCH_1):FM_COMP_P3V3_STBY_CEXT
   2    GND      B @S9S_MB_2U_LIB.S9S_MB_2U(SCH_1):GND

Q_RES_0402LF-100K,1%,1/16W,CHIA  I3  R1692
   1 PWRGD_DSW_PWROK_R1      A @S9S_MB_2U_LIB.S9S_MB_2U(SCH_1):PWRGD_DSW_PWROK_R1
   2    GND      B @S9S_MB_2U_LIB.S9S_MB_2U(SCH_1):GND

Q_CAP_C0402-1UF,25V,10%,EMPTY,A  I7  C1318
   1 PWRGD_DSW_PWROK_R1      A @S9S_MB_2U_LIB.S9S_MB_2U(SCH_1):PWRGD_DSW_PWROK_R1
   2    GND      B @S9S_MB_2U_LIB.S9S_MB_2U(SCH_1):GND

Q_CAP_0402-0.1UF,25V,10%,X7R,CA  I9  C1317
   1 P3V3_AUX      A @S9S_MB_2U_LIB.S9S_MB_2U(SCH_1):P3V3_AUX
   2    GND      B @S9S_MB_2U_LIB.S9S_MB_2U(SCH_1):GND

74LVC1G07SE7-74LVC1G07SE-7,SMLA  I11  U95
   5 P3V3_AUX    VCC @S9S_MB_2U_LIB.S9S_MB_2U(SCH_1):P3V3_AUX
   2 PWRGD_DSW_PWROK_R1      A @S9S_MB_2U_LIB.S9S_MB_2U(SCH_1):PWRGD_DSW_PWROK_R1
   3    GND    GND @S9S_MB_2U_LIB.S9S_MB_2U(SCH_1):GND
   4 PWRGD_DSW_PWROK_R2      Y @S9S_MB_2U_LIB.S9S_MB_2U(SCH_1):PWRGD_DSW_PWROK_R2
   1     NC    NC1     NC

Q_RES_0402LF-0,5%,1/16W,EMPTY,A  I13  R4807
   1 PWRGD_DSW_PWROK_R1      A @S9S_MB_2U_LIB.S9S_MB_2U(SCH_1):PWRGD_DSW_PWROK_R1
   2 PWRGD_DSW_PWROK_R2      B @S9S_MB_2U_LIB.S9S_MB_2U(SCH_1):PWRGD_DSW_PWROK_R2

MOSFET_NCH_GDS_ESD_PROTECTED-2A  I14  Q52
   D FM_COMP_P3V3_AUX_VIN_R      D @S9S_MB_2U_LIB.S9S_MB_2U(SCH_1):FM_COMP_P3V3_AUX_VIN_R
   G PWRGD_P3V3_AUX_R2      G @S9S_MB_2U_LIB.S9S_MB_2U(SCH_1):PWRGD_P3V3_AUX_R2
   S    GND      S @S9S_MB_2U_LIB.S9S_MB_2U(SCH_1):GND

Q_RES_0402LF-6.19K,1%,1/16W,CHA  I16  R1689
   1 FM_COMP_P3V3_AUX_VIN      A @S9S_MB_2U_LIB.S9S_MB_2U(SCH_1):FM_COMP_P3V3_AUX_VIN
   2    GND      B @S9S_MB_2U_LIB.S9S_MB_2U(SCH_1):GND

Q_RES_0402LF-100K,1%,1/16W,CHIA  I18  R1688
   1 P12V_AUX      A @S9S_MB_2U_LIB.S9S_MB_2U(SCH_1):P12V_AUX
   2 FM_COMP_P3V3_AUX_VIN      B @S9S_MB_2U_LIB.S9S_MB_2U(SCH_1):FM_COMP_P3V3_AUX_VIN

Q_RES_0402LF-0,5%,1/16W,CHIP,CA  I20  R1950
   1 FM_COMP_P3V3_AUX_VIN      A @S9S_MB_2U_LIB.S9S_MB_2U(SCH_1):FM_COMP_P3V3_AUX_VIN
   2 FM_COMP_P3V3_AUX_VIN_R      B @S9S_MB_2U_LIB.S9S_MB_2U(SCH_1):FM_COMP_P3V3_AUX_VIN_R

Q_RES_0402LF-0,5%,1/16W,EMPTY,A  I21  R1745
   1 FM_COMP_P3V3_AUX_ENIN      A @S9S_MB_2U_LIB.S9S_MB_2U(SCH_1):FM_COMP_P3V3_AUX_ENIN
   2 FM_PFR_DSW_PWROK_N      B @S9S_MB_2U_LIB.S9S_MB_2U(SCH_1):FM_PFR_DSW_PWROK_N

Q_RES_0402LF-10K,1%,1/16W,CHIPA  I22  R1690
   1 P3V3_AUX      A @S9S_MB_2U_LIB.S9S_MB_2U(SCH_1):P3V3_AUX
   2 FM_COMP_P3V3_AUX_ENIN      B @S9S_MB_2U_LIB.S9S_MB_2U(SCH_1):FM_COMP_P3V3_AUX_ENIN

Q_CAP_C0402-1UF,25V,10%,X6S,CHA  I24  C1315
   1 P3V3_AUX      A @S9S_MB_2U_LIB.S9S_MB_2U(SCH_1):P3V3_AUX
   2    GND      B @S9S_MB_2U_LIB.S9S_MB_2U(SCH_1):GND

TPS3895ADRYR-TPS3895ADRYR,SMLFA  I26  U117
   1 FM_COMP_P3V3_AUX_ENIN ENABLE @S9S_MB_2U_LIB.S9S_MB_2U(SCH_1):FM_COMP_P3V3_AUX_ENIN
   2    GND    GND @S9S_MB_2U_LIB.S9S_MB_2U(SCH_1):GND
   3 FM_COMP_P3V3_AUX_VIN  SENSE @S9S_MB_2U_LIB.S9S_MB_2U(SCH_1):FM_COMP_P3V3_AUX_VIN
   4 PWRGD_DSW_PWROK_R1 SENSE_OUT @S9S_MB_2U_LIB.S9S_MB_2U(SCH_1):PWRGD_DSW_PWROK_R1
   5 FM_COMP_P3V3_STBY_CEXT     CT @S9S_MB_2U_LIB.S9S_MB_2U(SCH_1):FM_COMP_P3V3_STBY_CEXT
   6 P3V3_AUX    VCC @S9S_MB_2U_LIB.S9S_MB_2U(SCH_1):P3V3_AUX

ADM1086AKSZREEL7-ADM1086AKSZ-RA  I27  U94
   6 P3V3_AUX    VCC @S9S_MB_2U_LIB.S9S_MB_2U(SCH_1):P3V3_AUX
   3 FM_COMP_P3V3_AUX_VIN    VIN @S9S_MB_2U_LIB.S9S_MB_2U(SCH_1):FM_COMP_P3V3_AUX_VIN
   1 FM_COMP_P3V3_AUX_ENIN   ENIN @S9S_MB_2U_LIB.S9S_MB_2U(SCH_1):FM_COMP_P3V3_AUX_ENIN
   4 PWRGD_DSW_PWROK_R1  ENOUT @S9S_MB_2U_LIB.S9S_MB_2U(SCH_1):PWRGD_DSW_PWROK_R1
   5 FM_COMP_P3V3_STBY_CEXT   CEXT @S9S_MB_2U_LIB.S9S_MB_2U(SCH_1):FM_COMP_P3V3_STBY_CEXT
   2    GND    GND @S9S_MB_2U_LIB.S9S_MB_2U(SCH_1):GND

Q_RES_0402LF-100K,1%,1/16W,EMPA  I31  R4808
   1 PWRGD_DSW_PWROK      A @S9S_MB_2U_LIB.S9S_MB_2U(SCH_1):PWRGD_DSW_PWROK
   2    GND      B @S9S_MB_2U_LIB.S9S_MB_2U(SCH_1):GND

Q_RES_0402LF-33.2,1%,1/16W,CHIA  I32  R1693
   1 PWRGD_DSW_PWROK_R2      A @S9S_MB_2U_LIB.S9S_MB_2U(SCH_1):PWRGD_DSW_PWROK_R2
   2 PWRGD_DSW_PWROK      B @S9S_MB_2U_LIB.S9S_MB_2U(SCH_1):PWRGD_DSW_PWROK

Q_RES_0402LF-0,5%,1/16W,EMPTY,A  I36  R1695
   1 PWRGD_DSW_PWROK      A @S9S_MB_2U_LIB.S9S_MB_2U(SCH_1):PWRGD_DSW_PWROK
   2 RST_RSMRST_PCH_N      B @S9S_MB_2U_LIB.S9S_MB_2U(SCH_1):RST_RSMRST_PCH_N

MOSFET_NCH_GDS_ESD_PROTECTED-2A  I39  Q53
   D PWRGD_P3V3_AUX_R2      D @S9S_MB_2U_LIB.S9S_MB_2U(SCH_1):PWRGD_P3V3_AUX_R2
   G PWRGD_P3V3_AUX      G @S9S_MB_2U_LIB.S9S_MB_2U(SCH_1):PWRGD_P3V3_AUX
   S    GND      S @S9S_MB_2U_LIB.S9S_MB_2U(SCH_1):GND

Q_RES_0402LF-10K,1%,1/16W,CHIPA  I40  R2486
   1 P3V3_AUX      A @S9S_MB_2U_LIB.S9S_MB_2U(SCH_1):P3V3_AUX
   2 PWRGD_P3V3_AUX_R2      B @S9S_MB_2U_LIB.S9S_MB_2U(SCH_1):PWRGD_P3V3_AUX_R2


DRAWING: @S9S_MB_2U_LIB.S9S_MB_2U(SCH_1):PAGE239 

Q_RES_0402LF-0,5%,1/16W,EMPTY,A  I19  R1793
   1 SMB_VR_3V3AUX_SCL_R1      A @S9S_MB_2U_LIB.S9S_MB_2U(SCH_1):SMB_VR_3V3AUX_SCL_R1
   2 SMB_SEN_MAM_3V3AUX_SCL      B @S9S_MB_2U_LIB.S9S_MB_2U(SCH_1):SMB_SEN_MAM_3V3AUX_SCL

Q_RES_0402LF-0,5%,1/16W,EMPTY,A  I20  R1792
   1 SMB_VR_3V3AUX_SDA_R1      A @S9S_MB_2U_LIB.S9S_MB_2U(SCH_1):SMB_VR_3V3AUX_SDA_R1
   2 SMB_SEN_MAM_3V3AUX_SDA      B @S9S_MB_2U_LIB.S9S_MB_2U(SCH_1):SMB_SEN_MAM_3V3AUX_SDA

MAX11617EEET-MAX11617EEE+T,SMLA  I57  U193
   1 MAX11617_VREF_R AIN11||REF @S9S_MB_2U_LIB.S9S_MB_2U(SCH_1):MAX11617_VREF_R
   2    GND  AIN10 @S9S_MB_2U_LIB.S9S_MB_2U(SCH_1):GND
   3    GND   AIN9 @S9S_MB_2U_LIB.S9S_MB_2U(SCH_1):GND
   4    GND   AIN8 @S9S_MB_2U_LIB.S9S_MB_2U(SCH_1):GND
   5 P12V_AUX_ADC_MAM   AIN0 @S9S_MB_2U_LIB.S9S_MB_2U(SCH_1):P12V_AUX_ADC_MAM
   6 P12V_OCP_SFF_ISENSE_MAM   AIN1 @S9S_MB_2U_LIB.S9S_MB_2U(SCH_1):P12V_OCP_SFF_ISENSE_MAM
   7 P12V_OCP_V3_2_ISENSE_MAM   AIN2 @S9S_MB_2U_LIB.S9S_MB_2U(SCH_1):P12V_OCP_V3_2_ISENSE_MAM
   8 P5V_ADC_MAM   AIN3 @S9S_MB_2U_LIB.S9S_MB_2U(SCH_1):P5V_ADC_MAM
   9 P3V3_ADC_MAM   AIN4 @S9S_MB_2U_LIB.S9S_MB_2U(SCH_1):P3V3_ADC_MAM
  10 P3V3_AUX_ADC_MAM   AIN5 @S9S_MB_2U_LIB.S9S_MB_2U(SCH_1):P3V3_AUX_ADC_MAM
  11 P3V3_PDB_AUX_ADC_MAM   AIN6 @S9S_MB_2U_LIB.S9S_MB_2U(SCH_1):P3V3_PDB_AUX_ADC_MAM
  12 P12V_E1S_0_ISENSE_MAM   AIN7 @S9S_MB_2U_LIB.S9S_MB_2U(SCH_1):P12V_E1S_0_ISENSE_MAM
  13 SMB_SEN_MAM_3V3AUX_SCL    SCL @S9S_MB_2U_LIB.S9S_MB_2U(SCH_1):SMB_SEN_MAM_3V3AUX_SCL
  14 SMB_SEN_MAM_3V3AUX_SDA    SDA @S9S_MB_2U_LIB.S9S_MB_2U(SCH_1):SMB_SEN_MAM_3V3AUX_SDA
  15    GND    GND @S9S_MB_2U_LIB.S9S_MB_2U(SCH_1):GND
  16 P3V3_MAX11617_VDD    VDD @S9S_MB_2U_LIB.S9S_MB_2U(SCH_1):P3V3_MAX11617 _VDD

Q_CAP_0402-0.1UF,25V,10%,EMPTYA  I58  C1757
   1 P3V3_MAX11617_VDD      A @S9S_MB_2U_LIB.S9S_MB_2U(SCH_1):P3V3_MAX11617 _VDD
   2    GND      B @S9S_MB_2U_LIB.S9S_MB_2U(SCH_1):GND

Q_CAP_C0805-10UF,16V,10%,EMPTYA  I61  C1768
   1 P3V3_MAX11617_VDD      A @S9S_MB_2U_LIB.S9S_MB_2U(SCH_1):P3V3_MAX11617 _VDD
   2    GND      B @S9S_MB_2U_LIB.S9S_MB_2U(SCH_1):GND

Q_INDUCTOR_SMLF-BLM18PG300SN1DA  I62  L15
   2 P3V3_AUX      2 @S9S_MB_2U_LIB.S9S_MB_2U(SCH_1):P3V3_AUX
   1 P3V3_MAX11617_VDD      1 @S9S_MB_2U_LIB.S9S_MB_2U(SCH_1):P3V3_MAX11617 _VDD

Q_CAP_C0805-10UF,16V,10%,EMPTYA  I68  C1767
   1 MAX11617_VREF      A @S9S_MB_2U_LIB.S9S_MB_2U(SCH_1):MAX11617_VREF
   2    GND      B @S9S_MB_2U_LIB.S9S_MB_2U(SCH_1):GND

Q_CAP_0402-0.1UF,25V,10%,EMPTYA  I70  C1347
   1 MAX11617_VREF      A @S9S_MB_2U_LIB.S9S_MB_2U(SCH_1):MAX11617_VREF
   2    GND      B @S9S_MB_2U_LIB.S9S_MB_2U(SCH_1):GND

Q_RES_0402LF-2K,1%,1/16W,EMPTYA  I72  R2900
   1 MAX11617_VREF      A @S9S_MB_2U_LIB.S9S_MB_2U(SCH_1):MAX11617_VREF
   2 MAX11617_VREF_R      B @S9S_MB_2U_LIB.S9S_MB_2U(SCH_1):MAX11617_VREF_R

ADC128D818CIMTXNOPB-ADC128D818A  I103  U269
   1 ADC128_VREF   VREF @S9S_MB_2U_LIB.S9S_MB_2U(SCH_1):ADC128_VREF
   5 P3V3_ADC128_VCC     V+ @S9S_MB_2U_LIB.S9S_MB_2U(SCH_1):P3V3_ADC128_VCC
   7 ADC128_A0     A0 @S9S_MB_2U_LIB.S9S_MB_2U(SCH_1):ADC128_A0
   8 ADC128_A1     A1 @S9S_MB_2U_LIB.S9S_MB_2U(SCH_1):ADC128_A1
   9 P12V_E1S_0_ISENSE_TIC    IN7 @S9S_MB_2U_LIB.S9S_MB_2U(SCH_1):P12V_E1S_0_ISENSE_TIC
  10 P3V3_PDB_AUX_ADC_TIC    IN6 @S9S_MB_2U_LIB.S9S_MB_2U(SCH_1):P3V3_PDB_AUX_ADC_TIC
  11 P3V3_AUX_ADC_TIC    IN5 @S9S_MB_2U_LIB.S9S_MB_2U(SCH_1):P3V3_AUX_ADC_TIC
  12 P3V3_ADC_TIC    IN4 @S9S_MB_2U_LIB.S9S_MB_2U(SCH_1):P3V3_ADC_TIC
  13 P5V_ADC_TIC    IN3 @S9S_MB_2U_LIB.S9S_MB_2U(SCH_1):P5V_ADC_TIC
  14 P12V_OCP_V3_2_ISENSE_TIC    IN2 @S9S_MB_2U_LIB.S9S_MB_2U(SCH_1):P12V_OCP_V3_2_ISENSE_TIC
  15 P12V_OCP_SFF_ISENSE_TIC    IN1 @S9S_MB_2U_LIB.S9S_MB_2U(SCH_1):P12V_OCP_SFF_ISENSE_TIC
  16 P12V_AUX_ADC_TIC    IN0 @S9S_MB_2U_LIB.S9S_MB_2U(SCH_1):P12V_AUX_ADC_TIC
   2 SMB_SEN_TIC_3V3AUX_SDA    SDA @S9S_MB_2U_LIB.S9S_MB_2U(SCH_1):SMB_SEN_TIC_3V3AUX_SDA
   3 SMB_SEN_TIC_3V3AUX_SCL    SCL @S9S_MB_2U_LIB.S9S_MB_2U(SCH_1):SMB_SEN_TIC_3V3AUX_SCL
   4    GND    GND @S9S_MB_2U_LIB.S9S_MB_2U(SCH_1):GND
   6 TP_ADC128_INT   INT# @S9S_MB_2U_LIB.S9S_MB_2U(SCH_1):TP_ADC128_INT

Q_RES_0402LF-0,5%,1/16W,CHIP,CA  I110  R3671
   1 SMB_VR_3V3AUX_SDA_R1      A @S9S_MB_2U_LIB.S9S_MB_2U(SCH_1):SMB_VR_3V3AUX_SDA_R1
   2 SMB_SEN_TIC_3V3AUX_SDA      B @S9S_MB_2U_LIB.S9S_MB_2U(SCH_1):SMB_SEN_TIC_3V3AUX_SDA

Q_RES_0402LF-0,5%,1/16W,CHIP,CA  I111  R3672
   1 SMB_VR_3V3AUX_SCL_R1      A @S9S_MB_2U_LIB.S9S_MB_2U(SCH_1):SMB_VR_3V3AUX_SCL_R1
   2 SMB_SEN_TIC_3V3AUX_SCL      B @S9S_MB_2U_LIB.S9S_MB_2U(SCH_1):SMB_SEN_TIC_3V3AUX_SCL

Q_INDUCTOR_SMLF-BLM18PG300SN1DB  I118  L16
   2 P3V3_ADC128_VCC      2 @S9S_MB_2U_LIB.S9S_MB_2U(SCH_1):P3V3_ADC128_VCC
   1 P3V3_AUX      1 @S9S_MB_2U_LIB.S9S_MB_2U(SCH_1):P3V3_AUX

Q_CAP_0402-0.1UF,25V,10%,X7R,CA  I127  C2051
   1 P3V3_ADC128_VCC      A @S9S_MB_2U_LIB.S9S_MB_2U(SCH_1):P3V3_ADC128_VCC
   2    GND      B @S9S_MB_2U_LIB.S9S_MB_2U(SCH_1):GND

Q_CAP_0402-0.1UF,25V,10%,X7R,CA  I128  C2052
   1 P3V3_ADC128_VCC      A @S9S_MB_2U_LIB.S9S_MB_2U(SCH_1):P3V3_ADC128_VCC
   2    GND      B @S9S_MB_2U_LIB.S9S_MB_2U(SCH_1):GND

Q_RES_0402LF-4.7K,1%,1/16W,EMPA  I129  R3689
   1 P3V3_ADC128_VCC      A @S9S_MB_2U_LIB.S9S_MB_2U(SCH_1):P3V3_ADC128_VCC
   2 ADC128_VREF      B @S9S_MB_2U_LIB.S9S_MB_2U(SCH_1):ADC128_VREF

Q_RES_0402LF-4.7K,1%,1/16W,EMPA  I131  R3690
   1 ADC128_VREF      A @S9S_MB_2U_LIB.S9S_MB_2U(SCH_1):ADC128_VREF
   2    GND      B @S9S_MB_2U_LIB.S9S_MB_2U(SCH_1):GND

Q_RES_0402LF-5.11K,1%,1/16W,CHA  I141  R2907
   1 P3V3_AUX      A @S9S_MB_2U_LIB.S9S_MB_2U(SCH_1):P3V3_AUX
   2 P3V3_AUX_ADC      B @S9S_MB_2U_LIB.S9S_MB_2U(SCH_1):P3V3_AUX_ADC

Q_RES_0402LF-4.7K,1%,1/16W,CHIA  I149  R1785
   1 P3V3_AUX_ADC      A @S9S_MB_2U_LIB.S9S_MB_2U(SCH_1):P3V3_AUX_ADC
   2    GND      B @S9S_MB_2U_LIB.S9S_MB_2U(SCH_1):GND

Q_RES_0402LF-5.11K,1%,1/16W,CHA  I161  R2908
   1   P3V3      A @S9S_MB_2U_LIB.S9S_MB_2U(SCH_1):P3V3
   2 P3V3_ADC      B @S9S_MB_2U_LIB.S9S_MB_2U(SCH_1):P3V3_ADC

Q_RES_0402LF-4.7K,1%,1/16W,CHIA  I162  R2843
   1 P3V3_ADC      A @S9S_MB_2U_LIB.S9S_MB_2U(SCH_1):P3V3_ADC
   2    GND      B @S9S_MB_2U_LIB.S9S_MB_2U(SCH_1):GND

Q_RES_0402LF-9.09K,1%,1/16W,CHA  I163  R1791
   1 P5V_ADC      A @S9S_MB_2U_LIB.S9S_MB_2U(SCH_1):P5V_ADC
   2    GND      B @S9S_MB_2U_LIB.S9S_MB_2U(SCH_1):GND

Q_RES_0402LF-18K,1%,1/16W,CHIPA  I168  R3005
   1    P5V      A @S9S_MB_2U_LIB.S9S_MB_2U(SCH_1):P5V
   2 P5V_ADC      B @S9S_MB_2U_LIB.S9S_MB_2U(SCH_1):P5V_ADC

Q_RES_0402LF-7.87K,1%,1/16W,CHA  I173  R1799
   1 P12V_AUX      A @S9S_MB_2U_LIB.S9S_MB_2U(SCH_1):P12V_AUX
   2 P12V_AUX_ADC      B @S9S_MB_2U_LIB.S9S_MB_2U(SCH_1):P12V_AUX_ADC

Q_RES_0402LF-1.21K,1%,1/16W,CHA  I174  R1800
   1 P12V_AUX_ADC      A @S9S_MB_2U_LIB.S9S_MB_2U(SCH_1):P12V_AUX_ADC
   2    GND      B @S9S_MB_2U_LIB.S9S_MB_2U(SCH_1):GND

Q_RES_0402LF-0,5%,1/16W,EMPTY,A  I176  R3681
   1 P3V3_AUX_ADC      A @S9S_MB_2U_LIB.S9S_MB_2U(SCH_1):P3V3_AUX_ADC
   2 P3V3_AUX_ADC_MAM      B @S9S_MB_2U_LIB.S9S_MB_2U(SCH_1):P3V3_AUX_ADC_MAM

Q_RES_0402LF-0,5%,1/16W,CHIP,CA  I179  R3682
   1 P3V3_AUX_ADC      A @S9S_MB_2U_LIB.S9S_MB_2U(SCH_1):P3V3_AUX_ADC
   2 P3V3_AUX_ADC_TIC      B @S9S_MB_2U_LIB.S9S_MB_2U(SCH_1):P3V3_AUX_ADC_TIC

Q_CAP_0402-100PF,50V,5%,EMPTY,A  I180  C2042
   1 P3V3_AUX_ADC_MAM      A @S9S_MB_2U_LIB.S9S_MB_2U(SCH_1):P3V3_AUX_ADC_MAM
   2    GND      B @S9S_MB_2U_LIB.S9S_MB_2U(SCH_1):GND

Q_CAP_0402-0.1UF,25V,10%,X7R,CA  I181  C2047
   1 P3V3_AUX_ADC_TIC      A @S9S_MB_2U_LIB.S9S_MB_2U(SCH_1):P3V3_AUX_ADC_TIC
   2    GND      B @S9S_MB_2U_LIB.S9S_MB_2U(SCH_1):GND

Q_CAP_0402-100PF,50V,5%,EMPTY,A  I187  C2044
   1 P5V_ADC_MAM      A @S9S_MB_2U_LIB.S9S_MB_2U(SCH_1):P5V_ADC_MAM
   2    GND      B @S9S_MB_2U_LIB.S9S_MB_2U(SCH_1):GND

Q_CAP_0402-0.1UF,25V,10%,X7R,CA  I188  C2049
   1 P5V_ADC_TIC      A @S9S_MB_2U_LIB.S9S_MB_2U(SCH_1):P5V_ADC_TIC
   2    GND      B @S9S_MB_2U_LIB.S9S_MB_2U(SCH_1):GND

Q_RES_0402LF-0,5%,1/16W,EMPTY,A  I190  R3685
   1 P5V_ADC      A @S9S_MB_2U_LIB.S9S_MB_2U(SCH_1):P5V_ADC
   2 P5V_ADC_MAM      B @S9S_MB_2U_LIB.S9S_MB_2U(SCH_1):P5V_ADC_MAM

Q_RES_0402LF-0,5%,1/16W,CHIP,CA  I191  R3686
   1 P5V_ADC      A @S9S_MB_2U_LIB.S9S_MB_2U(SCH_1):P5V_ADC
   2 P5V_ADC_TIC      B @S9S_MB_2U_LIB.S9S_MB_2U(SCH_1):P5V_ADC_TIC

Q_CAP_0402-100PF,50V,5%,EMPTY,A  I196  C2043
   1 P3V3_ADC_MAM      A @S9S_MB_2U_LIB.S9S_MB_2U(SCH_1):P3V3_ADC_MAM
   2    GND      B @S9S_MB_2U_LIB.S9S_MB_2U(SCH_1):GND

Q_CAP_0402-0.1UF,25V,10%,X7R,CA  I197  C2048
   1 P3V3_ADC_TIC      A @S9S_MB_2U_LIB.S9S_MB_2U(SCH_1):P3V3_ADC_TIC
   2    GND      B @S9S_MB_2U_LIB.S9S_MB_2U(SCH_1):GND

Q_RES_0402LF-0,5%,1/16W,EMPTY,A  I199  R3683
   1 P3V3_ADC      A @S9S_MB_2U_LIB.S9S_MB_2U(SCH_1):P3V3_ADC
   2 P3V3_ADC_MAM      B @S9S_MB_2U_LIB.S9S_MB_2U(SCH_1):P3V3_ADC_MAM

Q_RES_0402LF-0,5%,1/16W,CHIP,CA  I200  R3684
   1 P3V3_ADC      A @S9S_MB_2U_LIB.S9S_MB_2U(SCH_1):P3V3_ADC
   2 P3V3_ADC_TIC      B @S9S_MB_2U_LIB.S9S_MB_2U(SCH_1):P3V3_ADC_TIC

Q_CAP_0402-100PF,50V,5%,EMPTY,A  I205  C1344
   1 P12V_AUX_ADC_MAM      A @S9S_MB_2U_LIB.S9S_MB_2U(SCH_1):P12V_AUX_ADC_MAM
   2    GND      B @S9S_MB_2U_LIB.S9S_MB_2U(SCH_1):GND

Q_CAP_0402-0.1UF,25V,10%,X7R,CA  I207  C2046
   1 P12V_AUX_ADC_TIC      A @S9S_MB_2U_LIB.S9S_MB_2U(SCH_1):P12V_AUX_ADC_TIC
   2    GND      B @S9S_MB_2U_LIB.S9S_MB_2U(SCH_1):GND

Q_RES_0402LF-0,5%,1/16W,EMPTY,A  I209  R3679
   1 P12V_AUX_ADC      A @S9S_MB_2U_LIB.S9S_MB_2U(SCH_1):P12V_AUX_ADC
   2 P12V_AUX_ADC_MAM      B @S9S_MB_2U_LIB.S9S_MB_2U(SCH_1):P12V_AUX_ADC_MAM

Q_RES_0402LF-0,5%,1/16W,CHIP,CA  I210  R3680
   1 P12V_AUX_ADC      A @S9S_MB_2U_LIB.S9S_MB_2U(SCH_1):P12V_AUX_ADC
   2 P12V_AUX_ADC_TIC      B @S9S_MB_2U_LIB.S9S_MB_2U(SCH_1):P12V_AUX_ADC_TIC

Q_RES_0402LF-1K,1%,1/16W,CHIP,A  I223  R3668
   1 ADC128_A1      A @S9S_MB_2U_LIB.S9S_MB_2U(SCH_1):ADC128_A1
   2    GND      B @S9S_MB_2U_LIB.S9S_MB_2U(SCH_1):GND

Q_RES_0402LF-1K,1%,1/16W,EMPTYA  I224  R3667
   1 P3V3_AUX      A @S9S_MB_2U_LIB.S9S_MB_2U(SCH_1):P3V3_AUX
   2 ADC128_A1      B @S9S_MB_2U_LIB.S9S_MB_2U(SCH_1):ADC128_A1

Q_RES_0402LF-1K,1%,1/16W,CHIP,A  I227  R3670
   1 ADC128_A0      A @S9S_MB_2U_LIB.S9S_MB_2U(SCH_1):ADC128_A0
   2    GND      B @S9S_MB_2U_LIB.S9S_MB_2U(SCH_1):GND

Q_RES_0402LF-1K,1%,1/16W,EMPTYA  I228  R3669
   1 P3V3_AUX      A @S9S_MB_2U_LIB.S9S_MB_2U(SCH_1):P3V3_AUX
   2 ADC128_A0      B @S9S_MB_2U_LIB.S9S_MB_2U(SCH_1):ADC128_A0

Q_CAP_0402-100PF,50V,5%,EMPTY,A  I236  C2045
   1 P3V3_PDB_AUX_ADC_MAM      A @S9S_MB_2U_LIB.S9S_MB_2U(SCH_1):P3V3_PDB_AUX_ADC_MAM
   2    GND      B @S9S_MB_2U_LIB.S9S_MB_2U(SCH_1):GND

Q_CAP_0402-0.1UF,25V,10%,X7R,CA  I238  C2050
   1 P3V3_PDB_AUX_ADC_TIC      A @S9S_MB_2U_LIB.S9S_MB_2U(SCH_1):P3V3_PDB_AUX_ADC_TIC
   2    GND      B @S9S_MB_2U_LIB.S9S_MB_2U(SCH_1):GND

Q_RES_0402LF-0,5%,1/16W,EMPTY,A  I240  R3687
   1 P1V581_PDB_ADC      A @S9S_MB_2U_LIB.S9S_MB_2U(SCH_1):P1V581_PDB_ADC
   2 P3V3_PDB_AUX_ADC_MAM      B @S9S_MB_2U_LIB.S9S_MB_2U(SCH_1):P3V3_PDB_AUX_ADC_MAM

Q_RES_0402LF-0,5%,1/16W,CHIP,CA  I241  R3688
   1 P1V581_PDB_ADC      A @S9S_MB_2U_LIB.S9S_MB_2U(SCH_1):P1V581_PDB_ADC
   2 P3V3_PDB_AUX_ADC_TIC      B @S9S_MB_2U_LIB.S9S_MB_2U(SCH_1):P3V3_PDB_AUX_ADC_TIC

Q_CAP_0402-100PF,50V,5%,EMPTY,A  I304  C2176
   1 P12V_OCP_SFF_ISENSE_MAM      A @S9S_MB_2U_LIB.S9S_MB_2U(SCH_1):P12V_OCP_SFF_ISENSE_MAM
   2    GND      B @S9S_MB_2U_LIB.S9S_MB_2U(SCH_1):GND

Q_CAP_0402-0.1UF,25V,10%,X7R,CA  I305  C2178
   1 P12V_OCP_SFF_ISENSE_TIC      A @S9S_MB_2U_LIB.S9S_MB_2U(SCH_1):P12V_OCP_SFF_ISENSE_TIC
   2    GND      B @S9S_MB_2U_LIB.S9S_MB_2U(SCH_1):GND

Q_CAP_0402-100PF,50V,5%,EMPTY,A  I309  C2175
   1 P12V_OCP_V3_2_ISENSE_MAM      A @S9S_MB_2U_LIB.S9S_MB_2U(SCH_1):P12V_OCP_V3_2_ISENSE_MAM
   2    GND      B @S9S_MB_2U_LIB.S9S_MB_2U(SCH_1):GND

Q_CAP_0402-0.1UF,25V,10%,X7R,CA  I311  C2177
   1 P12V_OCP_V3_2_ISENSE_TIC      A @S9S_MB_2U_LIB.S9S_MB_2U(SCH_1):P12V_OCP_V3_2_ISENSE_TIC
   2    GND      B @S9S_MB_2U_LIB.S9S_MB_2U(SCH_1):GND

Q_RES_0402LF-0,5%,1/16W,EMPTY,A  I313  R3863
   1 P12V_OCP_SFF_ISENSE_MAM_MAM      A @S9S_MB_2U_LIB.S9S_MB_2U(SCH_1):P12V_OCP_SFF_ISENSE_MAM_MAM
   2 P12V_OCP_SFF_ISENSE_MAM      B @S9S_MB_2U_LIB.S9S_MB_2U(SCH_1):P12V_OCP_SFF_ISENSE_MAM

Q_RES_0402LF-0,5%,1/16W,EMPTY,A  I314  R3864
   1 P12V_OCP_SFF_ISENSE_MPS_MAM      A @S9S_MB_2U_LIB.S9S_MB_2U(SCH_1):P12V_OCP_SFF_ISENSE_MPS_MAM
   2 P12V_OCP_SFF_ISENSE_MAM      B @S9S_MB_2U_LIB.S9S_MB_2U(SCH_1):P12V_OCP_SFF_ISENSE_MAM

Q_RES_0402LF-0,5%,1/16W,EMPTY,A  I315  R3865
   1 P12V_OCP_SFF_ISENSE_MAM_TIC      A @S9S_MB_2U_LIB.S9S_MB_2U(SCH_1):P12V_OCP_SFF_ISENSE_MAM_TIC
   2 P12V_OCP_SFF_ISENSE_TIC      B @S9S_MB_2U_LIB.S9S_MB_2U(SCH_1):P12V_OCP_SFF_ISENSE_TIC

Q_RES_0402LF-0,5%,1/16W,CHIP,CA  I316  R3866
   1 P12V_OCP_SFF_ISENSE_MPS_TIC      A @S9S_MB_2U_LIB.S9S_MB_2U(SCH_1):P12V_OCP_SFF_ISENSE_MPS_TIC
   2 P12V_OCP_SFF_ISENSE_TIC      B @S9S_MB_2U_LIB.S9S_MB_2U(SCH_1):P12V_OCP_SFF_ISENSE_TIC

Q_RES_0402LF-0,5%,1/16W,EMPTY,A  I321  R3859
   1 P12V_OCP_V3_2_ISENSE_MAM_MAM      A @S9S_MB_2U_LIB.S9S_MB_2U(SCH_1):P12V_OCP_V3_2_ISENSE_MAM_MAM
   2 P12V_OCP_V3_2_ISENSE_MAM      B @S9S_MB_2U_LIB.S9S_MB_2U(SCH_1):P12V_OCP_V3_2_ISENSE_MAM

Q_RES_0402LF-0,5%,1/16W,EMPTY,A  I322  R3860
   1 P12V_OCP_V3_2_ISENSE_MPS_MAM      A @S9S_MB_2U_LIB.S9S_MB_2U(SCH_1):P12V_OCP_V3_2_ISENSE_MPS_MAM
   2 P12V_OCP_V3_2_ISENSE_MAM      B @S9S_MB_2U_LIB.S9S_MB_2U(SCH_1):P12V_OCP_V3_2_ISENSE_MAM

Q_RES_0402LF-0,5%,1/16W,EMPTY,A  I323  R3861
   1 P12V_OCP_V3_2_ISENSE_MAM_TIC      A @S9S_MB_2U_LIB.S9S_MB_2U(SCH_1):P12V_OCP_V3_2_ISENSE_MAM_TIC
   2 P12V_OCP_V3_2_ISENSE_TIC      B @S9S_MB_2U_LIB.S9S_MB_2U(SCH_1):P12V_OCP_V3_2_ISENSE_TIC

Q_RES_0402LF-0,5%,1/16W,CHIP,CA  I324  R3862
   1 P12V_OCP_V3_2_ISENSE_MPS_TIC      A @S9S_MB_2U_LIB.S9S_MB_2U(SCH_1):P12V_OCP_V3_2_ISENSE_MPS_TIC
   2 P12V_OCP_V3_2_ISENSE_TIC      B @S9S_MB_2U_LIB.S9S_MB_2U(SCH_1):P12V_OCP_V3_2_ISENSE_TIC

Q_RES_0402LF-0,5%,1/16W,EMPTY,A  I330  R3939
   1 P12V_E1S_0_ISENSE_MAM_MAM      A @S9S_MB_2U_LIB.S9S_MB_2U(SCH_1):P12V_E1S_0_ISENSE_MAM_MAM
   2 P12V_E1S_0_ISENSE_MAM      B @S9S_MB_2U_LIB.S9S_MB_2U(SCH_1):P12V_E1S_0_ISENSE_MAM

Q_CAP_0402-100PF,50V,5%,EMPTY,A  I333  C2195
   1 P12V_E1S_0_ISENSE_MAM      A @S9S_MB_2U_LIB.S9S_MB_2U(SCH_1):P12V_E1S_0_ISENSE_MAM
   2    GND      B @S9S_MB_2U_LIB.S9S_MB_2U(SCH_1):GND

Q_CAP_0402-0.1UF,25V,10%,X7R,CA  I336  C2194
   1 P12V_E1S_0_ISENSE_TIC      A @S9S_MB_2U_LIB.S9S_MB_2U(SCH_1):P12V_E1S_0_ISENSE_TIC
   2    GND      B @S9S_MB_2U_LIB.S9S_MB_2U(SCH_1):GND

Q_RES_0402LF-0,5%,1/16W,EMPTY,A  I337  R3940
   1 P12V_E1S_0_ISENSE_MPS_MAM      A @S9S_MB_2U_LIB.S9S_MB_2U(SCH_1):P12V_E1S_0_ISENSE_MPS_MAM
   2 P12V_E1S_0_ISENSE_MAM      B @S9S_MB_2U_LIB.S9S_MB_2U(SCH_1):P12V_E1S_0_ISENSE_MAM

Q_RES_0402LF-0,5%,1/16W,EMPTY,A  I338  R3941
   1 P12V_E1S_0_ISENSE_MAM_TIC      A @S9S_MB_2U_LIB.S9S_MB_2U(SCH_1):P12V_E1S_0_ISENSE_MAM_TIC
   2 P12V_E1S_0_ISENSE_TIC      B @S9S_MB_2U_LIB.S9S_MB_2U(SCH_1):P12V_E1S_0_ISENSE_TIC

Q_RES_0402LF-0,5%,1/16W,CHIP,CA  I339  R3942
   1 P12V_E1S_0_ISENSE_MPS_TIC      A @S9S_MB_2U_LIB.S9S_MB_2U(SCH_1):P12V_E1S_0_ISENSE_MPS_TIC
   2 P12V_E1S_0_ISENSE_TIC      B @S9S_MB_2U_LIB.S9S_MB_2U(SCH_1):P12V_E1S_0_ISENSE_TIC

Q_RES_0402LF-4.7K,1%,1/16W,CHIA  I346  R4568
   1 P1V581_PDB_ADC      A @S9S_MB_2U_LIB.S9S_MB_2U(SCH_1):P1V581_PDB_ADC
   2    GND      B @S9S_MB_2U_LIB.S9S_MB_2U(SCH_1):GND

Q_RES_0402LF-5.11K,1%,1/16W,CHA  I348  R4567
   1 P3V3_PDB_AUX_ADC      A @S9S_MB_2U_LIB.S9S_MB_2U(SCH_1):P3V3_PDB_AUX_ADC
   2 P1V581_PDB_ADC      B @S9S_MB_2U_LIB.S9S_MB_2U(SCH_1):P1V581_PDB_ADC


DRAWING: @S9S_MB_2U_LIB.S9S_MB_2U(SCH_1):PAGE240 

INA183A1IDBVR-INA183A1IDBVR,SMA  I22  U103
   1    GND   GND0 @S9S_MB_2U_LIB.S9S_MB_2U(SCH_1):GND
   2    GND   GND1 @S9S_MB_2U_LIB.S9S_MB_2U(SCH_1):GND
   3 PVCCD_HV_CPU1_NVDIMM_ISENSE    OUT @S9S_MB_2U_LIB.S9S_MB_2U(SCH_1):PVCCD_HV_CPU1_NVDIMM_ISENSE
   4 P12V_AUX_CPU1_DIMM_ISEN_N    IN- @S9S_MB_2U_LIB.S9S_MB_2U(SCH_1):P12V_AUX_CPU1_DIMM_ISEN_N
   5 P12V_AUX_CPU1_DIMM_ISEN_P    IN+ @S9S_MB_2U_LIB.S9S_MB_2U(SCH_1):P12V_AUX_CPU1_DIMM_ISEN_P

Q_RES_4P_12-0.001,1%,3W,SMLF,CA  I3  R1837
   1 P12V_AUX      1 @S9S_MB_2U_LIB.S9S_MB_2U(SCH_1):P12V_AUX
   2 P12V_S3_AUX_CPU1_NVDIMM      2 @S9S_MB_2U_LIB.S9S_MB_2U(SCH_1):P12V_S3_AUX_CPU1_NVDIMM
   3 P12V_AUX_CPU1_DIMM_ISEN_P      3 @S9S_MB_2U_LIB.S9S_MB_2U(SCH_1):P12V_AUX_CPU1_DIMM_ISEN_P
   4 P12V_AUX_CPU1_DIMM_ISEN_N      4 @S9S_MB_2U_LIB.S9S_MB_2U(SCH_1):P12V_AUX_CPU1_DIMM_ISEN_N

Q_RES_4P_12-0.001,1%,3W,SMLF,CA  I11  R1838
   1 P12V_AUX      1 @S9S_MB_2U_LIB.S9S_MB_2U(SCH_1):P12V_AUX
   2 P12V_S3_AUX_CPU0_NVDIMM      2 @S9S_MB_2U_LIB.S9S_MB_2U(SCH_1):P12V_S3_AUX_CPU0_NVDIMM
   3 P12V_AUX_CPU0_DIMM_ISEN_P      3 @S9S_MB_2U_LIB.S9S_MB_2U(SCH_1):P12V_AUX_CPU0_DIMM_ISEN_P
   4 P12V_AUX_CPU0_DIMM_ISEN_N      4 @S9S_MB_2U_LIB.S9S_MB_2U(SCH_1):P12V_AUX_CPU0_DIMM_ISEN_N

Q_CAP_0402-0.1UF,25V,10%,EMPTYA  I15  C2363
   1 HSC_TYPE_ADC      A @S9S_MB_2U_LIB.S9S_MB_2U(SCH_1):HSC_TYPE_ADC
   2    GND      B @S9S_MB_2U_LIB.S9S_MB_2U(SCH_1):GND

Q_RES_0402LF-0,5%,1/16W,EMPTY,A  I16  R4691
   1 HSC_TYPE_ADC_A0      A @S9S_MB_2U_LIB.S9S_MB_2U(SCH_1):HSC_TYPE_ADC_A0
   2 SMB_HSC_TYPE_ADC_SDA      B @S9S_MB_2U_LIB.S9S_MB_2U(SCH_1):SMB_HSC_TYPE_ADC_SDA

Q_RES_0402LF-4.7K,1%,1/16W,EMPA  I18  R4688
   1    GND      A @S9S_MB_2U_LIB.S9S_MB_2U(SCH_1):GND
   2 HSC_TYPE_ADC_A0      B @S9S_MB_2U_LIB.S9S_MB_2U(SCH_1):HSC_TYPE_ADC_A0

Q_RES_0402LF-4.7K,1%,1/16W,EMPA  I19  R4687
   1    GND      A @S9S_MB_2U_LIB.S9S_MB_2U(SCH_1):GND
   2 HSC_TYPE_ADC_A1      B @S9S_MB_2U_LIB.S9S_MB_2U(SCH_1):HSC_TYPE_ADC_A1

INA183A1IDBVR-INA183A1IDBVR,SMA  I29  U102
   1    GND   GND0 @S9S_MB_2U_LIB.S9S_MB_2U(SCH_1):GND
   2    GND   GND1 @S9S_MB_2U_LIB.S9S_MB_2U(SCH_1):GND
   3 PVCCD_HV_CPU0_NVDIMM_ISENSE    OUT @S9S_MB_2U_LIB.S9S_MB_2U(SCH_1):PVCCD_HV_CPU0_NVDIMM_ISENSE
   4 P12V_AUX_CPU0_DIMM_ISEN_N    IN- @S9S_MB_2U_LIB.S9S_MB_2U(SCH_1):P12V_AUX_CPU0_DIMM_ISEN_N
   5 P12V_AUX_CPU0_DIMM_ISEN_P    IN+ @S9S_MB_2U_LIB.S9S_MB_2U(SCH_1):P12V_AUX_CPU0_DIMM_ISEN_P

Q_CAP_0402-0.1UF,25V,10%,EMPTYA  I33  C2364
   1 P3V3_AUX      A @S9S_MB_2U_LIB.S9S_MB_2U(SCH_1):P3V3_AUX
   2    GND      B @S9S_MB_2U_LIB.S9S_MB_2U(SCH_1):GND

Q_RES_0402LF-4.7K,1%,1/16W,EMPA  I35  R4692
   1 P3V3_AUX      A @S9S_MB_2U_LIB.S9S_MB_2U(SCH_1):P3V3_AUX
   2 TP_HSC_TYPE_ADC_ALERT      B @S9S_MB_2U_LIB.S9S_MB_2U(SCH_1):TP_HSC_TYPE_ADC_ALERT

Q_RES_0402LF-33.2,1%,1/16W,EMPA  I37  R4690
   1 SMB_LM75_0_3V3AUX_SDA      A @S9S_MB_2U_LIB.S9S_MB_2U(SCH_1):SMB_LM75_0_3V3AUX_SDA
   2 SMB_HSC_TYPE_ADC_SDA      B @S9S_MB_2U_LIB.S9S_MB_2U(SCH_1):SMB_HSC_TYPE_ADC_SDA

Q_RES_0402LF-33.2,1%,1/16W,EMPA  I38  R4689
   1 SMB_LM75_0_3V3AUX_SCL      A @S9S_MB_2U_LIB.S9S_MB_2U(SCH_1):SMB_LM75_0_3V3AUX_SCL
   2 SMB_HSC_TYPE_ADC_SCL      B @S9S_MB_2U_LIB.S9S_MB_2U(SCH_1):SMB_HSC_TYPE_ADC_SCL

INA230AIRGTR-INA230AIRGTR,SMLFA  I39  U331
   9 P3V3_AUX     VS @S9S_MB_2U_LIB.S9S_MB_2U(SCH_1):P3V3_AUX
   1 HSC_TYPE_ADC_A1     A1 @S9S_MB_2U_LIB.S9S_MB_2U(SCH_1):HSC_TYPE_ADC_A1
   2 HSC_TYPE_ADC_A0     A0 @S9S_MB_2U_LIB.S9S_MB_2U(SCH_1):HSC_TYPE_ADC_A0
   5 SMB_HSC_TYPE_ADC_SCL    SCL @S9S_MB_2U_LIB.S9S_MB_2U(SCH_1):SMB_HSC_TYPE_ADC_SCL
   4 SMB_HSC_TYPE_ADC_SDA    SDA @S9S_MB_2U_LIB.S9S_MB_2U(SCH_1):SMB_HSC_TYPE_ADC_SDA
  11 HSC_TYPE_ADC    BUS @S9S_MB_2U_LIB.S9S_MB_2U(SCH_1):HSC_TYPE_ADC
  13 NC_HSC_TYPE_VINP    IN+ @S9S_MB_2U_LIB.S9S_MB_2U(SCH_1):NC_HSC_TYPE_VINP
  12 NC_HSC_TYPE_VINM    IN- @S9S_MB_2U_LIB.S9S_MB_2U(SCH_1):NC_HSC_TYPE_VINM
   3 TP_HSC_TYPE_ADC_ALERT  ALERT @S9S_MB_2U_LIB.S9S_MB_2U(SCH_1):TP_HSC_TYPE_ADC_ALERT
   6 NC_HSC_TYPE_NC0    NC0 @S9S_MB_2U_LIB.S9S_MB_2U(SCH_1):NC_HSC_TYPE_NC0
   7 NC_HSC_TYPE_NC1    NC1 @S9S_MB_2U_LIB.S9S_MB_2U(SCH_1):NC_HSC_TYPE_NC1
   8 NC_HSC_TYPE_NC2    NC2 @S9S_MB_2U_LIB.S9S_MB_2U(SCH_1):NC_HSC_TYPE_NC2
  14 NC_HSC_TYPE_NC3    NC3 @S9S_MB_2U_LIB.S9S_MB_2U(SCH_1):NC_HSC_TYPE_NC3
  15 NC_HSC_TYPE_NC4    NC4 @S9S_MB_2U_LIB.S9S_MB_2U(SCH_1):NC_HSC_TYPE_NC4
  16 NC_HSC_TYPE_NC5    NC5 @S9S_MB_2U_LIB.S9S_MB_2U(SCH_1):NC_HSC_TYPE_NC5
  10    GND    GND @S9S_MB_2U_LIB.S9S_MB_2U(SCH_1):GND
  TH    GND     TH @S9S_MB_2U_LIB.S9S_MB_2U(SCH_1):GND


DRAWING: @S9S_MB_2U_LIB.S9S_MB_2U(SCH_1):PAGE243 

Q_RES_0805LF-0,5%,1/8W,CHIP,CSA  I2  R1747
   1 P1V8_PCH_AUX      A @S9S_MB_2U_LIB.S9S_MB_2U(SCH_1):P1V8_PCH_AUX
   2 PGPPA_AUX      B @S9S_MB_2U_LIB.S9S_MB_2U(SCH_1):PGPPA_AUX

Q_CAP_C0805-22UF,16V,20%,X6S,CA  I4  C535
   1 PGPPA_AUX      A @S9S_MB_2U_LIB.S9S_MB_2U(SCH_1):PGPPA_AUX
   2    GND      B @S9S_MB_2U_LIB.S9S_MB_2U(SCH_1):GND

Q_CAP_C0805-22UF,16V,20%,X6S,CA  I5  C513
   1 PGPPA_AUX      A @S9S_MB_2U_LIB.S9S_MB_2U(SCH_1):PGPPA_AUX
   2    GND      B @S9S_MB_2U_LIB.S9S_MB_2U(SCH_1):GND

Q_RES_0402LF-10K,1%,1/16W,EMPTA  I7  R1763
   1 PGPPA_AUX      A @S9S_MB_2U_LIB.S9S_MB_2U(SCH_1):PGPPA_AUX
   2 FM_LPC_ESPI_SEL      B @S9S_MB_2U_LIB.S9S_MB_2U(SCH_1):FM_LPC_ESPI_SEL

Q_RES_0402LF-1K,1%,1/16W,EMPTYA  I8  R1764
   1 FM_LPC_ESPI_SEL      A @S9S_MB_2U_LIB.S9S_MB_2U(SCH_1):FM_LPC_ESPI_SEL
   2    GND      B @S9S_MB_2U_LIB.S9S_MB_2U(SCH_1):GND

Q_RES_0805LF-0,5%,1/8W,EMPTY,CA  I13  R1765
   1 PGPPA_AUX      A @S9S_MB_2U_LIB.S9S_MB_2U(SCH_1):PGPPA_AUX
   2 P3V3_AUX      B @S9S_MB_2U_LIB.S9S_MB_2U(SCH_1):P3V3_AUX

MOSFET_N_SMLF-BSS138K,BSS138K,A  I15  U307
   G FM_ESPI_PLD_R_EN_BUF_R   GATE @S9S_MB_2U_LIB.S9S_MB_2U(SCH_1):FM_ESPI_PLD_R_EN_BUF_R
   D FM_LPC_ESPI_SEL  DRAIN @S9S_MB_2U_LIB.S9S_MB_2U(SCH_1):FM_LPC_ESPI_SEL
   S    GND SOURCE @S9S_MB_2U_LIB.S9S_MB_2U(SCH_1):GND

Q_RES_0402LF-10K,1%,1/16W,CHIPA  I16  R4176
   1 P3V3_AUX      A @S9S_MB_2U_LIB.S9S_MB_2U(SCH_1):P3V3_AUX
   2 FM_LPC_ESPI_SEL      B @S9S_MB_2U_LIB.S9S_MB_2U(SCH_1):FM_LPC_ESPI_SEL

Q_RES_0402LF-0,5%,1/16W,CHIP,CA  I19  R4177
   1 FM_ESPI_PLD_R_EN_BUF_R      A @S9S_MB_2U_LIB.S9S_MB_2U(SCH_1):FM_ESPI_PLD_R_EN_BUF_R
   2 FM_ESPI_PLD_R_EN_BUF      B @S9S_MB_2U_LIB.S9S_MB_2U(SCH_1):FM_ESPI_PLD_R_EN_BUF


DRAWING: @S9S_MB_2U_LIB.S9S_MB_2U(SCH_1):PAGE244 

Q_RES_0402LF-11.8K,0.1%,1/16W,A  I25  PR91
   1 P5V_AUX_FB      A @S9S_MB_2U_LIB.S9S_MB_2U(SCH_1):P5V_AUX_FB
   2    GND      B @S9S_MB_2U_LIB.S9S_MB_2U(SCH_1):GND

Q_CAP_C0805-22UF,10V,20%,X6S,CA  I34  PC1856
   1 P5V_AUX      A @S9S_MB_2U_LIB.S9S_MB_2U(SCH_1):P5V_AUX
   2    GND      B @S9S_MB_2U_LIB.S9S_MB_2U(SCH_1):GND

Q_RES_0402LF-10K,1%,1/16W,CHIPA  I27  R2356
   1 P5V_AUX_VCC      A @S9S_MB_2U_LIB.S9S_MB_2U(SCH_1):P5V_AUX_VCC
   2 PWRGD_P5V_AUX_R      B @S9S_MB_2U_LIB.S9S_MB_2U(SCH_1):PWRGD_P5V_AUX_R

Q_RES_0402LF-0,5%,1/16W,CHIP,CA  I28  R2316
   1 PWRGD_P5V_AUX_R      A @S9S_MB_2U_LIB.S9S_MB_2U(SCH_1):PWRGD_P5V_AUX_R
   2 PWRGD_P5V_AUX      B @S9S_MB_2U_LIB.S9S_MB_2U(SCH_1):PWRGD_P5V_AUX

Q_INDUCTOR_SMLF-4.7UH,IND,CV-4A  I30  PL65
   2 P5V_AUX      2 @S9S_MB_2U_LIB.S9S_MB_2U(SCH_1):P5V_AUX
   1 SW_P5V_AUX_SW      1 @S9S_MB_2U_LIB.S9S_MB_2U(SCH_1):SW_P5V_AUX_SW

Q_RES_0402LF-0,5%,1/16W,CHIP,CA  I10  PR3337
   1 P5V_AUX_MODE      A @S9S_MB_2U_LIB.S9S_MB_2U(SCH_1):P5V_AUX_MODE
   2    GND      B @S9S_MB_2U_LIB.S9S_MB_2U(SCH_1):GND

Q_RES_0402LF-16.9K,1%,1/16W,CHA  I16  PR89
   1 P5V_AUX_CS      A @S9S_MB_2U_LIB.S9S_MB_2U(SCH_1):P5V_AUX_CS
   2    GND      B @S9S_MB_2U_LIB.S9S_MB_2U(SCH_1):GND

Q_CAP_C0805-22UF,16V,20%,X6S,CA  I12  PC1898
   1 SW_P5V_AUX_FLT      A @S9S_MB_2U_LIB.S9S_MB_2U(SCH_1):SW_P5V_AUX_FLT
   2    GND      B @S9S_MB_2U_LIB.S9S_MB_2U(SCH_1):GND

Q_CAP_C0402-0.22UF,25V,10%,X7RA  I26  PC1847
   1 SW_P5V_AUX_BST      A @S9S_MB_2U_LIB.S9S_MB_2U(SCH_1):SW_P5V_AUX_BST
   2 SW_P5V_AUX_SW      B @S9S_MB_2U_LIB.S9S_MB_2U(SCH_1):SW_P5V_AUX_SW

Q_CAP_C0402-100NF,50V,10%,X7R,A  I2  PC1648
   1 P12V_AUX      A @S9S_MB_2U_LIB.S9S_MB_2U(SCH_1):P12V_AUX
   2    GND      B @S9S_MB_2U_LIB.S9S_MB_2U(SCH_1):GND

Q_INDUCTOR_SMLF-BLM18SN220TN1DA  I5  PL64
   2 SW_P5V_AUX_FLT      2 @S9S_MB_2U_LIB.S9S_MB_2U(SCH_1):SW_P5V_AUX_FLT
   1 P12V_AUX      1 @S9S_MB_2U_LIB.S9S_MB_2U(SCH_1):P12V_AUX

Q_CAP_C0805-22UF,16V,20%,X6S,CA  I7  PC1849
   1 SW_P5V_AUX_FLT      A @S9S_MB_2U_LIB.S9S_MB_2U(SCH_1):SW_P5V_AUX_FLT
   2    GND      B @S9S_MB_2U_LIB.S9S_MB_2U(SCH_1):GND

Q_CAP_C0402-1UF,25V,10%,X6S,CHA  I8  PC1848
   1 P5V_AUX_VCC      A @S9S_MB_2U_LIB.S9S_MB_2U(SCH_1):P5V_AUX_VCC
   2    GND      B @S9S_MB_2U_LIB.S9S_MB_2U(SCH_1):GND

Q_CAP_C0805-22UF,16V,20%,X6S,CA  I11  PC1850
   1 SW_P5V_AUX_FLT      A @S9S_MB_2U_LIB.S9S_MB_2U(SCH_1):SW_P5V_AUX_FLT
   2    GND      B @S9S_MB_2U_LIB.S9S_MB_2U(SCH_1):GND

Q_CAP_C0402-1UF,16V,10%,X6S,CHA  I14  PC1846
   1 SW_P5V_AUX_FLT      A @S9S_MB_2U_LIB.S9S_MB_2U(SCH_1):SW_P5V_AUX_FLT
   2    GND      B @S9S_MB_2U_LIB.S9S_MB_2U(SCH_1):GND

RS53318LR-RS53318LR,SMLF,IC,ALA  I20  PU181
  10 SW_P5V_AUX_FLT   VIN1 @S9S_MB_2U_LIB.S9S_MB_2U(SCH_1):SW_P5V_AUX_FLT
   9 PWRGD_P5V_AUX_R  PGOOD @S9S_MB_2U_LIB.S9S_MB_2U(SCH_1):PWRGD_P5V_AUX_R
11_18    GND   PGND @S9S_MB_2U_LIB.S9S_MB_2U(SCH_1):GND
   8 PWRGD_P3V3_AUX     EN @S9S_MB_2U_LIB.S9S_MB_2U(SCH_1):PWRGD_P3V3_AUX
   1 SW_P5V_AUX_BST    BST @S9S_MB_2U_LIB.S9S_MB_2U(SCH_1):SW_P5V_AUX_BST
   7 P5V_AUX_FB     FB @S9S_MB_2U_LIB.S9S_MB_2U(SCH_1):P5V_AUX_FB
   2    GND   AGND @S9S_MB_2U_LIB.S9S_MB_2U(SCH_1):GND
  19 P5V_AUX_VCC    VCC @S9S_MB_2U_LIB.S9S_MB_2U(SCH_1):P5V_AUX_VCC
   6    GND    RTN @S9S_MB_2U_LIB.S9S_MB_2U(SCH_1):GND
  20 SW_P5V_AUX_SW     SW @S9S_MB_2U_LIB.S9S_MB_2U(SCH_1):SW_P5V_AUX_SW
   5 P5V_AUX_REF    REF @S9S_MB_2U_LIB.S9S_MB_2U(SCH_1):P5V_AUX_REF
   4 P5V_AUX_MODE   MODE @S9S_MB_2U_LIB.S9S_MB_2U(SCH_1):P5V_AUX_MODE
   3 P5V_AUX_CS     CS @S9S_MB_2U_LIB.S9S_MB_2U(SCH_1):P5V_AUX_CS
  21 SW_P5V_AUX_FLT   VIN2 @S9S_MB_2U_LIB.S9S_MB_2U(SCH_1):SW_P5V_AUX_FLT

Q_CAP_0402-0.1UF,25V,10%,X7R,CA  I21  PC1853
   1 P5V_AUX_REF      A @S9S_MB_2U_LIB.S9S_MB_2U(SCH_1):P5V_AUX_REF
   2    GND      B @S9S_MB_2U_LIB.S9S_MB_2U(SCH_1):GND

Q_CAP_0402-47PF,50V,5%,NPO,TMPA  I22  PC1877
   1 P5V_AUX_FB      A @S9S_MB_2U_LIB.S9S_MB_2U(SCH_1):P5V_AUX_FB
   2 P5V_AUX      B @S9S_MB_2U_LIB.S9S_MB_2U(SCH_1):P5V_AUX

Q_CAPP_SMLF-220UF,6.3V,20%,ALUA  I32  PC1845
   1 P5V_AUX      A @S9S_MB_2U_LIB.S9S_MB_2U(SCH_1):P5V_AUX
   2    GND      B @S9S_MB_2U_LIB.S9S_MB_2U(SCH_1):GND

Q_CAP_C0805-22UF,10V,20%,X6S,CA  I33  PC1855
   1 P5V_AUX      A @S9S_MB_2U_LIB.S9S_MB_2U(SCH_1):P5V_AUX
   2    GND      B @S9S_MB_2U_LIB.S9S_MB_2U(SCH_1):GND

Q_CAP_0402-0.1UF,25V,10%,X7R,CA  I36  PC1852
   1 P5V_AUX      A @S9S_MB_2U_LIB.S9S_MB_2U(SCH_1):P5V_AUX
   2    GND      B @S9S_MB_2U_LIB.S9S_MB_2U(SCH_1):GND

Q_RES_0402LF-88.7K,1%,1/16W,CHA  I39  PR92
   1 P5V_AUX_FB      A @S9S_MB_2U_LIB.S9S_MB_2U(SCH_1):P5V_AUX_FB
   2 P5V_AUX      B @S9S_MB_2U_LIB.S9S_MB_2U(SCH_1):P5V_AUX


DRAWING: @S9S_MB_2U_LIB.S9S_MB_2U(SCH_1):PAGE248 

Q_CAP_0402-1000PF,50V,5%,EMPTYA  I8  PC2286
   1 FM_P1V05_PCH_AUX_R_EN      A @S9S_MB_2U_LIB.S9S_MB_2U(SCH_1):FM_P1V05_PCH_AUX_R_EN
   2    GND      B @S9S_MB_2U_LIB.S9S_MB_2U(SCH_1):GND

Q_CAP_C0402-1UF,16V,10%,X6S,CHA  I30  PC1219
   1 SW_P12V_AUX_P1V05_PCH_AUX_FLT      A @S9S_MB_2U_LIB.S9S_MB_2U(SCH_1):SW_P12V_AUX_P1V05_PCH_AUX_FLT
   2    GND      B @S9S_MB_2U_LIB.S9S_MB_2U(SCH_1):GND

Q_RES_0402LF-10K,0.1%,1/16W,CHA  I34  PR187
   1 P1V05_PCH_AUX_FB      A @S9S_MB_2U_LIB.S9S_MB_2U(SCH_1):P1V05_PCH_AUX_FB
   2 SH_P1V05_PCH_AUX_N      B @S9S_MB_2U_LIB.S9S_MB_2U(SCH_1):SH_P1V05_PCH_AUX_N

Q_CAP_0402-680PF,50V,10%,X7R,TA  I35  PC1223
   1 P1V05_PCH_AUX_FB      A @S9S_MB_2U_LIB.S9S_MB_2U(SCH_1):P1V05_PCH_AUX_FB
   2 SH_P1V05_PCH_AUX_P      B @S9S_MB_2U_LIB.S9S_MB_2U(SCH_1):SH_P1V05_PCH_AUX_P

Q_RES_0402LF-7.32K,0.1%,1/16W,A  I36  PR1328
   1 P1V05_PCH_AUX_FB      A @S9S_MB_2U_LIB.S9S_MB_2U(SCH_1):P1V05_PCH_AUX_FB
   2 SH_P1V05_PCH_AUX_P      B @S9S_MB_2U_LIB.S9S_MB_2U(SCH_1):SH_P1V05_PCH_AUX_P

Q_CAP_0402-0.01UF,25V,10%,X7R,A  I37  PC2279
   1 SH_P1V05_PCH_AUX_P      A @S9S_MB_2U_LIB.S9S_MB_2U(SCH_1):SH_P1V05_PCH_AUX_P
   2 SH_P1V05_PCH_AUX_N      B @S9S_MB_2U_LIB.S9S_MB_2U(SCH_1):SH_P1V05_PCH_AUX_N

Q_CAPP_THLF-560UF,2.5V,20%,OSCA  I41  PC1227
   1 P1V05_PCH_AUX      A @S9S_MB_2U_LIB.S9S_MB_2U(SCH_1):P1V05_PCH_AUX
   2    GND      B @S9S_MB_2U_LIB.S9S_MB_2U(SCH_1):GND

Q_SHORT_SM-EMPTY,SHORT6  I43  PJ62
   1 SH_P1V05_PCH_AUX_P      1 @S9S_MB_2U_LIB.S9S_MB_2U(SCH_1):SH_P1V05_PCH_AUX_P
   2 P1V05_PCH_AUX      2 @S9S_MB_2U_LIB.S9S_MB_2U(SCH_1):P1V05_PCH_AUX

Q_RES_0402LF-2K,1%,1/16W,CHIP,A  I9  PR1649
   1 FM_P1V05_PCH_AUX_R_EN      A @S9S_MB_2U_LIB.S9S_MB_2U(SCH_1):FM_P1V05_PCH_AUX_R_EN
   2    GND      B @S9S_MB_2U_LIB.S9S_MB_2U(SCH_1):GND

Q_CAPP_SMLF-100UF,16V,20%,OSCOA  I23  PC1215
   1 SW_P12V_AUX_P1V05_PCH_AUX_FLT      A @S9S_MB_2U_LIB.S9S_MB_2U(SCH_1):SW_P12V_AUX_P1V05_PCH_AUX_FLT
   2    GND      B @S9S_MB_2U_LIB.S9S_MB_2U(SCH_1):GND

Q_RES_0402LF-10K,1%,1/16W,EMPTA  I26  PR1647
   1 P3V3_AUX      A @S9S_MB_2U_LIB.S9S_MB_2U(SCH_1):P3V3_AUX
   2 FM_P1V05_PCH_AUX_R_EN      B @S9S_MB_2U_LIB.S9S_MB_2U(SCH_1):FM_P1V05_PCH_AUX_R_EN

Q_CAP_C0805-47UF,4V,20%,X6S,CHA  I44  PC1225
   1 P1V05_PCH_AUX      A @S9S_MB_2U_LIB.S9S_MB_2U(SCH_1):P1V05_PCH_AUX
   2    GND      B @S9S_MB_2U_LIB.S9S_MB_2U(SCH_1):GND

Q_RES_0402LF-0,5%,1/16W,CHIP,CA  I51  R1650
   1 PWRGD_P1V05_PCH_AUX_R      A @S9S_MB_2U_LIB.S9S_MB_2U(SCH_1):PWRGD_P1V05_PCH_AUX_R
   2 PWRGD_P1V05_PCH_AUX      B @S9S_MB_2U_LIB.S9S_MB_2U(SCH_1):PWRGD_P1V05_PCH_AUX

Q_CAP_C0805-22UF,16V,20%,X6S,CA  I29  PC1218
   1 SW_P12V_AUX_P1V05_PCH_AUX_FLT      A @S9S_MB_2U_LIB.S9S_MB_2U(SCH_1):SW_P12V_AUX_P1V05_PCH_AUX_FLT
   2    GND      B @S9S_MB_2U_LIB.S9S_MB_2U(SCH_1):GND

Q_CAP_C0402-0.22UF,25V,10%,X7RA  I31  PC1222
   1 SW_P1V05_PCH_AUX_BST      A @S9S_MB_2U_LIB.S9S_MB_2U(SCH_1):SW_P1V05_PCH_AUX_BST
   2 SW_P1V05_PCH_AUX_SW      B @S9S_MB_2U_LIB.S9S_MB_2U(SCH_1):SW_P1V05_PCH_AUX_SW

Q_RES_0402LF-10K,1%,1/16W,CHIPA  I32  R2357
   1 P3V3_AUX      A @S9S_MB_2U_LIB.S9S_MB_2U(SCH_1):P3V3_AUX
   2 PWRGD_P1V05_PCH_AUX_R      B @S9S_MB_2U_LIB.S9S_MB_2U(SCH_1):PWRGD_P1V05_PCH_AUX_R

Q_SHORT_SM-EMPTY,SHORT6  I42  PJ63
   1 SH_P1V05_PCH_AUX_N      1 @S9S_MB_2U_LIB.S9S_MB_2U(SCH_1):SH_P1V05_PCH_AUX_N
   2    GND      2 @S9S_MB_2U_LIB.S9S_MB_2U(SCH_1):GND

Q_INDUCTOR_SMLF-300NH/33A,IND,A  I53  PL150
   2 P1V05_PCH_AUX      2 @S9S_MB_2U_LIB.S9S_MB_2U(SCH_1):P1V05_PCH_AUX
   1 SW_P1V05_PCH_AUX_SW      1 @S9S_MB_2U_LIB.S9S_MB_2U(SCH_1):SW_P1V05_PCH_AUX_SW

Q_RES_0402LF-0,5%,1/16W,CHIP,CA  I27  R1389
   1 FM_P1V05_PCH_AUX_EN      A @S9S_MB_2U_LIB.S9S_MB_2U(SCH_1):FM_P1V05_PCH_AUX_EN
   2 FM_P1V05_PCH_AUX_R_EN      B @S9S_MB_2U_LIB.S9S_MB_2U(SCH_1):FM_P1V05_PCH_AUX_R_EN

Q_CAP_C0805-47UF,4V,20%,X6S,CHA  I45  PC1226
   1 P1V05_PCH_AUX      A @S9S_MB_2U_LIB.S9S_MB_2U(SCH_1):P1V05_PCH_AUX
   2    GND      B @S9S_MB_2U_LIB.S9S_MB_2U(SCH_1):GND

Q_RES_0402LF-0,5%,1/16W,CHIP,CA  I3  PR1326
   1 P3V3_AUX      A @S9S_MB_2U_LIB.S9S_MB_2U(SCH_1):P3V3_AUX
   2 P1V05_PCH_AUX_VCC      B @S9S_MB_2U_LIB.S9S_MB_2U(SCH_1):P1V05_PCH_AUX_VCC

Q_RES_0402LF-8.45K,1%,1/16W,CHA  I6  PR1327
   1 P1V05_PCH_AUX_CS      A @S9S_MB_2U_LIB.S9S_MB_2U(SCH_1):P1V05_PCH_AUX_CS
   2    GND      B @S9S_MB_2U_LIB.S9S_MB_2U(SCH_1):GND

RS53319LR-RS53319LR,SMLF,IC,ALA  I11  PU73
  10 SW_P12V_AUX_P1V05_PCH_AUX_FLT   VIN1 @S9S_MB_2U_LIB.S9S_MB_2U(SCH_1):SW_P12V_AUX_P1V05_PCH_AUX_FLT
   9 PWRGD_P1V05_PCH_AUX_R  PGOOD @S9S_MB_2U_LIB.S9S_MB_2U(SCH_1):PWRGD_P1V05_PCH_AUX_R
11_18    GND   PGND @S9S_MB_2U_LIB.S9S_MB_2U(SCH_1):GND
   8 FM_P1V05_PCH_AUX_R_EN     EN @S9S_MB_2U_LIB.S9S_MB_2U(SCH_1):FM_P1V05_PCH_AUX_R_EN
   1 SW_P1V05_PCH_AUX_BST    BST @S9S_MB_2U_LIB.S9S_MB_2U(SCH_1):SW_P1V05_PCH_AUX_BST
   7 P1V05_PCH_AUX_FB     FB @S9S_MB_2U_LIB.S9S_MB_2U(SCH_1):P1V05_PCH_AUX_FB
   2    GND   AGND @S9S_MB_2U_LIB.S9S_MB_2U(SCH_1):GND
  19 P1V05_PCH_AUX_VCC    VCC @S9S_MB_2U_LIB.S9S_MB_2U(SCH_1):P1V05_PCH_AUX_VCC
   6 SH_P1V05_PCH_AUX_N    RTN @S9S_MB_2U_LIB.S9S_MB_2U(SCH_1):SH_P1V05_PCH_AUX_N
  20 SW_P1V05_PCH_AUX_SW     SW @S9S_MB_2U_LIB.S9S_MB_2U(SCH_1):SW_P1V05_PCH_AUX_SW
   5 P1V05_PCH_AUX_REF    REF @S9S_MB_2U_LIB.S9S_MB_2U(SCH_1):P1V05_PCH_AUX_REF
   4 P1V05_PCH_AUX_MODE   MODE @S9S_MB_2U_LIB.S9S_MB_2U(SCH_1):P1V05_PCH_AUX_MODE
   3 P1V05_PCH_AUX_CS     CS @S9S_MB_2U_LIB.S9S_MB_2U(SCH_1):P1V05_PCH_AUX_CS
  21 SW_P12V_AUX_P1V05_PCH_AUX_FLT   VIN2 @S9S_MB_2U_LIB.S9S_MB_2U(SCH_1):SW_P12V_AUX_P1V05_PCH_AUX_FLT

Q_CAP_C0402-100NF,50V,10%,X7R,A  I18  PC1650
   1 P12V_AUX      A @S9S_MB_2U_LIB.S9S_MB_2U(SCH_1):P12V_AUX
   2    GND      B @S9S_MB_2U_LIB.S9S_MB_2U(SCH_1):GND

Q_CAP_C0805-22UF,16V,20%,X6S,CA  I28  PC1217
   1 SW_P12V_AUX_P1V05_PCH_AUX_FLT      A @S9S_MB_2U_LIB.S9S_MB_2U(SCH_1):SW_P12V_AUX_P1V05_PCH_AUX_FLT
   2    GND      B @S9S_MB_2U_LIB.S9S_MB_2U(SCH_1):GND

Q_CAPP_SMLF-330UF,2V,35%,SPCAPA  I47  PC1229
   1 P1V05_PCH_AUX      A @S9S_MB_2U_LIB.S9S_MB_2U(SCH_1):P1V05_PCH_AUX
   2    GND      B @S9S_MB_2U_LIB.S9S_MB_2U(SCH_1):GND

Q_CAP_C0402-1UF,25V,10%,X6S,CHA  I2  PC113
   1 P1V05_PCH_AUX_VCC      A @S9S_MB_2U_LIB.S9S_MB_2U(SCH_1):P1V05_PCH_AUX_VCC
   2    GND      B @S9S_MB_2U_LIB.S9S_MB_2U(SCH_1):GND

Q_RES_0402LF-0,5%,1/16W,CHIP,CA  I10  PR338
   1 P1V05_PCH_AUX_MODE      A @S9S_MB_2U_LIB.S9S_MB_2U(SCH_1):P1V05_PCH_AUX_MODE
   2    GND      B @S9S_MB_2U_LIB.S9S_MB_2U(SCH_1):GND

Q_CAP_0402-0.022UF,16V,10%,X7RA  I14  PC2000
   1 P1V05_PCH_AUX_REF      A @S9S_MB_2U_LIB.S9S_MB_2U(SCH_1):P1V05_PCH_AUX_REF
   2    GND      B @S9S_MB_2U_LIB.S9S_MB_2U(SCH_1):GND

Q_CAP_0402-0.1UF,25V,10%,X7R,CA  I16  PC1221
   1 P1V05_PCH_AUX_REF      A @S9S_MB_2U_LIB.S9S_MB_2U(SCH_1):P1V05_PCH_AUX_REF
   2 SH_P1V05_PCH_AUX_N      B @S9S_MB_2U_LIB.S9S_MB_2U(SCH_1):SH_P1V05_PCH_AUX_N

Q_INDUCTOR_SMLF-100NH/16A,IND,A  I19  PL110
   2 SW_P12V_AUX_P1V05_PCH_AUX_FLT      2 @S9S_MB_2U_LIB.S9S_MB_2U(SCH_1):SW_P12V_AUX_P1V05_PCH_AUX_FLT
   1 P12V_AUX      1 @S9S_MB_2U_LIB.S9S_MB_2U(SCH_1):P12V_AUX

Q_CAP_C0805-22UF,16V,20%,X6S,CA  I25  PC1216
   1 SW_P12V_AUX_P1V05_PCH_AUX_FLT      A @S9S_MB_2U_LIB.S9S_MB_2U(SCH_1):SW_P12V_AUX_P1V05_PCH_AUX_FLT
   2    GND      B @S9S_MB_2U_LIB.S9S_MB_2U(SCH_1):GND

Q_CAP_0402-0.1UF,25V,10%,X7R,CA  I38  PC1224
   1 P1V05_PCH_AUX      A @S9S_MB_2U_LIB.S9S_MB_2U(SCH_1):P1V05_PCH_AUX
   2    GND      B @S9S_MB_2U_LIB.S9S_MB_2U(SCH_1):GND

Q_CAPP_SMLF-330UF,2V,35%,SPCAPA  I40  PC117
   1 P1V05_PCH_AUX      A @S9S_MB_2U_LIB.S9S_MB_2U(SCH_1):P1V05_PCH_AUX
   2    GND      B @S9S_MB_2U_LIB.S9S_MB_2U(SCH_1):GND

Q_CAPP_THLF-560UF,2.5V,20%,OSCA  I48  PC1230
   1 P1V05_PCH_AUX      A @S9S_MB_2U_LIB.S9S_MB_2U(SCH_1):P1V05_PCH_AUX
   2    GND      B @S9S_MB_2U_LIB.S9S_MB_2U(SCH_1):GND

Q_RES_0402LF-0,5%,1/16W,CHIP,CA  I52  R4780
   1 PWRGD_P1V05_PCH_AUX_R      A @S9S_MB_2U_LIB.S9S_MB_2U(SCH_1):PWRGD_P1V05_PCH_AUX_R
   2 PWRGD_PVNN_PCH_AUX      B @S9S_MB_2U_LIB.S9S_MB_2U(SCH_1):PWRGD_PVNN_PCH_AUX


DRAWING: @S9S_MB_2U_LIB.S9S_MB_2U(SCH_1):PAGE249 

NB682GDZ-NB682GD-Z,SMLF,IC,AL0A  I26  PU74
   1 SW_P1V8_PCH_AUX_FLT    VIN @S9S_MB_2U_LIB.S9S_MB_2U(SCH_1):SW_P1V8_PCH_AUX_FLT
  13 PWRGD_P1V8_PCH_AUX_R     PG @S9S_MB_2U_LIB.S9S_MB_2U(SCH_1):PWRGD_P1V8_PCH_AUX_R
   2    GND   PGND @S9S_MB_2U_LIB.S9S_MB_2U(SCH_1):GND
   5 FM_PCH_P1V8_AUX_EN_R     EN @S9S_MB_2U_LIB.S9S_MB_2U(SCH_1):FM_PCH_P1V8_AUX_EN_R
   9 SW_P1V8_PCH_AUX_BST    BST @S9S_MB_2U_LIB.S9S_MB_2U(SCH_1):SW_P1V8_PCH_AUX_BST
  11    GND   AGND @S9S_MB_2U_LIB.S9S_MB_2U(SCH_1):GND
   6 P1V8_PCH_AUX_VCC    LP# @S9S_MB_2U_LIB.S9S_MB_2U(SCH_1):P1V8_PCH_AUX_VCC
   3 P1V8_PCH_AUX_VCC     C1 @S9S_MB_2U_LIB.S9S_MB_2U(SCH_1):P1V8_PCH_AUX_VCC
   4    GND     C0 @S9S_MB_2U_LIB.S9S_MB_2U(SCH_1):GND
   7 P1V8_PCH_AUX_MODE   MODE @S9S_MB_2U_LIB.S9S_MB_2U(SCH_1):P1V8_PCH_AUX_MODE
  12 P1V8_PCH_AUX   VOUT @S9S_MB_2U_LIB.S9S_MB_2U(SCH_1):P1V8_PCH_AUX
   8 SW_P1V8_PCH_AUX_SW     SW @S9S_MB_2U_LIB.S9S_MB_2U(SCH_1):SW_P1V8_PCH_AUX_SW
  10 P1V8_PCH_AUX_VCC    3V3 @S9S_MB_2U_LIB.S9S_MB_2U(SCH_1):P1V8_PCH_AUX_VCC

Q_CAP_C0402-100NF,50V,10%,X7R,A  I28  PC1236
   1 P1V8_PCH_AUX      A @S9S_MB_2U_LIB.S9S_MB_2U(SCH_1):P1V8_PCH_AUX
   2    GND      B @S9S_MB_2U_LIB.S9S_MB_2U(SCH_1):GND

Q_CAP_C0402-0.22UF,25V,10%,X7RA  I30  PC1235
   1 SW_P1V8_PCH_AUX_BST      A @S9S_MB_2U_LIB.S9S_MB_2U(SCH_1):SW_P1V8_PCH_AUX_BST
   2 SW_P1V8_PCH_AUX_SW      B @S9S_MB_2U_LIB.S9S_MB_2U(SCH_1):SW_P1V8_PCH_AUX_SW

Q_CAP_C0805-22UF,4V,20%,X6S,CHA  I39  PC1240
   1 P1V8_PCH_AUX      A @S9S_MB_2U_LIB.S9S_MB_2U(SCH_1):P1V8_PCH_AUX
   2    GND      B @S9S_MB_2U_LIB.S9S_MB_2U(SCH_1):GND

Q_RES_0402LF-0,5%,1/16W,CHIP,CA  I8  PR395
   1 P3V3_AUX      A @S9S_MB_2U_LIB.S9S_MB_2U(SCH_1):P3V3_AUX
   2 PVCC1_AUX      B @S9S_MB_2U_LIB.S9S_MB_2U(SCH_1):PVCC1_AUX

Q_CAP_C0402-100NF,50V,10%,X7R,A  I14  PC1651
   1 P12V_AUX      A @S9S_MB_2U_LIB.S9S_MB_2U(SCH_1):P12V_AUX
   2    GND      B @S9S_MB_2U_LIB.S9S_MB_2U(SCH_1):GND

Q_RES_0402LF-150K,1%,1/16W,CHIA  I24  PR1330
   1 P1V8_PCH_AUX_MODE      A @S9S_MB_2U_LIB.S9S_MB_2U(SCH_1):P1V8_PCH_AUX_MODE
   2    GND      B @S9S_MB_2U_LIB.S9S_MB_2U(SCH_1):GND

Q_CAP_C0402-1UF,25V,10%,X6S,CHA  I4  PC1642
   1 P1V8_PCH_AUX_VCC      A @S9S_MB_2U_LIB.S9S_MB_2U(SCH_1):P1V8_PCH_AUX_VCC
   2    GND      B @S9S_MB_2U_LIB.S9S_MB_2U(SCH_1):GND

Q_RES_0402LF-0,5%,1/16W,CHIP,CA  I17  R2358
   1 FM_PCH_P1V8_AUX_EN      A @S9S_MB_2U_LIB.S9S_MB_2U(SCH_1):FM_PCH_P1V8_AUX_EN
   2 FM_PCH_P1V8_AUX_EN_R      B @S9S_MB_2U_LIB.S9S_MB_2U(SCH_1):FM_PCH_P1V8_AUX_EN_R

Q_CAP_C0402-100NF,50V,10%,X7R,A  I21  PC1234
   1 SW_P1V8_PCH_AUX_FLT      A @S9S_MB_2U_LIB.S9S_MB_2U(SCH_1):SW_P1V8_PCH_AUX_FLT
   2    GND      B @S9S_MB_2U_LIB.S9S_MB_2U(SCH_1):GND

Q_CAP_C0805-22UF,4V,20%,X6S,CHA  I29  PC1237
   1 P1V8_PCH_AUX      A @S9S_MB_2U_LIB.S9S_MB_2U(SCH_1):P1V8_PCH_AUX
   2    GND      B @S9S_MB_2U_LIB.S9S_MB_2U(SCH_1):GND

Q_CAP_C0402-0.01UF,50V,10%,X7RA  I36  C2287
   1 PWRGD_P1V8_PCH_AUX      A @S9S_MB_2U_LIB.S9S_MB_2U(SCH_1):PWRGD_P1V8_PCH_AUX
   2    GND      B @S9S_MB_2U_LIB.S9S_MB_2U(SCH_1):GND

Q_CAP_C0805-22UF,4V,20%,X6S,CHA  I37  PC1238
   1 P1V8_PCH_AUX      A @S9S_MB_2U_LIB.S9S_MB_2U(SCH_1):P1V8_PCH_AUX
   2    GND      B @S9S_MB_2U_LIB.S9S_MB_2U(SCH_1):GND

Q_CAP_C0805-22UF,4V,20%,X6S,CHA  I38  PC1239
   1 P1V8_PCH_AUX      A @S9S_MB_2U_LIB.S9S_MB_2U(SCH_1):P1V8_PCH_AUX
   2    GND      B @S9S_MB_2U_LIB.S9S_MB_2U(SCH_1):GND

Q_RES_0402LF-0,5%,1/16W,EMPTY,A  I2  PR396
   1 P5V_AUX      A @S9S_MB_2U_LIB.S9S_MB_2U(SCH_1):P5V_AUX
   2 PVCC1_AUX      B @S9S_MB_2U_LIB.S9S_MB_2U(SCH_1):PVCC1_AUX

Q_RES_0402LF-5.1,5%,1/16W,CHIPA  I5  PR1329
   1 PVCC1_AUX      A @S9S_MB_2U_LIB.S9S_MB_2U(SCH_1):PVCC1_AUX
   2 P1V8_PCH_AUX_VCC      B @S9S_MB_2U_LIB.S9S_MB_2U(SCH_1):P1V8_PCH_AUX_VCC

Q_RES_0402LF-1K,1%,1/16W,EMPTYA  I11  PR1850
   1    GND      A @S9S_MB_2U_LIB.S9S_MB_2U(SCH_1):GND
   2 FM_PCH_P1V8_AUX_EN_R      B @S9S_MB_2U_LIB.S9S_MB_2U(SCH_1):FM_PCH_P1V8_AUX_EN_R

Q_INDUCTOR_SMLF-BLM18SN220TN1DA  I16  PL16
   2 SW_P1V8_PCH_AUX_FLT      2 @S9S_MB_2U_LIB.S9S_MB_2U(SCH_1):SW_P1V8_PCH_AUX_FLT
   1 P12V_AUX      1 @S9S_MB_2U_LIB.S9S_MB_2U(SCH_1):P12V_AUX

Q_CAP_C0805-10UF,16V,10%,X6S,CB  I19  PC1232
   1 SW_P1V8_PCH_AUX_FLT      A @S9S_MB_2U_LIB.S9S_MB_2U(SCH_1):SW_P1V8_PCH_AUX_FLT
   2    GND      B @S9S_MB_2U_LIB.S9S_MB_2U(SCH_1):GND

Q_CAP_C0805-10UF,16V,10%,X6S,CB  I20  PC1233
   1 SW_P1V8_PCH_AUX_FLT      A @S9S_MB_2U_LIB.S9S_MB_2U(SCH_1):SW_P1V8_PCH_AUX_FLT
   2    GND      B @S9S_MB_2U_LIB.S9S_MB_2U(SCH_1):GND

Q_RES_0402LF-10K,1%,1/16W,CHIPA  I31  R2359
   1 P3V3_AUX      A @S9S_MB_2U_LIB.S9S_MB_2U(SCH_1):P3V3_AUX
   2 PWRGD_P1V8_PCH_AUX_R      B @S9S_MB_2U_LIB.S9S_MB_2U(SCH_1):PWRGD_P1V8_PCH_AUX_R

Q_RES_0402LF-0,5%,1/16W,CHIP,CA  I34  R2360
   1 PWRGD_P1V8_PCH_AUX_R      A @S9S_MB_2U_LIB.S9S_MB_2U(SCH_1):PWRGD_P1V8_PCH_AUX_R
   2 PWRGD_P1V8_PCH_AUX      B @S9S_MB_2U_LIB.S9S_MB_2U(SCH_1):PWRGD_P1V8_PCH_AUX

Q_CAP_C0805-22UF,4V,20%,X6S,CHA  I41  PC1241
   1 P1V8_PCH_AUX      A @S9S_MB_2U_LIB.S9S_MB_2U(SCH_1):P1V8_PCH_AUX
   2    GND      B @S9S_MB_2U_LIB.S9S_MB_2U(SCH_1):GND

Q_RES_0402LF-470,1%,1/16W,CHIPA  I42  PR1653
   1 P1V8_PCH_AUX      A @S9S_MB_2U_LIB.S9S_MB_2U(SCH_1):P1V8_PCH_AUX
   2    GND      B @S9S_MB_2U_LIB.S9S_MB_2U(SCH_1):GND

Q_INDUCTOR_SMLF-2.2UH,IND,CV-2A  I45  PL170
   2 P1V8_PCH_AUX      2 @S9S_MB_2U_LIB.S9S_MB_2U(SCH_1):P1V8_PCH_AUX
   1 SW_P1V8_PCH_AUX_SW      1 @S9S_MB_2U_LIB.S9S_MB_2U(SCH_1):SW_P1V8_PCH_AUX_SW


DRAWING: @S9S_MB_2U_LIB.S9S_MB_2U(SCH_1):PAGE252 

Q_RES_0402LF-1K,1%,1/16W,CHIP,A  I19  R2375
   1 P3V3_AUX      A @S9S_MB_2U_LIB.S9S_MB_2U(SCH_1):P3V3_AUX
   2 PVCCIN_CPU0_PIN_ALERT      B @S9S_MB_2U_LIB.S9S_MB_2U(SCH_1):PVCCIN_CPU0_PIN_ALERT

Q_SHORT_SM-EMPTY,SHORT6  I24  PJ53
   1 VSENSE_PVCCFA_EHV_FIVRA_CPU0_DP      1 @S9S_MB_2U_LIB.S9S_MB_2U(SCH_1):VSENSE_PVCCFA_EHV_FIVRA_CPU0_DP
   2 SH_PVCCFA_EHV_FIVRA_CPU0      2 @S9S_MB_2U_LIB.S9S_MB_2U(SCH_1):SH_PVCCFA_EHV_FIVRA_CPU0

Q_RES_0402LF-1K,1%,1/16W,CHIP,A  I50  R2365
   1 P3V3_AUX      A @S9S_MB_2U_LIB.S9S_MB_2U(SCH_1):P3V3_AUX
   2 PWRGD_PVCCIN_CPU0_R      B @S9S_MB_2U_LIB.S9S_MB_2U(SCH_1):PWRGD_PVCCIN_CPU0_R

Q_RES_0402LF-100,1%,1/16W,CHIPA  I15  PR586
   1 VSENSE_PVCCFA_EHV_FIVRA_CPU0_DN      A @S9S_MB_2U_LIB.S9S_MB_2U(SCH_1):VSENSE_PVCCFA_EHV_FIVRA_CPU0_DN
   2    GND      B @S9S_MB_2U_LIB.S9S_MB_2U(SCH_1):GND

Q_RES_0402LF-100,1%,1/16W,CHIPA  I38  PR531
   1 VSENSE_PVCCIN_CPU0_DP      A @S9S_MB_2U_LIB.S9S_MB_2U(SCH_1):VSENSE_PVCCIN_CPU0_DP
   2 PVCCIN_CPU0      B @S9S_MB_2U_LIB.S9S_MB_2U(SCH_1):PVCCIN_CPU0

Q_RES_0402LF-0,5%,1/16W,EMPTY,A  I74  PR4217
   1 PVCCFA_EHV_FIVRA_CPU0_IMON4      A @S9S_MB_2U_LIB.S9S_MB_2U(SCH_1):PVCCFA_EHV_FIVRA_CPU0_IMON4
   2    GND      B @S9S_MB_2U_LIB.S9S_MB_2U(SCH_1):GND

Q_SHORT_SM-EMPTY,SHORT6  I37  PJ47
   1 VSENSE_PVCCIN_CPU0_DP      1 @S9S_MB_2U_LIB.S9S_MB_2U(SCH_1):VSENSE_PVCCIN_CPU0_DP
   2 SH_PVCCIN_CPU0      2 @S9S_MB_2U_LIB.S9S_MB_2U(SCH_1):SH_PVCCIN_CPU0

Q_RES_0402LF-0,5%,1/16W,CHIP,CA  I49  R2366
   1 PWRGD_PVCCIN_CPU0      A @S9S_MB_2U_LIB.S9S_MB_2U(SCH_1):PWRGD_PVCCIN_CPU0
   2 PWRGD_PVCCIN_CPU0_R      B @S9S_MB_2U_LIB.S9S_MB_2U(SCH_1):PWRGD_PVCCIN_CPU0_R

Q_RES_0402LF-0,5%,1/16W,CHIP,CA  I51  PR158
   1 PVCCIN_CPU0_CSPIN      A @S9S_MB_2U_LIB.S9S_MB_2U(SCH_1):PVCCIN_CPU0_CSPIN
   2    GND      B @S9S_MB_2U_LIB.S9S_MB_2U(SCH_1):GND

RAA229126GNPHA0-RAA229126GNP#HA  I63  PU14
  27 PVCCIN_CPU0_IMON1   CS11 @S9S_MB_2U_LIB.S9S_MB_2U(SCH_1):PVCCIN_CPU0_IMON1
  47 PVCCIN_CPU0_VCC    VCC @S9S_MB_2U_LIB.S9S_MB_2U(SCH_1):PVCCIN_CPU0_VCC
  24 PVCCFA_EHV_FIVRA_CPU0_EN_R    EN1 @S9S_MB_2U_LIB.S9S_MB_2U(SCH_1):PVCCFA_EHV_FIVRA_CPU0_EN_R
  14 SMB_CLK_PVCCIN_CPU0  PMSCL @S9S_MB_2U_LIB.S9S_MB_2U(SCH_1):SMB_CLK_PVCCIN_CPU0
  22 SVID_DIO_PVCCIN_CPU0_R SVDATA @S9S_MB_2U_LIB.S9S_MB_2U(SCH_1):SVID_DIO_PVCCIN_CPU0_R
  32 PVCCIN_CPU0_IMON6    CS6 @S9S_MB_2U_LIB.S9S_MB_2U(SCH_1):PVCCIN_CPU0_IMON6
  23 SVID_ALERT_PVCCIN_CPU0_R NSVALERT @S9S_MB_2U_LIB.S9S_MB_2U(SCH_1):SVID_ALERT_PVCCIN_CPU0_R
  18 IRQ_PVCCIN_CPU0_VRHOT_N NVRHOT @S9S_MB_2U_LIB.S9S_MB_2U(SCH_1):IRQ_PVCCIN_CPU0_VRHOT_N
  33 PVCCIN_CPU0_IMON7    CS5 @S9S_MB_2U_LIB.S9S_MB_2U(SCH_1):PVCCIN_CPU0_IMON7
  34 PVCCIN_CPU0_IMON8    CS4 @S9S_MB_2U_LIB.S9S_MB_2U(SCH_1):PVCCIN_CPU0_IMON8
  20 PWRGD_PVCCFA_EHV_FIVRA_CPU0_R    PG1 @S9S_MB_2U_LIB.S9S_MB_2U(SCH_1):PWRGD_PVCCFA_EHV_FIVRA_CPU0_R
  21 SVID_CLK_PVCCIN_CPU0_R  SVCLK @S9S_MB_2U_LIB.S9S_MB_2U(SCH_1):SVID_CLK_PVCCIN_CPU0_R
  15 NC_PVCCIN_CPU0_SMB_ALERT NPMALERT @S9S_MB_2U_LIB.S9S_MB_2U(SCH_1):NC_PVCCIN_CPU0_SMB_ALERT
  17 PVCCIN_CPU0_EN_R    EN0 @S9S_MB_2U_LIB.S9S_MB_2U(SCH_1):PVCCIN_CPU0_EN_R
  26 VSENSE_PVCCIN_CPU0_DN  RGND0 @S9S_MB_2U_LIB.S9S_MB_2U(SCH_1):VSENSE_PVCCIN_CPU0_DN
  13 SMB_DIO_PVCCIN_CPU0  PMSDA @S9S_MB_2U_LIB.S9S_MB_2U(SCH_1):SMB_DIO_PVCCIN_CPU0
   5 PVCCIN_CPU0_PWM8   PWM4 @S9S_MB_2U_LIB.S9S_MB_2U(SCH_1):PVCCIN_CPU0_PWM8
   6 PVCCIN_CPU0_PWM7   PWM5 @S9S_MB_2U_LIB.S9S_MB_2U(SCH_1):PVCCIN_CPU0_PWM7
  25 SH_PVCCIN_CPU0_R  VSEN0 @S9S_MB_2U_LIB.S9S_MB_2U(SCH_1):SH_PVCCIN_CPU0_R
   2 PVCCFA_EHV_FIVRA_CPU0_PWM2   PWM1 @S9S_MB_2U_LIB.S9S_MB_2U(SCH_1):PVCCFA_EHV_FIVRA_CPU0_PWM2
  16 PWRGD_PVCCIN_CPU0_R    PG0 @S9S_MB_2U_LIB.S9S_MB_2U(SCH_1):PWRGD_PVCCIN_CPU0_R
   7 PVCCIN_CPU0_PWM6   PWM6 @S9S_MB_2U_LIB.S9S_MB_2U(SCH_1):PVCCIN_CPU0_PWM6
  48 PVCCIN_CPU0_VREF   VCCS @S9S_MB_2U_LIB.S9S_MB_2U(SCH_1):PVCCIN_CPU0_VREF
  45 PVCCIN_CPU0_CSPIN VMON||IINSEN||VSYS||ISYS @S9S_MB_2U_LIB.S9S_MB_2U(SCH_1):PVCCIN_CPU0_CSPIN
  46 PVCCIN_CPU0_VIN_CSNIN VINSEN||VSYS @S9S_MB_2U_LIB.S9S_MB_2U(SCH_1):PVCCIN_CPU0_VIN_CSNIN
  44 PVCCFA_EHV_FIVRA_CPU0_BTSEN TEMP1||ISYS @S9S_MB_2U_LIB.S9S_MB_2U(SCH_1):PVCCFA_EHV_FIVRA_CPU0_BTSEN
  19 PVCCIN_CPU0_PIN_ALERT NPINALERT||NPSYS_CRIT @S9S_MB_2U_LIB.S9S_MB_2U(SCH_1):PVCCIN_CPU0_PIN_ALERT
  40 SH_PVCCFA_EHV_FIVRA_CPU0_R  VSEN1 @S9S_MB_2U_LIB.S9S_MB_2U(SCH_1):SH_PVCCFA_EHV_FIVRA_CPU0_R
  39 VSENSE_PVCCFA_EHV_FIVRA_CPU0_DN  RGND1 @S9S_MB_2U_LIB.S9S_MB_2U(SCH_1):VSENSE_PVCCFA_EHV_FIVRA_CPU0_DN
  37 PVCCFA_EHV_FIVRA_CPU0_IMON2    CS1 @S9S_MB_2U_LIB.S9S_MB_2U(SCH_1):PVCCFA_EHV_FIVRA_CPU0_IMON2
  12 PVCCIN_CPU0_PWM1  PWM11 @S9S_MB_2U_LIB.S9S_MB_2U(SCH_1):PVCCIN_CPU0_PWM1
   4 PVCCFA_EHV_FIVRA_CPU0_PWM4   PWM3 @S9S_MB_2U_LIB.S9S_MB_2U(SCH_1):PVCCFA_EHV_FIVRA_CPU0_PWM4
  35 PVCCFA_EHV_FIVRA_CPU0_IMON4    CS3 @S9S_MB_2U_LIB.S9S_MB_2U(SCH_1):PVCCFA_EHV_FIVRA_CPU0_IMON4
   3 PVCCFA_EHV_FIVRA_CPU0_PWM3   PWM2 @S9S_MB_2U_LIB.S9S_MB_2U(SCH_1):PVCCFA_EHV_FIVRA_CPU0_PWM3
  36 PVCCFA_EHV_FIVRA_CPU0_IMON3    CS2 @S9S_MB_2U_LIB.S9S_MB_2U(SCH_1):PVCCFA_EHV_FIVRA_CPU0_IMON3
  41 PVCCIN_CPU0_VR_FAULT    CFP @S9S_MB_2U_LIB.S9S_MB_2U(SCH_1):PVCCIN_CPU0_VR_FAULT
  TH    GND TH_GND @S9S_MB_2U_LIB.S9S_MB_2U(SCH_1):GND
  42 PVCCIN_CPU0_ADDR ADDR_CFG @S9S_MB_2U_LIB.S9S_MB_2U(SCH_1):PVCCIN_CPU0_ADDR
  43 PVCCIN_CPU0_ATSEN  TEMP0 @S9S_MB_2U_LIB.S9S_MB_2U(SCH_1):PVCCIN_CPU0_ATSEN
   1 PVCCFA_EHV_FIVRA_CPU0_PWM1   PWM0 @S9S_MB_2U_LIB.S9S_MB_2U(SCH_1):PVCCFA_EHV_FIVRA_CPU0_PWM1
  38 PVCCFA_EHV_FIVRA_CPU0_IMON1    CS0 @S9S_MB_2U_LIB.S9S_MB_2U(SCH_1):PVCCFA_EHV_FIVRA_CPU0_IMON1
   8 PVCCIN_CPU0_PWM5   PWM7 @S9S_MB_2U_LIB.S9S_MB_2U(SCH_1):PVCCIN_CPU0_PWM5
  31 PVCCIN_CPU0_IMON5    CS7 @S9S_MB_2U_LIB.S9S_MB_2U(SCH_1):PVCCIN_CPU0_IMON5
   9 PVCCIN_CPU0_PWM4   PWM8 @S9S_MB_2U_LIB.S9S_MB_2U(SCH_1):PVCCIN_CPU0_PWM4
  30 PVCCIN_CPU0_IMON4    CS8 @S9S_MB_2U_LIB.S9S_MB_2U(SCH_1):PVCCIN_CPU0_IMON4
  10 PVCCIN_CPU0_PWM3   PWM9 @S9S_MB_2U_LIB.S9S_MB_2U(SCH_1):PVCCIN_CPU0_PWM3
  29 PVCCIN_CPU0_IMON3    CS9 @S9S_MB_2U_LIB.S9S_MB_2U(SCH_1):PVCCIN_CPU0_IMON3
  11 PVCCIN_CPU0_PWM2  PWM10 @S9S_MB_2U_LIB.S9S_MB_2U(SCH_1):PVCCIN_CPU0_PWM2
  28 PVCCIN_CPU0_IMON2   CS10 @S9S_MB_2U_LIB.S9S_MB_2U(SCH_1):PVCCIN_CPU0_IMON2

Q_RES_0402LF-0,5%,1/16W,CHIP,CA  I66  R4593
   1 IRQ_PVCCIN_CPU0_VRHOT_R_N      A @S9S_MB_2U_LIB.S9S_MB_2U(SCH_1):IRQ_PVCCIN_CPU0_VRHOT_R_N
   2 IRQ_PVCCIN_CPU0_VRHOT_N      B @S9S_MB_2U_LIB.S9S_MB_2U(SCH_1):IRQ_PVCCIN_CPU0_VRHOT_N

Q_CAP_0402-3300PF,50V,10%,X7R,A  I67  PC594
   1 SH_PVCCFA_EHV_FIVRA_CPU0_R      A @S9S_MB_2U_LIB.S9S_MB_2U(SCH_1):SH_PVCCFA_EHV_FIVRA_CPU0_R
   2 VSENSE_PVCCFA_EHV_FIVRA_CPU0_DN      B @S9S_MB_2U_LIB.S9S_MB_2U(SCH_1):VSENSE_PVCCFA_EHV_FIVRA_CPU0_DN

Q_RES_0402LF-1,1%,1/16W,CHIP,CA  I133  PR176
   1 PVCCIN_CPU0_VCC      A @S9S_MB_2U_LIB.S9S_MB_2U(SCH_1):PVCCIN_CPU0_VCC
   2 P3V3_AUX      B @S9S_MB_2U_LIB.S9S_MB_2U(SCH_1):P3V3_AUX

Q_RES_0402LF-28K,1%,1/16W,EMPTA  I5  PR159
   1 PVCCIN_CPU0_VREF      A @S9S_MB_2U_LIB.S9S_MB_2U(SCH_1):PVCCIN_CPU0_VREF
   2 PVCCIN_CPU0_ADDR      B @S9S_MB_2U_LIB.S9S_MB_2U(SCH_1):PVCCIN_CPU0_ADDR

Q_RES_0402LF-0,5%,1/16W,CHIP,CA  I10  PR156
   1 P12V_AUX      A @S9S_MB_2U_LIB.S9S_MB_2U(SCH_1):P12V_AUX
   2 PVCCIN_CPU0_VIN_CSNIN      B @S9S_MB_2U_LIB.S9S_MB_2U(SCH_1):PVCCIN_CPU0_VIN_CSNIN

Q_RES_0402LF-0,5%,1/16W,EMPTY,A  I11  PR157
   1 P12V_AUX      A @S9S_MB_2U_LIB.S9S_MB_2U(SCH_1):P12V_AUX
   2 PVCCIN_CPU0_CSPIN      B @S9S_MB_2U_LIB.S9S_MB_2U(SCH_1):PVCCIN_CPU0_CSPIN

Q_RES_0402LF-0,5%,1/16W,CHIP,CA  I17  R2376
   1 IRQ_PSYS_CRIT_N      A @S9S_MB_2U_LIB.S9S_MB_2U(SCH_1):IRQ_PSYS_CRIT_N
   2 PVCCIN_CPU0_PIN_ALERT      B @S9S_MB_2U_LIB.S9S_MB_2U(SCH_1):PVCCIN_CPU0_PIN_ALERT

Q_RES_0402LF-1K,1%,1/16W,CHIP,A  I20  R2589
   1 P3V3_AUX      A @S9S_MB_2U_LIB.S9S_MB_2U(SCH_1):P3V3_AUX
   2 PVCCIN_CPU0_VR_FAULT      B @S9S_MB_2U_LIB.S9S_MB_2U(SCH_1):PVCCIN_CPU0_VR_FAULT

Q_RES_0402LF-4.7K,5%,1/16W,EMPA  I40  R1713
   1 SMB_VR_3V3AUX_SCL_R3      A @S9S_MB_2U_LIB.S9S_MB_2U(SCH_1):SMB_VR_3V3AUX_SCL_R3
   2 P3V3_AUX      B @S9S_MB_2U_LIB.S9S_MB_2U(SCH_1):P3V3_AUX

Q_RES_0402LF-0,5%,1/16W,CHIP,CA  I41  R2370
   1 SVID_ALERT0_CPU0_R_N      A @S9S_MB_2U_LIB.S9S_MB_2U(SCH_1):SVID_ALERT0_CPU0_R_N
   2 SVID_ALERT_PVCCIN_CPU0_R      B @S9S_MB_2U_LIB.S9S_MB_2U(SCH_1):SVID_ALERT_PVCCIN_CPU0_R

Q_RES_0402LF-150,1%,1/16W,CHIPA  I44  R2368
   1 SVID_CLK0_CPU0_R      A @S9S_MB_2U_LIB.S9S_MB_2U(SCH_1):SVID_CLK0_CPU0_R
   2 SVID_CLK_PVCCIN_CPU0_R      B @S9S_MB_2U_LIB.S9S_MB_2U(SCH_1):SVID_CLK_PVCCIN_CPU0_R

Q_RES_0402LF-0,5%,1/16W,CHIP,CA  I48  R2591
   1 FM_PVCCIN_CPU0_EN      A @S9S_MB_2U_LIB.S9S_MB_2U(SCH_1):FM_PVCCIN_CPU0_EN
   2 PVCCIN_CPU0_EN_R      B @S9S_MB_2U_LIB.S9S_MB_2U(SCH_1):PVCCIN_CPU0_EN_R

Q_CAP_0402-1000PF,50V,5%,X7R,TA  I58  C3268
   1 PVCCFA_EHV_FIVRA_CPU0_EN_R      A @S9S_MB_2U_LIB.S9S_MB_2U(SCH_1):PVCCFA_EHV_FIVRA_CPU0_EN_R
   2    GND      B @S9S_MB_2U_LIB.S9S_MB_2U(SCH_1):GND

Q_RES_0402LF-1K,1%,1/16W,EMPTYA  I60  PR166
   1 PVCCIN_CPU0_VIN_CSNIN      A @S9S_MB_2U_LIB.S9S_MB_2U(SCH_1):PVCCIN_CPU0_VIN_CSNIN
   2    GND      B @S9S_MB_2U_LIB.S9S_MB_2U(SCH_1):GND

Q_CAP_0402-0.1UF,25V,10%,X7R,CA  I61  PC330
   1 PVCCIN_CPU0_VIN_CSNIN      A @S9S_MB_2U_LIB.S9S_MB_2U(SCH_1):PVCCIN_CPU0_VIN_CSNIN
   2    GND      B @S9S_MB_2U_LIB.S9S_MB_2U(SCH_1):GND

Q_CAP_0402-3300PF,50V,10%,X7R,A  I79  PC331
   1 SH_PVCCIN_CPU0_R      A @S9S_MB_2U_LIB.S9S_MB_2U(SCH_1):SH_PVCCIN_CPU0_R
   2 VSENSE_PVCCIN_CPU0_DN      B @S9S_MB_2U_LIB.S9S_MB_2U(SCH_1):VSENSE_PVCCIN_CPU0_DN

Q_CAP_C0402-10UF,6.3V,20%,X6S,B  I86  PC335
   1 PVCCIN_CPU0_VREF      A @S9S_MB_2U_LIB.S9S_MB_2U(SCH_1):PVCCIN_CPU0_VREF
   2    GND      B @S9S_MB_2U_LIB.S9S_MB_2U(SCH_1):GND

Q_RES_0402LF-49.9,1%,1/16W,EMPA  I123  R2382
   1 SVID_ALERT0_CPU0_R_N      A @S9S_MB_2U_LIB.S9S_MB_2U(SCH_1):SVID_ALERT0_CPU0_R_N
   2 PVNN_TERM_CPU0      B @S9S_MB_2U_LIB.S9S_MB_2U(SCH_1):PVNN_TERM_CPU0

Q_RES_0402LF-0,5%,1/16W,CHIP,CA  I8  PR171
   1 PVCCIN_CPU0_ADDR      A @S9S_MB_2U_LIB.S9S_MB_2U(SCH_1):PVCCIN_CPU0_ADDR
   2    GND      B @S9S_MB_2U_LIB.S9S_MB_2U(SCH_1):GND

Q_RES_0402LF-1K,1%,1/16W,CHIP,A  I23  R2373
   1 P3V3_AUX      A @S9S_MB_2U_LIB.S9S_MB_2U(SCH_1):P3V3_AUX
   2 IRQ_PVCCIN_CPU0_VRHOT_R_N      B @S9S_MB_2U_LIB.S9S_MB_2U(SCH_1):IRQ_PVCCIN_CPU0_VRHOT_R_N

Q_RES_0402LF-100,1%,1/16W,CHIPA  I25  PR587
   1 VSENSE_PVCCFA_EHV_FIVRA_CPU0_DP      A @S9S_MB_2U_LIB.S9S_MB_2U(SCH_1):VSENSE_PVCCFA_EHV_FIVRA_CPU0_DP
   2 PVCCFA_EHV_FIVRA_CPU0      B @S9S_MB_2U_LIB.S9S_MB_2U(SCH_1):PVCCFA_EHV_FIVRA_CPU0

Q_RES_0402LF-100,1%,1/16W,CHIPA  I26  PR527
   1 VSENSE_PVCCIN_CPU0_DN      A @S9S_MB_2U_LIB.S9S_MB_2U(SCH_1):VSENSE_PVCCIN_CPU0_DN
   2    GND      B @S9S_MB_2U_LIB.S9S_MB_2U(SCH_1):GND

CONN3_210HP1030BR1-CONN3_210-HB  I32  PJP1
   3 SMB_VR_3V3AUX_SDA_R3      3 @S9S_MB_2U_LIB.S9S_MB_2U(SCH_1):SMB_VR_3V3AUX_SDA_R3
   2    GND      2 @S9S_MB_2U_LIB.S9S_MB_2U(SCH_1):GND
   1 SMB_VR_3V3AUX_SCL_R3      1 @S9S_MB_2U_LIB.S9S_MB_2U(SCH_1):SMB_VR_3V3AUX_SCL_R3

Q_RES_0402LF-4.7K,5%,1/16W,EMPA  I42  R1712
   1 SMB_VR_3V3AUX_SDA_R3      A @S9S_MB_2U_LIB.S9S_MB_2U(SCH_1):SMB_VR_3V3AUX_SDA_R3
   2 P3V3_AUX      B @S9S_MB_2U_LIB.S9S_MB_2U(SCH_1):P3V3_AUX

Q_RES_0402LF-0,5%,1/16W,CHIP,CA  I43  R2369
   1 SVID_DIO0_CPU0_R      A @S9S_MB_2U_LIB.S9S_MB_2U(SCH_1):SVID_DIO0_CPU0_R
   2 SVID_DIO_PVCCIN_CPU0_R      B @S9S_MB_2U_LIB.S9S_MB_2U(SCH_1):SVID_DIO_PVCCIN_CPU0_R

Q_CAP_0402-0.1UF,25V,10%,EMPTYA  I53  PC329
   1 PVCCIN_CPU0_CSPIN      A @S9S_MB_2U_LIB.S9S_MB_2U(SCH_1):PVCCIN_CPU0_CSPIN
   2    GND      B @S9S_MB_2U_LIB.S9S_MB_2U(SCH_1):GND

Q_RES_0402LF-1K,1%,1/16W,CHIP,A  I54  R2377
   1 P3V3_AUX      A @S9S_MB_2U_LIB.S9S_MB_2U(SCH_1):P3V3_AUX
   2 PWRGD_PVCCFA_EHV_FIVRA_CPU0_R      B @S9S_MB_2U_LIB.S9S_MB_2U(SCH_1):PWRGD_PVCCFA_EHV_FIVRA_CPU0_R

Q_RES_0402LF-0,5%,1/16W,CHIP,CA  I55  R2379
   1 PWRGD_PVCCFA_EHV_FIVRA_CPU0      A @S9S_MB_2U_LIB.S9S_MB_2U(SCH_1):PWRGD_PVCCFA_EHV_FIVRA_CPU0
   2 PWRGD_PVCCFA_EHV_FIVRA_CPU0_R      B @S9S_MB_2U_LIB.S9S_MB_2U(SCH_1):PWRGD_PVCCFA_EHV_FIVRA_CPU0_R

Q_RES_0402LF-0,5%,1/16W,CHIP,CA  I56  R4216
   1 FM_PVCCFA_EHV_FIVRA_CPU0_EN      A @S9S_MB_2U_LIB.S9S_MB_2U(SCH_1):FM_PVCCFA_EHV_FIVRA_CPU0_EN
   2 PVCCFA_EHV_FIVRA_CPU0_EN_R      B @S9S_MB_2U_LIB.S9S_MB_2U(SCH_1):PVCCFA_EHV_FIVRA_CPU0_EN_R

Q_CAP_0402-1000PF,50V,5%,EMPTYA  I57  C3269
   1 PWRGD_PVCCFA_EHV_FIVRA_CPU0_R      A @S9S_MB_2U_LIB.S9S_MB_2U(SCH_1):PWRGD_PVCCFA_EHV_FIVRA_CPU0_R
   2    GND      B @S9S_MB_2U_LIB.S9S_MB_2U(SCH_1):GND

Q_RES_0402LF-0,5%,1/16W,CHIP,CA  I68  PR345
   1 SH_PVCCFA_EHV_FIVRA_CPU0      A @S9S_MB_2U_LIB.S9S_MB_2U(SCH_1):SH_PVCCFA_EHV_FIVRA_CPU0
   2 SH_PVCCFA_EHV_FIVRA_CPU0_R      B @S9S_MB_2U_LIB.S9S_MB_2U(SCH_1):SH_PVCCFA_EHV_FIVRA_CPU0_R

Q_CAP_0402-470PF,50V,10%,X7R,TA  I70  PC336
   1 PVCCIN_CPU0_ATSEN      A @S9S_MB_2U_LIB.S9S_MB_2U(SCH_1):PVCCIN_CPU0_ATSEN
   2    GND      B @S9S_MB_2U_LIB.S9S_MB_2U(SCH_1):GND

Q_RES_0402LF-10K,1%,1/16W,EMPTA  I72  PR400
   1 PVCCIN_CPU0_ATSEN      A @S9S_MB_2U_LIB.S9S_MB_2U(SCH_1):PVCCIN_CPU0_ATSEN
   2    GND      B @S9S_MB_2U_LIB.S9S_MB_2U(SCH_1):GND

Q_RES_0402LF-0,5%,1/16W,EMPTY,A  I73  PR4218
   1 PVCCFA_EHV_FIVRA_CPU0_IMON3      A @S9S_MB_2U_LIB.S9S_MB_2U(SCH_1):PVCCFA_EHV_FIVRA_CPU0_IMON3
   2    GND      B @S9S_MB_2U_LIB.S9S_MB_2U(SCH_1):GND

Q_RES_0402LF-0,5%,1/16W,CHIP,CA  I77  PR170
   1 SH_PVCCIN_CPU0      A @S9S_MB_2U_LIB.S9S_MB_2U(SCH_1):SH_PVCCIN_CPU0
   2 SH_PVCCIN_CPU0_R      B @S9S_MB_2U_LIB.S9S_MB_2U(SCH_1):SH_PVCCIN_CPU0_R

Q_RES_0402LF-33.2,1%,1/16W,CHIA  I78  R2372
   1 SMB_VR_3V3AUX_SDA_R3      A @S9S_MB_2U_LIB.S9S_MB_2U(SCH_1):SMB_VR_3V3AUX_SDA_R3
   2 SMB_DIO_PVCCIN_CPU0      B @S9S_MB_2U_LIB.S9S_MB_2U(SCH_1):SMB_DIO_PVCCIN_CPU0

Q_RES_0402LF-33.2,1%,1/16W,CHIA  I80  R2371
   1 SMB_VR_3V3AUX_SCL_R3      A @S9S_MB_2U_LIB.S9S_MB_2U(SCH_1):SMB_VR_3V3AUX_SCL_R3
   2 SMB_CLK_PVCCIN_CPU0      B @S9S_MB_2U_LIB.S9S_MB_2U(SCH_1):SMB_CLK_PVCCIN_CPU0

Q_CAP_0402-1000PF,50V,5%,X7R,TA  I82  C3267
   1 PVCCIN_CPU0_EN_R      A @S9S_MB_2U_LIB.S9S_MB_2U(SCH_1):PVCCIN_CPU0_EN_R
   2    GND      B @S9S_MB_2U_LIB.S9S_MB_2U(SCH_1):GND

Q_CAP_0402-1000PF,50V,5%,EMPTYA  I84  C3266
   1 PWRGD_PVCCIN_CPU0_R      A @S9S_MB_2U_LIB.S9S_MB_2U(SCH_1):PWRGD_PVCCIN_CPU0_R
   2    GND      B @S9S_MB_2U_LIB.S9S_MB_2U(SCH_1):GND

Q_CAP_C0402-1UF,16V,10%,X6S,CHA  I87  PC1173
   1 PVCCIN_CPU0_VREF      A @S9S_MB_2U_LIB.S9S_MB_2U(SCH_1):PVCCIN_CPU0_VREF
   2    GND      B @S9S_MB_2U_LIB.S9S_MB_2U(SCH_1):GND

Q_CAP_0402-0.1UF,25V,10%,EMPTYA  I88  PC334
   1 PVCCIN_CPU0_VCC      A @S9S_MB_2U_LIB.S9S_MB_2U(SCH_1):PVCCIN_CPU0_VCC
   2    GND      B @S9S_MB_2U_LIB.S9S_MB_2U(SCH_1):GND

Q_CAP_C0402-1UF,16V,10%,X6S,CHA  I89  PC337
   1 PVCCIN_CPU0_VCC      A @S9S_MB_2U_LIB.S9S_MB_2U(SCH_1):PVCCIN_CPU0_VCC
   2    GND      B @S9S_MB_2U_LIB.S9S_MB_2U(SCH_1):GND

Q_CAP_0402-470PF,50V,10%,X7R,TA  I116  PC100
   1 PVCCFA_EHV_FIVRA_CPU0_BTSEN      A @S9S_MB_2U_LIB.S9S_MB_2U(SCH_1):PVCCFA_EHV_FIVRA_CPU0_BTSEN
   2    GND      B @S9S_MB_2U_LIB.S9S_MB_2U(SCH_1):GND

Q_RES_0402LF-10K,1%,1/16W,EMPTA  I121  PR451
   1 PVCCFA_EHV_FIVRA_CPU0_BTSEN      A @S9S_MB_2U_LIB.S9S_MB_2U(SCH_1):PVCCFA_EHV_FIVRA_CPU0_BTSEN
   2    GND      B @S9S_MB_2U_LIB.S9S_MB_2U(SCH_1):GND

Q_RES_0402LF-100,1%,1/16W,CHIPA  I124  R2590
   1 SVID_DIO0_CPU0_R      A @S9S_MB_2U_LIB.S9S_MB_2U(SCH_1):SVID_DIO0_CPU0_R
   2 PVNN_TERM_CPU0      B @S9S_MB_2U_LIB.S9S_MB_2U(SCH_1):PVNN_TERM_CPU0

Q_RES_0402LF-49.9,1%,1/16W,CHIA  I125  R2381
   1 SVID_CLK0_CPU0_R      A @S9S_MB_2U_LIB.S9S_MB_2U(SCH_1):SVID_CLK0_CPU0_R
   2 PVNN_TERM_CPU0      B @S9S_MB_2U_LIB.S9S_MB_2U(SCH_1):PVNN_TERM_CPU0

Q_CAP_C0603-10UF,4V,20%,EMPTY,A  I127  C3270
   1 PVNN_TERM_CPU0      A @S9S_MB_2U_LIB.S9S_MB_2U(SCH_1):PVNN_TERM_CPU0
   2    GND      B @S9S_MB_2U_LIB.S9S_MB_2U(SCH_1):GND

Q_CAP_C0402-100NF,50V,10%,X7R,A  I128  C3271
   1 PVNN_TERM_CPU0      A @S9S_MB_2U_LIB.S9S_MB_2U(SCH_1):PVNN_TERM_CPU0
   2    GND      B @S9S_MB_2U_LIB.S9S_MB_2U(SCH_1):GND

Q_CAP_0402-0.1UF,25V,10%,EMPTYA  I136  PC2361
   1 PVCCIN_CPU0_VCC      A @S9S_MB_2U_LIB.S9S_MB_2U(SCH_1):PVCCIN_CPU0_VCC
   2    GND      B @S9S_MB_2U_LIB.S9S_MB_2U(SCH_1):GND


DRAWING: @S9S_MB_2U_LIB.S9S_MB_2U(SCH_1):PAGE253 

Q_CAP_0402-0.1UF,25V,10%,X7R,CA  I11  PC1355
   1    GND      A @S9S_MB_2U_LIB.S9S_MB_2U(SCH_1):GND
   2 PVCCIN_CPU0_VREF      B @S9S_MB_2U_LIB.S9S_MB_2U(SCH_1):PVCCIN_CPU0_VREF

Q_CAP_C0402-1UF,16V,10%,X6S,CHA  I22  PC298_P0_2
   1 SW_P12V_PVCCIN_CPU0_FLT      A @S9S_MB_2U_LIB.S9S_MB_2U(SCH_1):SW_P12V_PVCCIN_CPU0_FLT
   2    GND      B @S9S_MB_2U_LIB.S9S_MB_2U(SCH_1):GND

Q_CAP_C0805-22UF,16V,20%,X6S,CA  I24  PC304_P0_2
   1 SW_P12V_PVCCIN_CPU0_FLT      A @S9S_MB_2U_LIB.S9S_MB_2U(SCH_1):SW_P12V_PVCCIN_CPU0_FLT
   2    GND      B @S9S_MB_2U_LIB.S9S_MB_2U(SCH_1):GND

Q_CAP_C0402-2.2UF,10V,10%,X6S,A  I36  PC293
   1 PVCCIN_CPU0_VDD1      A @S9S_MB_2U_LIB.S9S_MB_2U(SCH_1):PVCCIN_CPU0_VDD1
   2    GND      B @S9S_MB_2U_LIB.S9S_MB_2U(SCH_1):GND

Q_CAP_C0402-2.2UF,10V,10%,X6S,A  I39  PC295_P0_1
   1 PVCCIN_CPU0_PVCC      A @S9S_MB_2U_LIB.S9S_MB_2U(SCH_1):PVCCIN_CPU0_PVCC
   2    GND      B @S9S_MB_2U_LIB.S9S_MB_2U(SCH_1):GND

ISL99390FRZTR5935-ISL99390FRZ-A  I40  PU13_P0_1
  34 PVCCIN_CPU0_PWM1    PWM @S9S_MB_2U_LIB.S9S_MB_2U(SCH_1):PVCCIN_CPU0_PWM1
  39 PVCCIN_CPU0_VREF  REFIN @S9S_MB_2U_LIB.S9S_MB_2U(SCH_1):PVCCIN_CPU0_VREF
   3 PVCCIN_CPU0_VDD1    VCC @S9S_MB_2U_LIB.S9S_MB_2U(SCH_1):PVCCIN_CPU0_VDD1
   2    GND   AGND @S9S_MB_2U_LIB.S9S_MB_2U(SCH_1):GND
  33 SW_PVCCIN_CPU0_BOOT1   BOOT @S9S_MB_2U_LIB.S9S_MB_2U(SCH_1):SW_PVCCIN_CPU0_BOOT1
25_29 SW_P12V_PVCCIN_CPU0_FLT   VIN1 @S9S_MB_2U_LIB.S9S_MB_2U(SCH_1):SW_P12V_PVCCIN_CPU0_FLT
  32 SW_PVCCIN_CPU0_BOOTR1  PHASE @S9S_MB_2U_LIB.S9S_MB_2U(SCH_1):SW_PVCCIN_CPU0_BOOTR1
   4 PVCCIN_CPU0_PVCC   PVCC @S9S_MB_2U_LIB.S9S_MB_2U(SCH_1):PVCCIN_CPU0_PVCC
  36 PVCCIN_CPU0_ATSEN TOUT_FLT @S9S_MB_2U_LIB.S9S_MB_2U(SCH_1):PVCCIN_CPU0_ATSEN
  38 PVCCIN_CPU0_IMON1   IOUT @S9S_MB_2U_LIB.S9S_MB_2U(SCH_1):PVCCIN_CPU0_IMON1
  37 PVCCIN_CPU0_LSET1   LSET @S9S_MB_2U_LIB.S9S_MB_2U(SCH_1):PVCCIN_CPU0_LSET1
10_19 SW_PVCCIN_CPU0_SW1     SW @S9S_MB_2U_LIB.S9S_MB_2U(SCH_1):SW_PVCCIN_CPU0_SW1
   5    GND  PGND1 @S9S_MB_2U_LIB.S9S_MB_2U(SCH_1):GND
  30 SW_P12V_PVCCIN_CPU0_FLT   VIN2 @S9S_MB_2U_LIB.S9S_MB_2U(SCH_1):SW_P12V_PVCCIN_CPU0_FLT
   1 PVCCIN_CPU0_VOS1    VOS @S9S_MB_2U_LIB.S9S_MB_2U(SCH_1):PVCCIN_CPU0_VOS1
  40    GND  PGND3 @S9S_MB_2U_LIB.S9S_MB_2U(SCH_1):GND
  35 PVCCIN_CPU0_VDD1     EN @S9S_MB_2U_LIB.S9S_MB_2U(SCH_1):PVCCIN_CPU0_VDD1
  31     NC    DNC     NC
   6     NC    GL1     NC
  41     NC    GL2     NC
7_9-20_24    GND  PGND2 @S9S_MB_2U_LIB.S9S_MB_2U(SCH_1):GND

Q_INDUCTOR4P_14-150NH,SMLF,INDA  I46  PL114
   2 IND_P0_CPL1      2 @S9S_MB_2U_LIB.S9S_MB_2U(SCH_1):IND_P0_CPL1
   3 IND_P0_CPL2      3 @S9S_MB_2U_LIB.S9S_MB_2U(SCH_1):IND_P0_CPL2
   4 PVCCIN_CPU0      4 @S9S_MB_2U_LIB.S9S_MB_2U(SCH_1):PVCCIN_CPU0
   1 SW_PVCCIN_CPU0_SW1      1 @S9S_MB_2U_LIB.S9S_MB_2U(SCH_1):SW_PVCCIN_CPU0_SW1

Q_CAP_C0805-22UF,16V,20%,X6S,CA  I54  PC306_P0_2
   1 SW_P12V_PVCCIN_CPU0_FLT      A @S9S_MB_2U_LIB.S9S_MB_2U(SCH_1):SW_P12V_PVCCIN_CPU0_FLT
   2    GND      B @S9S_MB_2U_LIB.S9S_MB_2U(SCH_1):GND

Q_CAPP_THLF-560UF,2.5V,20%,OSCA  I56  PC16
   1 PVCCIN_CPU0      A @S9S_MB_2U_LIB.S9S_MB_2U(SCH_1):PVCCIN_CPU0
   2    GND      B @S9S_MB_2U_LIB.S9S_MB_2U(SCH_1):GND

Q_CAPP_THLF-560UF,2.5V,20%,OSCA  I62  PC319
   1 PVCCIN_CPU0      A @S9S_MB_2U_LIB.S9S_MB_2U(SCH_1):PVCCIN_CPU0
   2    GND      B @S9S_MB_2U_LIB.S9S_MB_2U(SCH_1):GND

Q_CAP_C0402-1UF,16V,10%,X6S,CHA  I84  PC310_P0_1
   1 PVCCIN_CPU0      A @S9S_MB_2U_LIB.S9S_MB_2U(SCH_1):PVCCIN_CPU0
   2    GND      B @S9S_MB_2U_LIB.S9S_MB_2U(SCH_1):GND

Q_RES_0402LF-2.2,1%,1/16W,CHIPA  I37  PR153
   1 PVCCIN_CPU0_PVCC      A @S9S_MB_2U_LIB.S9S_MB_2U(SCH_1):PVCCIN_CPU0_PVCC
   2 PVCCIN_CPU0_VDD1      B @S9S_MB_2U_LIB.S9S_MB_2U(SCH_1):PVCCIN_CPU0_VDD1

Q_CAP_C0402-100NF,50V,10%,X7R,A  I48  PC301
   1 SW_PVCCIN_CPU0_BOOT1_R      A @S9S_MB_2U_LIB.S9S_MB_2U(SCH_1):SW_PVCCIN_CPU0_BOOT1_R
   2 SW_PVCCIN_CPU0_BOOTR1      B @S9S_MB_2U_LIB.S9S_MB_2U(SCH_1):SW_PVCCIN_CPU0_BOOTR1

Q_CAP_C0805-22UF,16V,20%,X6S,CA  I50  PC305_P0_1
   1 SW_P12V_PVCCIN_CPU0_FLT      A @S9S_MB_2U_LIB.S9S_MB_2U(SCH_1):SW_P12V_PVCCIN_CPU0_FLT
   2    GND      B @S9S_MB_2U_LIB.S9S_MB_2U(SCH_1):GND

Q_RES_0402LF-0,5%,1/16W,CHIP,CA  I51  PR154
   1 PVCCIN_CPU0_VOS2      A @S9S_MB_2U_LIB.S9S_MB_2U(SCH_1):PVCCIN_CPU0_VOS2
   2 PVCCIN_CPU0      B @S9S_MB_2U_LIB.S9S_MB_2U(SCH_1):PVCCIN_CPU0

Q_CAPP_THLF-560UF,2.5V,20%,OSCA  I61  PC316
   1 PVCCIN_CPU0      A @S9S_MB_2U_LIB.S9S_MB_2U(SCH_1):PVCCIN_CPU0
   2    GND      B @S9S_MB_2U_LIB.S9S_MB_2U(SCH_1):GND

Q_CAPP_SMLF-330UF,2.5V,+10/-35A  I64  PC323
   1 PVCCIN_CPU0      A @S9S_MB_2U_LIB.S9S_MB_2U(SCH_1):PVCCIN_CPU0
   2    GND      B @S9S_MB_2U_LIB.S9S_MB_2U(SCH_1):GND

Q_CAPP_THLF-560UF,2.5V,20%,OSCA  I70  PC325
   1 PVCCIN_CPU0      A @S9S_MB_2U_LIB.S9S_MB_2U(SCH_1):PVCCIN_CPU0
   2    GND      B @S9S_MB_2U_LIB.S9S_MB_2U(SCH_1):GND

Q_RES_0402LF-0,5%,1/16W,CHIP,CA  I73  PR155
   1 PVCCIN_CPU0_VOS1      A @S9S_MB_2U_LIB.S9S_MB_2U(SCH_1):PVCCIN_CPU0_VOS1
   2 PVCCIN_CPU0      B @S9S_MB_2U_LIB.S9S_MB_2U(SCH_1):PVCCIN_CPU0

Q_CAP_C0805-22UF,4V,20%,X6S,CHA  I86  PC314_P0_1
   1 PVCCIN_CPU0      A @S9S_MB_2U_LIB.S9S_MB_2U(SCH_1):PVCCIN_CPU0
   2    GND      B @S9S_MB_2U_LIB.S9S_MB_2U(SCH_1):GND

Q_CAPP_THLF-270UF,16V,20%,OSCOA  I91  PC315
   1 SW_P12V_PVCCIN_CPU0_FLT      A @S9S_MB_2U_LIB.S9S_MB_2U(SCH_1):SW_P12V_PVCCIN_CPU0_FLT
   2    GND      B @S9S_MB_2U_LIB.S9S_MB_2U(SCH_1):GND

Q_CAPP_THLF-270UF,16V,20%,OSCOA  I92  PC318
   1 SW_P12V_PVCCIN_CPU0_FLT      A @S9S_MB_2U_LIB.S9S_MB_2U(SCH_1):SW_P12V_PVCCIN_CPU0_FLT
   2    GND      B @S9S_MB_2U_LIB.S9S_MB_2U(SCH_1):GND

Q_CAPP_THLF-270UF,16V,20%,OSCOA  I95  PC2345
   1 SW_P12V_PVCCIN_CPU0_FLT      A @S9S_MB_2U_LIB.S9S_MB_2U(SCH_1):SW_P12V_PVCCIN_CPU0_FLT
   2    GND      B @S9S_MB_2U_LIB.S9S_MB_2U(SCH_1):GND

Q_RES_0402LF-8.87K,1%,1/16W,EMA  I2  PR150
   1 PVCCIN_CPU0_LSET2      A @S9S_MB_2U_LIB.S9S_MB_2U(SCH_1):PVCCIN_CPU0_LSET2
   2    GND      B @S9S_MB_2U_LIB.S9S_MB_2U(SCH_1):GND

Q_CAP_0402-3300PF,50V,10%,X7R,A  I19  PC296_P0_2
   1 SW_P12V_PVCCIN_CPU0_FLT      A @S9S_MB_2U_LIB.S9S_MB_2U(SCH_1):SW_P12V_PVCCIN_CPU0_FLT
   2    GND      B @S9S_MB_2U_LIB.S9S_MB_2U(SCH_1):GND

Q_INDUCTOR4P_14-150NH,SMLF,INDA  I21  PL13
   2 IND_P0_CPL2      2 @S9S_MB_2U_LIB.S9S_MB_2U(SCH_1):IND_P0_CPL2
   3 IND_P0_CPL3      3 @S9S_MB_2U_LIB.S9S_MB_2U(SCH_1):IND_P0_CPL3
   4 PVCCIN_CPU0      4 @S9S_MB_2U_LIB.S9S_MB_2U(SCH_1):PVCCIN_CPU0
   1 SW_PVCCIN_CPU0_SW2      1 @S9S_MB_2U_LIB.S9S_MB_2U(SCH_1):SW_PVCCIN_CPU0_SW2

Q_RES_0402LF-0,5%,1/16W,CHIP,CA  I26  PR402
   1    P5V      A @S9S_MB_2U_LIB.S9S_MB_2U(SCH_1):P5V
   2 PVCCIN_CPU0_PVCC      B @S9S_MB_2U_LIB.S9S_MB_2U(SCH_1):PVCCIN_CPU0_PVCC

Q_CAP_0402-0.1UF,25V,10%,X7R,CA  I34  PC1356
   1    GND      A @S9S_MB_2U_LIB.S9S_MB_2U(SCH_1):GND
   2 PVCCIN_CPU0_VREF      B @S9S_MB_2U_LIB.S9S_MB_2U(SCH_1):PVCCIN_CPU0_VREF

Q_CAP_C0805-22UF,16V,20%,X6S,CA  I49  PC303_P0_1
   1 SW_P12V_PVCCIN_CPU0_FLT      A @S9S_MB_2U_LIB.S9S_MB_2U(SCH_1):SW_P12V_PVCCIN_CPU0_FLT
   2    GND      B @S9S_MB_2U_LIB.S9S_MB_2U(SCH_1):GND

Q_RES_0402LF-499,1%,1/16W,CHIPA  I59  PR4219
   1 PVCCIN_CPU0      A @S9S_MB_2U_LIB.S9S_MB_2U(SCH_1):PVCCIN_CPU0
   2    GND      B @S9S_MB_2U_LIB.S9S_MB_2U(SCH_1):GND

Q_CAPP_SMLF-330UF,2.5V,+10/-35A  I63  PC1920
   1 PVCCIN_CPU0      A @S9S_MB_2U_LIB.S9S_MB_2U(SCH_1):PVCCIN_CPU0
   2    GND      B @S9S_MB_2U_LIB.S9S_MB_2U(SCH_1):GND

Q_CAPP_SMLF-330UF,2.5V,+10/-35A  I66  PC326
   1 PVCCIN_CPU0      A @S9S_MB_2U_LIB.S9S_MB_2U(SCH_1):PVCCIN_CPU0
   2    GND      B @S9S_MB_2U_LIB.S9S_MB_2U(SCH_1):GND

Q_CAPP_THLF-560UF,2.5V,20%,OSCA  I67  PC322
   1 PVCCIN_CPU0      A @S9S_MB_2U_LIB.S9S_MB_2U(SCH_1):PVCCIN_CPU0
   2    GND      B @S9S_MB_2U_LIB.S9S_MB_2U(SCH_1):GND

Q_CAP_C0805-22UF,16V,20%,X6S,CA  I75  PC307_P0_1
   1 SW_P12V_PVCCIN_CPU0_FLT      A @S9S_MB_2U_LIB.S9S_MB_2U(SCH_1):SW_P12V_PVCCIN_CPU0_FLT
   2    GND      B @S9S_MB_2U_LIB.S9S_MB_2U(SCH_1):GND

Q_RES_2512LF-0.03,0.1%,1W,EMPTA  I81  PR2554
   1 P12V_AUX      A @S9S_MB_2U_LIB.S9S_MB_2U(SCH_1):P12V_AUX
   2 SW_P12V_PVCCIN_CPU0_FLT      B @S9S_MB_2U_LIB.S9S_MB_2U(SCH_1):SW_P12V_PVCCIN_CPU0_FLT

ISL99390FRZTR5935-ISL99390FRZ-A  I6  PU12_P0_2
  34 PVCCIN_CPU0_PWM2    PWM @S9S_MB_2U_LIB.S9S_MB_2U(SCH_1):PVCCIN_CPU0_PWM2
  39 PVCCIN_CPU0_VREF  REFIN @S9S_MB_2U_LIB.S9S_MB_2U(SCH_1):PVCCIN_CPU0_VREF
   3 PVCCIN_CPU0_VDD2    VCC @S9S_MB_2U_LIB.S9S_MB_2U(SCH_1):PVCCIN_CPU0_VDD2
   2    GND   AGND @S9S_MB_2U_LIB.S9S_MB_2U(SCH_1):GND
  33 SW_PVCCIN_CPU0_BOOT2   BOOT @S9S_MB_2U_LIB.S9S_MB_2U(SCH_1):SW_PVCCIN_CPU0_BOOT2
25_29 SW_P12V_PVCCIN_CPU0_FLT   VIN1 @S9S_MB_2U_LIB.S9S_MB_2U(SCH_1):SW_P12V_PVCCIN_CPU0_FLT
  32 SW_PVCCIN_CPU0_BOOTR2  PHASE @S9S_MB_2U_LIB.S9S_MB_2U(SCH_1):SW_PVCCIN_CPU0_BOOTR2
   4 PVCCIN_CPU0_PVCC   PVCC @S9S_MB_2U_LIB.S9S_MB_2U(SCH_1):PVCCIN_CPU0_PVCC
  36 PVCCIN_CPU0_ATSEN TOUT_FLT @S9S_MB_2U_LIB.S9S_MB_2U(SCH_1):PVCCIN_CPU0_ATSEN
  38 PVCCIN_CPU0_IMON2   IOUT @S9S_MB_2U_LIB.S9S_MB_2U(SCH_1):PVCCIN_CPU0_IMON2
  37 PVCCIN_CPU0_LSET2   LSET @S9S_MB_2U_LIB.S9S_MB_2U(SCH_1):PVCCIN_CPU0_LSET2
10_19 SW_PVCCIN_CPU0_SW2     SW @S9S_MB_2U_LIB.S9S_MB_2U(SCH_1):SW_PVCCIN_CPU0_SW2
   5    GND  PGND1 @S9S_MB_2U_LIB.S9S_MB_2U(SCH_1):GND
  30 SW_P12V_PVCCIN_CPU0_FLT   VIN2 @S9S_MB_2U_LIB.S9S_MB_2U(SCH_1):SW_P12V_PVCCIN_CPU0_FLT
   1 PVCCIN_CPU0_VOS2    VOS @S9S_MB_2U_LIB.S9S_MB_2U(SCH_1):PVCCIN_CPU0_VOS2
  40    GND  PGND3 @S9S_MB_2U_LIB.S9S_MB_2U(SCH_1):GND
  35 PVCCIN_CPU0_VDD2     EN @S9S_MB_2U_LIB.S9S_MB_2U(SCH_1):PVCCIN_CPU0_VDD2
  31     NC    DNC     NC
   6     NC    GL1     NC
  41     NC    GL2     NC
7_9-20_24    GND  PGND2 @S9S_MB_2U_LIB.S9S_MB_2U(SCH_1):GND

Q_CAP_C0402-2.2UF,10V,10%,X6S,A  I9  PC292
   1 PVCCIN_CPU0_VDD2      A @S9S_MB_2U_LIB.S9S_MB_2U(SCH_1):PVCCIN_CPU0_VDD2
   2    GND      B @S9S_MB_2U_LIB.S9S_MB_2U(SCH_1):GND

Q_RES_0402LF-2.2,1%,1/16W,CHIPA  I12  PR152
   1 PVCCIN_CPU0_PVCC      A @S9S_MB_2U_LIB.S9S_MB_2U(SCH_1):PVCCIN_CPU0_PVCC
   2 PVCCIN_CPU0_VDD2      B @S9S_MB_2U_LIB.S9S_MB_2U(SCH_1):PVCCIN_CPU0_VDD2

Q_CAP_C0402-2.2UF,10V,10%,X6S,A  I15  PC294_P0_2
   1 PVCCIN_CPU0_PVCC      A @S9S_MB_2U_LIB.S9S_MB_2U(SCH_1):PVCCIN_CPU0_PVCC
   2    GND      B @S9S_MB_2U_LIB.S9S_MB_2U(SCH_1):GND

Q_RES_0402LF-3.3,1%,1/16W,CHIPA  I18  PR1786
   1 SW_PVCCIN_CPU0_BOOT2      A @S9S_MB_2U_LIB.S9S_MB_2U(SCH_1):SW_PVCCIN_CPU0_BOOT2
   2 SW_PVCCIN_CPU0_BOOT2_R      B @S9S_MB_2U_LIB.S9S_MB_2U(SCH_1):SW_PVCCIN_CPU0_BOOT2_R

Q_CAP_C0402-100NF,50V,10%,X7R,A  I20  PC300
   1 SW_PVCCIN_CPU0_BOOT2_R      A @S9S_MB_2U_LIB.S9S_MB_2U(SCH_1):SW_PVCCIN_CPU0_BOOT2_R
   2 SW_PVCCIN_CPU0_BOOTR2      B @S9S_MB_2U_LIB.S9S_MB_2U(SCH_1):SW_PVCCIN_CPU0_BOOTR2

Q_CAP_C0805-22UF,16V,20%,X6S,CA  I23  PC302_P0_2
   1 SW_P12V_PVCCIN_CPU0_FLT      A @S9S_MB_2U_LIB.S9S_MB_2U(SCH_1):SW_P12V_PVCCIN_CPU0_FLT
   2    GND      B @S9S_MB_2U_LIB.S9S_MB_2U(SCH_1):GND

Q_RES_0402LF-8.87K,1%,1/16W,EMA  I29  PR151
   1 PVCCIN_CPU0_LSET1      A @S9S_MB_2U_LIB.S9S_MB_2U(SCH_1):PVCCIN_CPU0_LSET1
   2    GND      B @S9S_MB_2U_LIB.S9S_MB_2U(SCH_1):GND

Q_RES_0402LF-0,5%,1/16W,EMPTY,A  I42  PR403
   1   P3V3      A @S9S_MB_2U_LIB.S9S_MB_2U(SCH_1):P3V3
   2 PVCCIN_CPU0_PVCC      B @S9S_MB_2U_LIB.S9S_MB_2U(SCH_1):PVCCIN_CPU0_PVCC

Q_CAP_0402-3300PF,50V,10%,X7R,A  I44  PC297_P0_1
   1 SW_P12V_PVCCIN_CPU0_FLT      A @S9S_MB_2U_LIB.S9S_MB_2U(SCH_1):SW_P12V_PVCCIN_CPU0_FLT
   2    GND      B @S9S_MB_2U_LIB.S9S_MB_2U(SCH_1):GND

Q_CAP_C0402-1UF,16V,10%,X6S,CHA  I47  PC299_P0_1
   1 SW_P12V_PVCCIN_CPU0_FLT      A @S9S_MB_2U_LIB.S9S_MB_2U(SCH_1):SW_P12V_PVCCIN_CPU0_FLT
   2    GND      B @S9S_MB_2U_LIB.S9S_MB_2U(SCH_1):GND

Q_CAP_C0805-22UF,4V,20%,X6S,CHA  I57  PC311_P0_2
   1 PVCCIN_CPU0      A @S9S_MB_2U_LIB.S9S_MB_2U(SCH_1):PVCCIN_CPU0
   2    GND      B @S9S_MB_2U_LIB.S9S_MB_2U(SCH_1):GND

Q_CAP_C0805-22UF,4V,20%,X6S,CHA  I58  PC313_P0_2
   1 PVCCIN_CPU0      A @S9S_MB_2U_LIB.S9S_MB_2U(SCH_1):PVCCIN_CPU0
   2    GND      B @S9S_MB_2U_LIB.S9S_MB_2U(SCH_1):GND

Q_CAPP_SMLF-330UF,2.5V,+10/-35A  I60  PC2336
   1 PVCCIN_CPU0      A @S9S_MB_2U_LIB.S9S_MB_2U(SCH_1):PVCCIN_CPU0
   2    GND      B @S9S_MB_2U_LIB.S9S_MB_2U(SCH_1):GND

Q_CAP_C0402-100NF,50V,10%,X7R,A  I80  PC1652
   1 P12V_AUX      A @S9S_MB_2U_LIB.S9S_MB_2U(SCH_1):P12V_AUX
   2    GND      B @S9S_MB_2U_LIB.S9S_MB_2U(SCH_1):GND

Q_INDUCTOR_SMLF-50NH/148A,IND,A  I82  PL15
   2 SW_P12V_PVCCIN_CPU0_FLT      2 @S9S_MB_2U_LIB.S9S_MB_2U(SCH_1):SW_P12V_PVCCIN_CPU0_FLT
   1 P12V_AUX      1 @S9S_MB_2U_LIB.S9S_MB_2U(SCH_1):P12V_AUX

Q_CAP_C0402-100NF,50V,10%,X7R,A  I83  PC308_P0_1
   1 PVCCIN_CPU0      A @S9S_MB_2U_LIB.S9S_MB_2U(SCH_1):PVCCIN_CPU0
   2    GND      B @S9S_MB_2U_LIB.S9S_MB_2U(SCH_1):GND

Q_CAP_C0805-22UF,4V,20%,X6S,CHA  I85  PC312_P0_1
   1 PVCCIN_CPU0      A @S9S_MB_2U_LIB.S9S_MB_2U(SCH_1):PVCCIN_CPU0
   2    GND      B @S9S_MB_2U_LIB.S9S_MB_2U(SCH_1):GND

Q_CAPP_THLF-270UF,16V,20%,OSCOA  I93  PC321
   1 SW_P12V_PVCCIN_CPU0_FLT      A @S9S_MB_2U_LIB.S9S_MB_2U(SCH_1):SW_P12V_PVCCIN_CPU0_FLT
   2    GND      B @S9S_MB_2U_LIB.S9S_MB_2U(SCH_1):GND

Q_CAPP_THLF-270UF,16V,20%,OSCOA  I94  PC324
   1 SW_P12V_PVCCIN_CPU0_FLT      A @S9S_MB_2U_LIB.S9S_MB_2U(SCH_1):SW_P12V_PVCCIN_CPU0_FLT
   2    GND      B @S9S_MB_2U_LIB.S9S_MB_2U(SCH_1):GND

Q_RES_0402LF-3.3,1%,1/16W,CHIPA  I97  PR1787
   1 SW_PVCCIN_CPU0_BOOT1      A @S9S_MB_2U_LIB.S9S_MB_2U(SCH_1):SW_PVCCIN_CPU0_BOOT1
   2 SW_PVCCIN_CPU0_BOOT1_R      B @S9S_MB_2U_LIB.S9S_MB_2U(SCH_1):SW_PVCCIN_CPU0_BOOT1_R


DRAWING: @S9S_MB_2U_LIB.S9S_MB_2U(SCH_1):PAGE254 

Q_RES_0402LF-8.87K,1%,1/16W,EMA  I2  PR144
   1 PVCCIN_CPU0_LSET4      A @S9S_MB_2U_LIB.S9S_MB_2U(SCH_1):PVCCIN_CPU0_LSET4
   2    GND      B @S9S_MB_2U_LIB.S9S_MB_2U(SCH_1):GND

ISL99390FRZTR5935-ISL99390FRZ-A  I13  PU10_P0_4
  34 PVCCIN_CPU0_PWM4    PWM @S9S_MB_2U_LIB.S9S_MB_2U(SCH_1):PVCCIN_CPU0_PWM4
  39 PVCCIN_CPU0_VREF  REFIN @S9S_MB_2U_LIB.S9S_MB_2U(SCH_1):PVCCIN_CPU0_VREF
   3 PVCCIN_CPU0_VDD4    VCC @S9S_MB_2U_LIB.S9S_MB_2U(SCH_1):PVCCIN_CPU0_VDD4
   2    GND   AGND @S9S_MB_2U_LIB.S9S_MB_2U(SCH_1):GND
  33 SW_PVCCIN_CPU0_BOOT4   BOOT @S9S_MB_2U_LIB.S9S_MB_2U(SCH_1):SW_PVCCIN_CPU0_BOOT4
25_29 SW_P12V_PVCCIN_CPU0_FLT   VIN1 @S9S_MB_2U_LIB.S9S_MB_2U(SCH_1):SW_P12V_PVCCIN_CPU0_FLT
  32 SW_PVCCIN_CPU0_BOOTR4  PHASE @S9S_MB_2U_LIB.S9S_MB_2U(SCH_1):SW_PVCCIN_CPU0_BOOTR4
   4 PVCCIN_CPU0_PVCC   PVCC @S9S_MB_2U_LIB.S9S_MB_2U(SCH_1):PVCCIN_CPU0_PVCC
  36 PVCCIN_CPU0_ATSEN TOUT_FLT @S9S_MB_2U_LIB.S9S_MB_2U(SCH_1):PVCCIN_CPU0_ATSEN
  38 PVCCIN_CPU0_IMON4   IOUT @S9S_MB_2U_LIB.S9S_MB_2U(SCH_1):PVCCIN_CPU0_IMON4
  37 PVCCIN_CPU0_LSET4   LSET @S9S_MB_2U_LIB.S9S_MB_2U(SCH_1):PVCCIN_CPU0_LSET4
10_19 SW_PVCCIN_CPU0_SW4     SW @S9S_MB_2U_LIB.S9S_MB_2U(SCH_1):SW_PVCCIN_CPU0_SW4
   5    GND  PGND1 @S9S_MB_2U_LIB.S9S_MB_2U(SCH_1):GND
  30 SW_P12V_PVCCIN_CPU0_FLT   VIN2 @S9S_MB_2U_LIB.S9S_MB_2U(SCH_1):SW_P12V_PVCCIN_CPU0_FLT
   1 PVCCIN_CPU0_VOS4    VOS @S9S_MB_2U_LIB.S9S_MB_2U(SCH_1):PVCCIN_CPU0_VOS4
  40    GND  PGND3 @S9S_MB_2U_LIB.S9S_MB_2U(SCH_1):GND
  35 PVCCIN_CPU0_VDD4     EN @S9S_MB_2U_LIB.S9S_MB_2U(SCH_1):PVCCIN_CPU0_VDD4
  31     NC    DNC     NC
   6     NC    GL1     NC
  41     NC    GL2     NC
7_9-20_24    GND  PGND2 @S9S_MB_2U_LIB.S9S_MB_2U(SCH_1):GND

Q_RES_0402LF-2.2,1%,1/16W,CHIPA  I14  PR146
   1 PVCCIN_CPU0_PVCC      A @S9S_MB_2U_LIB.S9S_MB_2U(SCH_1):PVCCIN_CPU0_PVCC
   2 PVCCIN_CPU0_VDD4      B @S9S_MB_2U_LIB.S9S_MB_2U(SCH_1):PVCCIN_CPU0_VDD4

Q_CAP_C0402-2.2UF,10V,10%,X6S,A  I17  PC272_P0_4
   1 PVCCIN_CPU0_PVCC      A @S9S_MB_2U_LIB.S9S_MB_2U(SCH_1):PVCCIN_CPU0_PVCC
   2    GND      B @S9S_MB_2U_LIB.S9S_MB_2U(SCH_1):GND

Q_CAP_0402-0.1UF,25V,10%,X7R,CA  I26  PC1341
   1    GND      A @S9S_MB_2U_LIB.S9S_MB_2U(SCH_1):GND
   2 PVCCIN_CPU0_VREF      B @S9S_MB_2U_LIB.S9S_MB_2U(SCH_1):PVCCIN_CPU0_VREF

Q_RES_0402LF-2.2,1%,1/16W,CHIPA  I27  PR147
   1 PVCCIN_CPU0_PVCC      A @S9S_MB_2U_LIB.S9S_MB_2U(SCH_1):PVCCIN_CPU0_PVCC
   2 PVCCIN_CPU0_VDD3      B @S9S_MB_2U_LIB.S9S_MB_2U(SCH_1):PVCCIN_CPU0_VDD3

Q_CAP_C0402-2.2UF,10V,10%,X6S,A  I30  PC273_P0_3
   1 PVCCIN_CPU0_PVCC      A @S9S_MB_2U_LIB.S9S_MB_2U(SCH_1):PVCCIN_CPU0_PVCC
   2    GND      B @S9S_MB_2U_LIB.S9S_MB_2U(SCH_1):GND

Q_CAP_0402-3300PF,50V,10%,X7R,A  I35  PC274_P0_4
   1 SW_P12V_PVCCIN_CPU0_FLT      A @S9S_MB_2U_LIB.S9S_MB_2U(SCH_1):SW_P12V_PVCCIN_CPU0_FLT
   2    GND      B @S9S_MB_2U_LIB.S9S_MB_2U(SCH_1):GND

Q_RES_0402LF-3.3,1%,1/16W,CHIPA  I36  PR1768
   1 SW_PVCCIN_CPU0_BOOT4      A @S9S_MB_2U_LIB.S9S_MB_2U(SCH_1):SW_PVCCIN_CPU0_BOOT4
   2 SW_PVCCIN_CPU0_BOOT4_R      B @S9S_MB_2U_LIB.S9S_MB_2U(SCH_1):SW_PVCCIN_CPU0_BOOT4_R

Q_CAP_C0402-1UF,16V,10%,X6S,CHA  I38  PC276_P0_4
   1 SW_P12V_PVCCIN_CPU0_FLT      A @S9S_MB_2U_LIB.S9S_MB_2U(SCH_1):SW_P12V_PVCCIN_CPU0_FLT
   2    GND      B @S9S_MB_2U_LIB.S9S_MB_2U(SCH_1):GND

Q_CAP_C0805-22UF,16V,20%,X6S,CA  I39  PC280_P0_4
   1 SW_P12V_PVCCIN_CPU0_FLT      A @S9S_MB_2U_LIB.S9S_MB_2U(SCH_1):SW_P12V_PVCCIN_CPU0_FLT
   2    GND      B @S9S_MB_2U_LIB.S9S_MB_2U(SCH_1):GND

Q_CAP_C0805-22UF,16V,20%,X6S,CA  I40  PC282_P0_4
   1 SW_P12V_PVCCIN_CPU0_FLT      A @S9S_MB_2U_LIB.S9S_MB_2U(SCH_1):SW_P12V_PVCCIN_CPU0_FLT
   2    GND      B @S9S_MB_2U_LIB.S9S_MB_2U(SCH_1):GND

Q_CAP_0402-3300PF,50V,10%,X7R,A  I48  PC275_P0_3
   1 SW_P12V_PVCCIN_CPU0_FLT      A @S9S_MB_2U_LIB.S9S_MB_2U(SCH_1):SW_P12V_PVCCIN_CPU0_FLT
   2    GND      B @S9S_MB_2U_LIB.S9S_MB_2U(SCH_1):GND

Q_RES_0402LF-3.3,1%,1/16W,CHIPA  I49  PR1769
   1 SW_PVCCIN_CPU0_BOOT3      A @S9S_MB_2U_LIB.S9S_MB_2U(SCH_1):SW_PVCCIN_CPU0_BOOT3
   2 SW_PVCCIN_CPU0_BOOT3_R      B @S9S_MB_2U_LIB.S9S_MB_2U(SCH_1):SW_PVCCIN_CPU0_BOOT3_R

Q_INDUCTOR4P_14-150NH,SMLF,INDA  I50  PL112
   2 IND_P0_CPL3      2 @S9S_MB_2U_LIB.S9S_MB_2U(SCH_1):IND_P0_CPL3
   3 IND_P0_CPL4      3 @S9S_MB_2U_LIB.S9S_MB_2U(SCH_1):IND_P0_CPL4
   4 PVCCIN_CPU0      4 @S9S_MB_2U_LIB.S9S_MB_2U(SCH_1):PVCCIN_CPU0
   1 SW_PVCCIN_CPU0_SW3      1 @S9S_MB_2U_LIB.S9S_MB_2U(SCH_1):SW_PVCCIN_CPU0_SW3

Q_CAP_C0402-100NF,50V,10%,X7R,A  I51  PC279
   1 SW_PVCCIN_CPU0_BOOT3_R      A @S9S_MB_2U_LIB.S9S_MB_2U(SCH_1):SW_PVCCIN_CPU0_BOOT3_R
   2 SW_PVCCIN_CPU0_BOOTR3      B @S9S_MB_2U_LIB.S9S_MB_2U(SCH_1):SW_PVCCIN_CPU0_BOOTR3

Q_CAP_C0805-22UF,16V,20%,X6S,CA  I53  PC281_P0_3
   1 SW_P12V_PVCCIN_CPU0_FLT      A @S9S_MB_2U_LIB.S9S_MB_2U(SCH_1):SW_P12V_PVCCIN_CPU0_FLT
   2    GND      B @S9S_MB_2U_LIB.S9S_MB_2U(SCH_1):GND

Q_CAP_C0805-22UF,16V,20%,X6S,CA  I56  PC285_P0_3
   1 SW_P12V_PVCCIN_CPU0_FLT      A @S9S_MB_2U_LIB.S9S_MB_2U(SCH_1):SW_P12V_PVCCIN_CPU0_FLT
   2    GND      B @S9S_MB_2U_LIB.S9S_MB_2U(SCH_1):GND

Q_RES_0402LF-8.87K,1%,1/16W,EMA  I4  PR145
   1 PVCCIN_CPU0_LSET3      A @S9S_MB_2U_LIB.S9S_MB_2U(SCH_1):PVCCIN_CPU0_LSET3
   2    GND      B @S9S_MB_2U_LIB.S9S_MB_2U(SCH_1):GND

Q_CAP_C0402-2.2UF,10V,10%,X6S,A  I11  PC270
   1 PVCCIN_CPU0_VDD4      A @S9S_MB_2U_LIB.S9S_MB_2U(SCH_1):PVCCIN_CPU0_VDD4
   2    GND      B @S9S_MB_2U_LIB.S9S_MB_2U(SCH_1):GND

Q_CAP_0402-0.1UF,25V,10%,X7R,CA  I12  PC1340
   1    GND      A @S9S_MB_2U_LIB.S9S_MB_2U(SCH_1):GND
   2 PVCCIN_CPU0_VREF      B @S9S_MB_2U_LIB.S9S_MB_2U(SCH_1):PVCCIN_CPU0_VREF

ISL99390FRZTR5935-ISL99390FRZ-A  I20  PU11_P0_3
  34 PVCCIN_CPU0_PWM3    PWM @S9S_MB_2U_LIB.S9S_MB_2U(SCH_1):PVCCIN_CPU0_PWM3
  39 PVCCIN_CPU0_VREF  REFIN @S9S_MB_2U_LIB.S9S_MB_2U(SCH_1):PVCCIN_CPU0_VREF
   3 PVCCIN_CPU0_VDD3    VCC @S9S_MB_2U_LIB.S9S_MB_2U(SCH_1):PVCCIN_CPU0_VDD3
   2    GND   AGND @S9S_MB_2U_LIB.S9S_MB_2U(SCH_1):GND
  33 SW_PVCCIN_CPU0_BOOT3   BOOT @S9S_MB_2U_LIB.S9S_MB_2U(SCH_1):SW_PVCCIN_CPU0_BOOT3
25_29 SW_P12V_PVCCIN_CPU0_FLT   VIN1 @S9S_MB_2U_LIB.S9S_MB_2U(SCH_1):SW_P12V_PVCCIN_CPU0_FLT
  32 SW_PVCCIN_CPU0_BOOTR3  PHASE @S9S_MB_2U_LIB.S9S_MB_2U(SCH_1):SW_PVCCIN_CPU0_BOOTR3
   4 PVCCIN_CPU0_PVCC   PVCC @S9S_MB_2U_LIB.S9S_MB_2U(SCH_1):PVCCIN_CPU0_PVCC
  36 PVCCIN_CPU0_ATSEN TOUT_FLT @S9S_MB_2U_LIB.S9S_MB_2U(SCH_1):PVCCIN_CPU0_ATSEN
  38 PVCCIN_CPU0_IMON3   IOUT @S9S_MB_2U_LIB.S9S_MB_2U(SCH_1):PVCCIN_CPU0_IMON3
  37 PVCCIN_CPU0_LSET3   LSET @S9S_MB_2U_LIB.S9S_MB_2U(SCH_1):PVCCIN_CPU0_LSET3
10_19 SW_PVCCIN_CPU0_SW3     SW @S9S_MB_2U_LIB.S9S_MB_2U(SCH_1):SW_PVCCIN_CPU0_SW3
   5    GND  PGND1 @S9S_MB_2U_LIB.S9S_MB_2U(SCH_1):GND
  30 SW_P12V_PVCCIN_CPU0_FLT   VIN2 @S9S_MB_2U_LIB.S9S_MB_2U(SCH_1):SW_P12V_PVCCIN_CPU0_FLT
   1 PVCCIN_CPU0_VOS3    VOS @S9S_MB_2U_LIB.S9S_MB_2U(SCH_1):PVCCIN_CPU0_VOS3
  40    GND  PGND3 @S9S_MB_2U_LIB.S9S_MB_2U(SCH_1):GND
  35 PVCCIN_CPU0_VDD3     EN @S9S_MB_2U_LIB.S9S_MB_2U(SCH_1):PVCCIN_CPU0_VDD3
  31     NC    DNC     NC
   6     NC    GL1     NC
  41     NC    GL2     NC
7_9-20_24    GND  PGND2 @S9S_MB_2U_LIB.S9S_MB_2U(SCH_1):GND

Q_CAP_C0402-2.2UF,10V,10%,X6S,A  I25  PC271
   1 PVCCIN_CPU0_VDD3      A @S9S_MB_2U_LIB.S9S_MB_2U(SCH_1):PVCCIN_CPU0_VDD3
   2    GND      B @S9S_MB_2U_LIB.S9S_MB_2U(SCH_1):GND

Q_INDUCTOR4P_14-150NH,SMLF,INDA  I33  PL11
   2 IND_P0_CPL4      2 @S9S_MB_2U_LIB.S9S_MB_2U(SCH_1):IND_P0_CPL4
   3 IND_P0_CPL5      3 @S9S_MB_2U_LIB.S9S_MB_2U(SCH_1):IND_P0_CPL5
   4 PVCCIN_CPU0      4 @S9S_MB_2U_LIB.S9S_MB_2U(SCH_1):PVCCIN_CPU0
   1 SW_PVCCIN_CPU0_SW4      1 @S9S_MB_2U_LIB.S9S_MB_2U(SCH_1):SW_PVCCIN_CPU0_SW4

Q_CAP_C0402-100NF,50V,10%,X7R,A  I34  PC278
   1 SW_PVCCIN_CPU0_BOOT4_R      A @S9S_MB_2U_LIB.S9S_MB_2U(SCH_1):SW_PVCCIN_CPU0_BOOT4_R
   2 SW_PVCCIN_CPU0_BOOTR4      B @S9S_MB_2U_LIB.S9S_MB_2U(SCH_1):SW_PVCCIN_CPU0_BOOTR4

Q_RES_0402LF-0,5%,1/16W,CHIP,CA  I41  PR148
   1 PVCCIN_CPU0_VOS4      A @S9S_MB_2U_LIB.S9S_MB_2U(SCH_1):PVCCIN_CPU0_VOS4
   2 PVCCIN_CPU0      B @S9S_MB_2U_LIB.S9S_MB_2U(SCH_1):PVCCIN_CPU0

Q_CAP_C0805-22UF,16V,20%,X6S,CA  I43  PC284_P0_4
   1 SW_P12V_PVCCIN_CPU0_FLT      A @S9S_MB_2U_LIB.S9S_MB_2U(SCH_1):SW_P12V_PVCCIN_CPU0_FLT
   2    GND      B @S9S_MB_2U_LIB.S9S_MB_2U(SCH_1):GND

Q_RES_0402LF-0,5%,1/16W,CHIP,CA  I46  PR149
   1 PVCCIN_CPU0_VOS3      A @S9S_MB_2U_LIB.S9S_MB_2U(SCH_1):PVCCIN_CPU0_VOS3
   2 PVCCIN_CPU0      B @S9S_MB_2U_LIB.S9S_MB_2U(SCH_1):PVCCIN_CPU0

Q_CAP_C0402-1UF,16V,10%,X6S,CHA  I52  PC277_P0_3
   1 SW_P12V_PVCCIN_CPU0_FLT      A @S9S_MB_2U_LIB.S9S_MB_2U(SCH_1):SW_P12V_PVCCIN_CPU0_FLT
   2    GND      B @S9S_MB_2U_LIB.S9S_MB_2U(SCH_1):GND

Q_CAP_C0805-22UF,16V,20%,X6S,CA  I54  PC283_P0_3
   1 SW_P12V_PVCCIN_CPU0_FLT      A @S9S_MB_2U_LIB.S9S_MB_2U(SCH_1):SW_P12V_PVCCIN_CPU0_FLT
   2    GND      B @S9S_MB_2U_LIB.S9S_MB_2U(SCH_1):GND

Q_CAP_C0805-22UF,4V,20%,X6S,CHA  I59  PC289_P0_3
   1 PVCCIN_CPU0      A @S9S_MB_2U_LIB.S9S_MB_2U(SCH_1):PVCCIN_CPU0
   2    GND      B @S9S_MB_2U_LIB.S9S_MB_2U(SCH_1):GND

Q_CAP_C0805-22UF,4V,20%,X6S,CHA  I60  PC288_P0_4
   1 PVCCIN_CPU0      A @S9S_MB_2U_LIB.S9S_MB_2U(SCH_1):PVCCIN_CPU0
   2    GND      B @S9S_MB_2U_LIB.S9S_MB_2U(SCH_1):GND

Q_CAP_C0805-22UF,4V,20%,X6S,CHA  I61  PC290_P0_4
   1 PVCCIN_CPU0      A @S9S_MB_2U_LIB.S9S_MB_2U(SCH_1):PVCCIN_CPU0
   2    GND      B @S9S_MB_2U_LIB.S9S_MB_2U(SCH_1):GND

Q_CAP_C0805-22UF,4V,20%,X6S,CHA  I65  PC291_P0_3
   1 PVCCIN_CPU0      A @S9S_MB_2U_LIB.S9S_MB_2U(SCH_1):PVCCIN_CPU0
   2    GND      B @S9S_MB_2U_LIB.S9S_MB_2U(SCH_1):GND


DRAWING: @S9S_MB_2U_LIB.S9S_MB_2U(SCH_1):PAGE255 

Q_RES_0402LF-8.87K,1%,1/16W,EMA  I2  PR138
   1 PVCCIN_CPU0_LSET6      A @S9S_MB_2U_LIB.S9S_MB_2U(SCH_1):PVCCIN_CPU0_LSET6
   2    GND      B @S9S_MB_2U_LIB.S9S_MB_2U(SCH_1):GND

Q_CAP_0402-0.1UF,25V,10%,X7R,CA  I11  PC1342
   1    GND      A @S9S_MB_2U_LIB.S9S_MB_2U(SCH_1):GND
   2 PVCCIN_CPU0_VREF      B @S9S_MB_2U_LIB.S9S_MB_2U(SCH_1):PVCCIN_CPU0_VREF

ISL99390FRZTR5935-ISL99390FRZ-A  I12  PU8_P0_6
  34 PVCCIN_CPU0_PWM6    PWM @S9S_MB_2U_LIB.S9S_MB_2U(SCH_1):PVCCIN_CPU0_PWM6
  39 PVCCIN_CPU0_VREF  REFIN @S9S_MB_2U_LIB.S9S_MB_2U(SCH_1):PVCCIN_CPU0_VREF
   3 PVCCIN_CPU0_VDD6    VCC @S9S_MB_2U_LIB.S9S_MB_2U(SCH_1):PVCCIN_CPU0_VDD6
   2    GND   AGND @S9S_MB_2U_LIB.S9S_MB_2U(SCH_1):GND
  33 SW_PVCCIN_CPU0_BOOT6   BOOT @S9S_MB_2U_LIB.S9S_MB_2U(SCH_1):SW_PVCCIN_CPU0_BOOT6
25_29 SW_P12V_PVCCIN_CPU0_FLT   VIN1 @S9S_MB_2U_LIB.S9S_MB_2U(SCH_1):SW_P12V_PVCCIN_CPU0_FLT
  32 SW_PVCCIN_CPU0_BOOTR6  PHASE @S9S_MB_2U_LIB.S9S_MB_2U(SCH_1):SW_PVCCIN_CPU0_BOOTR6
   4 PVCCIN_CPU0_PVCC   PVCC @S9S_MB_2U_LIB.S9S_MB_2U(SCH_1):PVCCIN_CPU0_PVCC
  36 PVCCIN_CPU0_ATSEN TOUT_FLT @S9S_MB_2U_LIB.S9S_MB_2U(SCH_1):PVCCIN_CPU0_ATSEN
  38 PVCCIN_CPU0_IMON6   IOUT @S9S_MB_2U_LIB.S9S_MB_2U(SCH_1):PVCCIN_CPU0_IMON6
  37 PVCCIN_CPU0_LSET6   LSET @S9S_MB_2U_LIB.S9S_MB_2U(SCH_1):PVCCIN_CPU0_LSET6
10_19 SW_PVCCIN_CPU0_SW6     SW @S9S_MB_2U_LIB.S9S_MB_2U(SCH_1):SW_PVCCIN_CPU0_SW6
   5    GND  PGND1 @S9S_MB_2U_LIB.S9S_MB_2U(SCH_1):GND
  30 SW_P12V_PVCCIN_CPU0_FLT   VIN2 @S9S_MB_2U_LIB.S9S_MB_2U(SCH_1):SW_P12V_PVCCIN_CPU0_FLT
   1 PVCCIN_CPU0_VOS6    VOS @S9S_MB_2U_LIB.S9S_MB_2U(SCH_1):PVCCIN_CPU0_VOS6
  40    GND  PGND3 @S9S_MB_2U_LIB.S9S_MB_2U(SCH_1):GND
  35 PVCCIN_CPU0_VDD6     EN @S9S_MB_2U_LIB.S9S_MB_2U(SCH_1):PVCCIN_CPU0_VDD6
  31     NC    DNC     NC
   6     NC    GL1     NC
  41     NC    GL2     NC
7_9-20_24    GND  PGND2 @S9S_MB_2U_LIB.S9S_MB_2U(SCH_1):GND

Q_CAP_C0402-2.2UF,10V,10%,X6S,A  I17  PC250_P0_6
   1 PVCCIN_CPU0_PVCC      A @S9S_MB_2U_LIB.S9S_MB_2U(SCH_1):PVCCIN_CPU0_PVCC
   2    GND      B @S9S_MB_2U_LIB.S9S_MB_2U(SCH_1):GND

Q_INDUCTOR4P_14-150NH,SMLF,INDA  I32  PL9
   2 IND_P0_CPL6      2 @S9S_MB_2U_LIB.S9S_MB_2U(SCH_1):IND_P0_CPL6
   3 IND_P0_CPL1      3 @S9S_MB_2U_LIB.S9S_MB_2U(SCH_1):IND_P0_CPL1
   4 PVCCIN_CPU0      4 @S9S_MB_2U_LIB.S9S_MB_2U(SCH_1):PVCCIN_CPU0
   1 SW_PVCCIN_CPU0_SW6      1 @S9S_MB_2U_LIB.S9S_MB_2U(SCH_1):SW_PVCCIN_CPU0_SW6

Q_CAP_0402-3300PF,50V,10%,X7R,A  I34  PC252_P0_6
   1 SW_P12V_PVCCIN_CPU0_FLT      A @S9S_MB_2U_LIB.S9S_MB_2U(SCH_1):SW_P12V_PVCCIN_CPU0_FLT
   2    GND      B @S9S_MB_2U_LIB.S9S_MB_2U(SCH_1):GND

Q_CAP_C0402-1UF,16V,10%,X6S,CHA  I37  PC254_P0_6
   1 SW_P12V_PVCCIN_CPU0_FLT      A @S9S_MB_2U_LIB.S9S_MB_2U(SCH_1):SW_P12V_PVCCIN_CPU0_FLT
   2    GND      B @S9S_MB_2U_LIB.S9S_MB_2U(SCH_1):GND

Q_CAP_C0805-22UF,16V,20%,X6S,CA  I38  PC258_P0_6
   1 SW_P12V_PVCCIN_CPU0_FLT      A @S9S_MB_2U_LIB.S9S_MB_2U(SCH_1):SW_P12V_PVCCIN_CPU0_FLT
   2    GND      B @S9S_MB_2U_LIB.S9S_MB_2U(SCH_1):GND

Q_CAP_C0805-22UF,16V,20%,X6S,CA  I39  PC260_P0_6
   1 SW_P12V_PVCCIN_CPU0_FLT      A @S9S_MB_2U_LIB.S9S_MB_2U(SCH_1):SW_P12V_PVCCIN_CPU0_FLT
   2    GND      B @S9S_MB_2U_LIB.S9S_MB_2U(SCH_1):GND

Q_RES_0402LF-0,5%,1/16W,CHIP,CA  I40  PR142
   1 PVCCIN_CPU0_VOS6      A @S9S_MB_2U_LIB.S9S_MB_2U(SCH_1):PVCCIN_CPU0_VOS6
   2 PVCCIN_CPU0      B @S9S_MB_2U_LIB.S9S_MB_2U(SCH_1):PVCCIN_CPU0

Q_CAP_C0805-22UF,4V,20%,X6S,CHA  I42  PC266_P0_6
   1 PVCCIN_CPU0      A @S9S_MB_2U_LIB.S9S_MB_2U(SCH_1):PVCCIN_CPU0
   2    GND      B @S9S_MB_2U_LIB.S9S_MB_2U(SCH_1):GND

Q_CAP_C0805-22UF,4V,20%,X6S,CHA  I59  PC268_P0_6
   1 PVCCIN_CPU0      A @S9S_MB_2U_LIB.S9S_MB_2U(SCH_1):PVCCIN_CPU0
   2    GND      B @S9S_MB_2U_LIB.S9S_MB_2U(SCH_1):GND

Q_RES_0402LF-8.87K,1%,1/16W,EMA  I4  PR139
   1 PVCCIN_CPU0_LSET5      A @S9S_MB_2U_LIB.S9S_MB_2U(SCH_1):PVCCIN_CPU0_LSET5
   2    GND      B @S9S_MB_2U_LIB.S9S_MB_2U(SCH_1):GND

Q_CAP_C0402-2.2UF,10V,10%,X6S,A  I13  PC248
   1 PVCCIN_CPU0_VDD6      A @S9S_MB_2U_LIB.S9S_MB_2U(SCH_1):PVCCIN_CPU0_VDD6
   2    GND      B @S9S_MB_2U_LIB.S9S_MB_2U(SCH_1):GND

Q_RES_0402LF-2.2,1%,1/16W,CHIPA  I14  PR140
   1 PVCCIN_CPU0_PVCC      A @S9S_MB_2U_LIB.S9S_MB_2U(SCH_1):PVCCIN_CPU0_PVCC
   2 PVCCIN_CPU0_VDD6      B @S9S_MB_2U_LIB.S9S_MB_2U(SCH_1):PVCCIN_CPU0_VDD6

Q_CAP_C0402-2.2UF,10V,10%,X6S,A  I24  PC249
   1 PVCCIN_CPU0_VDD5      A @S9S_MB_2U_LIB.S9S_MB_2U(SCH_1):PVCCIN_CPU0_VDD5
   2    GND      B @S9S_MB_2U_LIB.S9S_MB_2U(SCH_1):GND

Q_CAP_0402-0.1UF,25V,10%,X7R,CA  I25  PC1343
   1    GND      A @S9S_MB_2U_LIB.S9S_MB_2U(SCH_1):GND
   2 PVCCIN_CPU0_VREF      B @S9S_MB_2U_LIB.S9S_MB_2U(SCH_1):PVCCIN_CPU0_VREF

Q_RES_0402LF-2.2,1%,1/16W,CHIPA  I26  PR141
   1 PVCCIN_CPU0_PVCC      A @S9S_MB_2U_LIB.S9S_MB_2U(SCH_1):PVCCIN_CPU0_PVCC
   2 PVCCIN_CPU0_VDD5      B @S9S_MB_2U_LIB.S9S_MB_2U(SCH_1):PVCCIN_CPU0_VDD5

Q_CAP_C0402-2.2UF,10V,10%,X6S,A  I29  PC251_P0_5
   1 PVCCIN_CPU0_PVCC      A @S9S_MB_2U_LIB.S9S_MB_2U(SCH_1):PVCCIN_CPU0_PVCC
   2    GND      B @S9S_MB_2U_LIB.S9S_MB_2U(SCH_1):GND

Q_CAP_C0402-100NF,50V,10%,X7R,A  I33  PC256
   1 SW_PVCCIN_CPU0_BOOT6_R      A @S9S_MB_2U_LIB.S9S_MB_2U(SCH_1):SW_PVCCIN_CPU0_BOOT6_R
   2 SW_PVCCIN_CPU0_BOOTR6      B @S9S_MB_2U_LIB.S9S_MB_2U(SCH_1):SW_PVCCIN_CPU0_BOOTR6

Q_RES_0402LF-3.3,1%,1/16W,CHIPA  I35  PR1770
   1 SW_PVCCIN_CPU0_BOOT6      A @S9S_MB_2U_LIB.S9S_MB_2U(SCH_1):SW_PVCCIN_CPU0_BOOT6
   2 SW_PVCCIN_CPU0_BOOT6_R      B @S9S_MB_2U_LIB.S9S_MB_2U(SCH_1):SW_PVCCIN_CPU0_BOOT6_R

Q_CAP_C0805-22UF,16V,20%,X6S,CA  I43  PC262_P0_6
   1 SW_P12V_PVCCIN_CPU0_FLT      A @S9S_MB_2U_LIB.S9S_MB_2U(SCH_1):SW_P12V_PVCCIN_CPU0_FLT
   2    GND      B @S9S_MB_2U_LIB.S9S_MB_2U(SCH_1):GND

Q_RES_0402LF-0,5%,1/16W,CHIP,CA  I46  PR143
   1 PVCCIN_CPU0_VOS5      A @S9S_MB_2U_LIB.S9S_MB_2U(SCH_1):PVCCIN_CPU0_VOS5
   2 PVCCIN_CPU0      B @S9S_MB_2U_LIB.S9S_MB_2U(SCH_1):PVCCIN_CPU0

Q_CAP_0402-3300PF,50V,10%,X7R,A  I48  PC253_P0_5
   1 SW_P12V_PVCCIN_CPU0_FLT      A @S9S_MB_2U_LIB.S9S_MB_2U(SCH_1):SW_P12V_PVCCIN_CPU0_FLT
   2    GND      B @S9S_MB_2U_LIB.S9S_MB_2U(SCH_1):GND

Q_RES_0402LF-3.3,1%,1/16W,CHIPA  I49  PR1771
   1 SW_PVCCIN_CPU0_BOOT5      A @S9S_MB_2U_LIB.S9S_MB_2U(SCH_1):SW_PVCCIN_CPU0_BOOT5
   2 SW_PVCCIN_CPU0_BOOT5_R      B @S9S_MB_2U_LIB.S9S_MB_2U(SCH_1):SW_PVCCIN_CPU0_BOOT5_R

Q_INDUCTOR4P_14-150NH,SMLF,INDA  I50  PL10
   2 IND_P0_CPL5      2 @S9S_MB_2U_LIB.S9S_MB_2U(SCH_1):IND_P0_CPL5
   3 IND_P0_CPL8      3 @S9S_MB_2U_LIB.S9S_MB_2U(SCH_1):IND_P0_CPL8
   4 PVCCIN_CPU0      4 @S9S_MB_2U_LIB.S9S_MB_2U(SCH_1):PVCCIN_CPU0
   1 SW_PVCCIN_CPU0_SW5      1 @S9S_MB_2U_LIB.S9S_MB_2U(SCH_1):SW_PVCCIN_CPU0_SW5

Q_CAP_C0402-100NF,50V,10%,X7R,A  I51  PC257
   1 SW_PVCCIN_CPU0_BOOT5_R      A @S9S_MB_2U_LIB.S9S_MB_2U(SCH_1):SW_PVCCIN_CPU0_BOOT5_R
   2 SW_PVCCIN_CPU0_BOOTR5      B @S9S_MB_2U_LIB.S9S_MB_2U(SCH_1):SW_PVCCIN_CPU0_BOOTR5

Q_CAP_C0402-1UF,16V,10%,X6S,CHA  I52  PC255_P0_5
   1 SW_P12V_PVCCIN_CPU0_FLT      A @S9S_MB_2U_LIB.S9S_MB_2U(SCH_1):SW_P12V_PVCCIN_CPU0_FLT
   2    GND      B @S9S_MB_2U_LIB.S9S_MB_2U(SCH_1):GND

Q_CAP_C0805-22UF,16V,20%,X6S,CA  I53  PC259_P0_5
   1 SW_P12V_PVCCIN_CPU0_FLT      A @S9S_MB_2U_LIB.S9S_MB_2U(SCH_1):SW_P12V_PVCCIN_CPU0_FLT
   2    GND      B @S9S_MB_2U_LIB.S9S_MB_2U(SCH_1):GND

Q_CAP_C0805-22UF,16V,20%,X6S,CA  I54  PC261_P0_5
   1 SW_P12V_PVCCIN_CPU0_FLT      A @S9S_MB_2U_LIB.S9S_MB_2U(SCH_1):SW_P12V_PVCCIN_CPU0_FLT
   2    GND      B @S9S_MB_2U_LIB.S9S_MB_2U(SCH_1):GND

Q_CAP_C0805-22UF,16V,20%,X6S,CA  I56  PC263_P0_5
   1 SW_P12V_PVCCIN_CPU0_FLT      A @S9S_MB_2U_LIB.S9S_MB_2U(SCH_1):SW_P12V_PVCCIN_CPU0_FLT
   2    GND      B @S9S_MB_2U_LIB.S9S_MB_2U(SCH_1):GND

Q_CAP_C0805-22UF,4V,20%,X6S,CHA  I63  PC267_P0_5
   1 PVCCIN_CPU0      A @S9S_MB_2U_LIB.S9S_MB_2U(SCH_1):PVCCIN_CPU0
   2    GND      B @S9S_MB_2U_LIB.S9S_MB_2U(SCH_1):GND

Q_CAP_C0805-22UF,4V,20%,X6S,CHA  I64  PC269_P0_5
   1 PVCCIN_CPU0      A @S9S_MB_2U_LIB.S9S_MB_2U(SCH_1):PVCCIN_CPU0
   2    GND      B @S9S_MB_2U_LIB.S9S_MB_2U(SCH_1):GND

ISL99390FRZTR5935-ISL99390FRZ-A  I66  PU9_P0_5
  34 PVCCIN_CPU0_PWM5    PWM @S9S_MB_2U_LIB.S9S_MB_2U(SCH_1):PVCCIN_CPU0_PWM5
  39 PVCCIN_CPU0_VREF  REFIN @S9S_MB_2U_LIB.S9S_MB_2U(SCH_1):PVCCIN_CPU0_VREF
   3 PVCCIN_CPU0_VDD5    VCC @S9S_MB_2U_LIB.S9S_MB_2U(SCH_1):PVCCIN_CPU0_VDD5
   2    GND   AGND @S9S_MB_2U_LIB.S9S_MB_2U(SCH_1):GND
  33 SW_PVCCIN_CPU0_BOOT5   BOOT @S9S_MB_2U_LIB.S9S_MB_2U(SCH_1):SW_PVCCIN_CPU0_BOOT5
25_29 SW_P12V_PVCCIN_CPU0_FLT   VIN1 @S9S_MB_2U_LIB.S9S_MB_2U(SCH_1):SW_P12V_PVCCIN_CPU0_FLT
  32 SW_PVCCIN_CPU0_BOOTR5  PHASE @S9S_MB_2U_LIB.S9S_MB_2U(SCH_1):SW_PVCCIN_CPU0_BOOTR5
   4 PVCCIN_CPU0_PVCC   PVCC @S9S_MB_2U_LIB.S9S_MB_2U(SCH_1):PVCCIN_CPU0_PVCC
  36 PVCCIN_CPU0_ATSEN TOUT_FLT @S9S_MB_2U_LIB.S9S_MB_2U(SCH_1):PVCCIN_CPU0_ATSEN
  38 PVCCIN_CPU0_IMON5   IOUT @S9S_MB_2U_LIB.S9S_MB_2U(SCH_1):PVCCIN_CPU0_IMON5
  37 PVCCIN_CPU0_LSET5   LSET @S9S_MB_2U_LIB.S9S_MB_2U(SCH_1):PVCCIN_CPU0_LSET5
10_19 SW_PVCCIN_CPU0_SW5     SW @S9S_MB_2U_LIB.S9S_MB_2U(SCH_1):SW_PVCCIN_CPU0_SW5
   5    GND  PGND1 @S9S_MB_2U_LIB.S9S_MB_2U(SCH_1):GND
  30 SW_P12V_PVCCIN_CPU0_FLT   VIN2 @S9S_MB_2U_LIB.S9S_MB_2U(SCH_1):SW_P12V_PVCCIN_CPU0_FLT
   1 PVCCIN_CPU0_VOS5    VOS @S9S_MB_2U_LIB.S9S_MB_2U(SCH_1):PVCCIN_CPU0_VOS5
  40    GND  PGND3 @S9S_MB_2U_LIB.S9S_MB_2U(SCH_1):GND
  35 PVCCIN_CPU0_VDD5     EN @S9S_MB_2U_LIB.S9S_MB_2U(SCH_1):PVCCIN_CPU0_VDD5
  31     NC    DNC     NC
   6     NC    GL1     NC
  41     NC    GL2     NC
7_9-20_24    GND  PGND2 @S9S_MB_2U_LIB.S9S_MB_2U(SCH_1):GND


DRAWING: @S9S_MB_2U_LIB.S9S_MB_2U(SCH_1):PAGE256 

ISL99390FRZTR5935-ISL99390FRZ-A  I2  PU6_P0_8
  34 PVCCIN_CPU0_PWM8    PWM @S9S_MB_2U_LIB.S9S_MB_2U(SCH_1):PVCCIN_CPU0_PWM8
  39 PVCCIN_CPU0_VREF  REFIN @S9S_MB_2U_LIB.S9S_MB_2U(SCH_1):PVCCIN_CPU0_VREF
   3 PVCCIN_CPU0_VDD8    VCC @S9S_MB_2U_LIB.S9S_MB_2U(SCH_1):PVCCIN_CPU0_VDD8
   2    GND   AGND @S9S_MB_2U_LIB.S9S_MB_2U(SCH_1):GND
  33 SW_PVCCIN_CPU0_BOOT8   BOOT @S9S_MB_2U_LIB.S9S_MB_2U(SCH_1):SW_PVCCIN_CPU0_BOOT8
25_29 SW_P12V_PVCCIN_CPU0_FLT   VIN1 @S9S_MB_2U_LIB.S9S_MB_2U(SCH_1):SW_P12V_PVCCIN_CPU0_FLT
  32 SW_PVCCIN_CPU0_BOOTR8  PHASE @S9S_MB_2U_LIB.S9S_MB_2U(SCH_1):SW_PVCCIN_CPU0_BOOTR8
   4 PVCCIN_CPU0_PVCC   PVCC @S9S_MB_2U_LIB.S9S_MB_2U(SCH_1):PVCCIN_CPU0_PVCC
  36 PVCCIN_CPU0_ATSEN TOUT_FLT @S9S_MB_2U_LIB.S9S_MB_2U(SCH_1):PVCCIN_CPU0_ATSEN
  38 PVCCIN_CPU0_IMON8   IOUT @S9S_MB_2U_LIB.S9S_MB_2U(SCH_1):PVCCIN_CPU0_IMON8
  37 PVCCIN_CPU0_LSET8   LSET @S9S_MB_2U_LIB.S9S_MB_2U(SCH_1):PVCCIN_CPU0_LSET8
10_19 SW_PVCCIN_CPU0_SW8     SW @S9S_MB_2U_LIB.S9S_MB_2U(SCH_1):SW_PVCCIN_CPU0_SW8
   5    GND  PGND1 @S9S_MB_2U_LIB.S9S_MB_2U(SCH_1):GND
  30 SW_P12V_PVCCIN_CPU0_FLT   VIN2 @S9S_MB_2U_LIB.S9S_MB_2U(SCH_1):SW_P12V_PVCCIN_CPU0_FLT
   1 PVCCIN_CPU0_VOS8    VOS @S9S_MB_2U_LIB.S9S_MB_2U(SCH_1):PVCCIN_CPU0_VOS8
  40    GND  PGND3 @S9S_MB_2U_LIB.S9S_MB_2U(SCH_1):GND
  35 PVCCIN_CPU0_VDD8     EN @S9S_MB_2U_LIB.S9S_MB_2U(SCH_1):PVCCIN_CPU0_VDD8
  31     NC    DNC     NC
   6     NC    GL1     NC
  41     NC    GL2     NC
7_9-20_24    GND  PGND2 @S9S_MB_2U_LIB.S9S_MB_2U(SCH_1):GND

Q_RES_0402LF-3.3,1%,1/16W,CHIPA  I19  PR1772
   1 SW_PVCCIN_CPU0_BOOT8      A @S9S_MB_2U_LIB.S9S_MB_2U(SCH_1):SW_PVCCIN_CPU0_BOOT8
   2 SW_PVCCIN_CPU0_BOOT8_R      B @S9S_MB_2U_LIB.S9S_MB_2U(SCH_1):SW_PVCCIN_CPU0_BOOT8_R

Q_CAP_C0402-1UF,16V,10%,X6S,CHA  I20  PC232_P0_8
   1 SW_P12V_PVCCIN_CPU0_FLT      A @S9S_MB_2U_LIB.S9S_MB_2U(SCH_1):SW_P12V_PVCCIN_CPU0_FLT
   2    GND      B @S9S_MB_2U_LIB.S9S_MB_2U(SCH_1):GND

Q_RES_0402LF-2.2,1%,1/16W,CHIPA  I33  PR135
   1 PVCCIN_CPU0_PVCC      A @S9S_MB_2U_LIB.S9S_MB_2U(SCH_1):PVCCIN_CPU0_PVCC
   2 PVCCIN_CPU0_VDD7      B @S9S_MB_2U_LIB.S9S_MB_2U(SCH_1):PVCCIN_CPU0_VDD7

Q_CAP_C0402-2.2UF,10V,10%,X6S,A  I36  PC229_P0_7
   1 PVCCIN_CPU0_PVCC      A @S9S_MB_2U_LIB.S9S_MB_2U(SCH_1):PVCCIN_CPU0_PVCC
   2    GND      B @S9S_MB_2U_LIB.S9S_MB_2U(SCH_1):GND

Q_INDUCTOR_SMLF-120NH/69A,IND,A  I39  PL105
   2    GND      2 @S9S_MB_2U_LIB.S9S_MB_2U(SCH_1):GND
   1 IND_P0_CPL7      1 @S9S_MB_2U_LIB.S9S_MB_2U(SCH_1):IND_P0_CPL7

Q_RES_0402LF-3.3,1%,1/16W,CHIPA  I40  PR1773
   1 SW_PVCCIN_CPU0_BOOT7      A @S9S_MB_2U_LIB.S9S_MB_2U(SCH_1):SW_PVCCIN_CPU0_BOOT7
   2 SW_PVCCIN_CPU0_BOOT7_R      B @S9S_MB_2U_LIB.S9S_MB_2U(SCH_1):SW_PVCCIN_CPU0_BOOT7_R

Q_CAP_C0402-1UF,16V,10%,X6S,CHA  I52  PC242_P0_8
   1 PVCCIN_CPU0      A @S9S_MB_2U_LIB.S9S_MB_2U(SCH_1):PVCCIN_CPU0
   2    GND      B @S9S_MB_2U_LIB.S9S_MB_2U(SCH_1):GND

Q_RES_0402LF-0,5%,1/16W,CHIP,CA  I57  PR137
   1 PVCCIN_CPU0_VOS7      A @S9S_MB_2U_LIB.S9S_MB_2U(SCH_1):PVCCIN_CPU0_VOS7
   2 PVCCIN_CPU0      B @S9S_MB_2U_LIB.S9S_MB_2U(SCH_1):PVCCIN_CPU0

Q_INDUCTOR4P_14-150NH,SMLF,INDA  I58  PL8
   2 IND_P0_CPL7      2 @S9S_MB_2U_LIB.S9S_MB_2U(SCH_1):IND_P0_CPL7
   3 IND_P0_CPL6      3 @S9S_MB_2U_LIB.S9S_MB_2U(SCH_1):IND_P0_CPL6
   4 PVCCIN_CPU0      4 @S9S_MB_2U_LIB.S9S_MB_2U(SCH_1):PVCCIN_CPU0
   1 SW_PVCCIN_CPU0_SW7      1 @S9S_MB_2U_LIB.S9S_MB_2U(SCH_1):SW_PVCCIN_CPU0_SW7

Q_CAP_C0805-22UF,16V,20%,X6S,CA  I64  PC241_P0_7
   1 SW_P12V_PVCCIN_CPU0_FLT      A @S9S_MB_2U_LIB.S9S_MB_2U(SCH_1):SW_P12V_PVCCIN_CPU0_FLT
   2    GND      B @S9S_MB_2U_LIB.S9S_MB_2U(SCH_1):GND

Q_RES_0402LF-8.87K,1%,1/16W,EMA  I4  PR132
   1 PVCCIN_CPU0_LSET8      A @S9S_MB_2U_LIB.S9S_MB_2U(SCH_1):PVCCIN_CPU0_LSET8
   2    GND      B @S9S_MB_2U_LIB.S9S_MB_2U(SCH_1):GND

Q_CAP_0402-0.1UF,25V,10%,X7R,CA  I7  PC1344
   1    GND      A @S9S_MB_2U_LIB.S9S_MB_2U(SCH_1):GND
   2 PVCCIN_CPU0_VREF      B @S9S_MB_2U_LIB.S9S_MB_2U(SCH_1):PVCCIN_CPU0_VREF

Q_CAP_C0402-2.2UF,10V,10%,X6S,A  I11  PC226
   1 PVCCIN_CPU0_VDD8      A @S9S_MB_2U_LIB.S9S_MB_2U(SCH_1):PVCCIN_CPU0_VDD8
   2    GND      B @S9S_MB_2U_LIB.S9S_MB_2U(SCH_1):GND

Q_RES_0402LF-2.2,1%,1/16W,CHIPA  I12  PR134
   1 PVCCIN_CPU0_PVCC      A @S9S_MB_2U_LIB.S9S_MB_2U(SCH_1):PVCCIN_CPU0_PVCC
   2 PVCCIN_CPU0_VDD8      B @S9S_MB_2U_LIB.S9S_MB_2U(SCH_1):PVCCIN_CPU0_VDD8

Q_CAP_C0402-2.2UF,10V,10%,X6S,A  I15  PC228_P0_8
   1 PVCCIN_CPU0_PVCC      A @S9S_MB_2U_LIB.S9S_MB_2U(SCH_1):PVCCIN_CPU0_PVCC
   2    GND      B @S9S_MB_2U_LIB.S9S_MB_2U(SCH_1):GND

Q_CAP_0402-3300PF,50V,10%,X7R,A  I17  PC230_P0_8
   1 SW_P12V_PVCCIN_CPU0_FLT      A @S9S_MB_2U_LIB.S9S_MB_2U(SCH_1):SW_P12V_PVCCIN_CPU0_FLT
   2    GND      B @S9S_MB_2U_LIB.S9S_MB_2U(SCH_1):GND

Q_CAP_C0805-22UF,16V,20%,X6S,CA  I21  PC236_P0_8
   1 SW_P12V_PVCCIN_CPU0_FLT      A @S9S_MB_2U_LIB.S9S_MB_2U(SCH_1):SW_P12V_PVCCIN_CPU0_FLT
   2    GND      B @S9S_MB_2U_LIB.S9S_MB_2U(SCH_1):GND

Q_RES_0402LF-8.87K,1%,1/16W,EMA  I23  PR133
   1 PVCCIN_CPU0_LSET7      A @S9S_MB_2U_LIB.S9S_MB_2U(SCH_1):PVCCIN_CPU0_LSET7
   2    GND      B @S9S_MB_2U_LIB.S9S_MB_2U(SCH_1):GND

Q_CAP_0402-0.1UF,25V,10%,X7R,CA  I29  PC1345
   1    GND      A @S9S_MB_2U_LIB.S9S_MB_2U(SCH_1):GND
   2 PVCCIN_CPU0_VREF      B @S9S_MB_2U_LIB.S9S_MB_2U(SCH_1):PVCCIN_CPU0_VREF

Q_CAP_C0402-2.2UF,10V,10%,X6S,A  I31  PC227
   1 PVCCIN_CPU0_VDD7      A @S9S_MB_2U_LIB.S9S_MB_2U(SCH_1):PVCCIN_CPU0_VDD7
   2    GND      B @S9S_MB_2U_LIB.S9S_MB_2U(SCH_1):GND

ISL99390FRZTR5935-ISL99390FRZ-A  I32  PU7_P0_7
  34 PVCCIN_CPU0_PWM7    PWM @S9S_MB_2U_LIB.S9S_MB_2U(SCH_1):PVCCIN_CPU0_PWM7
  39 PVCCIN_CPU0_VREF  REFIN @S9S_MB_2U_LIB.S9S_MB_2U(SCH_1):PVCCIN_CPU0_VREF
   3 PVCCIN_CPU0_VDD7    VCC @S9S_MB_2U_LIB.S9S_MB_2U(SCH_1):PVCCIN_CPU0_VDD7
   2    GND   AGND @S9S_MB_2U_LIB.S9S_MB_2U(SCH_1):GND
  33 SW_PVCCIN_CPU0_BOOT7   BOOT @S9S_MB_2U_LIB.S9S_MB_2U(SCH_1):SW_PVCCIN_CPU0_BOOT7
25_29 SW_P12V_PVCCIN_CPU0_FLT   VIN1 @S9S_MB_2U_LIB.S9S_MB_2U(SCH_1):SW_P12V_PVCCIN_CPU0_FLT
  32 SW_PVCCIN_CPU0_BOOTR7  PHASE @S9S_MB_2U_LIB.S9S_MB_2U(SCH_1):SW_PVCCIN_CPU0_BOOTR7
   4 PVCCIN_CPU0_PVCC   PVCC @S9S_MB_2U_LIB.S9S_MB_2U(SCH_1):PVCCIN_CPU0_PVCC
  36 PVCCIN_CPU0_ATSEN TOUT_FLT @S9S_MB_2U_LIB.S9S_MB_2U(SCH_1):PVCCIN_CPU0_ATSEN
  38 PVCCIN_CPU0_IMON7   IOUT @S9S_MB_2U_LIB.S9S_MB_2U(SCH_1):PVCCIN_CPU0_IMON7
  37 PVCCIN_CPU0_LSET7   LSET @S9S_MB_2U_LIB.S9S_MB_2U(SCH_1):PVCCIN_CPU0_LSET7
10_19 SW_PVCCIN_CPU0_SW7     SW @S9S_MB_2U_LIB.S9S_MB_2U(SCH_1):SW_PVCCIN_CPU0_SW7
   5    GND  PGND1 @S9S_MB_2U_LIB.S9S_MB_2U(SCH_1):GND
  30 SW_P12V_PVCCIN_CPU0_FLT   VIN2 @S9S_MB_2U_LIB.S9S_MB_2U(SCH_1):SW_P12V_PVCCIN_CPU0_FLT
   1 PVCCIN_CPU0_VOS7    VOS @S9S_MB_2U_LIB.S9S_MB_2U(SCH_1):PVCCIN_CPU0_VOS7
  40    GND  PGND3 @S9S_MB_2U_LIB.S9S_MB_2U(SCH_1):GND
  35 PVCCIN_CPU0_VDD7     EN @S9S_MB_2U_LIB.S9S_MB_2U(SCH_1):PVCCIN_CPU0_VDD7
  31     NC    DNC     NC
   6     NC    GL1     NC
  41     NC    GL2     NC
7_9-20_24    GND  PGND2 @S9S_MB_2U_LIB.S9S_MB_2U(SCH_1):GND

Q_CAP_0402-3300PF,50V,10%,X7R,A  I41  PC231_P0_7
   1 SW_P12V_PVCCIN_CPU0_FLT      A @S9S_MB_2U_LIB.S9S_MB_2U(SCH_1):SW_P12V_PVCCIN_CPU0_FLT
   2    GND      B @S9S_MB_2U_LIB.S9S_MB_2U(SCH_1):GND

Q_CAP_C0402-1UF,16V,10%,X6S,CHA  I42  PC233_P0_7
   1 SW_P12V_PVCCIN_CPU0_FLT      A @S9S_MB_2U_LIB.S9S_MB_2U(SCH_1):SW_P12V_PVCCIN_CPU0_FLT
   2    GND      B @S9S_MB_2U_LIB.S9S_MB_2U(SCH_1):GND

Q_CAP_C0805-22UF,16V,20%,X6S,CA  I43  PC237_P0_7
   1 SW_P12V_PVCCIN_CPU0_FLT      A @S9S_MB_2U_LIB.S9S_MB_2U(SCH_1):SW_P12V_PVCCIN_CPU0_FLT
   2    GND      B @S9S_MB_2U_LIB.S9S_MB_2U(SCH_1):GND

Q_INDUCTOR4P_14-150NH,SMLF,INDA  I44  PL7
   2 IND_P0_CPL8      2 @S9S_MB_2U_LIB.S9S_MB_2U(SCH_1):IND_P0_CPL8
   3    GND      3 @S9S_MB_2U_LIB.S9S_MB_2U(SCH_1):GND
   4 PVCCIN_CPU0      4 @S9S_MB_2U_LIB.S9S_MB_2U(SCH_1):PVCCIN_CPU0
   1 SW_PVCCIN_CPU0_SW8      1 @S9S_MB_2U_LIB.S9S_MB_2U(SCH_1):SW_PVCCIN_CPU0_SW8

Q_CAP_C0402-100NF,50V,10%,X7R,A  I45  PC234
   1 SW_PVCCIN_CPU0_BOOT8_R      A @S9S_MB_2U_LIB.S9S_MB_2U(SCH_1):SW_PVCCIN_CPU0_BOOT8_R
   2 SW_PVCCIN_CPU0_BOOTR8      B @S9S_MB_2U_LIB.S9S_MB_2U(SCH_1):SW_PVCCIN_CPU0_BOOTR8

Q_RES_0402LF-0,5%,1/16W,CHIP,CA  I46  PR136
   1 PVCCIN_CPU0_VOS8      A @S9S_MB_2U_LIB.S9S_MB_2U(SCH_1):PVCCIN_CPU0_VOS8
   2 PVCCIN_CPU0      B @S9S_MB_2U_LIB.S9S_MB_2U(SCH_1):PVCCIN_CPU0

Q_CAP_C0805-22UF,16V,20%,X6S,CA  I47  PC238_P0_8
   1 SW_P12V_PVCCIN_CPU0_FLT      A @S9S_MB_2U_LIB.S9S_MB_2U(SCH_1):SW_P12V_PVCCIN_CPU0_FLT
   2    GND      B @S9S_MB_2U_LIB.S9S_MB_2U(SCH_1):GND

Q_CAP_C0805-22UF,16V,20%,X6S,CA  I48  PC240_P0_8
   1 SW_P12V_PVCCIN_CPU0_FLT      A @S9S_MB_2U_LIB.S9S_MB_2U(SCH_1):SW_P12V_PVCCIN_CPU0_FLT
   2    GND      B @S9S_MB_2U_LIB.S9S_MB_2U(SCH_1):GND

Q_CAP_C0805-22UF,4V,20%,X6S,CHA  I53  PC244_P0_8
   1 PVCCIN_CPU0      A @S9S_MB_2U_LIB.S9S_MB_2U(SCH_1):PVCCIN_CPU0
   2    GND      B @S9S_MB_2U_LIB.S9S_MB_2U(SCH_1):GND

Q_CAP_C0805-22UF,4V,20%,X6S,CHA  I54  PC246_P0_8
   1 PVCCIN_CPU0      A @S9S_MB_2U_LIB.S9S_MB_2U(SCH_1):PVCCIN_CPU0
   2    GND      B @S9S_MB_2U_LIB.S9S_MB_2U(SCH_1):GND

Q_CAP_C0402-100NF,50V,10%,X7R,A  I59  PC235
   1 SW_PVCCIN_CPU0_BOOT7_R      A @S9S_MB_2U_LIB.S9S_MB_2U(SCH_1):SW_PVCCIN_CPU0_BOOT7_R
   2 SW_PVCCIN_CPU0_BOOTR7      B @S9S_MB_2U_LIB.S9S_MB_2U(SCH_1):SW_PVCCIN_CPU0_BOOTR7

Q_CAP_C0402-1UF,16V,10%,X6S,CHA  I62  PC243_P0_7
   1 PVCCIN_CPU0      A @S9S_MB_2U_LIB.S9S_MB_2U(SCH_1):PVCCIN_CPU0
   2    GND      B @S9S_MB_2U_LIB.S9S_MB_2U(SCH_1):GND

Q_CAP_C0805-22UF,16V,20%,X6S,CA  I63  PC239_P0_7
   1 SW_P12V_PVCCIN_CPU0_FLT      A @S9S_MB_2U_LIB.S9S_MB_2U(SCH_1):SW_P12V_PVCCIN_CPU0_FLT
   2    GND      B @S9S_MB_2U_LIB.S9S_MB_2U(SCH_1):GND

Q_CAP_C0805-22UF,4V,20%,X6S,CHA  I66  PC245_P0_7
   1 PVCCIN_CPU0      A @S9S_MB_2U_LIB.S9S_MB_2U(SCH_1):PVCCIN_CPU0
   2    GND      B @S9S_MB_2U_LIB.S9S_MB_2U(SCH_1):GND

Q_CAP_C0805-22UF,4V,20%,X6S,CHA  I67  PC247_P0_7
   1 PVCCIN_CPU0      A @S9S_MB_2U_LIB.S9S_MB_2U(SCH_1):PVCCIN_CPU0
   2    GND      B @S9S_MB_2U_LIB.S9S_MB_2U(SCH_1):GND


DRAWING: @S9S_MB_2U_LIB.S9S_MB_2U(SCH_1):PAGE257 

Q_RES_0402LF-8.87K,1%,1/16W,EMA  I2  PR353
   1 PVCCFA_EHV_FIVRA_CPU0_LSET2      A @S9S_MB_2U_LIB.S9S_MB_2U(SCH_1):PVCCFA_EHV_FIVRA_CPU0_LSET2
   2    GND      B @S9S_MB_2U_LIB.S9S_MB_2U(SCH_1):GND

Q_RES_0402LF-2.2,1%,1/16W,CHIPA  I39  PR355
   1 PVCCFA_EHV_FIVRA_CPU0_PVCC1      A @S9S_MB_2U_LIB.S9S_MB_2U(SCH_1):PVCCFA_EHV_FIVRA_CPU0_PVCC1
   2 PVCCFA_EHV_FIVRA_CPU0_VDD1      B @S9S_MB_2U_LIB.S9S_MB_2U(SCH_1):PVCCFA_EHV_FIVRA_CPU0_VDD1

Q_RES_0402LF-3.3,1%,1/16W,CHIPA  I46  PR1780
   1 SW_PVCCFA_EHV_FIVRA_CPU0_BOOT1      A @S9S_MB_2U_LIB.S9S_MB_2U(SCH_1):SW_PVCCFA_EHV_FIVRA_CPU0_BOOT1
   2 SW_PVCCFA_EHV_FIVRA_CPU0_BOOT1_      B @S9S_MB_2U_LIB.S9S_MB_2U(SCH_1):SW_PVCCFA_EHV_FIVRA_CPU0_BOOT1_R

Q_CAP_C0805-22UF,16V,20%,X6S,CA  I48  PC610_P0_1
   1 SW_P12V_PVCCFA_EHV_FIVRA_CPU0_R      A @S9S_MB_2U_LIB.S9S_MB_2U(SCH_1):SW_P12V_PVCCFA_EHV_FIVRA_CPU0_R
   2    GND      B @S9S_MB_2U_LIB.S9S_MB_2U(SCH_1):GND

Q_INDUCTOR_SMLF-130NH/106A,INDA  I49  PL34
   2 PVCCFA_EHV_FIVRA_CPU0      2 @S9S_MB_2U_LIB.S9S_MB_2U(SCH_1):PVCCFA_EHV_FIVRA_CPU0
   1 SW_PVCCFA_EHV_FIVRA_CPU0_SW2      1 @S9S_MB_2U_LIB.S9S_MB_2U(SCH_1):SW_PVCCFA_EHV_FIVRA_CPU0_SW2

Q_RES_0402LF-0,5%,1/16W,CHIP,CA  I50  PR1323
   1 PVCCFA_EHV_FIVRA_CPU0_VOS2      A @S9S_MB_2U_LIB.S9S_MB_2U(SCH_1):PVCCFA_EHV_FIVRA_CPU0_VOS2
   2 PVCCFA_EHV_FIVRA_CPU0      B @S9S_MB_2U_LIB.S9S_MB_2U(SCH_1):PVCCFA_EHV_FIVRA_CPU0

Q_CAP_C0805-22UF,4V,20%,X6S,CHA  I59  PC618_P0_2
   1 PVCCFA_EHV_FIVRA_CPU0      A @S9S_MB_2U_LIB.S9S_MB_2U(SCH_1):PVCCFA_EHV_FIVRA_CPU0
   2    GND      B @S9S_MB_2U_LIB.S9S_MB_2U(SCH_1):GND

Q_CAPP_THLF-560UF,2.5V,20%,OSCA  I62  PC621
   1 PVCCFA_EHV_FIVRA_CPU0      A @S9S_MB_2U_LIB.S9S_MB_2U(SCH_1):PVCCFA_EHV_FIVRA_CPU0
   2    GND      B @S9S_MB_2U_LIB.S9S_MB_2U(SCH_1):GND

Q_CAP_0402-3300PF,50V,10%,X7R,A  I27  PC603_P0_2
   1 SW_P12V_PVCCFA_EHV_FIVRA_CPU0_L      A @S9S_MB_2U_LIB.S9S_MB_2U(SCH_1):SW_P12V_PVCCFA_EHV_FIVRA_CPU0_L
   2    GND      B @S9S_MB_2U_LIB.S9S_MB_2U(SCH_1):GND

Q_CAP_0402-3300PF,50V,10%,X7R,A  I44  PC602_P0_1
   1 SW_P12V_PVCCFA_EHV_FIVRA_CPU0_R      A @S9S_MB_2U_LIB.S9S_MB_2U(SCH_1):SW_P12V_PVCCFA_EHV_FIVRA_CPU0_R
   2    GND      B @S9S_MB_2U_LIB.S9S_MB_2U(SCH_1):GND

Q_CAP_C0402-1UF,16V,10%,X6S,CHA  I45  PC604_P0_1
   1 SW_P12V_PVCCFA_EHV_FIVRA_CPU0_R      A @S9S_MB_2U_LIB.S9S_MB_2U(SCH_1):SW_P12V_PVCCFA_EHV_FIVRA_CPU0_R
   2    GND      B @S9S_MB_2U_LIB.S9S_MB_2U(SCH_1):GND

Q_RES_0402LF-0,5%,1/16W,EMPTY,A  I22  PR633
   1   P3V3      A @S9S_MB_2U_LIB.S9S_MB_2U(SCH_1):P3V3
   2 PVCCFA_EHV_FIVRA_CPU0_PVCC2      B @S9S_MB_2U_LIB.S9S_MB_2U(SCH_1):PVCCFA_EHV_FIVRA_CPU0_PVCC2

Q_CAP_C0805-22UF,16V,20%,X6S,CA  I47  PC608_P0_1
   1 SW_P12V_PVCCFA_EHV_FIVRA_CPU0_R      A @S9S_MB_2U_LIB.S9S_MB_2U(SCH_1):SW_P12V_PVCCFA_EHV_FIVRA_CPU0_R
   2    GND      B @S9S_MB_2U_LIB.S9S_MB_2U(SCH_1):GND

Q_CAP_C0402-1UF,16V,10%,X6S,CHA  I51  PC613_P0_2
   1 PVCCFA_EHV_FIVRA_CPU0      A @S9S_MB_2U_LIB.S9S_MB_2U(SCH_1):PVCCFA_EHV_FIVRA_CPU0
   2    GND      B @S9S_MB_2U_LIB.S9S_MB_2U(SCH_1):GND

Q_CAP_C0805-22UF,16V,20%,X6S,CA  I84  PC1670
   1 SW_P12V_PVCCFA_EHV_FIVRA_CPU0_L      A @S9S_MB_2U_LIB.S9S_MB_2U(SCH_1):SW_P12V_PVCCFA_EHV_FIVRA_CPU0_L
   2    GND      B @S9S_MB_2U_LIB.S9S_MB_2U(SCH_1):GND

Q_RES_0402LF-8.87K,1%,1/16W,EMA  I8  PR354
   1 PVCCFA_EHV_FIVRA_CPU0_LSET1      A @S9S_MB_2U_LIB.S9S_MB_2U(SCH_1):PVCCFA_EHV_FIVRA_CPU0_LSET1
   2    GND      B @S9S_MB_2U_LIB.S9S_MB_2U(SCH_1):GND

ISL99390FRZTR5935-ISL99390FRZ-A  I16  PU70_P0_2
  34 PVCCFA_EHV_FIVRA_CPU0_PWM2    PWM @S9S_MB_2U_LIB.S9S_MB_2U(SCH_1):PVCCFA_EHV_FIVRA_CPU0_PWM2
  39 PVCCIN_CPU0_VREF  REFIN @S9S_MB_2U_LIB.S9S_MB_2U(SCH_1):PVCCIN_CPU0_VREF
   3 PVCCFA_EHV_FIVRA_CPU0_VDD2    VCC @S9S_MB_2U_LIB.S9S_MB_2U(SCH_1):PVCCFA_EHV_FIVRA_CPU0_VDD2
   2    GND   AGND @S9S_MB_2U_LIB.S9S_MB_2U(SCH_1):GND
  33 SW_PVCCFA_EHV_FIVRA_CPU0_BOOT2   BOOT @S9S_MB_2U_LIB.S9S_MB_2U(SCH_1):SW_PVCCFA_EHV_FIVRA_CPU0_BOOT2
25_29 SW_P12V_PVCCFA_EHV_FIVRA_CPU0_L   VIN1 @S9S_MB_2U_LIB.S9S_MB_2U(SCH_1):SW_P12V_PVCCFA_EHV_FIVRA_CPU0_L
  32 SW_PVCCFA_EHV_FIVRA_CPU0_BOOTR2  PHASE @S9S_MB_2U_LIB.S9S_MB_2U(SCH_1):SW_PVCCFA_EHV_FIVRA_CPU0_BOOTR2
   4 PVCCFA_EHV_FIVRA_CPU0_PVCC2   PVCC @S9S_MB_2U_LIB.S9S_MB_2U(SCH_1):PVCCFA_EHV_FIVRA_CPU0_PVCC2
  36 PVCCFA_EHV_FIVRA_CPU0_BTSEN TOUT_FLT @S9S_MB_2U_LIB.S9S_MB_2U(SCH_1):PVCCFA_EHV_FIVRA_CPU0_BTSEN
  38 PVCCFA_EHV_FIVRA_CPU0_IMON2   IOUT @S9S_MB_2U_LIB.S9S_MB_2U(SCH_1):PVCCFA_EHV_FIVRA_CPU0_IMON2
  37 PVCCFA_EHV_FIVRA_CPU0_LSET2   LSET @S9S_MB_2U_LIB.S9S_MB_2U(SCH_1):PVCCFA_EHV_FIVRA_CPU0_LSET2
10_19 SW_PVCCFA_EHV_FIVRA_CPU0_SW2     SW @S9S_MB_2U_LIB.S9S_MB_2U(SCH_1):SW_PVCCFA_EHV_FIVRA_CPU0_SW2
   5    GND  PGND1 @S9S_MB_2U_LIB.S9S_MB_2U(SCH_1):GND
  30 SW_P12V_PVCCFA_EHV_FIVRA_CPU0_L   VIN2 @S9S_MB_2U_LIB.S9S_MB_2U(SCH_1):SW_P12V_PVCCFA_EHV_FIVRA_CPU0_L
   1 PVCCFA_EHV_FIVRA_CPU0_VOS2    VOS @S9S_MB_2U_LIB.S9S_MB_2U(SCH_1):PVCCFA_EHV_FIVRA_CPU0_VOS2
  40    GND  PGND3 @S9S_MB_2U_LIB.S9S_MB_2U(SCH_1):GND
  35 PVCCFA_EHV_FIVRA_CPU0_VDD2     EN @S9S_MB_2U_LIB.S9S_MB_2U(SCH_1):PVCCFA_EHV_FIVRA_CPU0_VDD2
  31     NC    DNC     NC
   6     NC    GL1     NC
  41     NC    GL2     NC
7_9-20_24    GND  PGND2 @S9S_MB_2U_LIB.S9S_MB_2U(SCH_1):GND

Q_RES_0402LF-0,5%,1/16W,CHIP,CA  I69  PR1322
   1 PVCCFA_EHV_FIVRA_CPU0_VOS1      A @S9S_MB_2U_LIB.S9S_MB_2U(SCH_1):PVCCFA_EHV_FIVRA_CPU0_VOS1
   2 PVCCFA_EHV_FIVRA_CPU0      B @S9S_MB_2U_LIB.S9S_MB_2U(SCH_1):PVCCFA_EHV_FIVRA_CPU0

Q_CAP_C0805-22UF,4V,20%,X6S,CHA  I77  PC615_P0_1
   1 PVCCFA_EHV_FIVRA_CPU0      A @S9S_MB_2U_LIB.S9S_MB_2U(SCH_1):PVCCFA_EHV_FIVRA_CPU0
   2    GND      B @S9S_MB_2U_LIB.S9S_MB_2U(SCH_1):GND

Q_RES_0402LF-0,5%,1/16W,CHIP,CA  I4  PR447
   1    P5V      A @S9S_MB_2U_LIB.S9S_MB_2U(SCH_1):P5V
   2 PVCCFA_EHV_FIVRA_CPU0_PVCC2      B @S9S_MB_2U_LIB.S9S_MB_2U(SCH_1):PVCCFA_EHV_FIVRA_CPU0_PVCC2

Q_RES_0402LF-0,5%,1/16W,CHIP,CA  I9  PR444
   1    P5V      A @S9S_MB_2U_LIB.S9S_MB_2U(SCH_1):P5V
   2 PVCCFA_EHV_FIVRA_CPU0_PVCC1      B @S9S_MB_2U_LIB.S9S_MB_2U(SCH_1):PVCCFA_EHV_FIVRA_CPU0_PVCC1

Q_CAP_0402-0.1UF,25V,10%,X7R,CA  I15  PC1350
   1    GND      A @S9S_MB_2U_LIB.S9S_MB_2U(SCH_1):GND
   2 PVCCIN_CPU0_VREF      B @S9S_MB_2U_LIB.S9S_MB_2U(SCH_1):PVCCIN_CPU0_VREF

Q_CAP_C0402-2.2UF,10V,10%,X6S,A  I18  PC601
   1 PVCCFA_EHV_FIVRA_CPU0_VDD2      A @S9S_MB_2U_LIB.S9S_MB_2U(SCH_1):PVCCFA_EHV_FIVRA_CPU0_VDD2
   2    GND      B @S9S_MB_2U_LIB.S9S_MB_2U(SCH_1):GND

Q_RES_0402LF-2.2,1%,1/16W,CHIPA  I19  PR356
   1 PVCCFA_EHV_FIVRA_CPU0_PVCC2      A @S9S_MB_2U_LIB.S9S_MB_2U(SCH_1):PVCCFA_EHV_FIVRA_CPU0_PVCC2
   2 PVCCFA_EHV_FIVRA_CPU0_VDD2      B @S9S_MB_2U_LIB.S9S_MB_2U(SCH_1):PVCCFA_EHV_FIVRA_CPU0_VDD2

Q_CAP_C0402-2.2UF,10V,10%,X6S,A  I21  PC1212_P0_2
   1 PVCCFA_EHV_FIVRA_CPU0_PVCC2      A @S9S_MB_2U_LIB.S9S_MB_2U(SCH_1):PVCCFA_EHV_FIVRA_CPU0_PVCC2
   2    GND      B @S9S_MB_2U_LIB.S9S_MB_2U(SCH_1):GND

Q_RES_0402LF-3.3,1%,1/16W,CHIPA  I30  PR1781
   1 SW_PVCCFA_EHV_FIVRA_CPU0_BOOT2      A @S9S_MB_2U_LIB.S9S_MB_2U(SCH_1):SW_PVCCFA_EHV_FIVRA_CPU0_BOOT2
   2 SW_PVCCFA_EHV_FIVRA_CPU0_BOOT2_      B @S9S_MB_2U_LIB.S9S_MB_2U(SCH_1):SW_PVCCFA_EHV_FIVRA_CPU0_BOOT2_R

Q_CAP_C0805-22UF,16V,20%,X6S,CA  I31  PC609_P0_2
   1 SW_P12V_PVCCFA_EHV_FIVRA_CPU0_L      A @S9S_MB_2U_LIB.S9S_MB_2U(SCH_1):SW_P12V_PVCCFA_EHV_FIVRA_CPU0_L
   2    GND      B @S9S_MB_2U_LIB.S9S_MB_2U(SCH_1):GND

Q_CAP_C0805-22UF,4V,20%,X6S,CHA  I52  PC616_P0_2
   1 PVCCFA_EHV_FIVRA_CPU0      A @S9S_MB_2U_LIB.S9S_MB_2U(SCH_1):PVCCFA_EHV_FIVRA_CPU0
   2    GND      B @S9S_MB_2U_LIB.S9S_MB_2U(SCH_1):GND

Q_CAPP_THLF-560UF,2.5V,20%,OSCA  I57  PC619
   1 PVCCFA_EHV_FIVRA_CPU0      A @S9S_MB_2U_LIB.S9S_MB_2U(SCH_1):PVCCFA_EHV_FIVRA_CPU0
   2    GND      B @S9S_MB_2U_LIB.S9S_MB_2U(SCH_1):GND

Q_CAPP_THLF-560UF,2.5V,20%,OSCA  I58  PC620
   1 PVCCFA_EHV_FIVRA_CPU0      A @S9S_MB_2U_LIB.S9S_MB_2U(SCH_1):PVCCFA_EHV_FIVRA_CPU0
   2    GND      B @S9S_MB_2U_LIB.S9S_MB_2U(SCH_1):GND

Q_INDUCTOR_SMLF-130NH/106A,INDA  I70  PL33
   2 PVCCFA_EHV_FIVRA_CPU0      2 @S9S_MB_2U_LIB.S9S_MB_2U(SCH_1):PVCCFA_EHV_FIVRA_CPU0
   1 SW_PVCCFA_EHV_FIVRA_CPU0_SW1      1 @S9S_MB_2U_LIB.S9S_MB_2U(SCH_1):SW_PVCCFA_EHV_FIVRA_CPU0_SW1

Q_INDUCTOR_SMLF-100NH/16A,IND,A  I80  PL44
   2 SW_P12V_PVCCFA_EHV_FIVRA_CPU0_L      2 @S9S_MB_2U_LIB.S9S_MB_2U(SCH_1):SW_P12V_PVCCFA_EHV_FIVRA_CPU0_L
   1 P12V_AUX      1 @S9S_MB_2U_LIB.S9S_MB_2U(SCH_1):P12V_AUX

Q_CAP_C0805-22UF,16V,20%,X6S,CA  I83  PC1669
   1 SW_P12V_PVCCFA_EHV_FIVRA_CPU0_L      A @S9S_MB_2U_LIB.S9S_MB_2U(SCH_1):SW_P12V_PVCCFA_EHV_FIVRA_CPU0_L
   2    GND      B @S9S_MB_2U_LIB.S9S_MB_2U(SCH_1):GND

Q_CAP_C0805-22UF,16V,20%,X6S,CA  I85  PC1671
   1 SW_P12V_PVCCFA_EHV_FIVRA_CPU0_L      A @S9S_MB_2U_LIB.S9S_MB_2U(SCH_1):SW_P12V_PVCCFA_EHV_FIVRA_CPU0_L
   2    GND      B @S9S_MB_2U_LIB.S9S_MB_2U(SCH_1):GND

ISL99390FRZTR5935-ISL99390FRZ-A  I25  PU69_P0_1
  34 PVCCFA_EHV_FIVRA_CPU0_PWM1    PWM @S9S_MB_2U_LIB.S9S_MB_2U(SCH_1):PVCCFA_EHV_FIVRA_CPU0_PWM1
  39 PVCCIN_CPU0_VREF  REFIN @S9S_MB_2U_LIB.S9S_MB_2U(SCH_1):PVCCIN_CPU0_VREF
   3 PVCCFA_EHV_FIVRA_CPU0_VDD1    VCC @S9S_MB_2U_LIB.S9S_MB_2U(SCH_1):PVCCFA_EHV_FIVRA_CPU0_VDD1
   2    GND   AGND @S9S_MB_2U_LIB.S9S_MB_2U(SCH_1):GND
  33 SW_PVCCFA_EHV_FIVRA_CPU0_BOOT1   BOOT @S9S_MB_2U_LIB.S9S_MB_2U(SCH_1):SW_PVCCFA_EHV_FIVRA_CPU0_BOOT1
25_29 SW_P12V_PVCCFA_EHV_FIVRA_CPU0_R   VIN1 @S9S_MB_2U_LIB.S9S_MB_2U(SCH_1):SW_P12V_PVCCFA_EHV_FIVRA_CPU0_R
  32 SW_PVCCFA_EHV_FIVRA_CPU0_BOOTR1  PHASE @S9S_MB_2U_LIB.S9S_MB_2U(SCH_1):SW_PVCCFA_EHV_FIVRA_CPU0_BOOTR1
   4 PVCCFA_EHV_FIVRA_CPU0_PVCC1   PVCC @S9S_MB_2U_LIB.S9S_MB_2U(SCH_1):PVCCFA_EHV_FIVRA_CPU0_PVCC1
  36 PVCCFA_EHV_FIVRA_CPU0_BTSEN TOUT_FLT @S9S_MB_2U_LIB.S9S_MB_2U(SCH_1):PVCCFA_EHV_FIVRA_CPU0_BTSEN
  38 PVCCFA_EHV_FIVRA_CPU0_IMON1   IOUT @S9S_MB_2U_LIB.S9S_MB_2U(SCH_1):PVCCFA_EHV_FIVRA_CPU0_IMON1
  37 PVCCFA_EHV_FIVRA_CPU0_LSET1   LSET @S9S_MB_2U_LIB.S9S_MB_2U(SCH_1):PVCCFA_EHV_FIVRA_CPU0_LSET1
10_19 SW_PVCCFA_EHV_FIVRA_CPU0_SW1     SW @S9S_MB_2U_LIB.S9S_MB_2U(SCH_1):SW_PVCCFA_EHV_FIVRA_CPU0_SW1
   5    GND  PGND1 @S9S_MB_2U_LIB.S9S_MB_2U(SCH_1):GND
  30 SW_P12V_PVCCFA_EHV_FIVRA_CPU0_R   VIN2 @S9S_MB_2U_LIB.S9S_MB_2U(SCH_1):SW_P12V_PVCCFA_EHV_FIVRA_CPU0_R
   1 PVCCFA_EHV_FIVRA_CPU0_VOS1    VOS @S9S_MB_2U_LIB.S9S_MB_2U(SCH_1):PVCCFA_EHV_FIVRA_CPU0_VOS1
  40    GND  PGND3 @S9S_MB_2U_LIB.S9S_MB_2U(SCH_1):GND
  35 PVCCFA_EHV_FIVRA_CPU0_VDD1     EN @S9S_MB_2U_LIB.S9S_MB_2U(SCH_1):PVCCFA_EHV_FIVRA_CPU0_VDD1
  31     NC    DNC     NC
   6     NC    GL1     NC
  41     NC    GL2     NC
7_9-20_24    GND  PGND2 @S9S_MB_2U_LIB.S9S_MB_2U(SCH_1):GND

Q_CAP_C0402-1UF,16V,10%,X6S,CHA  I28  PC605_P0_2
   1 SW_P12V_PVCCFA_EHV_FIVRA_CPU0_L      A @S9S_MB_2U_LIB.S9S_MB_2U(SCH_1):SW_P12V_PVCCFA_EHV_FIVRA_CPU0_L
   2    GND      B @S9S_MB_2U_LIB.S9S_MB_2U(SCH_1):GND

Q_CAP_C0805-22UF,16V,20%,X6S,CA  I32  PC611_P0_2
   1 SW_P12V_PVCCFA_EHV_FIVRA_CPU0_L      A @S9S_MB_2U_LIB.S9S_MB_2U(SCH_1):SW_P12V_PVCCFA_EHV_FIVRA_CPU0_L
   2    GND      B @S9S_MB_2U_LIB.S9S_MB_2U(SCH_1):GND

Q_CAP_0402-0.1UF,25V,10%,X7R,CA  I35  PC1349
   1    GND      A @S9S_MB_2U_LIB.S9S_MB_2U(SCH_1):GND
   2 PVCCIN_CPU0_VREF      B @S9S_MB_2U_LIB.S9S_MB_2U(SCH_1):PVCCIN_CPU0_VREF

Q_CAP_C0402-2.2UF,10V,10%,X6S,A  I37  PC600
   1 PVCCFA_EHV_FIVRA_CPU0_VDD1      A @S9S_MB_2U_LIB.S9S_MB_2U(SCH_1):PVCCFA_EHV_FIVRA_CPU0_VDD1
   2    GND      B @S9S_MB_2U_LIB.S9S_MB_2U(SCH_1):GND

Q_RES_0402LF-0,5%,1/16W,EMPTY,A  I40  PR632
   1   P3V3      A @S9S_MB_2U_LIB.S9S_MB_2U(SCH_1):P3V3
   2 PVCCFA_EHV_FIVRA_CPU0_PVCC1      B @S9S_MB_2U_LIB.S9S_MB_2U(SCH_1):PVCCFA_EHV_FIVRA_CPU0_PVCC1

Q_CAP_C0402-2.2UF,10V,10%,X6S,A  I42  PC1211_P0_1
   1 PVCCFA_EHV_FIVRA_CPU0_PVCC1      A @S9S_MB_2U_LIB.S9S_MB_2U(SCH_1):PVCCFA_EHV_FIVRA_CPU0_PVCC1
   2    GND      B @S9S_MB_2U_LIB.S9S_MB_2U(SCH_1):GND

Q_CAP_C0402-100NF,50V,10%,X7R,A  I53  PC607
   1 SW_PVCCFA_EHV_FIVRA_CPU0_BOOT2_      A @S9S_MB_2U_LIB.S9S_MB_2U(SCH_1):SW_PVCCFA_EHV_FIVRA_CPU0_BOOT2_R
   2 SW_PVCCFA_EHV_FIVRA_CPU0_BOOTR2      B @S9S_MB_2U_LIB.S9S_MB_2U(SCH_1):SW_PVCCFA_EHV_FIVRA_CPU0_BOOTR2

Q_CAP_C0805-22UF,16V,20%,X6S,CA  I55  PC721_P0_2
   1 SW_P12V_PVCCFA_EHV_FIVRA_CPU0_L      A @S9S_MB_2U_LIB.S9S_MB_2U(SCH_1):SW_P12V_PVCCFA_EHV_FIVRA_CPU0_L
   2    GND      B @S9S_MB_2U_LIB.S9S_MB_2U(SCH_1):GND

Q_RES_0402LF-499,1%,1/16W,CHIPA  I60  PR4265
   1 PVCCFA_EHV_FIVRA_CPU0      A @S9S_MB_2U_LIB.S9S_MB_2U(SCH_1):PVCCFA_EHV_FIVRA_CPU0
   2    GND      B @S9S_MB_2U_LIB.S9S_MB_2U(SCH_1):GND

Q_CAPP_SMLF-330UF,2.5V,+10/-35B  I63  PC623
   1 PVCCFA_EHV_FIVRA_CPU0      A @S9S_MB_2U_LIB.S9S_MB_2U(SCH_1):PVCCFA_EHV_FIVRA_CPU0
   2    GND      B @S9S_MB_2U_LIB.S9S_MB_2U(SCH_1):GND

Q_CAPP_SMLF-330UF,2.5V,+10/-35B  I67  PC2645
   1 PVCCFA_EHV_FIVRA_CPU0      A @S9S_MB_2U_LIB.S9S_MB_2U(SCH_1):PVCCFA_EHV_FIVRA_CPU0
   2    GND      B @S9S_MB_2U_LIB.S9S_MB_2U(SCH_1):GND

Q_CAP_C0402-100NF,50V,10%,X7R,A  I71  PC606
   1 SW_PVCCFA_EHV_FIVRA_CPU0_BOOT1_      A @S9S_MB_2U_LIB.S9S_MB_2U(SCH_1):SW_PVCCFA_EHV_FIVRA_CPU0_BOOT1_R
   2 SW_PVCCFA_EHV_FIVRA_CPU0_BOOTR1      B @S9S_MB_2U_LIB.S9S_MB_2U(SCH_1):SW_PVCCFA_EHV_FIVRA_CPU0_BOOTR1

Q_CAP_C0805-22UF,16V,20%,X6S,CA  I73  PC720_P0_1
   1 SW_P12V_PVCCFA_EHV_FIVRA_CPU0_R      A @S9S_MB_2U_LIB.S9S_MB_2U(SCH_1):SW_P12V_PVCCFA_EHV_FIVRA_CPU0_R
   2    GND      B @S9S_MB_2U_LIB.S9S_MB_2U(SCH_1):GND

Q_CAP_C0402-100NF,50V,10%,X7R,A  I75  PC612_P0_1
   1 PVCCFA_EHV_FIVRA_CPU0      A @S9S_MB_2U_LIB.S9S_MB_2U(SCH_1):PVCCFA_EHV_FIVRA_CPU0
   2    GND      B @S9S_MB_2U_LIB.S9S_MB_2U(SCH_1):GND

Q_CAP_C0402-100NF,50V,10%,X7R,A  I78  PC1653
   1 P12V_AUX      A @S9S_MB_2U_LIB.S9S_MB_2U(SCH_1):P12V_AUX
   2    GND      B @S9S_MB_2U_LIB.S9S_MB_2U(SCH_1):GND

Q_CAP_C0805-22UF,4V,20%,X6S,CHA  I81  PC617_P0_1
   1 PVCCFA_EHV_FIVRA_CPU0      A @S9S_MB_2U_LIB.S9S_MB_2U(SCH_1):PVCCFA_EHV_FIVRA_CPU0
   2    GND      B @S9S_MB_2U_LIB.S9S_MB_2U(SCH_1):GND

Q_CAP_C0805-22UF,16V,20%,X6S,CA  I86  PC1672
   1 SW_P12V_PVCCFA_EHV_FIVRA_CPU0_L      A @S9S_MB_2U_LIB.S9S_MB_2U(SCH_1):SW_P12V_PVCCFA_EHV_FIVRA_CPU0_L
   2    GND      B @S9S_MB_2U_LIB.S9S_MB_2U(SCH_1):GND

Q_CAPP_THLF-270UF,16V,20%,OSCOA  I88  PC622
   1 SW_P12V_PVCCFA_EHV_FIVRA_CPU0_L      A @S9S_MB_2U_LIB.S9S_MB_2U(SCH_1):SW_P12V_PVCCFA_EHV_FIVRA_CPU0_L
   2    GND      B @S9S_MB_2U_LIB.S9S_MB_2U(SCH_1):GND


DRAWING: @S9S_MB_2U_LIB.S9S_MB_2U(SCH_1):PAGE258 

Q_CAP_C0402-2.2UF,10V,10%,X6S,A  I23  PC1171
   1 PVCCFA_EHV_FIVRA_CPU0_VDD3      A @S9S_MB_2U_LIB.S9S_MB_2U(SCH_1):PVCCFA_EHV_FIVRA_CPU0_VDD3
   2    GND      B @S9S_MB_2U_LIB.S9S_MB_2U(SCH_1):GND

Q_RES_0402LF-3.3,1%,1/16W,CHIPA  I33  PR1783
   1 SW_PVCCFA_EHV_FIVRA_CPU0_BOOT4      A @S9S_MB_2U_LIB.S9S_MB_2U(SCH_1):SW_PVCCFA_EHV_FIVRA_CPU0_BOOT4
   2 SW_PVCCFA_EHV_FIVRA_CPU0_BOOT4_      B @S9S_MB_2U_LIB.S9S_MB_2U(SCH_1):SW_PVCCFA_EHV_FIVRA_CPU0_BOOT4_R

Q_CAP_C0805-22UF,16V,20%,X6S,CA  I36  PC1182_P0_4
   1 SW_P12V_PVCCFA_EHV_FIVRA_CPU0_L      A @S9S_MB_2U_LIB.S9S_MB_2U(SCH_1):SW_P12V_PVCCFA_EHV_FIVRA_CPU0_L
   2    GND      B @S9S_MB_2U_LIB.S9S_MB_2U(SCH_1):GND

Q_INDUCTOR_SMLF-130NH/106A,INDA  I39  PL210
   2 PVCCFA_EHV_FIVRA_CPU0      2 @S9S_MB_2U_LIB.S9S_MB_2U(SCH_1):PVCCFA_EHV_FIVRA_CPU0
   1 SW_PVCCFA_EHV_FIVRA_CPU0_SW4      1 @S9S_MB_2U_LIB.S9S_MB_2U(SCH_1):SW_PVCCFA_EHV_FIVRA_CPU0_SW4

Q_CAP_C0402-100NF,50V,10%,X7R,A  I40  PC1183_P0_4
   1 PVCCFA_EHV_FIVRA_CPU0      A @S9S_MB_2U_LIB.S9S_MB_2U(SCH_1):PVCCFA_EHV_FIVRA_CPU0
   2    GND      B @S9S_MB_2U_LIB.S9S_MB_2U(SCH_1):GND

Q_CAP_0402-3300PF,50V,10%,X7R,A  I44  PC1173_P0_3
   1 SW_P12V_PVCCFA_EHV_FIVRA_CPU0_R      A @S9S_MB_2U_LIB.S9S_MB_2U(SCH_1):SW_P12V_PVCCFA_EHV_FIVRA_CPU0_R
   2    GND      B @S9S_MB_2U_LIB.S9S_MB_2U(SCH_1):GND

Q_RES_0402LF-3.3,1%,1/16W,CHIPA  I45  PR1782
   1 SW_PVCCFA_EHV_FIVRA_CPU0_BOOT3      A @S9S_MB_2U_LIB.S9S_MB_2U(SCH_1):SW_PVCCFA_EHV_FIVRA_CPU0_BOOT3
   2 SW_PVCCFA_EHV_FIVRA_CPU0_BOOT3_      B @S9S_MB_2U_LIB.S9S_MB_2U(SCH_1):SW_PVCCFA_EHV_FIVRA_CPU0_BOOT3_R

Q_CAP_C0402-1UF,16V,10%,X6S,CHA  I46  PC1175_P0_3
   1 SW_P12V_PVCCFA_EHV_FIVRA_CPU0_R      A @S9S_MB_2U_LIB.S9S_MB_2U(SCH_1):SW_P12V_PVCCFA_EHV_FIVRA_CPU0_R
   2    GND      B @S9S_MB_2U_LIB.S9S_MB_2U(SCH_1):GND

Q_CAP_C0402-1UF,16V,10%,X6S,CHA  I55  PC1183_P0_3
   1 PVCCFA_EHV_FIVRA_CPU0      A @S9S_MB_2U_LIB.S9S_MB_2U(SCH_1):PVCCFA_EHV_FIVRA_CPU0
   2    GND      B @S9S_MB_2U_LIB.S9S_MB_2U(SCH_1):GND

Q_CAP_C0805-22UF,4V,20%,X6S,CHA  I61  PC1188_P0_4
   1 PVCCFA_EHV_FIVRA_CPU0      A @S9S_MB_2U_LIB.S9S_MB_2U(SCH_1):PVCCFA_EHV_FIVRA_CPU0
   2    GND      B @S9S_MB_2U_LIB.S9S_MB_2U(SCH_1):GND

Q_CAPP_THLF-560UF,2.5V,20%,OSCA  I68  PC1186
   1 PVCCFA_EHV_FIVRA_CPU0      A @S9S_MB_2U_LIB.S9S_MB_2U(SCH_1):PVCCFA_EHV_FIVRA_CPU0
   2    GND      B @S9S_MB_2U_LIB.S9S_MB_2U(SCH_1):GND

Q_CAP_C0402-100NF,50V,10%,X7R,A  I37  PC1178
   1 SW_PVCCFA_EHV_FIVRA_CPU0_BOOT4_      A @S9S_MB_2U_LIB.S9S_MB_2U(SCH_1):SW_PVCCFA_EHV_FIVRA_CPU0_BOOT4_R
   2 SW_PVCCFA_EHV_FIVRA_CPU0_BOOTR4      B @S9S_MB_2U_LIB.S9S_MB_2U(SCH_1):SW_PVCCFA_EHV_FIVRA_CPU0_BOOTR4

Q_CAP_C0805-22UF,16V,20%,X6S,CA  I41  PC723_P0_4
   1 SW_P12V_PVCCFA_EHV_FIVRA_CPU0_L      A @S9S_MB_2U_LIB.S9S_MB_2U(SCH_1):SW_P12V_PVCCFA_EHV_FIVRA_CPU0_L
   2    GND      B @S9S_MB_2U_LIB.S9S_MB_2U(SCH_1):GND

Q_INDUCTOR_SMLF-130NH/106A,INDA  I51  PL2
   2 PVCCFA_EHV_FIVRA_CPU0      2 @S9S_MB_2U_LIB.S9S_MB_2U(SCH_1):PVCCFA_EHV_FIVRA_CPU0
   1 SW_PVCCFA_EHV_FIVRA_CPU0_SW3      1 @S9S_MB_2U_LIB.S9S_MB_2U(SCH_1):SW_PVCCFA_EHV_FIVRA_CPU0_SW3

Q_CAP_C0805-22UF,16V,20%,X6S,CA  I77  PC1675
   1 SW_P12V_PVCCFA_EHV_FIVRA_CPU0_R      A @S9S_MB_2U_LIB.S9S_MB_2U(SCH_1):SW_P12V_PVCCFA_EHV_FIVRA_CPU0_R
   2    GND      B @S9S_MB_2U_LIB.S9S_MB_2U(SCH_1):GND

Q_RES_0402LF-2.2,1%,1/16W,CHIPA  I11  PR1300
   1 PVCCFA_EHV_FIVRA_CPU0_PVCC2      A @S9S_MB_2U_LIB.S9S_MB_2U(SCH_1):PVCCFA_EHV_FIVRA_CPU0_PVCC2
   2 PVCCFA_EHV_FIVRA_CPU0_VDD4      B @S9S_MB_2U_LIB.S9S_MB_2U(SCH_1):PVCCFA_EHV_FIVRA_CPU0_VDD4

Q_RES_0402LF-8.87K,1%,1/16W,EMA  I15  PR1298
   1 PVCCFA_EHV_FIVRA_CPU0_LSET3      A @S9S_MB_2U_LIB.S9S_MB_2U(SCH_1):PVCCFA_EHV_FIVRA_CPU0_LSET3
   2    GND      B @S9S_MB_2U_LIB.S9S_MB_2U(SCH_1):GND

Q_CAP_0402-0.1UF,25V,10%,X7R,CA  I25  PC1351
   1    GND      A @S9S_MB_2U_LIB.S9S_MB_2U(SCH_1):GND
   2 PVCCIN_CPU0_VREF      B @S9S_MB_2U_LIB.S9S_MB_2U(SCH_1):PVCCIN_CPU0_VREF

Q_CAP_0402-3300PF,50V,10%,X7R,A  I31  PC1174_P0_4
   1 SW_P12V_PVCCFA_EHV_FIVRA_CPU0_L      A @S9S_MB_2U_LIB.S9S_MB_2U(SCH_1):SW_P12V_PVCCFA_EHV_FIVRA_CPU0_L
   2    GND      B @S9S_MB_2U_LIB.S9S_MB_2U(SCH_1):GND

Q_RES_0402LF-0,5%,1/16W,CHIP,CA  I38  PR1325
   1 PVCCFA_EHV_FIVRA_CPU0_VOS4      A @S9S_MB_2U_LIB.S9S_MB_2U(SCH_1):PVCCFA_EHV_FIVRA_CPU0_VOS4
   2 PVCCFA_EHV_FIVRA_CPU0      B @S9S_MB_2U_LIB.S9S_MB_2U(SCH_1):PVCCFA_EHV_FIVRA_CPU0

Q_CAP_C0805-22UF,4V,20%,X6S,CHA  I72  PC1185_P0_3
   1 PVCCFA_EHV_FIVRA_CPU0      A @S9S_MB_2U_LIB.S9S_MB_2U(SCH_1):PVCCFA_EHV_FIVRA_CPU0
   2    GND      B @S9S_MB_2U_LIB.S9S_MB_2U(SCH_1):GND

Q_CAP_C0805-22UF,16V,20%,X6S,CA  I76  PC1674
   1 SW_P12V_PVCCFA_EHV_FIVRA_CPU0_R      A @S9S_MB_2U_LIB.S9S_MB_2U(SCH_1):SW_P12V_PVCCFA_EHV_FIVRA_CPU0_R
   2    GND      B @S9S_MB_2U_LIB.S9S_MB_2U(SCH_1):GND

Q_CAP_C0805-22UF,16V,20%,X6S,CA  I48  PC1181_P0_3
   1 SW_P12V_PVCCFA_EHV_FIVRA_CPU0_R      A @S9S_MB_2U_LIB.S9S_MB_2U(SCH_1):SW_P12V_PVCCFA_EHV_FIVRA_CPU0_R
   2    GND      B @S9S_MB_2U_LIB.S9S_MB_2U(SCH_1):GND

Q_RES_0402LF-0,5%,1/16W,CHIP,CA  I50  PR1324
   1 PVCCFA_EHV_FIVRA_CPU0_VOS3      A @S9S_MB_2U_LIB.S9S_MB_2U(SCH_1):PVCCFA_EHV_FIVRA_CPU0_VOS3
   2 PVCCFA_EHV_FIVRA_CPU0      B @S9S_MB_2U_LIB.S9S_MB_2U(SCH_1):PVCCFA_EHV_FIVRA_CPU0

Q_CAP_C0402-100NF,50V,10%,X7R,A  I57  PC1654
   1 P12V_AUX      A @S9S_MB_2U_LIB.S9S_MB_2U(SCH_1):P12V_AUX
   2    GND      B @S9S_MB_2U_LIB.S9S_MB_2U(SCH_1):GND

Q_CAP_C0805-22UF,4V,20%,X6S,CHA  I60  PC1186_P0_4
   1 PVCCFA_EHV_FIVRA_CPU0      A @S9S_MB_2U_LIB.S9S_MB_2U(SCH_1):PVCCFA_EHV_FIVRA_CPU0
   2    GND      B @S9S_MB_2U_LIB.S9S_MB_2U(SCH_1):GND

Q_CAP_C0805-22UF,16V,20%,X6S,CA  I75  PC1673
   1 SW_P12V_PVCCFA_EHV_FIVRA_CPU0_R      A @S9S_MB_2U_LIB.S9S_MB_2U(SCH_1):SW_P12V_PVCCFA_EHV_FIVRA_CPU0_R
   2    GND      B @S9S_MB_2U_LIB.S9S_MB_2U(SCH_1):GND

Q_CAPP_THLF-270UF,16V,20%,OSCOA  I80  PC1189
   1 SW_P12V_PVCCFA_EHV_FIVRA_CPU0_R      A @S9S_MB_2U_LIB.S9S_MB_2U(SCH_1):SW_P12V_PVCCFA_EHV_FIVRA_CPU0_R
   2    GND      B @S9S_MB_2U_LIB.S9S_MB_2U(SCH_1):GND

ISL99390FRZTR5935-ISL99390FRZ-A  I82  PU71_P0_3
  34 PVCCFA_EHV_FIVRA_CPU0_PWM3    PWM @S9S_MB_2U_LIB.S9S_MB_2U(SCH_1):PVCCFA_EHV_FIVRA_CPU0_PWM3
  39 PVCCIN_CPU0_VREF  REFIN @S9S_MB_2U_LIB.S9S_MB_2U(SCH_1):PVCCIN_CPU0_VREF
   3 PVCCFA_EHV_FIVRA_CPU0_VDD3    VCC @S9S_MB_2U_LIB.S9S_MB_2U(SCH_1):PVCCFA_EHV_FIVRA_CPU0_VDD3
   2    GND   AGND @S9S_MB_2U_LIB.S9S_MB_2U(SCH_1):GND
  33 SW_PVCCFA_EHV_FIVRA_CPU0_BOOT3   BOOT @S9S_MB_2U_LIB.S9S_MB_2U(SCH_1):SW_PVCCFA_EHV_FIVRA_CPU0_BOOT3
25_29 SW_P12V_PVCCFA_EHV_FIVRA_CPU0_R   VIN1 @S9S_MB_2U_LIB.S9S_MB_2U(SCH_1):SW_P12V_PVCCFA_EHV_FIVRA_CPU0_R
  32 SW_PVCCFA_EHV_FIVRA_CPU0_BOOTR3  PHASE @S9S_MB_2U_LIB.S9S_MB_2U(SCH_1):SW_PVCCFA_EHV_FIVRA_CPU0_BOOTR3
   4 PVCCFA_EHV_FIVRA_CPU0_PVCC1   PVCC @S9S_MB_2U_LIB.S9S_MB_2U(SCH_1):PVCCFA_EHV_FIVRA_CPU0_PVCC1
  36 PVCCFA_EHV_FIVRA_CPU0_BTSEN TOUT_FLT @S9S_MB_2U_LIB.S9S_MB_2U(SCH_1):PVCCFA_EHV_FIVRA_CPU0_BTSEN
  38 PVCCFA_EHV_FIVRA_CPU0_IMON3   IOUT @S9S_MB_2U_LIB.S9S_MB_2U(SCH_1):PVCCFA_EHV_FIVRA_CPU0_IMON3
  37 PVCCFA_EHV_FIVRA_CPU0_LSET3   LSET @S9S_MB_2U_LIB.S9S_MB_2U(SCH_1):PVCCFA_EHV_FIVRA_CPU0_LSET3
10_19 SW_PVCCFA_EHV_FIVRA_CPU0_SW3     SW @S9S_MB_2U_LIB.S9S_MB_2U(SCH_1):SW_PVCCFA_EHV_FIVRA_CPU0_SW3
   5    GND  PGND1 @S9S_MB_2U_LIB.S9S_MB_2U(SCH_1):GND
  30 SW_P12V_PVCCFA_EHV_FIVRA_CPU0_R   VIN2 @S9S_MB_2U_LIB.S9S_MB_2U(SCH_1):SW_P12V_PVCCFA_EHV_FIVRA_CPU0_R
   1 PVCCFA_EHV_FIVRA_CPU0_VOS3    VOS @S9S_MB_2U_LIB.S9S_MB_2U(SCH_1):PVCCFA_EHV_FIVRA_CPU0_VOS3
  40    GND  PGND3 @S9S_MB_2U_LIB.S9S_MB_2U(SCH_1):GND
  35 PVCCFA_EHV_FIVRA_CPU0_VDD3     EN @S9S_MB_2U_LIB.S9S_MB_2U(SCH_1):PVCCFA_EHV_FIVRA_CPU0_VDD3
  31     NC    DNC     NC
   6     NC    GL1     NC
  41     NC    GL2     NC
7_9-20_24    GND  PGND2 @S9S_MB_2U_LIB.S9S_MB_2U(SCH_1):GND

Q_RES_0402LF-8.87K,1%,1/16W,EMA  I3  PR1297
   1 PVCCFA_EHV_FIVRA_CPU0_LSET4      A @S9S_MB_2U_LIB.S9S_MB_2U(SCH_1):PVCCFA_EHV_FIVRA_CPU0_LSET4
   2    GND      B @S9S_MB_2U_LIB.S9S_MB_2U(SCH_1):GND

Q_CAP_0402-0.1UF,25V,10%,X7R,CA  I9  PC1352
   1    GND      A @S9S_MB_2U_LIB.S9S_MB_2U(SCH_1):GND
   2 PVCCIN_CPU0_VREF      B @S9S_MB_2U_LIB.S9S_MB_2U(SCH_1):PVCCIN_CPU0_VREF

ISL99390FRZTR5935-ISL99390FRZ-A  I10  PU72_P0_4
  34 PVCCFA_EHV_FIVRA_CPU0_PWM4    PWM @S9S_MB_2U_LIB.S9S_MB_2U(SCH_1):PVCCFA_EHV_FIVRA_CPU0_PWM4
  39 PVCCIN_CPU0_VREF  REFIN @S9S_MB_2U_LIB.S9S_MB_2U(SCH_1):PVCCIN_CPU0_VREF
   3 PVCCFA_EHV_FIVRA_CPU0_VDD4    VCC @S9S_MB_2U_LIB.S9S_MB_2U(SCH_1):PVCCFA_EHV_FIVRA_CPU0_VDD4
   2    GND   AGND @S9S_MB_2U_LIB.S9S_MB_2U(SCH_1):GND
  33 SW_PVCCFA_EHV_FIVRA_CPU0_BOOT4   BOOT @S9S_MB_2U_LIB.S9S_MB_2U(SCH_1):SW_PVCCFA_EHV_FIVRA_CPU0_BOOT4
25_29 SW_P12V_PVCCFA_EHV_FIVRA_CPU0_L   VIN1 @S9S_MB_2U_LIB.S9S_MB_2U(SCH_1):SW_P12V_PVCCFA_EHV_FIVRA_CPU0_L
  32 SW_PVCCFA_EHV_FIVRA_CPU0_BOOTR4  PHASE @S9S_MB_2U_LIB.S9S_MB_2U(SCH_1):SW_PVCCFA_EHV_FIVRA_CPU0_BOOTR4
   4 PVCCFA_EHV_FIVRA_CPU0_PVCC2   PVCC @S9S_MB_2U_LIB.S9S_MB_2U(SCH_1):PVCCFA_EHV_FIVRA_CPU0_PVCC2
  36 PVCCFA_EHV_FIVRA_CPU0_BTSEN TOUT_FLT @S9S_MB_2U_LIB.S9S_MB_2U(SCH_1):PVCCFA_EHV_FIVRA_CPU0_BTSEN
  38 PVCCFA_EHV_FIVRA_CPU0_IMON4   IOUT @S9S_MB_2U_LIB.S9S_MB_2U(SCH_1):PVCCFA_EHV_FIVRA_CPU0_IMON4
  37 PVCCFA_EHV_FIVRA_CPU0_LSET4   LSET @S9S_MB_2U_LIB.S9S_MB_2U(SCH_1):PVCCFA_EHV_FIVRA_CPU0_LSET4
10_19 SW_PVCCFA_EHV_FIVRA_CPU0_SW4     SW @S9S_MB_2U_LIB.S9S_MB_2U(SCH_1):SW_PVCCFA_EHV_FIVRA_CPU0_SW4
   5    GND  PGND1 @S9S_MB_2U_LIB.S9S_MB_2U(SCH_1):GND
  30 SW_P12V_PVCCFA_EHV_FIVRA_CPU0_L   VIN2 @S9S_MB_2U_LIB.S9S_MB_2U(SCH_1):SW_P12V_PVCCFA_EHV_FIVRA_CPU0_L
   1 PVCCFA_EHV_FIVRA_CPU0_VOS4    VOS @S9S_MB_2U_LIB.S9S_MB_2U(SCH_1):PVCCFA_EHV_FIVRA_CPU0_VOS4
  40    GND  PGND3 @S9S_MB_2U_LIB.S9S_MB_2U(SCH_1):GND
  35 PVCCFA_EHV_FIVRA_CPU0_VDD4     EN @S9S_MB_2U_LIB.S9S_MB_2U(SCH_1):PVCCFA_EHV_FIVRA_CPU0_VDD4
  31     NC    DNC     NC
   6     NC    GL1     NC
  41     NC    GL2     NC
7_9-20_24    GND  PGND2 @S9S_MB_2U_LIB.S9S_MB_2U(SCH_1):GND

Q_CAP_C0402-2.2UF,10V,10%,X6S,A  I13  PC1172
   1 PVCCFA_EHV_FIVRA_CPU0_VDD4      A @S9S_MB_2U_LIB.S9S_MB_2U(SCH_1):PVCCFA_EHV_FIVRA_CPU0_VDD4
   2    GND      B @S9S_MB_2U_LIB.S9S_MB_2U(SCH_1):GND

Q_CAP_C0402-2.2UF,10V,10%,X6S,A  I18  PC1214_P0_4
   1 PVCCFA_EHV_FIVRA_CPU0_PVCC2      A @S9S_MB_2U_LIB.S9S_MB_2U(SCH_1):PVCCFA_EHV_FIVRA_CPU0_PVCC2
   2    GND      B @S9S_MB_2U_LIB.S9S_MB_2U(SCH_1):GND

Q_RES_0402LF-2.2,1%,1/16W,CHIPA  I26  PR1299
   1 PVCCFA_EHV_FIVRA_CPU0_PVCC1      A @S9S_MB_2U_LIB.S9S_MB_2U(SCH_1):PVCCFA_EHV_FIVRA_CPU0_PVCC1
   2 PVCCFA_EHV_FIVRA_CPU0_VDD3      B @S9S_MB_2U_LIB.S9S_MB_2U(SCH_1):PVCCFA_EHV_FIVRA_CPU0_VDD3

Q_CAP_C0402-2.2UF,10V,10%,X6S,A  I28  PC1213_P0_3
   1 PVCCFA_EHV_FIVRA_CPU0_PVCC1      A @S9S_MB_2U_LIB.S9S_MB_2U(SCH_1):PVCCFA_EHV_FIVRA_CPU0_PVCC1
   2    GND      B @S9S_MB_2U_LIB.S9S_MB_2U(SCH_1):GND

Q_CAP_C0402-1UF,16V,10%,X6S,CHA  I34  PC1176_P0_4
   1 SW_P12V_PVCCFA_EHV_FIVRA_CPU0_L      A @S9S_MB_2U_LIB.S9S_MB_2U(SCH_1):SW_P12V_PVCCFA_EHV_FIVRA_CPU0_L
   2    GND      B @S9S_MB_2U_LIB.S9S_MB_2U(SCH_1):GND

Q_CAP_C0805-22UF,16V,20%,X6S,CA  I35  PC1180_P0_4
   1 SW_P12V_PVCCFA_EHV_FIVRA_CPU0_L      A @S9S_MB_2U_LIB.S9S_MB_2U(SCH_1):SW_P12V_PVCCFA_EHV_FIVRA_CPU0_L
   2    GND      B @S9S_MB_2U_LIB.S9S_MB_2U(SCH_1):GND

Q_CAP_C0805-22UF,16V,20%,X6S,CA  I47  PC1179_P0_3
   1 SW_P12V_PVCCFA_EHV_FIVRA_CPU0_R      A @S9S_MB_2U_LIB.S9S_MB_2U(SCH_1):SW_P12V_PVCCFA_EHV_FIVRA_CPU0_R
   2    GND      B @S9S_MB_2U_LIB.S9S_MB_2U(SCH_1):GND

Q_CAP_C0402-100NF,50V,10%,X7R,A  I49  PC1177
   1 SW_PVCCFA_EHV_FIVRA_CPU0_BOOT3_      A @S9S_MB_2U_LIB.S9S_MB_2U(SCH_1):SW_PVCCFA_EHV_FIVRA_CPU0_BOOT3_R
   2 SW_PVCCFA_EHV_FIVRA_CPU0_BOOTR3      B @S9S_MB_2U_LIB.S9S_MB_2U(SCH_1):SW_PVCCFA_EHV_FIVRA_CPU0_BOOTR3

Q_CAP_C0805-22UF,16V,20%,X6S,CA  I53  PC722_P0_3
   1 SW_P12V_PVCCFA_EHV_FIVRA_CPU0_R      A @S9S_MB_2U_LIB.S9S_MB_2U(SCH_1):SW_P12V_PVCCFA_EHV_FIVRA_CPU0_R
   2    GND      B @S9S_MB_2U_LIB.S9S_MB_2U(SCH_1):GND

Q_INDUCTOR_SMLF-100NH/16A,IND,A  I59  PL101
   2 SW_P12V_PVCCFA_EHV_FIVRA_CPU0_R      2 @S9S_MB_2U_LIB.S9S_MB_2U(SCH_1):SW_P12V_PVCCFA_EHV_FIVRA_CPU0_R
   1 P12V_AUX      1 @S9S_MB_2U_LIB.S9S_MB_2U(SCH_1):P12V_AUX

Q_CAPP_THLF-560UF,2.5V,20%,OSCA  I64  PC1183
   1 PVCCFA_EHV_FIVRA_CPU0      A @S9S_MB_2U_LIB.S9S_MB_2U(SCH_1):PVCCFA_EHV_FIVRA_CPU0
   2    GND      B @S9S_MB_2U_LIB.S9S_MB_2U(SCH_1):GND

Q_CAPP_THLF-560UF,2.5V,20%,OSCA  I65  PC1185
   1 PVCCFA_EHV_FIVRA_CPU0      A @S9S_MB_2U_LIB.S9S_MB_2U(SCH_1):PVCCFA_EHV_FIVRA_CPU0
   2    GND      B @S9S_MB_2U_LIB.S9S_MB_2U(SCH_1):GND

Q_CAPP_SMLF-330UF,2.5V,+10/-35B  I69  PC1187
   1 PVCCFA_EHV_FIVRA_CPU0      A @S9S_MB_2U_LIB.S9S_MB_2U(SCH_1):PVCCFA_EHV_FIVRA_CPU0
   2    GND      B @S9S_MB_2U_LIB.S9S_MB_2U(SCH_1):GND

Q_CAPP_SMLF-330UF,2.5V,+10/-35B  I70  PC2170
   1 PVCCFA_EHV_FIVRA_CPU0      A @S9S_MB_2U_LIB.S9S_MB_2U(SCH_1):PVCCFA_EHV_FIVRA_CPU0
   2    GND      B @S9S_MB_2U_LIB.S9S_MB_2U(SCH_1):GND

Q_CAP_C0805-22UF,4V,20%,X6S,CHA  I73  PC1187_P0_3
   1 PVCCFA_EHV_FIVRA_CPU0      A @S9S_MB_2U_LIB.S9S_MB_2U(SCH_1):PVCCFA_EHV_FIVRA_CPU0
   2    GND      B @S9S_MB_2U_LIB.S9S_MB_2U(SCH_1):GND

Q_CAP_C0805-22UF,16V,20%,X6S,CA  I79  PC1676
   1 SW_P12V_PVCCFA_EHV_FIVRA_CPU0_R      A @S9S_MB_2U_LIB.S9S_MB_2U(SCH_1):SW_P12V_PVCCFA_EHV_FIVRA_CPU0_R
   2    GND      B @S9S_MB_2U_LIB.S9S_MB_2U(SCH_1):GND


DRAWING: @S9S_MB_2U_LIB.S9S_MB_2U(SCH_1):PAGE260 

Q_RES_0402LF-100,1%,1/16W,EMPTA  I37  R2386
   1 PVNN_TERM_CPU0      A @S9S_MB_2U_LIB.S9S_MB_2U(SCH_1):PVNN_TERM_CPU0
   2 SVID_DIO0_CPU0_R      B @S9S_MB_2U_LIB.S9S_MB_2U(SCH_1):SVID_DIO0_CPU0_R

Q_RES_0402LF-1K,1%,1/16W,CHIP,A  I59  R2383
   1 P3V3_AUX      A @S9S_MB_2U_LIB.S9S_MB_2U(SCH_1):P3V3_AUX
   2 PWRGD_PVCCINFAON_CPU0_R      B @S9S_MB_2U_LIB.S9S_MB_2U(SCH_1):PWRGD_PVCCINFAON_CPU0_R

Q_CAP_0402-1000PF,50V,5%,X7R,TA  I60  C3274
   1 PVCCINFAON_CPU0_EN_R      A @S9S_MB_2U_LIB.S9S_MB_2U(SCH_1):PVCCINFAON_CPU0_EN_R
   2    GND      B @S9S_MB_2U_LIB.S9S_MB_2U(SCH_1):GND

Q_CAP_0402-1000PF,50V,5%,EMPTYA  I61  C3273
   1 PWRGD_PVCCINFAON_CPU0_R      A @S9S_MB_2U_LIB.S9S_MB_2U(SCH_1):PWRGD_PVCCINFAON_CPU0_R
   2    GND      B @S9S_MB_2U_LIB.S9S_MB_2U(SCH_1):GND

ISL69260IRAZT-ISL69260IRAZ-T,SA  I65  PU5
  23 PVCCINFAON_CPU0_ACSP1    CS7 @S9S_MB_2U_LIB.S9S_MB_2U(SCH_1):PVCCINFAON_CPU0_ACSP1
  39 PVCCINFAON_CPU0_VCC    VCC @S9S_MB_2U_LIB.S9S_MB_2U(SCH_1):PVCCINFAON_CPU0_VCC
  20 PVCCFA_EHV_CPU0_EN_R    EN1 @S9S_MB_2U_LIB.S9S_MB_2U(SCH_1):PVCCFA_EHV_CPU0_EN_R
  10 SMB_CLK_PVCCINFAON_CPU0  PMSCL @S9S_MB_2U_LIB.S9S_MB_2U(SCH_1):SMB_CLK_PVCCINFAON_CPU0
  18 SVID_DIO_PVCCINFAON_CPU0_R SVDATA @S9S_MB_2U_LIB.S9S_MB_2U(SCH_1):SVID_DIO_PVCCINFAON_CPU0_R
  24 PVCCINFAON_CPU0_ACSP2    CS6 @S9S_MB_2U_LIB.S9S_MB_2U(SCH_1):PVCCINFAON_CPU0_ACSP2
  19 SVID_ALERT_PVCCINFAON_CPU0_R NSVALERT# @S9S_MB_2U_LIB.S9S_MB_2U(SCH_1):SVID_ALERT_PVCCINFAON_CPU0_R
  14 IRQ_PVCCFA_CPU0_VRHOT_N NVRHOT# @S9S_MB_2U_LIB.S9S_MB_2U(SCH_1):IRQ_PVCCFA_CPU0_VRHOT_N
  25 NC_PVCCINFAON_CPU0_ACSP3    CS5 @S9S_MB_2U_LIB.S9S_MB_2U(SCH_1):NC_PVCCINFAON_CPU0_ACSP3
  26 NC_PVCCINFAON_CPU0_ACSP4    CS4 @S9S_MB_2U_LIB.S9S_MB_2U(SCH_1):NC_PVCCINFAON_CPU0_ACSP4
  16 PWRGD_PVCCFA_EHV_CPU0_R    PG1 @S9S_MB_2U_LIB.S9S_MB_2U(SCH_1):PWRGD_PVCCFA_EHV_CPU0_R
  17 SVID_CLK_PVCCINFAON_CPU0_R  SVCLK @S9S_MB_2U_LIB.S9S_MB_2U(SCH_1):SVID_CLK_PVCCINFAON_CPU0_R
  11 NC_PVCCINFAON_CPU0_SMB_ALERT NPMALERT# @S9S_MB_2U_LIB.S9S_MB_2U(SCH_1):NC_PVCCINFAON_CPU0_SMB_ALERT
  13 PVCCINFAON_CPU0_EN_R    EN0 @S9S_MB_2U_LIB.S9S_MB_2U(SCH_1):PVCCINFAON_CPU0_EN_R
  22 VSENSE_PVCCINFAON_CPU0_DN  RGND0 @S9S_MB_2U_LIB.S9S_MB_2U(SCH_1):VSENSE_PVCCINFAON_CPU0_DN
   9 SMB_DIO_PVCCINFAON_CPU0  PMSDA @S9S_MB_2U_LIB.S9S_MB_2U(SCH_1):SMB_DIO_PVCCINFAON_CPU0
   5 NC_PVCCINFAON_CPU0_APWM4   PWM4 @S9S_MB_2U_LIB.S9S_MB_2U(SCH_1):NC_PVCCINFAON_CPU0_APWM4
   6 NC_PVCCINFAON_CPU0_APWM3   PWM5 @S9S_MB_2U_LIB.S9S_MB_2U(SCH_1):NC_PVCCINFAON_CPU0_APWM3
  21 SH_PVCCINFAON_CPU0_R  VSEN0 @S9S_MB_2U_LIB.S9S_MB_2U(SCH_1):SH_PVCCINFAON_CPU0_R
   2 NC_PVCCINFAON_CPU0_APWM7   PWM1 @S9S_MB_2U_LIB.S9S_MB_2U(SCH_1):NC_PVCCINFAON_CPU0_APWM7
  12 PWRGD_PVCCINFAON_CPU0_R    PG0 @S9S_MB_2U_LIB.S9S_MB_2U(SCH_1):PWRGD_PVCCINFAON_CPU0_R
   7 PVCCINFAON_CPU0_APWM2   PWM6 @S9S_MB_2U_LIB.S9S_MB_2U(SCH_1):PVCCINFAON_CPU0_APWM2
  40 PVCCINFAON_CPU0_VREF   VCCS @S9S_MB_2U_LIB.S9S_MB_2U(SCH_1):PVCCINFAON_CPU0_VREF
  37 PVCCINFAON_CPU0_CSPIN VMON||IINSEN||VSYS||ISYS @S9S_MB_2U_LIB.S9S_MB_2U(SCH_1):PVCCINFAON_CPU0_CSPIN
  38 PVCCINFAON_CPU0_VIN_CSNIN VINSEN||VSYS @S9S_MB_2U_LIB.S9S_MB_2U(SCH_1):PVCCINFAON_CPU0_VIN_CSNIN
  36 PVCCFA_EHV_CPU0_BTSEN TEMP1||ISYS @S9S_MB_2U_LIB.S9S_MB_2U(SCH_1):PVCCFA_EHV_CPU0_BTSEN
  15 PVCCINFAON_CPU0_PIN_ALERT NPINALERT#||NPSYSCRIT# @S9S_MB_2U_LIB.S9S_MB_2U(SCH_1):PVCCINFAON_CPU0_PIN_ALERT
  32 SH_PVCCFA_EHV_CPU0_R  VSEN1 @S9S_MB_2U_LIB.S9S_MB_2U(SCH_1):SH_PVCCFA_EHV_CPU0_R
  31 VSENSE_PVCCFA_EHV_CPU0_DN  RGND1 @S9S_MB_2U_LIB.S9S_MB_2U(SCH_1):VSENSE_PVCCFA_EHV_CPU0_DN
  29 NC_PVCCINFAON_CPU0_ACSP7    CS1 @S9S_MB_2U_LIB.S9S_MB_2U(SCH_1):NC_PVCCINFAON_CPU0_ACSP7
   8 PVCCINFAON_CPU0_APWM1   PWM7 @S9S_MB_2U_LIB.S9S_MB_2U(SCH_1):PVCCINFAON_CPU0_APWM1
   4 NC_PVCCINFAON_CPU0_APWM5   PWM3 @S9S_MB_2U_LIB.S9S_MB_2U(SCH_1):NC_PVCCINFAON_CPU0_APWM5
  27 NC_PVCCINFAON_CPU0_ACSP5    CS3 @S9S_MB_2U_LIB.S9S_MB_2U(SCH_1):NC_PVCCINFAON_CPU0_ACSP5
   3 NC_PVCCINFAON_CPU0_APWM6   PWM2 @S9S_MB_2U_LIB.S9S_MB_2U(SCH_1):NC_PVCCINFAON_CPU0_APWM6
  28 NC_PVCCINFAON_CPU0_ACSP6    CS2 @S9S_MB_2U_LIB.S9S_MB_2U(SCH_1):NC_PVCCINFAON_CPU0_ACSP6
  33 PVCCINFAON_CPU0_VR_FAULT    CFP @S9S_MB_2U_LIB.S9S_MB_2U(SCH_1):PVCCINFAON_CPU0_VR_FAULT
  TH    GND TH_GND @S9S_MB_2U_LIB.S9S_MB_2U(SCH_1):GND
  34 PVCCINFAON_CPU0_ADDR ADDR_CFG @S9S_MB_2U_LIB.S9S_MB_2U(SCH_1):PVCCINFAON_CPU0_ADDR
  35 PVCCINFAON_CPU0_ATSEN  TEMP0 @S9S_MB_2U_LIB.S9S_MB_2U(SCH_1):PVCCINFAON_CPU0_ATSEN
   1 PVCCFA_EHV_CPU0_BPWM1   PWM0 @S9S_MB_2U_LIB.S9S_MB_2U(SCH_1):PVCCFA_EHV_CPU0_BPWM1
  30 PVCCFA_EHV_CPU0_BCSP1    CS0 @S9S_MB_2U_LIB.S9S_MB_2U(SCH_1):PVCCFA_EHV_CPU0_BCSP1

Q_RES_0402LF-100,1%,1/16W,CHIPA  I40  PR522
   1 VSENSE_PVCCFA_EHV_CPU0_DP      A @S9S_MB_2U_LIB.S9S_MB_2U(SCH_1):VSENSE_PVCCFA_EHV_CPU0_DP
   2 PVCCFA_EHV_CPU0      B @S9S_MB_2U_LIB.S9S_MB_2U(SCH_1):PVCCFA_EHV_CPU0

Q_RES_0402LF-100,1%,1/16W,CHIPA  I44  PR521
   1 VSENSE_PVCCINFAON_CPU0_DP      A @S9S_MB_2U_LIB.S9S_MB_2U(SCH_1):VSENSE_PVCCINFAON_CPU0_DP
   2 PVCCINFAON_CPU0      B @S9S_MB_2U_LIB.S9S_MB_2U(SCH_1):PVCCINFAON_CPU0

Q_CAP_0402-3300PF,50V,10%,X7R,A  I48  PC216
   1 SH_PVCCFA_EHV_CPU0_R      A @S9S_MB_2U_LIB.S9S_MB_2U(SCH_1):SH_PVCCFA_EHV_CPU0_R
   2 VSENSE_PVCCFA_EHV_CPU0_DN      B @S9S_MB_2U_LIB.S9S_MB_2U(SCH_1):VSENSE_PVCCFA_EHV_CPU0_DN

Q_CAP_0402-3300PF,50V,10%,X7R,A  I50  PC215
   1 SH_PVCCINFAON_CPU0_R      A @S9S_MB_2U_LIB.S9S_MB_2U(SCH_1):SH_PVCCINFAON_CPU0_R
   2 VSENSE_PVCCINFAON_CPU0_DN      B @S9S_MB_2U_LIB.S9S_MB_2U(SCH_1):VSENSE_PVCCINFAON_CPU0_DN

Q_RES_0402LF-49.9,1%,1/16W,EMPA  I36  R2322
   1 PVNN_TERM_CPU0      A @S9S_MB_2U_LIB.S9S_MB_2U(SCH_1):PVNN_TERM_CPU0
   2 SVID_CLK0_CPU0_R      B @S9S_MB_2U_LIB.S9S_MB_2U(SCH_1):SVID_CLK0_CPU0_R

Q_RES_0402LF-0,5%,1/16W,CHIP,CA  I55  R2594
   1 FM_PVCCINFAON_CPU0_EN      A @S9S_MB_2U_LIB.S9S_MB_2U(SCH_1):FM_PVCCINFAON_CPU0_EN
   2 PVCCINFAON_CPU0_EN_R      B @S9S_MB_2U_LIB.S9S_MB_2U(SCH_1):PVCCINFAON_CPU0_EN_R

Q_CAP_0402-0.1UF,25V,10%,X7R,CA  I63  PC221
   1 PVCCINFAON_CPU0_VIN_CSNIN      A @S9S_MB_2U_LIB.S9S_MB_2U(SCH_1):PVCCINFAON_CPU0_VIN_CSNIN
   2    GND      B @S9S_MB_2U_LIB.S9S_MB_2U(SCH_1):GND

Q_RES_0402LF-1K,1%,1/16W,CHIP,A  I79  R2398
   1 P3V3_AUX      A @S9S_MB_2U_LIB.S9S_MB_2U(SCH_1):P3V3_AUX
   2 IRQ_PVCCFA_CPU0_VRHOT_R_N      B @S9S_MB_2U_LIB.S9S_MB_2U(SCH_1):IRQ_PVCCFA_CPU0_VRHOT_R_N

Q_RES_0402LF-0,5%,1/16W,CHIP,CA  I14  R2394
   1 FM_PVCCFA_EHV_CPU0_EN      A @S9S_MB_2U_LIB.S9S_MB_2U(SCH_1):FM_PVCCFA_EHV_CPU0_EN
   2 PVCCFA_EHV_CPU0_EN_R      B @S9S_MB_2U_LIB.S9S_MB_2U(SCH_1):PVCCFA_EHV_CPU0_EN_R

Q_RES_0402LF-1K,1%,1/16W,CHIP,A  I18  R2392
   1 P3V3_AUX      A @S9S_MB_2U_LIB.S9S_MB_2U(SCH_1):P3V3_AUX
   2 PVCCINFAON_CPU0_VR_FAULT      B @S9S_MB_2U_LIB.S9S_MB_2U(SCH_1):PVCCINFAON_CPU0_VR_FAULT

Q_CAP_0402-1000PF,50V,5%,X7R,TA  I23  C3275
   1 PVCCFA_EHV_CPU0_EN_R      A @S9S_MB_2U_LIB.S9S_MB_2U(SCH_1):PVCCFA_EHV_CPU0_EN_R
   2    GND      B @S9S_MB_2U_LIB.S9S_MB_2U(SCH_1):GND

Q_RES_0402LF-0,5%,1/16W,CHIP,CA  I51  R2391
   1 SMB_VR_3V3AUX_SDA_R2      A @S9S_MB_2U_LIB.S9S_MB_2U(SCH_1):SMB_VR_3V3AUX_SDA_R2
   2 SMB_DIO_PVCCINFAON_CPU0      B @S9S_MB_2U_LIB.S9S_MB_2U(SCH_1):SMB_DIO_PVCCINFAON_CPU0

Q_RES_0402LF-0,5%,1/16W,CHIP,CA  I52  R2389
   1 SVID_ALERT0_CPU0_R_N      A @S9S_MB_2U_LIB.S9S_MB_2U(SCH_1):SVID_ALERT0_CPU0_R_N
   2 SVID_ALERT_PVCCINFAON_CPU0_R      B @S9S_MB_2U_LIB.S9S_MB_2U(SCH_1):SVID_ALERT_PVCCINFAON_CPU0_R

Q_RES_0402LF-0,5%,1/16W,CHIP,CA  I57  R2388
   1 SVID_DIO0_CPU0_R      A @S9S_MB_2U_LIB.S9S_MB_2U(SCH_1):SVID_DIO0_CPU0_R
   2 SVID_DIO_PVCCINFAON_CPU0_R      B @S9S_MB_2U_LIB.S9S_MB_2U(SCH_1):SVID_DIO_PVCCINFAON_CPU0_R

Q_RES_0402LF-0,5%,1/16W,CHIP,CA  I78  R2597
   1 IRQ_PVCCFA_CPU0_VRHOT_N      A @S9S_MB_2U_LIB.S9S_MB_2U(SCH_1):IRQ_PVCCFA_CPU0_VRHOT_N
   2 IRQ_PVCCFA_CPU0_VRHOT_R_N      B @S9S_MB_2U_LIB.S9S_MB_2U(SCH_1):IRQ_PVCCFA_CPU0_VRHOT_R_N

Q_RES_0402LF-0,5%,1/16W,CHIP,CA  I84  PR4224
   1 NC_PVCCINFAON_CPU0_ACSP6      A @S9S_MB_2U_LIB.S9S_MB_2U(SCH_1):NC_PVCCINFAON_CPU0_ACSP6
   2    GND      B @S9S_MB_2U_LIB.S9S_MB_2U(SCH_1):GND

Q_RES_0402LF-0,5%,1/16W,CHIP,CA  I85  PR4223
   1 NC_PVCCINFAON_CPU0_ACSP5      A @S9S_MB_2U_LIB.S9S_MB_2U(SCH_1):NC_PVCCINFAON_CPU0_ACSP5
   2    GND      B @S9S_MB_2U_LIB.S9S_MB_2U(SCH_1):GND

Q_RES_0402LF-0,5%,1/16W,CHIP,CA  I86  PR4222
   1 NC_PVCCINFAON_CPU0_ACSP4      A @S9S_MB_2U_LIB.S9S_MB_2U(SCH_1):NC_PVCCINFAON_CPU0_ACSP4
   2    GND      B @S9S_MB_2U_LIB.S9S_MB_2U(SCH_1):GND

Q_CAP_C0402-10UF,6.3V,20%,X6S,B  I92  PC224
   1 PVCCINFAON_CPU0_VREF      A @S9S_MB_2U_LIB.S9S_MB_2U(SCH_1):PVCCINFAON_CPU0_VREF
   2    GND      B @S9S_MB_2U_LIB.S9S_MB_2U(SCH_1):GND

Q_RES_0402LF-28K,1%,1/16W,EMPTA  I7  PR105
   1 PVCCINFAON_CPU0_VREF      A @S9S_MB_2U_LIB.S9S_MB_2U(SCH_1):PVCCINFAON_CPU0_VREF
   2 PVCCINFAON_CPU0_ADDR      B @S9S_MB_2U_LIB.S9S_MB_2U(SCH_1):PVCCINFAON_CPU0_ADDR

Q_RES_0402LF-0,5%,1/16W,CHIP,CA  I9  PR108
   1 P12V_AUX      A @S9S_MB_2U_LIB.S9S_MB_2U(SCH_1):P12V_AUX
   2 PVCCINFAON_CPU0_VIN_CSNIN      B @S9S_MB_2U_LIB.S9S_MB_2U(SCH_1):PVCCINFAON_CPU0_VIN_CSNIN

Q_RES_0402LF-0,5%,1/16W,EMPTY,A  I10  PR107
   1 P12V_AUX      A @S9S_MB_2U_LIB.S9S_MB_2U(SCH_1):P12V_AUX
   2 PVCCINFAON_CPU0_CSPIN      B @S9S_MB_2U_LIB.S9S_MB_2U(SCH_1):PVCCINFAON_CPU0_CSPIN

Q_RES_0402LF-0,5%,1/16W,CHIP,CA  I11  R2397
   1 PWRGD_PVCCFA_EHV_CPU0      A @S9S_MB_2U_LIB.S9S_MB_2U(SCH_1):PWRGD_PVCCFA_EHV_CPU0
   2 PWRGD_PVCCFA_EHV_CPU0_R      B @S9S_MB_2U_LIB.S9S_MB_2U(SCH_1):PWRGD_PVCCFA_EHV_CPU0_R

Q_RES_0402LF-1K,1%,1/16W,CHIP,A  I13  R2396
   1 P3V3_AUX      A @S9S_MB_2U_LIB.S9S_MB_2U(SCH_1):P3V3_AUX
   2 PWRGD_PVCCFA_EHV_CPU0_R      B @S9S_MB_2U_LIB.S9S_MB_2U(SCH_1):PWRGD_PVCCFA_EHV_CPU0_R

Q_RES_0402LF-1K,1%,1/16W,CHIP,A  I17  R2393
   1 P3V3_AUX      A @S9S_MB_2U_LIB.S9S_MB_2U(SCH_1):P3V3_AUX
   2 PVCCINFAON_CPU0_PIN_ALERT      B @S9S_MB_2U_LIB.S9S_MB_2U(SCH_1):PVCCINFAON_CPU0_PIN_ALERT

Q_RES_0402LF-0,5%,1/16W,CHIP,CA  I19  PR4220
   1 PVCCINFAON_CPU0_CSPIN      A @S9S_MB_2U_LIB.S9S_MB_2U(SCH_1):PVCCINFAON_CPU0_CSPIN
   2    GND      B @S9S_MB_2U_LIB.S9S_MB_2U(SCH_1):GND

Q_CAP_0402-0.1UF,25V,10%,EMPTYA  I20  PC214
   1 PVCCINFAON_CPU0_CSPIN      A @S9S_MB_2U_LIB.S9S_MB_2U(SCH_1):PVCCINFAON_CPU0_CSPIN
   2    GND      B @S9S_MB_2U_LIB.S9S_MB_2U(SCH_1):GND

Q_RES_0402LF-1K,1%,1/16W,EMPTYA  I21  PR123
   1 PVCCINFAON_CPU0_VIN_CSNIN      A @S9S_MB_2U_LIB.S9S_MB_2U(SCH_1):PVCCINFAON_CPU0_VIN_CSNIN
   2    GND      B @S9S_MB_2U_LIB.S9S_MB_2U(SCH_1):GND

Q_CAP_0402-1000PF,50V,5%,EMPTYA  I22  C3276
   1 PWRGD_PVCCFA_EHV_CPU0_R      A @S9S_MB_2U_LIB.S9S_MB_2U(SCH_1):PWRGD_PVCCFA_EHV_CPU0_R
   2    GND      B @S9S_MB_2U_LIB.S9S_MB_2U(SCH_1):GND

Q_RES_0402LF-100,1%,1/16W,CHIPA  I38  PR520
   1 VSENSE_PVCCFA_EHV_CPU0_DN      A @S9S_MB_2U_LIB.S9S_MB_2U(SCH_1):VSENSE_PVCCFA_EHV_CPU0_DN
   2    GND      B @S9S_MB_2U_LIB.S9S_MB_2U(SCH_1):GND

Q_SHORT_SM-EMPTY,SHORT6  I39  PJ46
   1 VSENSE_PVCCFA_EHV_CPU0_DP      1 @S9S_MB_2U_LIB.S9S_MB_2U(SCH_1):VSENSE_PVCCFA_EHV_CPU0_DP
   2 SH_PVCCFA_EHV_CPU0      2 @S9S_MB_2U_LIB.S9S_MB_2U(SCH_1):SH_PVCCFA_EHV_CPU0

Q_RES_0402LF-100,1%,1/16W,CHIPA  I42  PR519
   1 VSENSE_PVCCINFAON_CPU0_DN      A @S9S_MB_2U_LIB.S9S_MB_2U(SCH_1):VSENSE_PVCCINFAON_CPU0_DN
   2    GND      B @S9S_MB_2U_LIB.S9S_MB_2U(SCH_1):GND

Q_SHORT_SM-EMPTY,SHORT6  I43  PJ45
   1 VSENSE_PVCCINFAON_CPU0_DP      1 @S9S_MB_2U_LIB.S9S_MB_2U(SCH_1):VSENSE_PVCCINFAON_CPU0_DP
   2 SH_PVCCINFAON_CPU0      2 @S9S_MB_2U_LIB.S9S_MB_2U(SCH_1):SH_PVCCINFAON_CPU0

Q_RES_0402LF-0,5%,1/16W,CHIP,CA  I47  PR121
   1 SH_PVCCFA_EHV_CPU0      A @S9S_MB_2U_LIB.S9S_MB_2U(SCH_1):SH_PVCCFA_EHV_CPU0
   2 SH_PVCCFA_EHV_CPU0_R      B @S9S_MB_2U_LIB.S9S_MB_2U(SCH_1):SH_PVCCFA_EHV_CPU0_R

Q_RES_0402LF-0,5%,1/16W,CHIP,CA  I49  PR120
   1 SH_PVCCINFAON_CPU0      A @S9S_MB_2U_LIB.S9S_MB_2U(SCH_1):SH_PVCCINFAON_CPU0
   2 SH_PVCCINFAON_CPU0_R      B @S9S_MB_2U_LIB.S9S_MB_2U(SCH_1):SH_PVCCINFAON_CPU0_R

Q_RES_0402LF-0,5%,1/16W,CHIP,CA  I53  R2390
   1 SMB_VR_3V3AUX_SCL_R2      A @S9S_MB_2U_LIB.S9S_MB_2U(SCH_1):SMB_VR_3V3AUX_SCL_R2
   2 SMB_CLK_PVCCINFAON_CPU0      B @S9S_MB_2U_LIB.S9S_MB_2U(SCH_1):SMB_CLK_PVCCINFAON_CPU0

Q_RES_0402LF-150,1%,1/16W,CHIPA  I56  R2596
   1 SVID_CLK0_CPU0_R      A @S9S_MB_2U_LIB.S9S_MB_2U(SCH_1):SVID_CLK0_CPU0_R
   2 SVID_CLK_PVCCINFAON_CPU0_R      B @S9S_MB_2U_LIB.S9S_MB_2U(SCH_1):SVID_CLK_PVCCINFAON_CPU0_R

Q_RES_0402LF-0,5%,1/16W,CHIP,CA  I58  R2595
   1 PWRGD_PVCCINFAON_CPU0      A @S9S_MB_2U_LIB.S9S_MB_2U(SCH_1):PWRGD_PVCCINFAON_CPU0
   2 PWRGD_PVCCINFAON_CPU0_R      B @S9S_MB_2U_LIB.S9S_MB_2U(SCH_1):PWRGD_PVCCINFAON_CPU0_R

Q_CAP_0402-470PF,50V,10%,X7R,TA  I69  PC222
   1 PVCCINFAON_CPU0_ATSEN      A @S9S_MB_2U_LIB.S9S_MB_2U(SCH_1):PVCCINFAON_CPU0_ATSEN
   2    GND      B @S9S_MB_2U_LIB.S9S_MB_2U(SCH_1):GND

Q_RES_0402LF-10K,1%,1/16W,EMPTA  I71  PR435
   1 PVCCINFAON_CPU0_ATSEN      A @S9S_MB_2U_LIB.S9S_MB_2U(SCH_1):PVCCINFAON_CPU0_ATSEN
   2    GND      B @S9S_MB_2U_LIB.S9S_MB_2U(SCH_1):GND

Q_CAP_0402-470PF,50V,10%,X7R,TA  I73  PC1271
   1 PVCCFA_EHV_CPU0_BTSEN      A @S9S_MB_2U_LIB.S9S_MB_2U(SCH_1):PVCCFA_EHV_CPU0_BTSEN
   2    GND      B @S9S_MB_2U_LIB.S9S_MB_2U(SCH_1):GND

Q_RES_0402LF-0,5%,1/16W,CHIP,CA  I76  PR4225
   1 NC_PVCCINFAON_CPU0_ACSP7      A @S9S_MB_2U_LIB.S9S_MB_2U(SCH_1):NC_PVCCINFAON_CPU0_ACSP7
   2    GND      B @S9S_MB_2U_LIB.S9S_MB_2U(SCH_1):GND

Q_RES_0402LF-0,5%,1/16W,CHIP,CA  I87  PR4221
   1 NC_PVCCINFAON_CPU0_ACSP3      A @S9S_MB_2U_LIB.S9S_MB_2U(SCH_1):NC_PVCCINFAON_CPU0_ACSP3
   2    GND      B @S9S_MB_2U_LIB.S9S_MB_2U(SCH_1):GND

Q_CAP_C0402-1UF,16V,10%,X6S,CHA  I95  PC1372
   1 PVCCINFAON_CPU0_VREF      A @S9S_MB_2U_LIB.S9S_MB_2U(SCH_1):PVCCINFAON_CPU0_VREF
   2    GND      B @S9S_MB_2U_LIB.S9S_MB_2U(SCH_1):GND

Q_CAP_C0402-100NF,50V,10%,EMPTA  I98  PC223
   1 PVCCINFAON_CPU0_VCC      A @S9S_MB_2U_LIB.S9S_MB_2U(SCH_1):PVCCINFAON_CPU0_VCC
   2    GND      B @S9S_MB_2U_LIB.S9S_MB_2U(SCH_1):GND

Q_CAP_C0402-1UF,16V,10%,X6S,CHA  I99  PC225
   1 PVCCINFAON_CPU0_VCC      A @S9S_MB_2U_LIB.S9S_MB_2U(SCH_1):PVCCINFAON_CPU0_VCC
   2    GND      B @S9S_MB_2U_LIB.S9S_MB_2U(SCH_1):GND

Q_RES_0402LF-1,1%,1/16W,CHIP,CA  I100  PR130
   1 PVCCINFAON_CPU0_VCC      A @S9S_MB_2U_LIB.S9S_MB_2U(SCH_1):PVCCINFAON_CPU0_VCC
   2 P3V3_AUX      B @S9S_MB_2U_LIB.S9S_MB_2U(SCH_1):P3V3_AUX

Q_RES_0402LF-10K,1%,1/16W,EMPTA  I106  PR436
   1 PVCCFA_EHV_CPU0_BTSEN      A @S9S_MB_2U_LIB.S9S_MB_2U(SCH_1):PVCCFA_EHV_CPU0_BTSEN
   2    GND      B @S9S_MB_2U_LIB.S9S_MB_2U(SCH_1):GND

Q_RES_0402LF-681,1%,1/16W,CHIPA  I109  PR106
   1 PVCCINFAON_CPU0_ADDR      A @S9S_MB_2U_LIB.S9S_MB_2U(SCH_1):PVCCINFAON_CPU0_ADDR
   2    GND      B @S9S_MB_2U_LIB.S9S_MB_2U(SCH_1):GND

Q_CAP_0402-0.1UF,25V,10%,EMPTYA  I110  PC2362
   1 PVCCINFAON_CPU0_VCC      A @S9S_MB_2U_LIB.S9S_MB_2U(SCH_1):PVCCINFAON_CPU0_VCC
   2    GND      B @S9S_MB_2U_LIB.S9S_MB_2U(SCH_1):GND


DRAWING: @S9S_MB_2U_LIB.S9S_MB_2U(SCH_1):PAGE262 

Q_RES_0402LF-0,5%,1/16W,EMPTY,A  I15  PR4228
   1 PVCCFA_EHV_CPU0_FAULT      A @S9S_MB_2U_LIB.S9S_MB_2U(SCH_1):PVCCFA_EHV_CPU0_FAULT
   2    GND      B @S9S_MB_2U_LIB.S9S_MB_2U(SCH_1):GND

Q_RES_0402LF-2.2,1%,1/16W,CHIPA  I21  PR97
   1 PVCCFA_EHV_CPU0_PVCC      A @S9S_MB_2U_LIB.S9S_MB_2U(SCH_1):PVCCFA_EHV_CPU0_PVCC
   2 PVCCFA_EHV_CPU0_VDD1      B @S9S_MB_2U_LIB.S9S_MB_2U(SCH_1):PVCCFA_EHV_CPU0_VDD1

Q_CAP_0402-3300PF,50V,10%,X7R,A  I24  PC176
   1 SW_P12V_PVCCINFAON_CPU0_FLT      A @S9S_MB_2U_LIB.S9S_MB_2U(SCH_1):SW_P12V_PVCCINFAON_CPU0_FLT
   2    GND      B @S9S_MB_2U_LIB.S9S_MB_2U(SCH_1):GND

Q_CAP_C0402-1UF,16V,10%,X6S,CHA  I25  PC177
   1 SW_P12V_PVCCINFAON_CPU0_FLT      A @S9S_MB_2U_LIB.S9S_MB_2U(SCH_1):SW_P12V_PVCCINFAON_CPU0_FLT
   2    GND      B @S9S_MB_2U_LIB.S9S_MB_2U(SCH_1):GND

Q_CAP_C0805-22UF,16V,20%,X6S,CA  I27  PC180
   1 SW_P12V_PVCCINFAON_CPU0_FLT      A @S9S_MB_2U_LIB.S9S_MB_2U(SCH_1):SW_P12V_PVCCINFAON_CPU0_FLT
   2    GND      B @S9S_MB_2U_LIB.S9S_MB_2U(SCH_1):GND

Q_CAP_C0402-100NF,50V,10%,X7R,A  I28  PC181
   1 PVCCFA_EHV_CPU0      A @S9S_MB_2U_LIB.S9S_MB_2U(SCH_1):PVCCFA_EHV_CPU0
   2    GND      B @S9S_MB_2U_LIB.S9S_MB_2U(SCH_1):GND

Q_CAP_C0805-22UF,4V,20%,X6S,CHA  I31  PC184
   1 PVCCFA_EHV_CPU0      A @S9S_MB_2U_LIB.S9S_MB_2U(SCH_1):PVCCFA_EHV_CPU0
   2    GND      B @S9S_MB_2U_LIB.S9S_MB_2U(SCH_1):GND

Q_CAP_C0402-2.2UF,10V,10%,X6S,A  I12  PC175
   1 PVCCFA_EHV_CPU0_VDD1      A @S9S_MB_2U_LIB.S9S_MB_2U(SCH_1):PVCCFA_EHV_CPU0_VDD1
   2    GND      B @S9S_MB_2U_LIB.S9S_MB_2U(SCH_1):GND

Q_INDUCTOR_SMLF-300NH/33A,IND,A  I29  PL3
   2 PVCCFA_EHV_CPU0      2 @S9S_MB_2U_LIB.S9S_MB_2U(SCH_1):PVCCFA_EHV_CPU0
   1 SW_PVCCFA_EHV_CPU0_SW1      1 @S9S_MB_2U_LIB.S9S_MB_2U(SCH_1):SW_PVCCFA_EHV_CPU0_SW1

Q_CAPP_THLF-560UF,2.5V,20%,OSCA  I33  PC2180
   1 PVCCFA_EHV_CPU0      A @S9S_MB_2U_LIB.S9S_MB_2U(SCH_1):PVCCFA_EHV_CPU0
   2    GND      B @S9S_MB_2U_LIB.S9S_MB_2U(SCH_1):GND

Q_RES_0402LF-0,5%,1/16W,CHIP,CA  I8  PR442
   1    P5V      A @S9S_MB_2U_LIB.S9S_MB_2U(SCH_1):P5V
   2 PVCCFA_EHV_CPU0_PVCC      B @S9S_MB_2U_LIB.S9S_MB_2U(SCH_1):PVCCFA_EHV_CPU0_PVCC

Q_RES_0402LF-3.3,1%,1/16W,CHIPA  I17  PR1778
   1 SW_PVCCFA_EHV_CPU0_BOOT1      A @S9S_MB_2U_LIB.S9S_MB_2U(SCH_1):SW_PVCCFA_EHV_CPU0_BOOT1
   2 SW_PVCCFA_EHV_CPU0_BOOT1_R      B @S9S_MB_2U_LIB.S9S_MB_2U(SCH_1):SW_PVCCFA_EHV_CPU0_BOOT1_R

Q_CAP_C0805-22UF,16V,20%,X6S,CA  I26  PC179
   1 SW_P12V_PVCCINFAON_CPU0_FLT      A @S9S_MB_2U_LIB.S9S_MB_2U(SCH_1):SW_P12V_PVCCINFAON_CPU0_FLT
   2    GND      B @S9S_MB_2U_LIB.S9S_MB_2U(SCH_1):GND

Q_CAP_C0805-22UF,4V,20%,X6S,CHA  I32  PC186
   1 PVCCFA_EHV_CPU0      A @S9S_MB_2U_LIB.S9S_MB_2U(SCH_1):PVCCFA_EHV_CPU0
   2    GND      B @S9S_MB_2U_LIB.S9S_MB_2U(SCH_1):GND

Q_CAPP_SMLF-330UF,2.5V,+10/-35B  I34  PC1900
   1 PVCCFA_EHV_CPU0      A @S9S_MB_2U_LIB.S9S_MB_2U(SCH_1):PVCCFA_EHV_CPU0
   2    GND      B @S9S_MB_2U_LIB.S9S_MB_2U(SCH_1):GND

Q_RES_0402LF-499,1%,1/16W,CHIPA  I36  PR4229
   1 PVCCFA_EHV_CPU0      A @S9S_MB_2U_LIB.S9S_MB_2U(SCH_1):PVCCFA_EHV_CPU0
   2    GND      B @S9S_MB_2U_LIB.S9S_MB_2U(SCH_1):GND

Q_RES_0402LF-8.87K,1%,1/16W,EMA  I2  PR1709
   1 PVCCFA_EHV_CPU0_LSET1      A @S9S_MB_2U_LIB.S9S_MB_2U(SCH_1):PVCCFA_EHV_CPU0_LSET1
   2    GND      B @S9S_MB_2U_LIB.S9S_MB_2U(SCH_1):GND

Q_CAP_0402-0.1UF,25V,10%,X7R,CA  I10  PC1348
   1    GND      A @S9S_MB_2U_LIB.S9S_MB_2U(SCH_1):GND
   2 PVCCINFAON_CPU0_VREF      B @S9S_MB_2U_LIB.S9S_MB_2U(SCH_1):PVCCINFAON_CPU0_VREF

Q_RES_0402LF-0,5%,1/16W,EMPTY,A  I13  PR4227
   1 PVCCFA_EHV_CPU0_VDD1      A @S9S_MB_2U_LIB.S9S_MB_2U(SCH_1):PVCCFA_EHV_CPU0_VDD1
   2 PVCCFA_EHV_CPU0_NC2      B @S9S_MB_2U_LIB.S9S_MB_2U(SCH_1):PVCCFA_EHV_CPU0_NC2

RAA2213404GNPHB0-RAA2213404GNPA  I14  PU42
  21 PVCCFA_EHV_CPU0_BPWM1    PWM @S9S_MB_2U_LIB.S9S_MB_2U(SCH_1):PVCCFA_EHV_CPU0_BPWM1
  24 PVCCINFAON_CPU0_VREF  REFIN @S9S_MB_2U_LIB.S9S_MB_2U(SCH_1):PVCCINFAON_CPU0_VREF
  23    GND   GND2 @S9S_MB_2U_LIB.S9S_MB_2U(SCH_1):GND
  20 SW_PVCCFA_EHV_CPU0_BOOT1   BOOT @S9S_MB_2U_LIB.S9S_MB_2U(SCH_1):SW_PVCCFA_EHV_CPU0_BOOT1
16_18-28 SW_P12V_PVCCINFAON_CPU0_FLT    VIN @S9S_MB_2U_LIB.S9S_MB_2U(SCH_1):SW_P12V_PVCCINFAON_CPU0_FLT
  19 SW_PVCCFA_EHV_CPU0_BOOTR1  PHASE @S9S_MB_2U_LIB.S9S_MB_2U(SCH_1):SW_PVCCFA_EHV_CPU0_BOOTR1
   4 PVCCFA_EHV_CPU0_VDD1    VCC @S9S_MB_2U_LIB.S9S_MB_2U(SCH_1):PVCCFA_EHV_CPU0_VDD1
   1 PVCCFA_EHV_CPU0_BTSEN   TMON @S9S_MB_2U_LIB.S9S_MB_2U(SCH_1):PVCCFA_EHV_CPU0_BTSEN
  25 PVCCFA_EHV_CPU0_BCSP1   IMON @S9S_MB_2U_LIB.S9S_MB_2U(SCH_1):PVCCFA_EHV_CPU0_BCSP1
6_7-13_15-29    GND   GND1 @S9S_MB_2U_LIB.S9S_MB_2U(SCH_1):GND
  27     NC    GL2     NC
8_12 SW_PVCCFA_EHV_CPU0_SW1     SW @S9S_MB_2U_LIB.S9S_MB_2U(SCH_1):SW_PVCCFA_EHV_CPU0_SW1
   2 PVCCFA_EHV_CPU0_FAULT FAULT# @S9S_MB_2U_LIB.S9S_MB_2U(SCH_1):PVCCFA_EHV_CPU0_FAULT
  26    GND   GND3 @S9S_MB_2U_LIB.S9S_MB_2U(SCH_1):GND
  22 PVCCFA_EHV_CPU0_NC2    NC1 @S9S_MB_2U_LIB.S9S_MB_2U(SCH_1):PVCCFA_EHV_CPU0_NC2
   5 PVCCFA_EHV_CPU0_LSET1    GL1 @S9S_MB_2U_LIB.S9S_MB_2U(SCH_1):PVCCFA_EHV_CPU0_LSET1
   3 PVCCFA_EHV_CPU0_NC1 LGCTRL @S9S_MB_2U_LIB.S9S_MB_2U(SCH_1):PVCCFA_EHV_CPU0_NC1

Q_RES_0402LF-0,5%,1/16W,CHIP,CA  I16  PR1779
   1 PVCCFA_EHV_CPU0_NC1      A @S9S_MB_2U_LIB.S9S_MB_2U(SCH_1):PVCCFA_EHV_CPU0_NC1
   2 PVCCFA_EHV_CPU0_VDD1      B @S9S_MB_2U_LIB.S9S_MB_2U(SCH_1):PVCCFA_EHV_CPU0_VDD1

Q_CAP_C0402-100NF,50V,10%,X7R,A  I20  PC178
   1 SW_PVCCFA_EHV_CPU0_BOOT1_R      A @S9S_MB_2U_LIB.S9S_MB_2U(SCH_1):SW_PVCCFA_EHV_CPU0_BOOT1_R
   2 SW_PVCCFA_EHV_CPU0_BOOTR1      B @S9S_MB_2U_LIB.S9S_MB_2U(SCH_1):SW_PVCCFA_EHV_CPU0_BOOTR1

Q_RES_0402LF-0,5%,1/16W,EMPTY,A  I22  PR443
   1   P3V3      A @S9S_MB_2U_LIB.S9S_MB_2U(SCH_1):P3V3
   2 PVCCFA_EHV_CPU0_PVCC      B @S9S_MB_2U_LIB.S9S_MB_2U(SCH_1):PVCCFA_EHV_CPU0_PVCC


DRAWING: @S9S_MB_2U_LIB.S9S_MB_2U(SCH_1):PAGE264 

Q_RES_0402LF-0,5%,1/16W,CHIP,CA  I38  R2403
   1 SMB_VR_3V3AUX_SDA_R2      A @S9S_MB_2U_LIB.S9S_MB_2U(SCH_1):SMB_VR_3V3AUX_SDA_R2
   2 SMB_DIO_PVCCD_HV_CPU0      B @S9S_MB_2U_LIB.S9S_MB_2U(SCH_1):SMB_DIO_PVCCD_HV_CPU0

Q_RES_0402LF-0,5%,1/16W,CHIP,CA  I45  R363
   1 FM_PVCCD_HV_CPU0_EN      A @S9S_MB_2U_LIB.S9S_MB_2U(SCH_1):FM_PVCCD_HV_CPU0_EN
   2 PVCCD_HV_CPU0_EN_R      B @S9S_MB_2U_LIB.S9S_MB_2U(SCH_1):PVCCD_HV_CPU0_EN_R

Q_RES_0402LF-1K,1%,1/16W,CHIP,A  I46  R361
   1 P3V3_AUX      A @S9S_MB_2U_LIB.S9S_MB_2U(SCH_1):P3V3_AUX
   2 PWRGD_PVCCD_HV_CPU0_R      B @S9S_MB_2U_LIB.S9S_MB_2U(SCH_1):PWRGD_PVCCD_HV_CPU0_R

Q_RES_0402LF-1K,1%,1/16W,EMPTYA  I48  PR373
   1 PVCCD_HV_CPU0_ISENSE_N      A @S9S_MB_2U_LIB.S9S_MB_2U(SCH_1):PVCCD_HV_CPU0_ISENSE_N
   2    GND      B @S9S_MB_2U_LIB.S9S_MB_2U(SCH_1):GND

Q_RES_0402LF-0,5%,1/16W,CHIP,CA  I60  R2405
   1 IRQ_PVCCD_CPU0_VRHOT_LVC3_R_N      A @S9S_MB_2U_LIB.S9S_MB_2U(SCH_1):IRQ_PVCCD_CPU0_VRHOT_LVC3_R_N
   2 IRQ_PVCCD_CPU0_VRHOT_LVC3_N      B @S9S_MB_2U_LIB.S9S_MB_2U(SCH_1):IRQ_PVCCD_CPU0_VRHOT_LVC3_N

Q_CAP_C0402-100NF,50V,10%,EMPTA  I72  PC629
   1 PVCCD_HV_CPU0_VCC      A @S9S_MB_2U_LIB.S9S_MB_2U(SCH_1):PVCCD_HV_CPU0_VCC
   2    GND      B @S9S_MB_2U_LIB.S9S_MB_2U(SCH_1):GND

Q_CAP_0402-1000PF,50V,5%,EMPTYA  I47  C626
   1 PWRGD_PVCCD_HV_CPU0_R      A @S9S_MB_2U_LIB.S9S_MB_2U(SCH_1):PWRGD_PVCCD_HV_CPU0_R
   2    GND      B @S9S_MB_2U_LIB.S9S_MB_2U(SCH_1):GND

Q_CAP_0402-0.1UF,25V,10%,X7R,CA  I50  PC628
   1 PVCCD_HV_CPU0_ISENSE_N      A @S9S_MB_2U_LIB.S9S_MB_2U(SCH_1):PVCCD_HV_CPU0_ISENSE_N
   2    GND      B @S9S_MB_2U_LIB.S9S_MB_2U(SCH_1):GND

ISL69260IRAZT-ISL69260IRAZ-T,SA  I53  PU35
  23 PVCCD_HV_CPU0_ACSP1    CS7 @S9S_MB_2U_LIB.S9S_MB_2U(SCH_1):PVCCD_HV_CPU0_ACSP1
  39 PVCCD_HV_CPU0_VCC    VCC @S9S_MB_2U_LIB.S9S_MB_2U(SCH_1):PVCCD_HV_CPU0_VCC
  20    GND    EN1 @S9S_MB_2U_LIB.S9S_MB_2U(SCH_1):GND
  10 SMB_CLK_PVCCD_HV_CPU0  PMSCL @S9S_MB_2U_LIB.S9S_MB_2U(SCH_1):SMB_CLK_PVCCD_HV_CPU0
  18 SVID_DIO_PVCCD_HV_CPU0_R SVDATA @S9S_MB_2U_LIB.S9S_MB_2U(SCH_1):SVID_DIO_PVCCD_HV_CPU0_R
  24 NC_PVCCD_HV_CPU0_ACSP2    CS6 @S9S_MB_2U_LIB.S9S_MB_2U(SCH_1):NC_PVCCD_HV_CPU0_ACSP2
  19 SVID_ALERT_PVCCD_HV_CPU0_R NSVALERT# @S9S_MB_2U_LIB.S9S_MB_2U(SCH_1):SVID_ALERT_PVCCD_HV_CPU0_R
  14 IRQ_PVCCD_CPU0_VRHOT_LVC3_R_N NVRHOT# @S9S_MB_2U_LIB.S9S_MB_2U(SCH_1):IRQ_PVCCD_CPU0_VRHOT_LVC3_R_N
  25 NC_PVCCD_HV_CPU0_ACSP3    CS5 @S9S_MB_2U_LIB.S9S_MB_2U(SCH_1):NC_PVCCD_HV_CPU0_ACSP3
  26 NC_PVCCD_HV_CPU0_ACSP4    CS4 @S9S_MB_2U_LIB.S9S_MB_2U(SCH_1):NC_PVCCD_HV_CPU0_ACSP4
  16 NC_PVCCD_HV_CPU0_BVR_RDY    PG1 @S9S_MB_2U_LIB.S9S_MB_2U(SCH_1):NC_PVCCD_HV_CPU0_BVR_RDY
  17 SVID_CLK_PVCCD_HV_CPU0_R  SVCLK @S9S_MB_2U_LIB.S9S_MB_2U(SCH_1):SVID_CLK_PVCCD_HV_CPU0_R
  11 NC_PVCCD_HV_CPU0_SMB_ALERT NPMALERT# @S9S_MB_2U_LIB.S9S_MB_2U(SCH_1):NC_PVCCD_HV_CPU0_SMB_ALERT
  13 PVCCD_HV_CPU0_EN_R    EN0 @S9S_MB_2U_LIB.S9S_MB_2U(SCH_1):PVCCD_HV_CPU0_EN_R
  22 VSENSE_PVCCD_HV_CPU0_DN  RGND0 @S9S_MB_2U_LIB.S9S_MB_2U(SCH_1):VSENSE_PVCCD_HV_CPU0_DN
   9 SMB_DIO_PVCCD_HV_CPU0  PMSDA @S9S_MB_2U_LIB.S9S_MB_2U(SCH_1):SMB_DIO_PVCCD_HV_CPU0
   5 NC_PVCCD_HV_CPU0_APWM4   PWM4 @S9S_MB_2U_LIB.S9S_MB_2U(SCH_1):NC_PVCCD_HV_CPU0_APWM4
   6 NC_PVCCD_HV_CPU0_APWM3   PWM5 @S9S_MB_2U_LIB.S9S_MB_2U(SCH_1):NC_PVCCD_HV_CPU0_APWM3
  21 SH_PVCCD_HV_CPU0_R  VSEN0 @S9S_MB_2U_LIB.S9S_MB_2U(SCH_1):SH_PVCCD_HV_CPU0_R
   2 NC_PVCCD_HV_CPU0_APWM7   PWM1 @S9S_MB_2U_LIB.S9S_MB_2U(SCH_1):NC_PVCCD_HV_CPU0_APWM7
  12 PWRGD_PVCCD_HV_CPU0_R    PG0 @S9S_MB_2U_LIB.S9S_MB_2U(SCH_1):PWRGD_PVCCD_HV_CPU0_R
   7 NC_PVCCD_HV_CPU0_APWM2   PWM6 @S9S_MB_2U_LIB.S9S_MB_2U(SCH_1):NC_PVCCD_HV_CPU0_APWM2
  40 PVCCD_HV_CPU0_VREF   VCCS @S9S_MB_2U_LIB.S9S_MB_2U(SCH_1):PVCCD_HV_CPU0_VREF
  37 PVCCD_HV_CPU0_ISENSE_P VMON||IINSEN||VSYS||ISYS @S9S_MB_2U_LIB.S9S_MB_2U(SCH_1):PVCCD_HV_CPU0_ISENSE_P
  38 PVCCD_HV_CPU0_ISENSE_N VINSEN||VSYS @S9S_MB_2U_LIB.S9S_MB_2U(SCH_1):PVCCD_HV_CPU0_ISENSE_N
  36 PVCCD_HV_CPU0_ISYS_R TEMP1||ISYS @S9S_MB_2U_LIB.S9S_MB_2U(SCH_1):PVCCD_HV_CPU0_ISYS_R
  15 PVCCD_HV_CPU0_PIN_ALT NPINALERT#||NPSYSCRIT# @S9S_MB_2U_LIB.S9S_MB_2U(SCH_1):PVCCD_HV_CPU0_PIN_ALT
  32    GND  VSEN1 @S9S_MB_2U_LIB.S9S_MB_2U(SCH_1):GND
  31    GND  RGND1 @S9S_MB_2U_LIB.S9S_MB_2U(SCH_1):GND
  29 NC_PVCCD_HV_CPU0_ACSP7    CS1 @S9S_MB_2U_LIB.S9S_MB_2U(SCH_1):NC_PVCCD_HV_CPU0_ACSP7
   8 PVCCD_HV_CPU0_APWM1   PWM7 @S9S_MB_2U_LIB.S9S_MB_2U(SCH_1):PVCCD_HV_CPU0_APWM1
   4 NC_PVCCD_HV_CPU0_APWM5   PWM3 @S9S_MB_2U_LIB.S9S_MB_2U(SCH_1):NC_PVCCD_HV_CPU0_APWM5
  27 NC_PVCCD_HV_CPU0_ACSP5    CS3 @S9S_MB_2U_LIB.S9S_MB_2U(SCH_1):NC_PVCCD_HV_CPU0_ACSP5
   3 NC_PVCCD_HV_CPU0_APWM6   PWM2 @S9S_MB_2U_LIB.S9S_MB_2U(SCH_1):NC_PVCCD_HV_CPU0_APWM6
  28 NC_PVCCD_HV_CPU0_ACSP6    CS2 @S9S_MB_2U_LIB.S9S_MB_2U(SCH_1):NC_PVCCD_HV_CPU0_ACSP6
  33 PVCCD_HV_CPU0_FAULT    CFP @S9S_MB_2U_LIB.S9S_MB_2U(SCH_1):PVCCD_HV_CPU0_FAULT
  TH    GND TH_GND @S9S_MB_2U_LIB.S9S_MB_2U(SCH_1):GND
  34 PVCCD_HV_CPU0_ADDR ADDR_CFG @S9S_MB_2U_LIB.S9S_MB_2U(SCH_1):PVCCD_HV_CPU0_ADDR
  35 PVCCD_HV_CPU0_ATSEN  TEMP0 @S9S_MB_2U_LIB.S9S_MB_2U(SCH_1):PVCCD_HV_CPU0_ATSEN
   1 NC_PVCCD_HV_CPU0_APWM8   PWM0 @S9S_MB_2U_LIB.S9S_MB_2U(SCH_1):NC_PVCCD_HV_CPU0_APWM8
  30 NC_PVCCD_HV_CPU0_ACSP8    CS0 @S9S_MB_2U_LIB.S9S_MB_2U(SCH_1):NC_PVCCD_HV_CPU0_ACSP8

Q_RES_0402LF-0,5%,1/16W,CHIP,CA  I61  PR4236
   1 NC_PVCCD_HV_CPU0_ACSP8      A @S9S_MB_2U_LIB.S9S_MB_2U(SCH_1):NC_PVCCD_HV_CPU0_ACSP8
   2    GND      B @S9S_MB_2U_LIB.S9S_MB_2U(SCH_1):GND

Q_RES_0402LF-0,5%,1/16W,CHIP,CA  I62  PR4235
   1 NC_PVCCD_HV_CPU0_ACSP7      A @S9S_MB_2U_LIB.S9S_MB_2U(SCH_1):NC_PVCCD_HV_CPU0_ACSP7
   2    GND      B @S9S_MB_2U_LIB.S9S_MB_2U(SCH_1):GND

Q_RES_0402LF-1K,1%,1/16W,CHIP,A  I14  PR372
   1 P3V3_AUX      A @S9S_MB_2U_LIB.S9S_MB_2U(SCH_1):P3V3_AUX
   2 PVCCD_HV_CPU0_FAULT      B @S9S_MB_2U_LIB.S9S_MB_2U(SCH_1):PVCCD_HV_CPU0_FAULT

Q_RES_0402LF-49.9,1%,1/16W,CHIA  I25  R1717
   1 PVNN_TERM_CPU0      A @S9S_MB_2U_LIB.S9S_MB_2U(SCH_1):PVNN_TERM_CPU0
   2 SVID_CLK1_CPU0_R      B @S9S_MB_2U_LIB.S9S_MB_2U(SCH_1):SVID_CLK1_CPU0_R

Q_RES_0402LF-100,1%,1/16W,CHIPA  I30  PR591
   1 VSENSE_PVCCD_HV_CPU0_DN      A @S9S_MB_2U_LIB.S9S_MB_2U(SCH_1):VSENSE_PVCCD_HV_CPU0_DN
   2    GND      B @S9S_MB_2U_LIB.S9S_MB_2U(SCH_1):GND

Q_SHORT_SM-EMPTY,SHORT6  I32  PJ54
   1 VSENSE_PVCCD_HV_CPU0_DP      1 @S9S_MB_2U_LIB.S9S_MB_2U(SCH_1):VSENSE_PVCCD_HV_CPU0_DP
   2 SH_PVCCD_HV_CPU0      2 @S9S_MB_2U_LIB.S9S_MB_2U(SCH_1):SH_PVCCD_HV_CPU0

Q_RES_0402LF-0,5%,1/16W,CHIP,CA  I39  R2402
   1 SMB_VR_3V3AUX_SCL_R2      A @S9S_MB_2U_LIB.S9S_MB_2U(SCH_1):SMB_VR_3V3AUX_SCL_R2
   2 SMB_CLK_PVCCD_HV_CPU0      B @S9S_MB_2U_LIB.S9S_MB_2U(SCH_1):SMB_CLK_PVCCD_HV_CPU0

Q_RES_0402LF-10K,1%,1/16W,EMPTA  I57  PR634
   1 PVCCD_HV_CPU0_ATSEN      A @S9S_MB_2U_LIB.S9S_MB_2U(SCH_1):PVCCD_HV_CPU0_ATSEN
   2    GND      B @S9S_MB_2U_LIB.S9S_MB_2U(SCH_1):GND

Q_RES_0402LF-0,5%,1/16W,CHIP,CA  I59  PR1311
   1 PVCCD_HV_CPU0_ISYS_R      A @S9S_MB_2U_LIB.S9S_MB_2U(SCH_1):PVCCD_HV_CPU0_ISYS_R
   2    GND      B @S9S_MB_2U_LIB.S9S_MB_2U(SCH_1):GND

Q_RES_0402LF-100,1%,1/16W,CHIPA  I31  PR592
   1 VSENSE_PVCCD_HV_CPU0_DP      A @S9S_MB_2U_LIB.S9S_MB_2U(SCH_1):VSENSE_PVCCD_HV_CPU0_DP
   2 PVCCD_HV_CPU0      B @S9S_MB_2U_LIB.S9S_MB_2U(SCH_1):PVCCD_HV_CPU0

Q_RES_0402LF-0,5%,1/16W,CHIP,CA  I40  R2401
   1 SVID_ALERT1_CPU0_R_N      A @S9S_MB_2U_LIB.S9S_MB_2U(SCH_1):SVID_ALERT1_CPU0_R_N
   2 SVID_ALERT_PVCCD_HV_CPU0_R      B @S9S_MB_2U_LIB.S9S_MB_2U(SCH_1):SVID_ALERT_PVCCD_HV_CPU0_R

Q_RES_0402LF-0,5%,1/16W,CHIP,CA  I42  R2400
   1 SVID_DIO1_CPU0_R      A @S9S_MB_2U_LIB.S9S_MB_2U(SCH_1):SVID_DIO1_CPU0_R
   2 SVID_DIO_PVCCD_HV_CPU0_R      B @S9S_MB_2U_LIB.S9S_MB_2U(SCH_1):SVID_DIO_PVCCD_HV_CPU0_R

Q_RES_0402LF-0,5%,1/16W,EMPTY,A  I63  PR409
   1 PVCCD_HV_CPU0_ISYS_R      A @S9S_MB_2U_LIB.S9S_MB_2U(SCH_1):PVCCD_HV_CPU0_ISYS_R
   2 PVCCD_HV_CPU0_NVDIMM_ISENSE      B @S9S_MB_2U_LIB.S9S_MB_2U(SCH_1):PVCCD_HV_CPU0_NVDIMM_ISENSE

Q_RES_0402LF-0,5%,1/16W,CHIP,CA  I66  PR4234
   1 NC_PVCCD_HV_CPU0_ACSP6      A @S9S_MB_2U_LIB.S9S_MB_2U(SCH_1):NC_PVCCD_HV_CPU0_ACSP6
   2    GND      B @S9S_MB_2U_LIB.S9S_MB_2U(SCH_1):GND

Q_RES_0402LF-0,5%,1/16W,CHIP,CA  I67  PR4233
   1 NC_PVCCD_HV_CPU0_ACSP5      A @S9S_MB_2U_LIB.S9S_MB_2U(SCH_1):NC_PVCCD_HV_CPU0_ACSP5
   2    GND      B @S9S_MB_2U_LIB.S9S_MB_2U(SCH_1):GND

Q_RES_0402LF-0,5%,1/16W,CHIP,CA  I68  PR4232
   1 NC_PVCCD_HV_CPU0_ACSP4      A @S9S_MB_2U_LIB.S9S_MB_2U(SCH_1):NC_PVCCD_HV_CPU0_ACSP4
   2    GND      B @S9S_MB_2U_LIB.S9S_MB_2U(SCH_1):GND

Q_RES_0402LF-1K,1%,1/16W,CHIP,A  I85  R2404
   1 P3V3_AUX      A @S9S_MB_2U_LIB.S9S_MB_2U(SCH_1):P3V3_AUX
   2 IRQ_PVCCD_CPU0_VRHOT_LVC3_N      B @S9S_MB_2U_LIB.S9S_MB_2U(SCH_1):IRQ_PVCCD_CPU0_VRHOT_LVC3_N

Q_RES_0402LF-28K,1%,1/16W,EMPTA  I5  PR357
   1 PVCCD_HV_CPU0_VREF      A @S9S_MB_2U_LIB.S9S_MB_2U(SCH_1):PVCCD_HV_CPU0_VREF
   2 PVCCD_HV_CPU0_ADDR      B @S9S_MB_2U_LIB.S9S_MB_2U(SCH_1):PVCCD_HV_CPU0_ADDR

Q_RES_0402LF-1K,1%,1/16W,EMPTYA  I7  PR369
   1 PVCCD_HV_CPU0_ISENSE_P      A @S9S_MB_2U_LIB.S9S_MB_2U(SCH_1):PVCCD_HV_CPU0_ISENSE_P
   2    GND      B @S9S_MB_2U_LIB.S9S_MB_2U(SCH_1):GND

Q_CAP_0402-0.1UF,25V,10%,X7R,CA  I9  PC624
   1 PVCCD_HV_CPU0_ISENSE_P      A @S9S_MB_2U_LIB.S9S_MB_2U(SCH_1):PVCCD_HV_CPU0_ISENSE_P
   2    GND      B @S9S_MB_2U_LIB.S9S_MB_2U(SCH_1):GND

Q_RES_0402LF-49.9,1%,1/16W,CHIA  I10  PR1390
   1 P12V_AUX_CPU0_DIMM_ISEN_N      A @S9S_MB_2U_LIB.S9S_MB_2U(SCH_1):P12V_AUX_CPU0_DIMM_ISEN_N
   2 PVCCD_HV_CPU0_ISENSE_N      B @S9S_MB_2U_LIB.S9S_MB_2U(SCH_1):PVCCD_HV_CPU0_ISENSE_N

Q_RES_0402LF-49.9,1%,1/16W,CHIA  I11  PR1380
   1 P12V_AUX_CPU0_DIMM_ISEN_P      A @S9S_MB_2U_LIB.S9S_MB_2U(SCH_1):P12V_AUX_CPU0_DIMM_ISEN_P
   2 PVCCD_HV_CPU0_ISENSE_P      B @S9S_MB_2U_LIB.S9S_MB_2U(SCH_1):PVCCD_HV_CPU0_ISENSE_P

Q_RES_0402LF-1K,1%,1/16W,CHIP,A  I13  PR370
   1 P3V3_AUX      A @S9S_MB_2U_LIB.S9S_MB_2U(SCH_1):P3V3_AUX
   2 PVCCD_HV_CPU0_PIN_ALT      B @S9S_MB_2U_LIB.S9S_MB_2U(SCH_1):PVCCD_HV_CPU0_PIN_ALT

Q_CAP_C0402-10UF,6.3V,20%,X6S,B  I18  C2443
   1 PVNN_TERM_CPU0      A @S9S_MB_2U_LIB.S9S_MB_2U(SCH_1):PVNN_TERM_CPU0
   2    GND      B @S9S_MB_2U_LIB.S9S_MB_2U(SCH_1):GND

Q_CAP_0402-0.1UF,25V,10%,X7R,CA  I19  C2444
   1 PVNN_TERM_CPU0      A @S9S_MB_2U_LIB.S9S_MB_2U(SCH_1):PVNN_TERM_CPU0
   2    GND      B @S9S_MB_2U_LIB.S9S_MB_2U(SCH_1):GND

Q_RES_0402LF-100,1%,1/16W,CHIPA  I24  R1735
   1 PVNN_TERM_CPU0      A @S9S_MB_2U_LIB.S9S_MB_2U(SCH_1):PVNN_TERM_CPU0
   2 SVID_DIO1_CPU0_R      B @S9S_MB_2U_LIB.S9S_MB_2U(SCH_1):SVID_DIO1_CPU0_R

Q_RES_0402LF-0,5%,1/16W,CHIP,CA  I36  PR371
   1 SH_PVCCD_HV_CPU0      A @S9S_MB_2U_LIB.S9S_MB_2U(SCH_1):SH_PVCCD_HV_CPU0
   2 SH_PVCCD_HV_CPU0_R      B @S9S_MB_2U_LIB.S9S_MB_2U(SCH_1):SH_PVCCD_HV_CPU0_R

Q_CAP_0402-3300PF,50V,10%,X7R,A  I37  PC627
   1 SH_PVCCD_HV_CPU0_R      A @S9S_MB_2U_LIB.S9S_MB_2U(SCH_1):SH_PVCCD_HV_CPU0_R
   2 VSENSE_PVCCD_HV_CPU0_DN      B @S9S_MB_2U_LIB.S9S_MB_2U(SCH_1):VSENSE_PVCCD_HV_CPU0_DN

Q_RES_0402LF-150,1%,1/16W,CHIPA  I43  R2399
   1 SVID_CLK1_CPU0_R      A @S9S_MB_2U_LIB.S9S_MB_2U(SCH_1):SVID_CLK1_CPU0_R
   2 SVID_CLK_PVCCD_HV_CPU0_R      B @S9S_MB_2U_LIB.S9S_MB_2U(SCH_1):SVID_CLK_PVCCD_HV_CPU0_R

Q_RES_0402LF-0,5%,1/16W,CHIP,CA  I44  R362
   1 PWRGD_PVCCD_HV_CPU0      A @S9S_MB_2U_LIB.S9S_MB_2U(SCH_1):PWRGD_PVCCD_HV_CPU0
   2 PWRGD_PVCCD_HV_CPU0_R      B @S9S_MB_2U_LIB.S9S_MB_2U(SCH_1):PWRGD_PVCCD_HV_CPU0_R

Q_CAP_C0402-1UF,16V,10%,X6S,CHA  I51  PC813
   1 PVCCD_HV_CPU0_ISENSE_N      A @S9S_MB_2U_LIB.S9S_MB_2U(SCH_1):PVCCD_HV_CPU0_ISENSE_N
   2 PVCCD_HV_CPU0_ISENSE_P      B @S9S_MB_2U_LIB.S9S_MB_2U(SCH_1):PVCCD_HV_CPU0_ISENSE_P

Q_CAP_0402-470PF,50V,10%,X7R,TA  I56  PC631
   1 PVCCD_HV_CPU0_ATSEN      A @S9S_MB_2U_LIB.S9S_MB_2U(SCH_1):PVCCD_HV_CPU0_ATSEN
   2    GND      B @S9S_MB_2U_LIB.S9S_MB_2U(SCH_1):GND

Q_RES_0402LF-0,5%,1/16W,CHIP,CA  I69  PR4231
   1 NC_PVCCD_HV_CPU0_ACSP3      A @S9S_MB_2U_LIB.S9S_MB_2U(SCH_1):NC_PVCCD_HV_CPU0_ACSP3
   2    GND      B @S9S_MB_2U_LIB.S9S_MB_2U(SCH_1):GND

Q_CAP_C0402-10UF,6.3V,20%,X6S,B  I70  PC630
   1 PVCCD_HV_CPU0_VREF      A @S9S_MB_2U_LIB.S9S_MB_2U(SCH_1):PVCCD_HV_CPU0_VREF
   2    GND      B @S9S_MB_2U_LIB.S9S_MB_2U(SCH_1):GND

Q_CAP_C0402-1UF,16V,10%,X6S,CHA  I71  PC1196
   1 PVCCD_HV_CPU0_VREF      A @S9S_MB_2U_LIB.S9S_MB_2U(SCH_1):PVCCD_HV_CPU0_VREF
   2    GND      B @S9S_MB_2U_LIB.S9S_MB_2U(SCH_1):GND

Q_CAP_C0402-1UF,16V,10%,X6S,CHA  I73  PC632
   1 PVCCD_HV_CPU0_VCC      A @S9S_MB_2U_LIB.S9S_MB_2U(SCH_1):PVCCD_HV_CPU0_VCC
   2    GND      B @S9S_MB_2U_LIB.S9S_MB_2U(SCH_1):GND

Q_RES_0402LF-0,5%,1/16W,CHIP,CA  I74  PR4230
   1 NC_PVCCD_HV_CPU0_ACSP2      A @S9S_MB_2U_LIB.S9S_MB_2U(SCH_1):NC_PVCCD_HV_CPU0_ACSP2
   2    GND      B @S9S_MB_2U_LIB.S9S_MB_2U(SCH_1):GND

Q_RES_0402LF-1,1%,1/16W,CHIP,CA  I80  PR375
   1 PVCCD_HV_CPU0_VCC      A @S9S_MB_2U_LIB.S9S_MB_2U(SCH_1):PVCCD_HV_CPU0_VCC
   2 P3V3_AUX      B @S9S_MB_2U_LIB.S9S_MB_2U(SCH_1):P3V3_AUX

Q_RES_0402LF-3.57K,1%,1/16W,CHA  I95  PR358
   1    GND      A @S9S_MB_2U_LIB.S9S_MB_2U(SCH_1):GND
   2 PVCCD_HV_CPU0_ADDR      B @S9S_MB_2U_LIB.S9S_MB_2U(SCH_1):PVCCD_HV_CPU0_ADDR

Q_CAP_0402-0.1UF,25V,10%,EMPTYA  I96  PC2365
   1 PVCCD_HV_CPU0_VCC      A @S9S_MB_2U_LIB.S9S_MB_2U(SCH_1):PVCCD_HV_CPU0_VCC
   2    GND      B @S9S_MB_2U_LIB.S9S_MB_2U(SCH_1):GND


DRAWING: @S9S_MB_2U_LIB.S9S_MB_2U(SCH_1):PAGE267 

Q_CAP_0402-1000PF,50V,5%,EMPTYA  I12  C1300
   1 FM_PVPP_HBM_CPU0_EN      A @S9S_MB_2U_LIB.S9S_MB_2U(SCH_1):FM_PVPP_HBM_CPU0_EN
   2    GND      B @S9S_MB_2U_LIB.S9S_MB_2U(SCH_1):GND

Q_CAP_C0805-22UF,16V,20%,X6S,CA  I16  PC1248
   1 SW_P12V_PVCCIN_CPU0_FLT      A @S9S_MB_2U_LIB.S9S_MB_2U(SCH_1):SW_P12V_PVCCIN_CPU0_FLT
   2    GND      B @S9S_MB_2U_LIB.S9S_MB_2U(SCH_1):GND

Q_CAP_C0402-1UF,16V,10%,X6S,CHA  I17  PC1249
   1 SW_P12V_PVCCIN_CPU0_FLT      A @S9S_MB_2U_LIB.S9S_MB_2U(SCH_1):SW_P12V_PVCCIN_CPU0_FLT
   2    GND      B @S9S_MB_2U_LIB.S9S_MB_2U(SCH_1):GND

Q_RES_0402LF-30.1K,1%,1/16W,CHA  I18  PR3335
   1 PVPP_HBM_CPU0_MODE      A @S9S_MB_2U_LIB.S9S_MB_2U(SCH_1):PVPP_HBM_CPU0_MODE
   2    GND      B @S9S_MB_2U_LIB.S9S_MB_2U(SCH_1):GND

Q_CAP_C0402-0.22UF,25V,10%,X7RA  I27  PC1252
   1 SW_PVPP_HBM_CPU0_BST      A @S9S_MB_2U_LIB.S9S_MB_2U(SCH_1):SW_PVPP_HBM_CPU0_BST
   2 SW_PVPP_HBM_CPU0_SW      B @S9S_MB_2U_LIB.S9S_MB_2U(SCH_1):SW_PVPP_HBM_CPU0_SW

Q_RES_0402LF-26.1K,0.1%,1/16W,A  I34  PR2336
   1 PVPP_HBM_CPU0_FB      A @S9S_MB_2U_LIB.S9S_MB_2U(SCH_1):PVPP_HBM_CPU0_FB
   2 FM_HBM_VPP_SEL_CPU0_D      B @S9S_MB_2U_LIB.S9S_MB_2U(SCH_1):FM_HBM_VPP_SEL_CPU0_D

Q_CAP_0402-0.1UF,25V,10%,X7R,CA  I38  PC1254
   1 PVPP_HBM_CPU0      A @S9S_MB_2U_LIB.S9S_MB_2U(SCH_1):PVPP_HBM_CPU0
   2    GND      B @S9S_MB_2U_LIB.S9S_MB_2U(SCH_1):GND

Q_CAP_C0805-22UF,4V,20%,X6S,CHA  I42  PC1255
   1 PVPP_HBM_CPU0      A @S9S_MB_2U_LIB.S9S_MB_2U(SCH_1):PVPP_HBM_CPU0
   2    GND      B @S9S_MB_2U_LIB.S9S_MB_2U(SCH_1):GND

Q_CAP_C0402-1UF,25V,10%,X6S,CHA  I4  PC2643
   1 PVPP_HBM_CPU0_VCC      A @S9S_MB_2U_LIB.S9S_MB_2U(SCH_1):PVPP_HBM_CPU0_VCC
   2    GND      B @S9S_MB_2U_LIB.S9S_MB_2U(SCH_1):GND

Q_RES_0402LF-10K,1%,1/16W,EMPTA  I9  R2406
   1 P3V3_AUX      A @S9S_MB_2U_LIB.S9S_MB_2U(SCH_1):P3V3_AUX
   2 FM_PVPP_HBM_CPU0_EN      B @S9S_MB_2U_LIB.S9S_MB_2U(SCH_1):FM_PVPP_HBM_CPU0_EN

Q_RES_0402LF-11.3K,0.1%,1/16W,A  I26  PR1310
   1 PVPP_HBM_CPU0_FB      A @S9S_MB_2U_LIB.S9S_MB_2U(SCH_1):PVPP_HBM_CPU0_FB
   2 SH_PVPP_HBM_CPU0_N      B @S9S_MB_2U_LIB.S9S_MB_2U(SCH_1):SH_PVPP_HBM_CPU0_N

Q_CAP_0402-1000PF,50V,5%,X7R,TA  I30  C1301
   1 PWRGD_PVPP_HBM_CPU0_R      A @S9S_MB_2U_LIB.S9S_MB_2U(SCH_1):PWRGD_PVPP_HBM_CPU0_R
   2    GND      B @S9S_MB_2U_LIB.S9S_MB_2U(SCH_1):GND

Q_INDUCTOR_SMLF-0.68UH,IND,CV+A  I28  PL118
   2 PVPP_HBM_CPU0      2 @S9S_MB_2U_LIB.S9S_MB_2U(SCH_1):PVPP_HBM_CPU0
   1 SW_PVPP_HBM_CPU0_SW      1 @S9S_MB_2U_LIB.S9S_MB_2U(SCH_1):SW_PVPP_HBM_CPU0_SW

Q_RES_0402LF-38.3K,0.1%,1/16W,A  I36  PR1337
   1 PVPP_HBM_CPU0_FB      A @S9S_MB_2U_LIB.S9S_MB_2U(SCH_1):PVPP_HBM_CPU0_FB
   2 SH_PVPP_HBM_CPU0_P      B @S9S_MB_2U_LIB.S9S_MB_2U(SCH_1):SH_PVPP_HBM_CPU0_P

Q_CAPP_THLF-560UF,6.3V,20%,OSCA  I49  PC1258
   1 PVPP_HBM_CPU0      A @S9S_MB_2U_LIB.S9S_MB_2U(SCH_1):PVPP_HBM_CPU0
   2    GND      B @S9S_MB_2U_LIB.S9S_MB_2U(SCH_1):GND

Q_RES_0402LF-9.76K,1%,1/16W,CHA  I15  PR1336
   1 PVPP_HBM_CPU0_CS      A @S9S_MB_2U_LIB.S9S_MB_2U(SCH_1):PVPP_HBM_CPU0_CS
   2    GND      B @S9S_MB_2U_LIB.S9S_MB_2U(SCH_1):GND

Q_SHORT_SM-EMPTY,SHORT6  I33  PJ65
   1 SH_PVPP_HBM_CPU0_N      1 @S9S_MB_2U_LIB.S9S_MB_2U(SCH_1):SH_PVPP_HBM_CPU0_N
   2    GND      2 @S9S_MB_2U_LIB.S9S_MB_2U(SCH_1):GND

Q_RES_0402LF-10K,1%,1/16W,CHIPA  I45  R2407
   1 P3V3_AUX      A @S9S_MB_2U_LIB.S9S_MB_2U(SCH_1):P3V3_AUX
   2 PWRGD_PVPP_HBM_CPU0_R      B @S9S_MB_2U_LIB.S9S_MB_2U(SCH_1):PWRGD_PVPP_HBM_CPU0_R

Q_CAP_C0805-22UF,16V,20%,X6S,CA  I7  PC831
   1 SW_P12V_PVCCIN_CPU0_FLT      A @S9S_MB_2U_LIB.S9S_MB_2U(SCH_1):SW_P12V_PVCCIN_CPU0_FLT
   2    GND      B @S9S_MB_2U_LIB.S9S_MB_2U(SCH_1):GND

Q_CAP_0402-0.022UF,16V,10%,X7RA  I23  PC2001
   1 PVPP_HBM_CPU0_REF      A @S9S_MB_2U_LIB.S9S_MB_2U(SCH_1):PVPP_HBM_CPU0_REF
   2    GND      B @S9S_MB_2U_LIB.S9S_MB_2U(SCH_1):GND

MOSFET_N_SMLF-BSS138K,BSS138K,B  I31  PU173
   G FM_HBM2_HBM3_VPP_SEL   GATE @S9S_MB_2U_LIB.S9S_MB_2U(SCH_1):FM_HBM2_HBM3_VPP_SEL
   D FM_HBM_VPP_SEL_CPU0_D  DRAIN @S9S_MB_2U_LIB.S9S_MB_2U(SCH_1):FM_HBM_VPP_SEL_CPU0_D
   S SH_PVPP_HBM_CPU0_N SOURCE @S9S_MB_2U_LIB.S9S_MB_2U(SCH_1):SH_PVPP_HBM_CPU0_N

Q_CAP_C0402-680PF,50V,10%,X7R,A  I35  PC1253
   1 PVPP_HBM_CPU0_FB      A @S9S_MB_2U_LIB.S9S_MB_2U(SCH_1):PVPP_HBM_CPU0_FB
   2 SH_PVPP_HBM_CPU0_P      B @S9S_MB_2U_LIB.S9S_MB_2U(SCH_1):SH_PVPP_HBM_CPU0_P

Q_CAP_C0805-22UF,4V,20%,X6S,CHA  I43  PC1256
   1 PVPP_HBM_CPU0      A @S9S_MB_2U_LIB.S9S_MB_2U(SCH_1):PVPP_HBM_CPU0
   2    GND      B @S9S_MB_2U_LIB.S9S_MB_2U(SCH_1):GND

Q_RES_0402LF-0,5%,1/16W,CHIP,CA  I5  PR1335
   1 P3V3_AUX      A @S9S_MB_2U_LIB.S9S_MB_2U(SCH_1):P3V3_AUX
   2 PVPP_HBM_CPU0_VCC      B @S9S_MB_2U_LIB.S9S_MB_2U(SCH_1):PVPP_HBM_CPU0_VCC

Q_CAP_C0805-22UF,16V,20%,X6S,CA  I10  PC1247
   1 SW_P12V_PVCCIN_CPU0_FLT      A @S9S_MB_2U_LIB.S9S_MB_2U(SCH_1):SW_P12V_PVCCIN_CPU0_FLT
   2    GND      B @S9S_MB_2U_LIB.S9S_MB_2U(SCH_1):GND

Q_RES_0402LF-2K,1%,1/16W,CHIP,A  I14  R2332
   1 FM_PVPP_HBM_CPU0_EN      A @S9S_MB_2U_LIB.S9S_MB_2U(SCH_1):FM_PVPP_HBM_CPU0_EN
   2    GND      B @S9S_MB_2U_LIB.S9S_MB_2U(SCH_1):GND

RS53318LR-RS53318LR,SMLF,IC,ALA  I19  PU79
  10 SW_P12V_PVCCIN_CPU0_FLT   VIN1 @S9S_MB_2U_LIB.S9S_MB_2U(SCH_1):SW_P12V_PVCCIN_CPU0_FLT
   9 PWRGD_PVPP_HBM_CPU0_R  PGOOD @S9S_MB_2U_LIB.S9S_MB_2U(SCH_1):PWRGD_PVPP_HBM_CPU0_R
11_18    GND   PGND @S9S_MB_2U_LIB.S9S_MB_2U(SCH_1):GND
   8 FM_PVPP_HBM_CPU0_EN     EN @S9S_MB_2U_LIB.S9S_MB_2U(SCH_1):FM_PVPP_HBM_CPU0_EN
   1 SW_PVPP_HBM_CPU0_BST    BST @S9S_MB_2U_LIB.S9S_MB_2U(SCH_1):SW_PVPP_HBM_CPU0_BST
   7 PVPP_HBM_CPU0_FB     FB @S9S_MB_2U_LIB.S9S_MB_2U(SCH_1):PVPP_HBM_CPU0_FB
   2    GND   AGND @S9S_MB_2U_LIB.S9S_MB_2U(SCH_1):GND
  19 PVPP_HBM_CPU0_VCC    VCC @S9S_MB_2U_LIB.S9S_MB_2U(SCH_1):PVPP_HBM_CPU0_VCC
   6 SH_PVPP_HBM_CPU0_N    RTN @S9S_MB_2U_LIB.S9S_MB_2U(SCH_1):SH_PVPP_HBM_CPU0_N
  20 SW_PVPP_HBM_CPU0_SW     SW @S9S_MB_2U_LIB.S9S_MB_2U(SCH_1):SW_PVPP_HBM_CPU0_SW
   5 PVPP_HBM_CPU0_REF    REF @S9S_MB_2U_LIB.S9S_MB_2U(SCH_1):PVPP_HBM_CPU0_REF
   4 PVPP_HBM_CPU0_MODE   MODE @S9S_MB_2U_LIB.S9S_MB_2U(SCH_1):PVPP_HBM_CPU0_MODE
   3 PVPP_HBM_CPU0_CS     CS @S9S_MB_2U_LIB.S9S_MB_2U(SCH_1):PVPP_HBM_CPU0_CS
  21 SW_P12V_PVCCIN_CPU0_FLT   VIN2 @S9S_MB_2U_LIB.S9S_MB_2U(SCH_1):SW_P12V_PVCCIN_CPU0_FLT

Q_CAP_0402-0.1UF,25V,10%,X7R,CA  I25  PC1251
   1 PVPP_HBM_CPU0_REF      A @S9S_MB_2U_LIB.S9S_MB_2U(SCH_1):PVPP_HBM_CPU0_REF
   2 SH_PVPP_HBM_CPU0_N      B @S9S_MB_2U_LIB.S9S_MB_2U(SCH_1):SH_PVPP_HBM_CPU0_N

Q_RES_0402LF-0,5%,1/16W,CHIP,CA  I29  R2408
   1 PWRGD_PVPP_HBM_CPU0_R      A @S9S_MB_2U_LIB.S9S_MB_2U(SCH_1):PWRGD_PVPP_HBM_CPU0_R
   2 PWRGD_PVPP_HBM_CPU0      B @S9S_MB_2U_LIB.S9S_MB_2U(SCH_1):PWRGD_PVPP_HBM_CPU0

Q_CAP_0402-0.01UF,25V,10%,X7R,A  I40  PC1421
   1 SH_PVPP_HBM_CPU0_P      A @S9S_MB_2U_LIB.S9S_MB_2U(SCH_1):SH_PVPP_HBM_CPU0_P
   2 SH_PVPP_HBM_CPU0_N      B @S9S_MB_2U_LIB.S9S_MB_2U(SCH_1):SH_PVPP_HBM_CPU0_N

Q_SHORT_SM-EMPTY,SHORT6  I41  PJ64
   1 SH_PVPP_HBM_CPU0_P      1 @S9S_MB_2U_LIB.S9S_MB_2U(SCH_1):SH_PVPP_HBM_CPU0_P
   2 PVPP_HBM_CPU0      2 @S9S_MB_2U_LIB.S9S_MB_2U(SCH_1):PVPP_HBM_CPU0

Q_CAP_C0805-22UF,4V,20%,X6S,CHA  I44  PC1257
   1 PVPP_HBM_CPU0      A @S9S_MB_2U_LIB.S9S_MB_2U(SCH_1):PVPP_HBM_CPU0
   2    GND      B @S9S_MB_2U_LIB.S9S_MB_2U(SCH_1):GND


DRAWING: @S9S_MB_2U_LIB.S9S_MB_2U(SCH_1):PAGE271 

Q_CAP_C0805-22UF,16V,20%,X6S,CA  I22  PC566_P1_2
   1 SW_P12V_PVCCIN_CPU1_FLT      A @S9S_MB_2U_LIB.S9S_MB_2U(SCH_1):SW_P12V_PVCCIN_CPU1_FLT
   2    GND      B @S9S_MB_2U_LIB.S9S_MB_2U(SCH_1):GND

Q_RES_0402LF-8.87K,1%,1/16W,EMA  I29  PR326
   1 PVCCIN_CPU1_LSET1      A @S9S_MB_2U_LIB.S9S_MB_2U(SCH_1):PVCCIN_CPU1_LSET1
   2    GND      B @S9S_MB_2U_LIB.S9S_MB_2U(SCH_1):GND

Q_RES_0402LF-3.3,1%,1/16W,CHIPA  I46  PR1767
   1 SW_PVCCIN_CPU1_BOOT1      A @S9S_MB_2U_LIB.S9S_MB_2U(SCH_1):SW_PVCCIN_CPU1_BOOT1
   2 SW_PVCCIN_CPU1_BOOT1_R      B @S9S_MB_2U_LIB.S9S_MB_2U(SCH_1):SW_PVCCIN_CPU1_BOOT1_R

Q_CAPP_SMLF-330UF,2.5V,+10/-35A  I61  PC1990
   1 PVCCIN_CPU1      A @S9S_MB_2U_LIB.S9S_MB_2U(SCH_1):PVCCIN_CPU1
   2    GND      B @S9S_MB_2U_LIB.S9S_MB_2U(SCH_1):GND

Q_CAPP_SMLF-330UF,2.5V,+10/-35A  I65  PC587
   1 PVCCIN_CPU1      A @S9S_MB_2U_LIB.S9S_MB_2U(SCH_1):PVCCIN_CPU1
   2    GND      B @S9S_MB_2U_LIB.S9S_MB_2U(SCH_1):GND

Q_CAPP_THLF-560UF,2.5V,20%,OSCA  I69  PC586
   1 PVCCIN_CPU1      A @S9S_MB_2U_LIB.S9S_MB_2U(SCH_1):PVCCIN_CPU1
   2    GND      B @S9S_MB_2U_LIB.S9S_MB_2U(SCH_1):GND

Q_INDUCTOR4P_14-150NH,SMLF,INDA  I74  PL31
   2 IND_P1_CPL1      2 @S9S_MB_2U_LIB.S9S_MB_2U(SCH_1):IND_P1_CPL1
   3 IND_P1_CPL6      3 @S9S_MB_2U_LIB.S9S_MB_2U(SCH_1):IND_P1_CPL6
   4 PVCCIN_CPU1      4 @S9S_MB_2U_LIB.S9S_MB_2U(SCH_1):PVCCIN_CPU1
   1 SW_PVCCIN_CPU1_SW1      1 @S9S_MB_2U_LIB.S9S_MB_2U(SCH_1):SW_PVCCIN_CPU1_SW1

Q_CAP_C0402-100NF,50V,10%,X7R,A  I79  PC1656
   1 P12V_AUX      A @S9S_MB_2U_LIB.S9S_MB_2U(SCH_1):P12V_AUX
   2    GND      B @S9S_MB_2U_LIB.S9S_MB_2U(SCH_1):GND

Q_INDUCTOR_SMLF-50NH/148A,IND,A  I83  PL32
   2 SW_P12V_PVCCIN_CPU1_FLT      2 @S9S_MB_2U_LIB.S9S_MB_2U(SCH_1):SW_P12V_PVCCIN_CPU1_FLT
   1 P12V_AUX      1 @S9S_MB_2U_LIB.S9S_MB_2U(SCH_1):P12V_AUX

Q_CAP_C0402-100NF,50V,10%,X7R,A  I84  PC572_P1_1
   1 PVCCIN_CPU1      A @S9S_MB_2U_LIB.S9S_MB_2U(SCH_1):PVCCIN_CPU1
   2    GND      B @S9S_MB_2U_LIB.S9S_MB_2U(SCH_1):GND

Q_RES_0402LF-8.87K,1%,1/16W,EMA  I3  PR325
   1 PVCCIN_CPU1_LSET2      A @S9S_MB_2U_LIB.S9S_MB_2U(SCH_1):PVCCIN_CPU1_LSET2
   2    GND      B @S9S_MB_2U_LIB.S9S_MB_2U(SCH_1):GND

Q_CAP_0402-0.1UF,25V,10%,X7R,CA  I6  PC1338
   1    GND      A @S9S_MB_2U_LIB.S9S_MB_2U(SCH_1):GND
   2 PVCCIN_CPU1_VREF      B @S9S_MB_2U_LIB.S9S_MB_2U(SCH_1):PVCCIN_CPU1_VREF

Q_CAP_C0402-2.2UF,10V,10%,X6S,A  I11  PC556
   1 PVCCIN_CPU1_VDD2      A @S9S_MB_2U_LIB.S9S_MB_2U(SCH_1):PVCCIN_CPU1_VDD2
   2    GND      B @S9S_MB_2U_LIB.S9S_MB_2U(SCH_1):GND

Q_CAP_C0402-100NF,50V,10%,X7R,A  I23  PC564
   1 SW_PVCCIN_CPU1_BOOT2_R      A @S9S_MB_2U_LIB.S9S_MB_2U(SCH_1):SW_PVCCIN_CPU1_BOOT2_R
   2 SW_PVCCIN_CPU1_BOOTR2      B @S9S_MB_2U_LIB.S9S_MB_2U(SCH_1):SW_PVCCIN_CPU1_BOOTR2

Q_CAP_C0805-22UF,16V,20%,X6S,CA  I24  PC568_P1_2
   1 SW_P12V_PVCCIN_CPU1_FLT      A @S9S_MB_2U_LIB.S9S_MB_2U(SCH_1):SW_P12V_PVCCIN_CPU1_FLT
   2    GND      B @S9S_MB_2U_LIB.S9S_MB_2U(SCH_1):GND

Q_CAP_C0402-1UF,16V,10%,X6S,CHA  I47  PC563_P1_1
   1 SW_P12V_PVCCIN_CPU1_FLT      A @S9S_MB_2U_LIB.S9S_MB_2U(SCH_1):SW_P12V_PVCCIN_CPU1_FLT
   2    GND      B @S9S_MB_2U_LIB.S9S_MB_2U(SCH_1):GND

Q_CAP_C0805-22UF,16V,20%,X6S,CA  I48  PC567_P1_1
   1 SW_P12V_PVCCIN_CPU1_FLT      A @S9S_MB_2U_LIB.S9S_MB_2U(SCH_1):SW_P12V_PVCCIN_CPU1_FLT
   2    GND      B @S9S_MB_2U_LIB.S9S_MB_2U(SCH_1):GND

Q_CAP_C0402-100NF,50V,10%,X7R,A  I49  PC565
   1 SW_PVCCIN_CPU1_BOOT1_R      A @S9S_MB_2U_LIB.S9S_MB_2U(SCH_1):SW_PVCCIN_CPU1_BOOT1_R
   2 SW_PVCCIN_CPU1_BOOTR1      B @S9S_MB_2U_LIB.S9S_MB_2U(SCH_1):SW_PVCCIN_CPU1_BOOTR1

Q_CAP_C0805-22UF,16V,20%,X6S,CA  I50  PC569_P1_1
   1 SW_P12V_PVCCIN_CPU1_FLT      A @S9S_MB_2U_LIB.S9S_MB_2U(SCH_1):SW_P12V_PVCCIN_CPU1_FLT
   2    GND      B @S9S_MB_2U_LIB.S9S_MB_2U(SCH_1):GND

Q_CAP_C0805-22UF,4V,20%,X6S,CHA  I57  PC575_P1_2
   1 PVCCIN_CPU1      A @S9S_MB_2U_LIB.S9S_MB_2U(SCH_1):PVCCIN_CPU1
   2    GND      B @S9S_MB_2U_LIB.S9S_MB_2U(SCH_1):GND

Q_CAP_C0805-22UF,4V,20%,X6S,CHA  I58  PC577_P1_2
   1 PVCCIN_CPU1      A @S9S_MB_2U_LIB.S9S_MB_2U(SCH_1):PVCCIN_CPU1
   2    GND      B @S9S_MB_2U_LIB.S9S_MB_2U(SCH_1):GND

Q_RES_0402LF-499,1%,1/16W,CHIPA  I59  PR4240
   1 PVCCIN_CPU1      A @S9S_MB_2U_LIB.S9S_MB_2U(SCH_1):PVCCIN_CPU1
   2    GND      B @S9S_MB_2U_LIB.S9S_MB_2U(SCH_1):GND

Q_CAPP_THLF-560UF,2.5V,20%,OSCA  I63  PC580
   1 PVCCIN_CPU1      A @S9S_MB_2U_LIB.S9S_MB_2U(SCH_1):PVCCIN_CPU1
   2    GND      B @S9S_MB_2U_LIB.S9S_MB_2U(SCH_1):GND

Q_CAPP_THLF-560UF,2.5V,20%,OSCA  I72  PC589
   1 PVCCIN_CPU1      A @S9S_MB_2U_LIB.S9S_MB_2U(SCH_1):PVCCIN_CPU1
   2    GND      B @S9S_MB_2U_LIB.S9S_MB_2U(SCH_1):GND

Q_RES_2512LF-0.03,0.1%,1W,EMPTA  I82  PR2556
   1 P12V_AUX      A @S9S_MB_2U_LIB.S9S_MB_2U(SCH_1):P12V_AUX
   2 SW_P12V_PVCCIN_CPU1_FLT      B @S9S_MB_2U_LIB.S9S_MB_2U(SCH_1):SW_P12V_PVCCIN_CPU1_FLT

Q_CAP_C0402-1UF,16V,10%,X6S,CHA  I85  PC574_P1_1
   1 PVCCIN_CPU1      A @S9S_MB_2U_LIB.S9S_MB_2U(SCH_1):PVCCIN_CPU1
   2    GND      B @S9S_MB_2U_LIB.S9S_MB_2U(SCH_1):GND

Q_CAP_C0402-2.2UF,10V,10%,X6S,A  I15  PC558_P1_2
   1 PVCCIN_CPU1_PVCC      A @S9S_MB_2U_LIB.S9S_MB_2U(SCH_1):PVCCIN_CPU1_PVCC
   2    GND      B @S9S_MB_2U_LIB.S9S_MB_2U(SCH_1):GND

Q_CAP_0402-3300PF,50V,10%,X7R,A  I19  PC560_P1_2
   1 SW_P12V_PVCCIN_CPU1_FLT      A @S9S_MB_2U_LIB.S9S_MB_2U(SCH_1):SW_P12V_PVCCIN_CPU1_FLT
   2    GND      B @S9S_MB_2U_LIB.S9S_MB_2U(SCH_1):GND

Q_RES_0402LF-3.3,1%,1/16W,CHIPA  I20  PR1766
   1 SW_PVCCIN_CPU1_BOOT2      A @S9S_MB_2U_LIB.S9S_MB_2U(SCH_1):SW_PVCCIN_CPU1_BOOT2
   2 SW_PVCCIN_CPU1_BOOT2_R      B @S9S_MB_2U_LIB.S9S_MB_2U(SCH_1):SW_PVCCIN_CPU1_BOOT2_R

Q_CAP_C0402-1UF,16V,10%,X6S,CHA  I21  PC562_P1_2
   1 SW_P12V_PVCCIN_CPU1_FLT      A @S9S_MB_2U_LIB.S9S_MB_2U(SCH_1):SW_P12V_PVCCIN_CPU1_FLT
   2    GND      B @S9S_MB_2U_LIB.S9S_MB_2U(SCH_1):GND

Q_RES_0402LF-2.2,1%,1/16W,CHIPA  I37  PR328
   1 PVCCIN_CPU1_PVCC      A @S9S_MB_2U_LIB.S9S_MB_2U(SCH_1):PVCCIN_CPU1_PVCC
   2 PVCCIN_CPU1_VDD1      B @S9S_MB_2U_LIB.S9S_MB_2U(SCH_1):PVCCIN_CPU1_VDD1

Q_CAP_C0402-2.2UF,10V,10%,X6S,A  I39  PC559_P1_1
   1 PVCCIN_CPU1_PVCC      A @S9S_MB_2U_LIB.S9S_MB_2U(SCH_1):PVCCIN_CPU1_PVCC
   2    GND      B @S9S_MB_2U_LIB.S9S_MB_2U(SCH_1):GND

ISL99390FRZTR5935-ISL99390FRZ-A  I40  PU31_P1_1
  34 PVCCIN_CPU1_PWM1    PWM @S9S_MB_2U_LIB.S9S_MB_2U(SCH_1):PVCCIN_CPU1_PWM1
  39 PVCCIN_CPU1_VREF  REFIN @S9S_MB_2U_LIB.S9S_MB_2U(SCH_1):PVCCIN_CPU1_VREF
   3 PVCCIN_CPU1_VDD1    VCC @S9S_MB_2U_LIB.S9S_MB_2U(SCH_1):PVCCIN_CPU1_VDD1
   2    GND   AGND @S9S_MB_2U_LIB.S9S_MB_2U(SCH_1):GND
  33 SW_PVCCIN_CPU1_BOOT1   BOOT @S9S_MB_2U_LIB.S9S_MB_2U(SCH_1):SW_PVCCIN_CPU1_BOOT1
25_29 SW_P12V_PVCCIN_CPU1_FLT   VIN1 @S9S_MB_2U_LIB.S9S_MB_2U(SCH_1):SW_P12V_PVCCIN_CPU1_FLT
  32 SW_PVCCIN_CPU1_BOOTR1  PHASE @S9S_MB_2U_LIB.S9S_MB_2U(SCH_1):SW_PVCCIN_CPU1_BOOTR1
   4 PVCCIN_CPU1_PVCC   PVCC @S9S_MB_2U_LIB.S9S_MB_2U(SCH_1):PVCCIN_CPU1_PVCC
  36 PVCCIN_CPU1_ATSEN TOUT_FLT @S9S_MB_2U_LIB.S9S_MB_2U(SCH_1):PVCCIN_CPU1_ATSEN
  38 PVCCIN_CPU1_IMON1   IOUT @S9S_MB_2U_LIB.S9S_MB_2U(SCH_1):PVCCIN_CPU1_IMON1
  37 PVCCIN_CPU1_LSET1   LSET @S9S_MB_2U_LIB.S9S_MB_2U(SCH_1):PVCCIN_CPU1_LSET1
10_19 SW_PVCCIN_CPU1_SW1     SW @S9S_MB_2U_LIB.S9S_MB_2U(SCH_1):SW_PVCCIN_CPU1_SW1
   5    GND  PGND1 @S9S_MB_2U_LIB.S9S_MB_2U(SCH_1):GND
  30 SW_P12V_PVCCIN_CPU1_FLT   VIN2 @S9S_MB_2U_LIB.S9S_MB_2U(SCH_1):SW_P12V_PVCCIN_CPU1_FLT
   1 PVCCIN_CPU1_VOS1    VOS @S9S_MB_2U_LIB.S9S_MB_2U(SCH_1):PVCCIN_CPU1_VOS1
  40    GND  PGND3 @S9S_MB_2U_LIB.S9S_MB_2U(SCH_1):GND
  35 PVCCIN_CPU1_VDD1     EN @S9S_MB_2U_LIB.S9S_MB_2U(SCH_1):PVCCIN_CPU1_VDD1
  31     NC    DNC     NC
   6     NC    GL1     NC
  41     NC    GL2     NC
7_9-20_24    GND  PGND2 @S9S_MB_2U_LIB.S9S_MB_2U(SCH_1):GND

Q_CAPP_THLF-560UF,2.5V,20%,OSCA  I56  PC83
   1 PVCCIN_CPU1      A @S9S_MB_2U_LIB.S9S_MB_2U(SCH_1):PVCCIN_CPU1
   2    GND      B @S9S_MB_2U_LIB.S9S_MB_2U(SCH_1):GND

Q_CAPP_SMLF-330UF,2.5V,+10/-35A  I62  PC189
   1 PVCCIN_CPU1      A @S9S_MB_2U_LIB.S9S_MB_2U(SCH_1):PVCCIN_CPU1
   2    GND      B @S9S_MB_2U_LIB.S9S_MB_2U(SCH_1):GND

Q_RES_0402LF-0,5%,1/16W,CHIP,CA  I73  PR330
   1 PVCCIN_CPU1_VOS1      A @S9S_MB_2U_LIB.S9S_MB_2U(SCH_1):PVCCIN_CPU1_VOS1
   2 PVCCIN_CPU1      B @S9S_MB_2U_LIB.S9S_MB_2U(SCH_1):PVCCIN_CPU1

Q_CAPP_THLF-270UF,16V,20%,OSCOA  I87  PC582
   1 SW_P12V_PVCCIN_CPU1_FLT      A @S9S_MB_2U_LIB.S9S_MB_2U(SCH_1):SW_P12V_PVCCIN_CPU1_FLT
   2    GND      B @S9S_MB_2U_LIB.S9S_MB_2U(SCH_1):GND

Q_CAP_C0805-22UF,4V,20%,X6S,CHA  I88  PC576_P1_1
   1 PVCCIN_CPU1      A @S9S_MB_2U_LIB.S9S_MB_2U(SCH_1):PVCCIN_CPU1
   2    GND      B @S9S_MB_2U_LIB.S9S_MB_2U(SCH_1):GND

Q_CAP_C0805-22UF,4V,20%,X6S,CHA  I91  PC578_P1_1
   1 PVCCIN_CPU1      A @S9S_MB_2U_LIB.S9S_MB_2U(SCH_1):PVCCIN_CPU1
   2    GND      B @S9S_MB_2U_LIB.S9S_MB_2U(SCH_1):GND

Q_CAPP_THLF-270UF,16V,20%,OSCOA  I96  PC2346
   1 SW_P12V_PVCCIN_CPU1_FLT      A @S9S_MB_2U_LIB.S9S_MB_2U(SCH_1):SW_P12V_PVCCIN_CPU1_FLT
   2    GND      B @S9S_MB_2U_LIB.S9S_MB_2U(SCH_1):GND

ISL99390FRZTR5935-ISL99390FRZ-A  I7  PU30_P1_2
  34 PVCCIN_CPU1_PWM2    PWM @S9S_MB_2U_LIB.S9S_MB_2U(SCH_1):PVCCIN_CPU1_PWM2
  39 PVCCIN_CPU1_VREF  REFIN @S9S_MB_2U_LIB.S9S_MB_2U(SCH_1):PVCCIN_CPU1_VREF
   3 PVCCIN_CPU1_VDD2    VCC @S9S_MB_2U_LIB.S9S_MB_2U(SCH_1):PVCCIN_CPU1_VDD2
   2    GND   AGND @S9S_MB_2U_LIB.S9S_MB_2U(SCH_1):GND
  33 SW_PVCCIN_CPU1_BOOT2   BOOT @S9S_MB_2U_LIB.S9S_MB_2U(SCH_1):SW_PVCCIN_CPU1_BOOT2
25_29 SW_P12V_PVCCIN_CPU1_FLT   VIN1 @S9S_MB_2U_LIB.S9S_MB_2U(SCH_1):SW_P12V_PVCCIN_CPU1_FLT
  32 SW_PVCCIN_CPU1_BOOTR2  PHASE @S9S_MB_2U_LIB.S9S_MB_2U(SCH_1):SW_PVCCIN_CPU1_BOOTR2
   4 PVCCIN_CPU1_PVCC   PVCC @S9S_MB_2U_LIB.S9S_MB_2U(SCH_1):PVCCIN_CPU1_PVCC
  36 PVCCIN_CPU1_ATSEN TOUT_FLT @S9S_MB_2U_LIB.S9S_MB_2U(SCH_1):PVCCIN_CPU1_ATSEN
  38 PVCCIN_CPU1_IMON2   IOUT @S9S_MB_2U_LIB.S9S_MB_2U(SCH_1):PVCCIN_CPU1_IMON2
  37 PVCCIN_CPU1_LSET2   LSET @S9S_MB_2U_LIB.S9S_MB_2U(SCH_1):PVCCIN_CPU1_LSET2
10_19 SW_PVCCIN_CPU1_SW2     SW @S9S_MB_2U_LIB.S9S_MB_2U(SCH_1):SW_PVCCIN_CPU1_SW2
   5    GND  PGND1 @S9S_MB_2U_LIB.S9S_MB_2U(SCH_1):GND
  30 SW_P12V_PVCCIN_CPU1_FLT   VIN2 @S9S_MB_2U_LIB.S9S_MB_2U(SCH_1):SW_P12V_PVCCIN_CPU1_FLT
   1 PVCCIN_CPU1_VOS2    VOS @S9S_MB_2U_LIB.S9S_MB_2U(SCH_1):PVCCIN_CPU1_VOS2
  40    GND  PGND3 @S9S_MB_2U_LIB.S9S_MB_2U(SCH_1):GND
  35 PVCCIN_CPU1_VDD2     EN @S9S_MB_2U_LIB.S9S_MB_2U(SCH_1):PVCCIN_CPU1_VDD2
  31     NC    DNC     NC
   6     NC    GL1     NC
  41     NC    GL2     NC
7_9-20_24    GND  PGND2 @S9S_MB_2U_LIB.S9S_MB_2U(SCH_1):GND

Q_RES_0402LF-2.2,1%,1/16W,CHIPA  I13  PR327
   1 PVCCIN_CPU1_PVCC      A @S9S_MB_2U_LIB.S9S_MB_2U(SCH_1):PVCCIN_CPU1_PVCC
   2 PVCCIN_CPU1_VDD2      B @S9S_MB_2U_LIB.S9S_MB_2U(SCH_1):PVCCIN_CPU1_VDD2

Q_INDUCTOR4P_14-150NH,SMLF,INDA  I18  PL30
   2 IND_P1_CPL2      2 @S9S_MB_2U_LIB.S9S_MB_2U(SCH_1):IND_P1_CPL2
   3 IND_P1_CPL1      3 @S9S_MB_2U_LIB.S9S_MB_2U(SCH_1):IND_P1_CPL1
   4 PVCCIN_CPU1      4 @S9S_MB_2U_LIB.S9S_MB_2U(SCH_1):PVCCIN_CPU1
   1 SW_PVCCIN_CPU1_SW2      1 @S9S_MB_2U_LIB.S9S_MB_2U(SCH_1):SW_PVCCIN_CPU1_SW2

Q_RES_0402LF-0,5%,1/16W,CHIP,CA  I26  PR639
   1    P5V      A @S9S_MB_2U_LIB.S9S_MB_2U(SCH_1):P5V
   2 PVCCIN_CPU1_PVCC      B @S9S_MB_2U_LIB.S9S_MB_2U(SCH_1):PVCCIN_CPU1_PVCC

Q_CAP_0402-0.1UF,25V,10%,X7R,CA  I34  PC1339
   1    GND      A @S9S_MB_2U_LIB.S9S_MB_2U(SCH_1):GND
   2 PVCCIN_CPU1_VREF      B @S9S_MB_2U_LIB.S9S_MB_2U(SCH_1):PVCCIN_CPU1_VREF

Q_CAP_C0402-2.2UF,10V,10%,X6S,A  I36  PC557
   1 PVCCIN_CPU1_VDD1      A @S9S_MB_2U_LIB.S9S_MB_2U(SCH_1):PVCCIN_CPU1_VDD1
   2    GND      B @S9S_MB_2U_LIB.S9S_MB_2U(SCH_1):GND

Q_RES_0402LF-0,5%,1/16W,EMPTY,A  I41  PR640
   1   P3V3      A @S9S_MB_2U_LIB.S9S_MB_2U(SCH_1):P3V3
   2 PVCCIN_CPU1_PVCC      B @S9S_MB_2U_LIB.S9S_MB_2U(SCH_1):PVCCIN_CPU1_PVCC

Q_CAP_0402-3300PF,50V,10%,X7R,A  I44  PC561_P1_1
   1 SW_P12V_PVCCIN_CPU1_FLT      A @S9S_MB_2U_LIB.S9S_MB_2U(SCH_1):SW_P12V_PVCCIN_CPU1_FLT
   2    GND      B @S9S_MB_2U_LIB.S9S_MB_2U(SCH_1):GND

Q_RES_0402LF-0,5%,1/16W,CHIP,CA  I51  PR329
   1 PVCCIN_CPU1_VOS2      A @S9S_MB_2U_LIB.S9S_MB_2U(SCH_1):PVCCIN_CPU1_VOS2
   2 PVCCIN_CPU1      B @S9S_MB_2U_LIB.S9S_MB_2U(SCH_1):PVCCIN_CPU1

Q_CAP_C0805-22UF,16V,20%,X6S,CA  I53  PC570_P1_2
   1 SW_P12V_PVCCIN_CPU1_FLT      A @S9S_MB_2U_LIB.S9S_MB_2U(SCH_1):SW_P12V_PVCCIN_CPU1_FLT
   2    GND      B @S9S_MB_2U_LIB.S9S_MB_2U(SCH_1):GND

Q_CAPP_THLF-560UF,2.5V,20%,OSCA  I64  PC583
   1 PVCCIN_CPU1      A @S9S_MB_2U_LIB.S9S_MB_2U(SCH_1):PVCCIN_CPU1
   2    GND      B @S9S_MB_2U_LIB.S9S_MB_2U(SCH_1):GND

Q_CAPP_SMLF-330UF,2.5V,+10/-35A  I68  PC590
   1 PVCCIN_CPU1      A @S9S_MB_2U_LIB.S9S_MB_2U(SCH_1):PVCCIN_CPU1
   2    GND      B @S9S_MB_2U_LIB.S9S_MB_2U(SCH_1):GND

Q_CAP_C0805-22UF,16V,20%,X6S,CA  I76  PC571_P1_1
   1 SW_P12V_PVCCIN_CPU1_FLT      A @S9S_MB_2U_LIB.S9S_MB_2U(SCH_1):SW_P12V_PVCCIN_CPU1_FLT
   2    GND      B @S9S_MB_2U_LIB.S9S_MB_2U(SCH_1):GND

Q_CAPP_THLF-270UF,16V,20%,OSCOA  I86  PC579
   1 SW_P12V_PVCCIN_CPU1_FLT      A @S9S_MB_2U_LIB.S9S_MB_2U(SCH_1):SW_P12V_PVCCIN_CPU1_FLT
   2    GND      B @S9S_MB_2U_LIB.S9S_MB_2U(SCH_1):GND

Q_CAPP_THLF-270UF,16V,20%,OSCOA  I92  PC585
   1 SW_P12V_PVCCIN_CPU1_FLT      A @S9S_MB_2U_LIB.S9S_MB_2U(SCH_1):SW_P12V_PVCCIN_CPU1_FLT
   2    GND      B @S9S_MB_2U_LIB.S9S_MB_2U(SCH_1):GND

Q_CAPP_THLF-270UF,16V,20%,OSCOA  I94  PC588
   1 SW_P12V_PVCCIN_CPU1_FLT      A @S9S_MB_2U_LIB.S9S_MB_2U(SCH_1):SW_P12V_PVCCIN_CPU1_FLT
   2    GND      B @S9S_MB_2U_LIB.S9S_MB_2U(SCH_1):GND


DRAWING: @S9S_MB_2U_LIB.S9S_MB_2U(SCH_1):PAGE272 

Q_CAP_C0402-2.2UF,10V,10%,X6S,A  I11  PC523
   1 PVCCIN_CPU1_VDD4      A @S9S_MB_2U_LIB.S9S_MB_2U(SCH_1):PVCCIN_CPU1_VDD4
   2    GND      B @S9S_MB_2U_LIB.S9S_MB_2U(SCH_1):GND

Q_RES_0402LF-2.2,1%,1/16W,CHIPA  I12  PR299
   1 PVCCIN_CPU1_PVCC      A @S9S_MB_2U_LIB.S9S_MB_2U(SCH_1):PVCCIN_CPU1_PVCC
   2 PVCCIN_CPU1_VDD4      B @S9S_MB_2U_LIB.S9S_MB_2U(SCH_1):PVCCIN_CPU1_VDD4

Q_CAP_0402-0.1UF,25V,10%,X7R,CA  I27  PC1359
   1    GND      A @S9S_MB_2U_LIB.S9S_MB_2U(SCH_1):GND
   2 PVCCIN_CPU1_VREF      B @S9S_MB_2U_LIB.S9S_MB_2U(SCH_1):PVCCIN_CPU1_VREF

Q_RES_0402LF-3.3,1%,1/16W,CHIPA  I34  PR1788
   1 SW_PVCCIN_CPU1_BOOT4      A @S9S_MB_2U_LIB.S9S_MB_2U(SCH_1):SW_PVCCIN_CPU1_BOOT4
   2 SW_PVCCIN_CPU1_BOOT4_R      B @S9S_MB_2U_LIB.S9S_MB_2U(SCH_1):SW_PVCCIN_CPU1_BOOT4_R

Q_CAP_C0402-1UF,16V,10%,X6S,CHA  I35  PC529_P1_4
   1 SW_P12V_PVCCIN_CPU1_FLT      A @S9S_MB_2U_LIB.S9S_MB_2U(SCH_1):SW_P12V_PVCCIN_CPU1_FLT
   2    GND      B @S9S_MB_2U_LIB.S9S_MB_2U(SCH_1):GND

Q_CAP_C0805-22UF,16V,20%,X6S,CA  I36  PC533_P1_4
   1 SW_P12V_PVCCIN_CPU1_FLT      A @S9S_MB_2U_LIB.S9S_MB_2U(SCH_1):SW_P12V_PVCCIN_CPU1_FLT
   2    GND      B @S9S_MB_2U_LIB.S9S_MB_2U(SCH_1):GND

Q_CAP_C0805-22UF,16V,20%,X6S,CA  I41  PC535_P1_4
   1 SW_P12V_PVCCIN_CPU1_FLT      A @S9S_MB_2U_LIB.S9S_MB_2U(SCH_1):SW_P12V_PVCCIN_CPU1_FLT
   2    GND      B @S9S_MB_2U_LIB.S9S_MB_2U(SCH_1):GND

Q_CAP_C0805-22UF,16V,20%,X6S,CA  I42  PC537_P1_4
   1 SW_P12V_PVCCIN_CPU1_FLT      A @S9S_MB_2U_LIB.S9S_MB_2U(SCH_1):SW_P12V_PVCCIN_CPU1_FLT
   2    GND      B @S9S_MB_2U_LIB.S9S_MB_2U(SCH_1):GND

Q_RES_0402LF-3.3,1%,1/16W,CHIPA  I46  PR1789
   1 SW_PVCCIN_CPU1_BOOT3      A @S9S_MB_2U_LIB.S9S_MB_2U(SCH_1):SW_PVCCIN_CPU1_BOOT3
   2 SW_PVCCIN_CPU1_BOOT3_R      B @S9S_MB_2U_LIB.S9S_MB_2U(SCH_1):SW_PVCCIN_CPU1_BOOT3_R

Q_CAP_0402-3300PF,50V,10%,X7R,A  I48  PC528_P1_3
   1 SW_P12V_PVCCIN_CPU1_FLT      A @S9S_MB_2U_LIB.S9S_MB_2U(SCH_1):SW_P12V_PVCCIN_CPU1_FLT
   2    GND      B @S9S_MB_2U_LIB.S9S_MB_2U(SCH_1):GND

Q_CAP_C0402-1UF,16V,10%,X6S,CHA  I49  PC530_P1_3
   1 SW_P12V_PVCCIN_CPU1_FLT      A @S9S_MB_2U_LIB.S9S_MB_2U(SCH_1):SW_P12V_PVCCIN_CPU1_FLT
   2    GND      B @S9S_MB_2U_LIB.S9S_MB_2U(SCH_1):GND

Q_CAP_C0402-100NF,50V,10%,X7R,A  I52  PC532
   1 SW_PVCCIN_CPU1_BOOT3_R      A @S9S_MB_2U_LIB.S9S_MB_2U(SCH_1):SW_PVCCIN_CPU1_BOOT3_R
   2 SW_PVCCIN_CPU1_BOOTR3      B @S9S_MB_2U_LIB.S9S_MB_2U(SCH_1):SW_PVCCIN_CPU1_BOOTR3

Q_CAP_C0805-22UF,16V,20%,X6S,CA  I54  PC536_P1_3
   1 SW_P12V_PVCCIN_CPU1_FLT      A @S9S_MB_2U_LIB.S9S_MB_2U(SCH_1):SW_P12V_PVCCIN_CPU1_FLT
   2    GND      B @S9S_MB_2U_LIB.S9S_MB_2U(SCH_1):GND

Q_RES_0402LF-8.87K,1%,1/16W,EMA  I3  PR297
   1 PVCCIN_CPU1_LSET4      A @S9S_MB_2U_LIB.S9S_MB_2U(SCH_1):PVCCIN_CPU1_LSET4
   2    GND      B @S9S_MB_2U_LIB.S9S_MB_2U(SCH_1):GND

Q_CAP_0402-0.1UF,25V,10%,X7R,CA  I6  PC1358
   1    GND      A @S9S_MB_2U_LIB.S9S_MB_2U(SCH_1):GND
   2 PVCCIN_CPU1_VREF      B @S9S_MB_2U_LIB.S9S_MB_2U(SCH_1):PVCCIN_CPU1_VREF

ISL99390FRZTR5935-ISL99390FRZ-A  I10  PU27_P1_4
  34 PVCCIN_CPU1_PWM4    PWM @S9S_MB_2U_LIB.S9S_MB_2U(SCH_1):PVCCIN_CPU1_PWM4
  39 PVCCIN_CPU1_VREF  REFIN @S9S_MB_2U_LIB.S9S_MB_2U(SCH_1):PVCCIN_CPU1_VREF
   3 PVCCIN_CPU1_VDD4    VCC @S9S_MB_2U_LIB.S9S_MB_2U(SCH_1):PVCCIN_CPU1_VDD4
   2    GND   AGND @S9S_MB_2U_LIB.S9S_MB_2U(SCH_1):GND
  33 SW_PVCCIN_CPU1_BOOT4   BOOT @S9S_MB_2U_LIB.S9S_MB_2U(SCH_1):SW_PVCCIN_CPU1_BOOT4
25_29 SW_P12V_PVCCIN_CPU1_FLT   VIN1 @S9S_MB_2U_LIB.S9S_MB_2U(SCH_1):SW_P12V_PVCCIN_CPU1_FLT
  32 SW_PVCCIN_CPU1_BOOTR4  PHASE @S9S_MB_2U_LIB.S9S_MB_2U(SCH_1):SW_PVCCIN_CPU1_BOOTR4
   4 PVCCIN_CPU1_PVCC   PVCC @S9S_MB_2U_LIB.S9S_MB_2U(SCH_1):PVCCIN_CPU1_PVCC
  36 PVCCIN_CPU1_ATSEN TOUT_FLT @S9S_MB_2U_LIB.S9S_MB_2U(SCH_1):PVCCIN_CPU1_ATSEN
  38 PVCCIN_CPU1_IMON4   IOUT @S9S_MB_2U_LIB.S9S_MB_2U(SCH_1):PVCCIN_CPU1_IMON4
  37 PVCCIN_CPU1_LSET4   LSET @S9S_MB_2U_LIB.S9S_MB_2U(SCH_1):PVCCIN_CPU1_LSET4
10_19 SW_PVCCIN_CPU1_SW4     SW @S9S_MB_2U_LIB.S9S_MB_2U(SCH_1):SW_PVCCIN_CPU1_SW4
   5    GND  PGND1 @S9S_MB_2U_LIB.S9S_MB_2U(SCH_1):GND
  30 SW_P12V_PVCCIN_CPU1_FLT   VIN2 @S9S_MB_2U_LIB.S9S_MB_2U(SCH_1):SW_P12V_PVCCIN_CPU1_FLT
   1 PVCCIN_CPU1_VOS4    VOS @S9S_MB_2U_LIB.S9S_MB_2U(SCH_1):PVCCIN_CPU1_VOS4
  40    GND  PGND3 @S9S_MB_2U_LIB.S9S_MB_2U(SCH_1):GND
  35 PVCCIN_CPU1_VDD4     EN @S9S_MB_2U_LIB.S9S_MB_2U(SCH_1):PVCCIN_CPU1_VDD4
  31     NC    DNC     NC
   6     NC    GL1     NC
  41     NC    GL2     NC
7_9-20_24    GND  PGND2 @S9S_MB_2U_LIB.S9S_MB_2U(SCH_1):GND

Q_RES_0402LF-8.87K,1%,1/16W,EMA  I15  PR298
   1 PVCCIN_CPU1_LSET3      A @S9S_MB_2U_LIB.S9S_MB_2U(SCH_1):PVCCIN_CPU1_LSET3
   2    GND      B @S9S_MB_2U_LIB.S9S_MB_2U(SCH_1):GND

Q_CAP_C0402-2.2UF,10V,10%,X6S,A  I19  PC525_P1_4
   1 PVCCIN_CPU1_PVCC      A @S9S_MB_2U_LIB.S9S_MB_2U(SCH_1):PVCCIN_CPU1_PVCC
   2    GND      B @S9S_MB_2U_LIB.S9S_MB_2U(SCH_1):GND

Q_CAP_C0402-2.2UF,10V,10%,X6S,A  I24  PC524
   1 PVCCIN_CPU1_VDD3      A @S9S_MB_2U_LIB.S9S_MB_2U(SCH_1):PVCCIN_CPU1_VDD3
   2    GND      B @S9S_MB_2U_LIB.S9S_MB_2U(SCH_1):GND

Q_RES_0402LF-2.2,1%,1/16W,CHIPA  I25  PR300
   1 PVCCIN_CPU1_PVCC      A @S9S_MB_2U_LIB.S9S_MB_2U(SCH_1):PVCCIN_CPU1_PVCC
   2 PVCCIN_CPU1_VDD3      B @S9S_MB_2U_LIB.S9S_MB_2U(SCH_1):PVCCIN_CPU1_VDD3

Q_CAP_C0402-2.2UF,10V,10%,X6S,A  I29  PC526_P1_3
   1 PVCCIN_CPU1_PVCC      A @S9S_MB_2U_LIB.S9S_MB_2U(SCH_1):PVCCIN_CPU1_PVCC
   2    GND      B @S9S_MB_2U_LIB.S9S_MB_2U(SCH_1):GND

Q_CAP_0402-3300PF,50V,10%,X7R,A  I33  PC527_P1_4
   1 SW_P12V_PVCCIN_CPU1_FLT      A @S9S_MB_2U_LIB.S9S_MB_2U(SCH_1):SW_P12V_PVCCIN_CPU1_FLT
   2    GND      B @S9S_MB_2U_LIB.S9S_MB_2U(SCH_1):GND

Q_INDUCTOR4P_14-150NH,SMLF,INDA  I37  PL28
   2 IND_P1_CPL4      2 @S9S_MB_2U_LIB.S9S_MB_2U(SCH_1):IND_P1_CPL4
   3 IND_P1_CPL3      3 @S9S_MB_2U_LIB.S9S_MB_2U(SCH_1):IND_P1_CPL3
   4 PVCCIN_CPU1      4 @S9S_MB_2U_LIB.S9S_MB_2U(SCH_1):PVCCIN_CPU1
   1 SW_PVCCIN_CPU1_SW4      1 @S9S_MB_2U_LIB.S9S_MB_2U(SCH_1):SW_PVCCIN_CPU1_SW4

Q_RES_0402LF-0,5%,1/16W,CHIP,CA  I38  PR301
   1 PVCCIN_CPU1_VOS4      A @S9S_MB_2U_LIB.S9S_MB_2U(SCH_1):PVCCIN_CPU1_VOS4
   2 PVCCIN_CPU1      B @S9S_MB_2U_LIB.S9S_MB_2U(SCH_1):PVCCIN_CPU1

Q_CAP_C0402-100NF,50V,10%,X7R,A  I39  PC531
   1 SW_PVCCIN_CPU1_BOOT4_R      A @S9S_MB_2U_LIB.S9S_MB_2U(SCH_1):SW_PVCCIN_CPU1_BOOT4_R
   2 SW_PVCCIN_CPU1_BOOTR4      B @S9S_MB_2U_LIB.S9S_MB_2U(SCH_1):SW_PVCCIN_CPU1_BOOTR4

Q_RES_0402LF-0,5%,1/16W,CHIP,CA  I45  PR302
   1 PVCCIN_CPU1_VOS3      A @S9S_MB_2U_LIB.S9S_MB_2U(SCH_1):PVCCIN_CPU1_VOS3
   2 PVCCIN_CPU1      B @S9S_MB_2U_LIB.S9S_MB_2U(SCH_1):PVCCIN_CPU1

Q_CAP_C0805-22UF,16V,20%,X6S,CA  I50  PC534_P1_3
   1 SW_P12V_PVCCIN_CPU1_FLT      A @S9S_MB_2U_LIB.S9S_MB_2U(SCH_1):SW_P12V_PVCCIN_CPU1_FLT
   2    GND      B @S9S_MB_2U_LIB.S9S_MB_2U(SCH_1):GND

Q_INDUCTOR4P_14-150NH,SMLF,INDA  I51  PL29
   2 IND_P1_CPL3      2 @S9S_MB_2U_LIB.S9S_MB_2U(SCH_1):IND_P1_CPL3
   3 IND_P1_CPL2      3 @S9S_MB_2U_LIB.S9S_MB_2U(SCH_1):IND_P1_CPL2
   4 PVCCIN_CPU1      4 @S9S_MB_2U_LIB.S9S_MB_2U(SCH_1):PVCCIN_CPU1
   1 SW_PVCCIN_CPU1_SW3      1 @S9S_MB_2U_LIB.S9S_MB_2U(SCH_1):SW_PVCCIN_CPU1_SW3

Q_CAP_C0805-22UF,16V,20%,X6S,CA  I55  PC538_P1_3
   1 SW_P12V_PVCCIN_CPU1_FLT      A @S9S_MB_2U_LIB.S9S_MB_2U(SCH_1):SW_P12V_PVCCIN_CPU1_FLT
   2    GND      B @S9S_MB_2U_LIB.S9S_MB_2U(SCH_1):GND

Q_CAP_C0805-22UF,4V,20%,X6S,CHA  I58  PC541_P1_4
   1 PVCCIN_CPU1      A @S9S_MB_2U_LIB.S9S_MB_2U(SCH_1):PVCCIN_CPU1
   2    GND      B @S9S_MB_2U_LIB.S9S_MB_2U(SCH_1):GND

Q_CAP_C0805-22UF,4V,20%,X6S,CHA  I59  PC543_P1_4
   1 PVCCIN_CPU1      A @S9S_MB_2U_LIB.S9S_MB_2U(SCH_1):PVCCIN_CPU1
   2    GND      B @S9S_MB_2U_LIB.S9S_MB_2U(SCH_1):GND

Q_CAP_C0805-22UF,4V,20%,X6S,CHA  I63  PC542_P1_3
   1 PVCCIN_CPU1      A @S9S_MB_2U_LIB.S9S_MB_2U(SCH_1):PVCCIN_CPU1
   2    GND      B @S9S_MB_2U_LIB.S9S_MB_2U(SCH_1):GND

Q_CAP_C0805-22UF,4V,20%,X6S,CHA  I64  PC544_P1_3
   1 PVCCIN_CPU1      A @S9S_MB_2U_LIB.S9S_MB_2U(SCH_1):PVCCIN_CPU1
   2    GND      B @S9S_MB_2U_LIB.S9S_MB_2U(SCH_1):GND

ISL99390FRZTR5935-ISL99390FRZ-A  I66  PU28_P1_3
  34 PVCCIN_CPU1_PWM3    PWM @S9S_MB_2U_LIB.S9S_MB_2U(SCH_1):PVCCIN_CPU1_PWM3
  39 PVCCIN_CPU1_VREF  REFIN @S9S_MB_2U_LIB.S9S_MB_2U(SCH_1):PVCCIN_CPU1_VREF
   3 PVCCIN_CPU1_VDD3    VCC @S9S_MB_2U_LIB.S9S_MB_2U(SCH_1):PVCCIN_CPU1_VDD3
   2    GND   AGND @S9S_MB_2U_LIB.S9S_MB_2U(SCH_1):GND
  33 SW_PVCCIN_CPU1_BOOT3   BOOT @S9S_MB_2U_LIB.S9S_MB_2U(SCH_1):SW_PVCCIN_CPU1_BOOT3
25_29 SW_P12V_PVCCIN_CPU1_FLT   VIN1 @S9S_MB_2U_LIB.S9S_MB_2U(SCH_1):SW_P12V_PVCCIN_CPU1_FLT
  32 SW_PVCCIN_CPU1_BOOTR3  PHASE @S9S_MB_2U_LIB.S9S_MB_2U(SCH_1):SW_PVCCIN_CPU1_BOOTR3
   4 PVCCIN_CPU1_PVCC   PVCC @S9S_MB_2U_LIB.S9S_MB_2U(SCH_1):PVCCIN_CPU1_PVCC
  36 PVCCIN_CPU1_ATSEN TOUT_FLT @S9S_MB_2U_LIB.S9S_MB_2U(SCH_1):PVCCIN_CPU1_ATSEN
  38 PVCCIN_CPU1_IMON3   IOUT @S9S_MB_2U_LIB.S9S_MB_2U(SCH_1):PVCCIN_CPU1_IMON3
  37 PVCCIN_CPU1_LSET3   LSET @S9S_MB_2U_LIB.S9S_MB_2U(SCH_1):PVCCIN_CPU1_LSET3
10_19 SW_PVCCIN_CPU1_SW3     SW @S9S_MB_2U_LIB.S9S_MB_2U(SCH_1):SW_PVCCIN_CPU1_SW3
   5    GND  PGND1 @S9S_MB_2U_LIB.S9S_MB_2U(SCH_1):GND
  30 SW_P12V_PVCCIN_CPU1_FLT   VIN2 @S9S_MB_2U_LIB.S9S_MB_2U(SCH_1):SW_P12V_PVCCIN_CPU1_FLT
   1 PVCCIN_CPU1_VOS3    VOS @S9S_MB_2U_LIB.S9S_MB_2U(SCH_1):PVCCIN_CPU1_VOS3
  40    GND  PGND3 @S9S_MB_2U_LIB.S9S_MB_2U(SCH_1):GND
  35 PVCCIN_CPU1_VDD3     EN @S9S_MB_2U_LIB.S9S_MB_2U(SCH_1):PVCCIN_CPU1_VDD3
  31     NC    DNC     NC
   6     NC    GL1     NC
  41     NC    GL2     NC
7_9-20_24    GND  PGND2 @S9S_MB_2U_LIB.S9S_MB_2U(SCH_1):GND


DRAWING: @S9S_MB_2U_LIB.S9S_MB_2U(SCH_1):PAGE273 

Q_RES_0402LF-8.87K,1%,1/16W,EMA  I2  PR291
   1 PVCCIN_CPU1_LSET6      A @S9S_MB_2U_LIB.S9S_MB_2U(SCH_1):PVCCIN_CPU1_LSET6
   2    GND      B @S9S_MB_2U_LIB.S9S_MB_2U(SCH_1):GND

Q_CAP_C0402-2.2UF,10V,10%,X6S,A  I21  PC503_P1_6
   1 PVCCIN_CPU1_PVCC      A @S9S_MB_2U_LIB.S9S_MB_2U(SCH_1):PVCCIN_CPU1_PVCC
   2    GND      B @S9S_MB_2U_LIB.S9S_MB_2U(SCH_1):GND

ISL99390FRZTR5935-ISL99390FRZ-A  I23  PU26_P1_5
  34 PVCCIN_CPU1_PWM5    PWM @S9S_MB_2U_LIB.S9S_MB_2U(SCH_1):PVCCIN_CPU1_PWM5
  39 PVCCIN_CPU1_VREF  REFIN @S9S_MB_2U_LIB.S9S_MB_2U(SCH_1):PVCCIN_CPU1_VREF
   3 PVCCIN_CPU1_VDD5    VCC @S9S_MB_2U_LIB.S9S_MB_2U(SCH_1):PVCCIN_CPU1_VDD5
   2    GND   AGND @S9S_MB_2U_LIB.S9S_MB_2U(SCH_1):GND
  33 SW_PVCCIN_CPU1_BOOT5   BOOT @S9S_MB_2U_LIB.S9S_MB_2U(SCH_1):SW_PVCCIN_CPU1_BOOT5
25_29 SW_P12V_PVCCIN_CPU1_FLT   VIN1 @S9S_MB_2U_LIB.S9S_MB_2U(SCH_1):SW_P12V_PVCCIN_CPU1_FLT
  32 SW_PVCCIN_CPU1_BOOTR5  PHASE @S9S_MB_2U_LIB.S9S_MB_2U(SCH_1):SW_PVCCIN_CPU1_BOOTR5
   4 PVCCIN_CPU1_PVCC   PVCC @S9S_MB_2U_LIB.S9S_MB_2U(SCH_1):PVCCIN_CPU1_PVCC
  36 PVCCIN_CPU1_ATSEN TOUT_FLT @S9S_MB_2U_LIB.S9S_MB_2U(SCH_1):PVCCIN_CPU1_ATSEN
  38 PVCCIN_CPU1_IMON5   IOUT @S9S_MB_2U_LIB.S9S_MB_2U(SCH_1):PVCCIN_CPU1_IMON5
  37 PVCCIN_CPU1_LSET5   LSET @S9S_MB_2U_LIB.S9S_MB_2U(SCH_1):PVCCIN_CPU1_LSET5
10_19 SW_PVCCIN_CPU1_SW5     SW @S9S_MB_2U_LIB.S9S_MB_2U(SCH_1):SW_PVCCIN_CPU1_SW5
   5    GND  PGND1 @S9S_MB_2U_LIB.S9S_MB_2U(SCH_1):GND
  30 SW_P12V_PVCCIN_CPU1_FLT   VIN2 @S9S_MB_2U_LIB.S9S_MB_2U(SCH_1):SW_P12V_PVCCIN_CPU1_FLT
   1 PVCCIN_CPU1_VOS5    VOS @S9S_MB_2U_LIB.S9S_MB_2U(SCH_1):PVCCIN_CPU1_VOS5
  40    GND  PGND3 @S9S_MB_2U_LIB.S9S_MB_2U(SCH_1):GND
  35 PVCCIN_CPU1_VDD5     EN @S9S_MB_2U_LIB.S9S_MB_2U(SCH_1):PVCCIN_CPU1_VDD5
  31     NC    DNC     NC
   6     NC    GL1     NC
  41     NC    GL2     NC
7_9-20_24    GND  PGND2 @S9S_MB_2U_LIB.S9S_MB_2U(SCH_1):GND

Q_INDUCTOR4P_14-150NH,SMLF,INDA  I28  PL26
   2 IND_P1_CPL6      2 @S9S_MB_2U_LIB.S9S_MB_2U(SCH_1):IND_P1_CPL6
   3 IND_P1_CPL7      3 @S9S_MB_2U_LIB.S9S_MB_2U(SCH_1):IND_P1_CPL7
   4 PVCCIN_CPU1      4 @S9S_MB_2U_LIB.S9S_MB_2U(SCH_1):PVCCIN_CPU1
   1 SW_PVCCIN_CPU1_SW6      1 @S9S_MB_2U_LIB.S9S_MB_2U(SCH_1):SW_PVCCIN_CPU1_SW6

Q_CAP_0402-3300PF,50V,10%,X7R,A  I29  PC505_P1_6
   1 SW_P12V_PVCCIN_CPU1_FLT      A @S9S_MB_2U_LIB.S9S_MB_2U(SCH_1):SW_P12V_PVCCIN_CPU1_FLT
   2    GND      B @S9S_MB_2U_LIB.S9S_MB_2U(SCH_1):GND

Q_CAP_C0402-1UF,16V,10%,X6S,CHA  I31  PC507_P1_6
   1 SW_P12V_PVCCIN_CPU1_FLT      A @S9S_MB_2U_LIB.S9S_MB_2U(SCH_1):SW_P12V_PVCCIN_CPU1_FLT
   2    GND      B @S9S_MB_2U_LIB.S9S_MB_2U(SCH_1):GND

Q_CAP_C0805-22UF,16V,20%,X6S,CA  I34  PC513_P1_6
   1 SW_P12V_PVCCIN_CPU1_FLT      A @S9S_MB_2U_LIB.S9S_MB_2U(SCH_1):SW_P12V_PVCCIN_CPU1_FLT
   2    GND      B @S9S_MB_2U_LIB.S9S_MB_2U(SCH_1):GND

Q_CAP_0402-0.1UF,25V,10%,X7R,CA  I36  PC1361
   1    GND      A @S9S_MB_2U_LIB.S9S_MB_2U(SCH_1):GND
   2 PVCCIN_CPU1_VREF      B @S9S_MB_2U_LIB.S9S_MB_2U(SCH_1):PVCCIN_CPU1_VREF

Q_CAP_C0402-2.2UF,10V,10%,X6S,A  I37  PC502
   1 PVCCIN_CPU1_VDD5      A @S9S_MB_2U_LIB.S9S_MB_2U(SCH_1):PVCCIN_CPU1_VDD5
   2    GND      B @S9S_MB_2U_LIB.S9S_MB_2U(SCH_1):GND

Q_RES_0402LF-2.2,1%,1/16W,CHIPA  I39  PR294
   1 PVCCIN_CPU1_PVCC      A @S9S_MB_2U_LIB.S9S_MB_2U(SCH_1):PVCCIN_CPU1_PVCC
   2 PVCCIN_CPU1_VDD5      B @S9S_MB_2U_LIB.S9S_MB_2U(SCH_1):PVCCIN_CPU1_VDD5

Q_CAP_C0402-2.2UF,10V,10%,X6S,A  I41  PC504_P1_5
   1 PVCCIN_CPU1_PVCC      A @S9S_MB_2U_LIB.S9S_MB_2U(SCH_1):PVCCIN_CPU1_PVCC
   2    GND      B @S9S_MB_2U_LIB.S9S_MB_2U(SCH_1):GND

Q_RES_0402LF-3.3,1%,1/16W,CHIPA  I44  PR1791
   1 SW_PVCCIN_CPU1_BOOT5      A @S9S_MB_2U_LIB.S9S_MB_2U(SCH_1):SW_PVCCIN_CPU1_BOOT5
   2 SW_PVCCIN_CPU1_BOOT5_R      B @S9S_MB_2U_LIB.S9S_MB_2U(SCH_1):SW_PVCCIN_CPU1_BOOT5_R

Q_CAP_0402-3300PF,50V,10%,X7R,A  I45  PC506_P1_5
   1 SW_P12V_PVCCIN_CPU1_FLT      A @S9S_MB_2U_LIB.S9S_MB_2U(SCH_1):SW_P12V_PVCCIN_CPU1_FLT
   2    GND      B @S9S_MB_2U_LIB.S9S_MB_2U(SCH_1):GND

Q_CAP_C0402-100NF,50V,10%,X7R,A  I47  PC510
   1 SW_PVCCIN_CPU1_BOOT5_R      A @S9S_MB_2U_LIB.S9S_MB_2U(SCH_1):SW_PVCCIN_CPU1_BOOT5_R
   2 SW_PVCCIN_CPU1_BOOTR5      B @S9S_MB_2U_LIB.S9S_MB_2U(SCH_1):SW_PVCCIN_CPU1_BOOTR5

Q_INDUCTOR4P_14-150NH,SMLF,INDA  I48  PL27
   2 IND_P1_CPL5      2 @S9S_MB_2U_LIB.S9S_MB_2U(SCH_1):IND_P1_CPL5
   3 IND_P1_CPL4      3 @S9S_MB_2U_LIB.S9S_MB_2U(SCH_1):IND_P1_CPL4
   4 PVCCIN_CPU1      4 @S9S_MB_2U_LIB.S9S_MB_2U(SCH_1):PVCCIN_CPU1
   1 SW_PVCCIN_CPU1_SW5      1 @S9S_MB_2U_LIB.S9S_MB_2U(SCH_1):SW_PVCCIN_CPU1_SW5

Q_RES_0402LF-0,5%,1/16W,CHIP,CA  I49  PR296
   1 PVCCIN_CPU1_VOS5      A @S9S_MB_2U_LIB.S9S_MB_2U(SCH_1):PVCCIN_CPU1_VOS5
   2 PVCCIN_CPU1      B @S9S_MB_2U_LIB.S9S_MB_2U(SCH_1):PVCCIN_CPU1

Q_CAP_C0805-22UF,16V,20%,X6S,CA  I50  PC512_P1_5
   1 SW_P12V_PVCCIN_CPU1_FLT      A @S9S_MB_2U_LIB.S9S_MB_2U(SCH_1):SW_P12V_PVCCIN_CPU1_FLT
   2    GND      B @S9S_MB_2U_LIB.S9S_MB_2U(SCH_1):GND

Q_CAP_C0805-22UF,4V,20%,X6S,CHA  I54  PC519_P1_6
   1 PVCCIN_CPU1      A @S9S_MB_2U_LIB.S9S_MB_2U(SCH_1):PVCCIN_CPU1
   2    GND      B @S9S_MB_2U_LIB.S9S_MB_2U(SCH_1):GND

Q_RES_0402LF-8.87K,1%,1/16W,EMA  I7  PR292
   1 PVCCIN_CPU1_LSET5      A @S9S_MB_2U_LIB.S9S_MB_2U(SCH_1):PVCCIN_CPU1_LSET5
   2    GND      B @S9S_MB_2U_LIB.S9S_MB_2U(SCH_1):GND

Q_CAP_0402-0.1UF,25V,10%,X7R,CA  I15  PC1360
   1    GND      A @S9S_MB_2U_LIB.S9S_MB_2U(SCH_1):GND
   2 PVCCIN_CPU1_VREF      B @S9S_MB_2U_LIB.S9S_MB_2U(SCH_1):PVCCIN_CPU1_VREF

ISL99390FRZTR5935-ISL99390FRZ-A  I16  PU25_P1_6
  34 PVCCIN_CPU1_PWM6    PWM @S9S_MB_2U_LIB.S9S_MB_2U(SCH_1):PVCCIN_CPU1_PWM6
  39 PVCCIN_CPU1_VREF  REFIN @S9S_MB_2U_LIB.S9S_MB_2U(SCH_1):PVCCIN_CPU1_VREF
   3 PVCCIN_CPU1_VDD6    VCC @S9S_MB_2U_LIB.S9S_MB_2U(SCH_1):PVCCIN_CPU1_VDD6
   2    GND   AGND @S9S_MB_2U_LIB.S9S_MB_2U(SCH_1):GND
  33 SW_PVCCIN_CPU1_BOOT6   BOOT @S9S_MB_2U_LIB.S9S_MB_2U(SCH_1):SW_PVCCIN_CPU1_BOOT6
25_29 SW_P12V_PVCCIN_CPU1_FLT   VIN1 @S9S_MB_2U_LIB.S9S_MB_2U(SCH_1):SW_P12V_PVCCIN_CPU1_FLT
  32 SW_PVCCIN_CPU1_BOOTR6  PHASE @S9S_MB_2U_LIB.S9S_MB_2U(SCH_1):SW_PVCCIN_CPU1_BOOTR6
   4 PVCCIN_CPU1_PVCC   PVCC @S9S_MB_2U_LIB.S9S_MB_2U(SCH_1):PVCCIN_CPU1_PVCC
  36 PVCCIN_CPU1_ATSEN TOUT_FLT @S9S_MB_2U_LIB.S9S_MB_2U(SCH_1):PVCCIN_CPU1_ATSEN
  38 PVCCIN_CPU1_IMON6   IOUT @S9S_MB_2U_LIB.S9S_MB_2U(SCH_1):PVCCIN_CPU1_IMON6
  37 PVCCIN_CPU1_LSET6   LSET @S9S_MB_2U_LIB.S9S_MB_2U(SCH_1):PVCCIN_CPU1_LSET6
10_19 SW_PVCCIN_CPU1_SW6     SW @S9S_MB_2U_LIB.S9S_MB_2U(SCH_1):SW_PVCCIN_CPU1_SW6
   5    GND  PGND1 @S9S_MB_2U_LIB.S9S_MB_2U(SCH_1):GND
  30 SW_P12V_PVCCIN_CPU1_FLT   VIN2 @S9S_MB_2U_LIB.S9S_MB_2U(SCH_1):SW_P12V_PVCCIN_CPU1_FLT
   1 PVCCIN_CPU1_VOS6    VOS @S9S_MB_2U_LIB.S9S_MB_2U(SCH_1):PVCCIN_CPU1_VOS6
  40    GND  PGND3 @S9S_MB_2U_LIB.S9S_MB_2U(SCH_1):GND
  35 PVCCIN_CPU1_VDD6     EN @S9S_MB_2U_LIB.S9S_MB_2U(SCH_1):PVCCIN_CPU1_VDD6
  31     NC    DNC     NC
   6     NC    GL1     NC
  41     NC    GL2     NC
7_9-20_24    GND  PGND2 @S9S_MB_2U_LIB.S9S_MB_2U(SCH_1):GND

Q_CAP_C0402-2.2UF,10V,10%,X6S,A  I17  PC501
   1 PVCCIN_CPU1_VDD6      A @S9S_MB_2U_LIB.S9S_MB_2U(SCH_1):PVCCIN_CPU1_VDD6
   2    GND      B @S9S_MB_2U_LIB.S9S_MB_2U(SCH_1):GND

Q_RES_0402LF-2.2,1%,1/16W,CHIPA  I19  PR293
   1 PVCCIN_CPU1_PVCC      A @S9S_MB_2U_LIB.S9S_MB_2U(SCH_1):PVCCIN_CPU1_PVCC
   2 PVCCIN_CPU1_VDD6      B @S9S_MB_2U_LIB.S9S_MB_2U(SCH_1):PVCCIN_CPU1_VDD6

Q_CAP_C0402-100NF,50V,10%,X7R,A  I26  PC509
   1 SW_PVCCIN_CPU1_BOOT6_R      A @S9S_MB_2U_LIB.S9S_MB_2U(SCH_1):SW_PVCCIN_CPU1_BOOT6_R
   2 SW_PVCCIN_CPU1_BOOTR6      B @S9S_MB_2U_LIB.S9S_MB_2U(SCH_1):SW_PVCCIN_CPU1_BOOTR6

Q_RES_0402LF-0,5%,1/16W,CHIP,CA  I27  PR295
   1 PVCCIN_CPU1_VOS6      A @S9S_MB_2U_LIB.S9S_MB_2U(SCH_1):PVCCIN_CPU1_VOS6
   2 PVCCIN_CPU1      B @S9S_MB_2U_LIB.S9S_MB_2U(SCH_1):PVCCIN_CPU1

Q_RES_0402LF-3.3,1%,1/16W,CHIPA  I30  PR1790
   1 SW_PVCCIN_CPU1_BOOT6      A @S9S_MB_2U_LIB.S9S_MB_2U(SCH_1):SW_PVCCIN_CPU1_BOOT6
   2 SW_PVCCIN_CPU1_BOOT6_R      B @S9S_MB_2U_LIB.S9S_MB_2U(SCH_1):SW_PVCCIN_CPU1_BOOT6_R

Q_CAP_C0805-22UF,16V,20%,X6S,CA  I33  PC511_P1_6
   1 SW_P12V_PVCCIN_CPU1_FLT      A @S9S_MB_2U_LIB.S9S_MB_2U(SCH_1):SW_P12V_PVCCIN_CPU1_FLT
   2    GND      B @S9S_MB_2U_LIB.S9S_MB_2U(SCH_1):GND

Q_CAP_C0805-22UF,16V,20%,X6S,CA  I35  PC515_P1_6
   1 SW_P12V_PVCCIN_CPU1_FLT      A @S9S_MB_2U_LIB.S9S_MB_2U(SCH_1):SW_P12V_PVCCIN_CPU1_FLT
   2    GND      B @S9S_MB_2U_LIB.S9S_MB_2U(SCH_1):GND

Q_CAP_C0402-1UF,16V,10%,X6S,CHA  I46  PC508_P1_5
   1 SW_P12V_PVCCIN_CPU1_FLT      A @S9S_MB_2U_LIB.S9S_MB_2U(SCH_1):SW_P12V_PVCCIN_CPU1_FLT
   2    GND      B @S9S_MB_2U_LIB.S9S_MB_2U(SCH_1):GND

Q_CAP_C0805-22UF,16V,20%,X6S,CA  I51  PC514_P1_5
   1 SW_P12V_PVCCIN_CPU1_FLT      A @S9S_MB_2U_LIB.S9S_MB_2U(SCH_1):SW_P12V_PVCCIN_CPU1_FLT
   2    GND      B @S9S_MB_2U_LIB.S9S_MB_2U(SCH_1):GND

Q_CAP_C0805-22UF,16V,20%,X6S,CA  I52  PC516_P1_5
   1 SW_P12V_PVCCIN_CPU1_FLT      A @S9S_MB_2U_LIB.S9S_MB_2U(SCH_1):SW_P12V_PVCCIN_CPU1_FLT
   2    GND      B @S9S_MB_2U_LIB.S9S_MB_2U(SCH_1):GND

Q_CAP_C0805-22UF,4V,20%,X6S,CHA  I57  PC521_P1_6
   1 PVCCIN_CPU1      A @S9S_MB_2U_LIB.S9S_MB_2U(SCH_1):PVCCIN_CPU1
   2    GND      B @S9S_MB_2U_LIB.S9S_MB_2U(SCH_1):GND

Q_CAP_C0805-22UF,4V,20%,X6S,CHA  I64  PC520_P1_5
   1 PVCCIN_CPU1      A @S9S_MB_2U_LIB.S9S_MB_2U(SCH_1):PVCCIN_CPU1
   2    GND      B @S9S_MB_2U_LIB.S9S_MB_2U(SCH_1):GND

Q_CAP_C0805-22UF,4V,20%,X6S,CHA  I65  PC522_P1_5
   1 PVCCIN_CPU1      A @S9S_MB_2U_LIB.S9S_MB_2U(SCH_1):PVCCIN_CPU1
   2    GND      B @S9S_MB_2U_LIB.S9S_MB_2U(SCH_1):GND


DRAWING: @S9S_MB_2U_LIB.S9S_MB_2U(SCH_1):PAGE274 

Q_CAP_C0402-2.2UF,10V,10%,X6S,A  I9  PC479
   1 PVCCIN_CPU1_VDD8      A @S9S_MB_2U_LIB.S9S_MB_2U(SCH_1):PVCCIN_CPU1_VDD8
   2    GND      B @S9S_MB_2U_LIB.S9S_MB_2U(SCH_1):GND

Q_CAP_C0402-2.2UF,10V,10%,X6S,A  I18  PC481_P1_8
   1 PVCCIN_CPU1_PVCC      A @S9S_MB_2U_LIB.S9S_MB_2U(SCH_1):PVCCIN_CPU1_PVCC
   2    GND      B @S9S_MB_2U_LIB.S9S_MB_2U(SCH_1):GND

Q_RES_0402LF-3.3,1%,1/16W,CHIPA  I26  PR1792
   1 SW_PVCCIN_CPU1_BOOT8      A @S9S_MB_2U_LIB.S9S_MB_2U(SCH_1):SW_PVCCIN_CPU1_BOOT8
   2 SW_PVCCIN_CPU1_BOOT8_R      B @S9S_MB_2U_LIB.S9S_MB_2U(SCH_1):SW_PVCCIN_CPU1_BOOT8_R

Q_CAP_C0805-22UF,16V,20%,X6S,CA  I28  PC489_P1_8
   1 SW_P12V_PVCCIN_CPU1_FLT      A @S9S_MB_2U_LIB.S9S_MB_2U(SCH_1):SW_P12V_PVCCIN_CPU1_FLT
   2    GND      B @S9S_MB_2U_LIB.S9S_MB_2U(SCH_1):GND

Q_CAP_0402-0.1UF,25V,10%,X7R,CA  I32  PC1363
   1    GND      A @S9S_MB_2U_LIB.S9S_MB_2U(SCH_1):GND
   2 PVCCIN_CPU1_VREF      B @S9S_MB_2U_LIB.S9S_MB_2U(SCH_1):PVCCIN_CPU1_VREF

Q_CAP_C0402-2.2UF,10V,10%,X6S,A  I34  PC480
   1 PVCCIN_CPU1_VDD7      A @S9S_MB_2U_LIB.S9S_MB_2U(SCH_1):PVCCIN_CPU1_VDD7
   2    GND      B @S9S_MB_2U_LIB.S9S_MB_2U(SCH_1):GND

Q_CAP_0402-3300PF,50V,10%,X7R,A  I37  PC484_P1_7
   1 SW_P12V_PVCCIN_CPU1_FLT      A @S9S_MB_2U_LIB.S9S_MB_2U(SCH_1):SW_P12V_PVCCIN_CPU1_FLT
   2    GND      B @S9S_MB_2U_LIB.S9S_MB_2U(SCH_1):GND

Q_RES_0402LF-3.3,1%,1/16W,CHIPA  I39  PR1793
   1 SW_PVCCIN_CPU1_BOOT7      A @S9S_MB_2U_LIB.S9S_MB_2U(SCH_1):SW_PVCCIN_CPU1_BOOT7
   2 SW_PVCCIN_CPU1_BOOT7_R      B @S9S_MB_2U_LIB.S9S_MB_2U(SCH_1):SW_PVCCIN_CPU1_BOOT7_R

Q_CAP_C0402-1UF,16V,10%,X6S,CHA  I40  PC486_P1_7
   1 SW_P12V_PVCCIN_CPU1_FLT      A @S9S_MB_2U_LIB.S9S_MB_2U(SCH_1):SW_P12V_PVCCIN_CPU1_FLT
   2    GND      B @S9S_MB_2U_LIB.S9S_MB_2U(SCH_1):GND

Q_CAP_C0805-22UF,16V,20%,X6S,CA  I41  PC490_P1_7
   1 SW_P12V_PVCCIN_CPU1_FLT      A @S9S_MB_2U_LIB.S9S_MB_2U(SCH_1):SW_P12V_PVCCIN_CPU1_FLT
   2    GND      B @S9S_MB_2U_LIB.S9S_MB_2U(SCH_1):GND

Q_CAP_C0402-100NF,50V,10%,X7R,A  I42  PC487
   1 SW_PVCCIN_CPU1_BOOT8_R      A @S9S_MB_2U_LIB.S9S_MB_2U(SCH_1):SW_PVCCIN_CPU1_BOOT8_R
   2 SW_PVCCIN_CPU1_BOOTR8      B @S9S_MB_2U_LIB.S9S_MB_2U(SCH_1):SW_PVCCIN_CPU1_BOOTR8

Q_INDUCTOR4P_14-150NH,SMLF,INDA  I43  PL24
   2 IND_P1_CPL8      2 @S9S_MB_2U_LIB.S9S_MB_2U(SCH_1):IND_P1_CPL8
   3 IND_P1_CPL5      3 @S9S_MB_2U_LIB.S9S_MB_2U(SCH_1):IND_P1_CPL5
   4 PVCCIN_CPU1      4 @S9S_MB_2U_LIB.S9S_MB_2U(SCH_1):PVCCIN_CPU1
   1 SW_PVCCIN_CPU1_SW8      1 @S9S_MB_2U_LIB.S9S_MB_2U(SCH_1):SW_PVCCIN_CPU1_SW8

Q_RES_0402LF-0,5%,1/16W,CHIP,CA  I44  PR289
   1 PVCCIN_CPU1_VOS8      A @S9S_MB_2U_LIB.S9S_MB_2U(SCH_1):PVCCIN_CPU1_VOS8
   2 PVCCIN_CPU1      B @S9S_MB_2U_LIB.S9S_MB_2U(SCH_1):PVCCIN_CPU1

Q_CAP_C0805-22UF,16V,20%,X6S,CA  I46  PC491_P1_8
   1 SW_P12V_PVCCIN_CPU1_FLT      A @S9S_MB_2U_LIB.S9S_MB_2U(SCH_1):SW_P12V_PVCCIN_CPU1_FLT
   2    GND      B @S9S_MB_2U_LIB.S9S_MB_2U(SCH_1):GND

Q_CAP_C0805-22UF,16V,20%,X6S,CA  I47  PC493_P1_8
   1 SW_P12V_PVCCIN_CPU1_FLT      A @S9S_MB_2U_LIB.S9S_MB_2U(SCH_1):SW_P12V_PVCCIN_CPU1_FLT
   2    GND      B @S9S_MB_2U_LIB.S9S_MB_2U(SCH_1):GND

Q_CAP_C0402-1UF,16V,10%,X6S,CHA  I52  PC495_P1_8
   1 PVCCIN_CPU1      A @S9S_MB_2U_LIB.S9S_MB_2U(SCH_1):PVCCIN_CPU1
   2    GND      B @S9S_MB_2U_LIB.S9S_MB_2U(SCH_1):GND

Q_CAP_C0805-22UF,4V,20%,X6S,CHA  I53  PC497_P1_8
   1 PVCCIN_CPU1      A @S9S_MB_2U_LIB.S9S_MB_2U(SCH_1):PVCCIN_CPU1
   2    GND      B @S9S_MB_2U_LIB.S9S_MB_2U(SCH_1):GND

Q_CAP_C0805-22UF,4V,20%,X6S,CHA  I54  PC499_P1_8
   1 PVCCIN_CPU1      A @S9S_MB_2U_LIB.S9S_MB_2U(SCH_1):PVCCIN_CPU1
   2    GND      B @S9S_MB_2U_LIB.S9S_MB_2U(SCH_1):GND

Q_RES_0402LF-8.87K,1%,1/16W,EMA  I3  PR285
   1 PVCCIN_CPU1_LSET8      A @S9S_MB_2U_LIB.S9S_MB_2U(SCH_1):PVCCIN_CPU1_LSET8
   2    GND      B @S9S_MB_2U_LIB.S9S_MB_2U(SCH_1):GND

Q_CAP_0402-0.1UF,25V,10%,X7R,CA  I7  PC1362
   1    GND      A @S9S_MB_2U_LIB.S9S_MB_2U(SCH_1):GND
   2 PVCCIN_CPU1_VREF      B @S9S_MB_2U_LIB.S9S_MB_2U(SCH_1):PVCCIN_CPU1_VREF

ISL99390FRZTR5935-ISL99390FRZ-A  I11  PU23_P1_8
  34 PVCCIN_CPU1_PWM8    PWM @S9S_MB_2U_LIB.S9S_MB_2U(SCH_1):PVCCIN_CPU1_PWM8
  39 PVCCIN_CPU1_VREF  REFIN @S9S_MB_2U_LIB.S9S_MB_2U(SCH_1):PVCCIN_CPU1_VREF
   3 PVCCIN_CPU1_VDD8    VCC @S9S_MB_2U_LIB.S9S_MB_2U(SCH_1):PVCCIN_CPU1_VDD8
   2    GND   AGND @S9S_MB_2U_LIB.S9S_MB_2U(SCH_1):GND
  33 SW_PVCCIN_CPU1_BOOT8   BOOT @S9S_MB_2U_LIB.S9S_MB_2U(SCH_1):SW_PVCCIN_CPU1_BOOT8
25_29 SW_P12V_PVCCIN_CPU1_FLT   VIN1 @S9S_MB_2U_LIB.S9S_MB_2U(SCH_1):SW_P12V_PVCCIN_CPU1_FLT
  32 SW_PVCCIN_CPU1_BOOTR8  PHASE @S9S_MB_2U_LIB.S9S_MB_2U(SCH_1):SW_PVCCIN_CPU1_BOOTR8
   4 PVCCIN_CPU1_PVCC   PVCC @S9S_MB_2U_LIB.S9S_MB_2U(SCH_1):PVCCIN_CPU1_PVCC
  36 PVCCIN_CPU1_ATSEN TOUT_FLT @S9S_MB_2U_LIB.S9S_MB_2U(SCH_1):PVCCIN_CPU1_ATSEN
  38 PVCCIN_CPU1_IMON8   IOUT @S9S_MB_2U_LIB.S9S_MB_2U(SCH_1):PVCCIN_CPU1_IMON8
  37 PVCCIN_CPU1_LSET8   LSET @S9S_MB_2U_LIB.S9S_MB_2U(SCH_1):PVCCIN_CPU1_LSET8
10_19 SW_PVCCIN_CPU1_SW8     SW @S9S_MB_2U_LIB.S9S_MB_2U(SCH_1):SW_PVCCIN_CPU1_SW8
   5    GND  PGND1 @S9S_MB_2U_LIB.S9S_MB_2U(SCH_1):GND
  30 SW_P12V_PVCCIN_CPU1_FLT   VIN2 @S9S_MB_2U_LIB.S9S_MB_2U(SCH_1):SW_P12V_PVCCIN_CPU1_FLT
   1 PVCCIN_CPU1_VOS8    VOS @S9S_MB_2U_LIB.S9S_MB_2U(SCH_1):PVCCIN_CPU1_VOS8
  40    GND  PGND3 @S9S_MB_2U_LIB.S9S_MB_2U(SCH_1):GND
  35 PVCCIN_CPU1_VDD8     EN @S9S_MB_2U_LIB.S9S_MB_2U(SCH_1):PVCCIN_CPU1_VDD8
  31     NC    DNC     NC
   6     NC    GL1     NC
  41     NC    GL2     NC
7_9-20_24    GND  PGND2 @S9S_MB_2U_LIB.S9S_MB_2U(SCH_1):GND

Q_RES_0402LF-2.2,1%,1/16W,CHIPA  I12  PR287
   1 PVCCIN_CPU1_PVCC      A @S9S_MB_2U_LIB.S9S_MB_2U(SCH_1):PVCCIN_CPU1_PVCC
   2 PVCCIN_CPU1_VDD8      B @S9S_MB_2U_LIB.S9S_MB_2U(SCH_1):PVCCIN_CPU1_VDD8

Q_RES_0402LF-8.87K,1%,1/16W,EMA  I15  PR286
   1 PVCCIN_CPU1_LSET7      A @S9S_MB_2U_LIB.S9S_MB_2U(SCH_1):PVCCIN_CPU1_LSET7
   2    GND      B @S9S_MB_2U_LIB.S9S_MB_2U(SCH_1):GND

ISL99390FRZTR5935-ISL99390FRZ-A  I20  PU24_P1_7
  34 PVCCIN_CPU1_PWM7    PWM @S9S_MB_2U_LIB.S9S_MB_2U(SCH_1):PVCCIN_CPU1_PWM7
  39 PVCCIN_CPU1_VREF  REFIN @S9S_MB_2U_LIB.S9S_MB_2U(SCH_1):PVCCIN_CPU1_VREF
   3 PVCCIN_CPU1_VDD7    VCC @S9S_MB_2U_LIB.S9S_MB_2U(SCH_1):PVCCIN_CPU1_VDD7
   2    GND   AGND @S9S_MB_2U_LIB.S9S_MB_2U(SCH_1):GND
  33 SW_PVCCIN_CPU1_BOOT7   BOOT @S9S_MB_2U_LIB.S9S_MB_2U(SCH_1):SW_PVCCIN_CPU1_BOOT7
25_29 SW_P12V_PVCCIN_CPU1_FLT   VIN1 @S9S_MB_2U_LIB.S9S_MB_2U(SCH_1):SW_P12V_PVCCIN_CPU1_FLT
  32 SW_PVCCIN_CPU1_BOOTR7  PHASE @S9S_MB_2U_LIB.S9S_MB_2U(SCH_1):SW_PVCCIN_CPU1_BOOTR7
   4 PVCCIN_CPU1_PVCC   PVCC @S9S_MB_2U_LIB.S9S_MB_2U(SCH_1):PVCCIN_CPU1_PVCC
  36 PVCCIN_CPU1_ATSEN TOUT_FLT @S9S_MB_2U_LIB.S9S_MB_2U(SCH_1):PVCCIN_CPU1_ATSEN
  38 PVCCIN_CPU1_IMON7   IOUT @S9S_MB_2U_LIB.S9S_MB_2U(SCH_1):PVCCIN_CPU1_IMON7
  37 PVCCIN_CPU1_LSET7   LSET @S9S_MB_2U_LIB.S9S_MB_2U(SCH_1):PVCCIN_CPU1_LSET7
10_19 SW_PVCCIN_CPU1_SW7     SW @S9S_MB_2U_LIB.S9S_MB_2U(SCH_1):SW_PVCCIN_CPU1_SW7
   5    GND  PGND1 @S9S_MB_2U_LIB.S9S_MB_2U(SCH_1):GND
  30 SW_P12V_PVCCIN_CPU1_FLT   VIN2 @S9S_MB_2U_LIB.S9S_MB_2U(SCH_1):SW_P12V_PVCCIN_CPU1_FLT
   1 PVCCIN_CPU1_VOS7    VOS @S9S_MB_2U_LIB.S9S_MB_2U(SCH_1):PVCCIN_CPU1_VOS7
  40    GND  PGND3 @S9S_MB_2U_LIB.S9S_MB_2U(SCH_1):GND
  35 PVCCIN_CPU1_VDD7     EN @S9S_MB_2U_LIB.S9S_MB_2U(SCH_1):PVCCIN_CPU1_VDD7
  31     NC    DNC     NC
   6     NC    GL1     NC
  41     NC    GL2     NC
7_9-20_24    GND  PGND2 @S9S_MB_2U_LIB.S9S_MB_2U(SCH_1):GND

Q_INDUCTOR_SMLF-120NH/69A,IND,A  I23  PL106
   2    GND      2 @S9S_MB_2U_LIB.S9S_MB_2U(SCH_1):GND
   1 IND_P1_CPL8      1 @S9S_MB_2U_LIB.S9S_MB_2U(SCH_1):IND_P1_CPL8

Q_CAP_0402-3300PF,50V,10%,X7R,A  I24  PC483_P1_8
   1 SW_P12V_PVCCIN_CPU1_FLT      A @S9S_MB_2U_LIB.S9S_MB_2U(SCH_1):SW_P12V_PVCCIN_CPU1_FLT
   2    GND      B @S9S_MB_2U_LIB.S9S_MB_2U(SCH_1):GND

Q_CAP_C0402-1UF,16V,10%,X6S,CHA  I27  PC485_P1_8
   1 SW_P12V_PVCCIN_CPU1_FLT      A @S9S_MB_2U_LIB.S9S_MB_2U(SCH_1):SW_P12V_PVCCIN_CPU1_FLT
   2    GND      B @S9S_MB_2U_LIB.S9S_MB_2U(SCH_1):GND

Q_RES_0402LF-0,5%,1/16W,CHIP,CA  I50  PR290
   1 PVCCIN_CPU1_VOS7      A @S9S_MB_2U_LIB.S9S_MB_2U(SCH_1):PVCCIN_CPU1_VOS7
   2 PVCCIN_CPU1      B @S9S_MB_2U_LIB.S9S_MB_2U(SCH_1):PVCCIN_CPU1

Q_INDUCTOR4P_14-150NH,SMLF,INDA  I58  PL25
   2 IND_P1_CPL7      2 @S9S_MB_2U_LIB.S9S_MB_2U(SCH_1):IND_P1_CPL7
   3    GND      3 @S9S_MB_2U_LIB.S9S_MB_2U(SCH_1):GND
   4 PVCCIN_CPU1      4 @S9S_MB_2U_LIB.S9S_MB_2U(SCH_1):PVCCIN_CPU1
   1 SW_PVCCIN_CPU1_SW7      1 @S9S_MB_2U_LIB.S9S_MB_2U(SCH_1):SW_PVCCIN_CPU1_SW7

Q_CAP_C0402-100NF,50V,10%,X7R,A  I59  PC488
   1 SW_PVCCIN_CPU1_BOOT7_R      A @S9S_MB_2U_LIB.S9S_MB_2U(SCH_1):SW_PVCCIN_CPU1_BOOT7_R
   2 SW_PVCCIN_CPU1_BOOTR7      B @S9S_MB_2U_LIB.S9S_MB_2U(SCH_1):SW_PVCCIN_CPU1_BOOTR7

Q_CAP_C0805-22UF,16V,20%,X6S,CA  I61  PC492_P1_7
   1 SW_P12V_PVCCIN_CPU1_FLT      A @S9S_MB_2U_LIB.S9S_MB_2U(SCH_1):SW_P12V_PVCCIN_CPU1_FLT
   2    GND      B @S9S_MB_2U_LIB.S9S_MB_2U(SCH_1):GND

Q_CAP_C0805-22UF,16V,20%,X6S,CA  I62  PC494_P1_7
   1 SW_P12V_PVCCIN_CPU1_FLT      A @S9S_MB_2U_LIB.S9S_MB_2U(SCH_1):SW_P12V_PVCCIN_CPU1_FLT
   2    GND      B @S9S_MB_2U_LIB.S9S_MB_2U(SCH_1):GND

Q_CAP_C0402-1UF,16V,10%,X6S,CHA  I64  PC496_P1_7
   1 PVCCIN_CPU1      A @S9S_MB_2U_LIB.S9S_MB_2U(SCH_1):PVCCIN_CPU1
   2    GND      B @S9S_MB_2U_LIB.S9S_MB_2U(SCH_1):GND

Q_CAP_C0805-22UF,4V,20%,X6S,CHA  I65  PC498_P1_7
   1 PVCCIN_CPU1      A @S9S_MB_2U_LIB.S9S_MB_2U(SCH_1):PVCCIN_CPU1
   2    GND      B @S9S_MB_2U_LIB.S9S_MB_2U(SCH_1):GND

Q_CAP_C0805-22UF,4V,20%,X6S,CHA  I66  PC500_P1_7
   1 PVCCIN_CPU1      A @S9S_MB_2U_LIB.S9S_MB_2U(SCH_1):PVCCIN_CPU1
   2    GND      B @S9S_MB_2U_LIB.S9S_MB_2U(SCH_1):GND

Q_RES_0402LF-2.2,1%,1/16W,CHIPA  I68  PR288
   1 PVCCIN_CPU1_PVCC      A @S9S_MB_2U_LIB.S9S_MB_2U(SCH_1):PVCCIN_CPU1_PVCC
   2 PVCCIN_CPU1_VDD7      B @S9S_MB_2U_LIB.S9S_MB_2U(SCH_1):PVCCIN_CPU1_VDD7

Q_CAP_C0402-2.2UF,10V,10%,X6S,A  I69  PC482_P1_7
   1 PVCCIN_CPU1_PVCC      A @S9S_MB_2U_LIB.S9S_MB_2U(SCH_1):PVCCIN_CPU1_PVCC
   2    GND      B @S9S_MB_2U_LIB.S9S_MB_2U(SCH_1):GND


DRAWING: @S9S_MB_2U_LIB.S9S_MB_2U(SCH_1):PAGE276 

Q_RES_0402LF-8.87K,1%,1/16W,EMA  I2  PR1304
   1 PVCCFA_EHV_FIVRA_CPU1_LSET4      A @S9S_MB_2U_LIB.S9S_MB_2U(SCH_1):PVCCFA_EHV_FIVRA_CPU1_LSET4
   2    GND      B @S9S_MB_2U_LIB.S9S_MB_2U(SCH_1):GND

Q_CAP_0402-3300PF,50V,10%,X7R,A  I33  PC1194_P1_4
   1 SW_P12V_PVCCFA_EHV_FIVRA_CPU1_L      A @S9S_MB_2U_LIB.S9S_MB_2U(SCH_1):SW_P12V_PVCCFA_EHV_FIVRA_CPU1_L
   2    GND      B @S9S_MB_2U_LIB.S9S_MB_2U(SCH_1):GND

Q_CAP_C0805-22UF,16V,20%,X6S,CA  I36  PC1200_P1_4
   1 SW_P12V_PVCCFA_EHV_FIVRA_CPU1_L      A @S9S_MB_2U_LIB.S9S_MB_2U(SCH_1):SW_P12V_PVCCFA_EHV_FIVRA_CPU1_L
   2    GND      B @S9S_MB_2U_LIB.S9S_MB_2U(SCH_1):GND

Q_RES_0402LF-3.3,1%,1/16W,CHIPA  I40  PR1802
   1 SW_PVCCFA_EHV_FIVRA_CPU1_BOOT3      A @S9S_MB_2U_LIB.S9S_MB_2U(SCH_1):SW_PVCCFA_EHV_FIVRA_CPU1_BOOT3
   2 SW_PVCCFA_EHV_FIVRA_CPU1_BOOT3_      B @S9S_MB_2U_LIB.S9S_MB_2U(SCH_1):SW_PVCCFA_EHV_FIVRA_CPU1_BOOT3_R

Q_INDUCTOR_SMLF-130NH/106A,INDA  I44  PL113
   2 PVCCFA_EHV_FIVRA_CPU1      2 @S9S_MB_2U_LIB.S9S_MB_2U(SCH_1):PVCCFA_EHV_FIVRA_CPU1
   1 SW_PVCCFA_EHV_FIVRA_CPU1_SW4      1 @S9S_MB_2U_LIB.S9S_MB_2U(SCH_1):SW_PVCCFA_EHV_FIVRA_CPU1_SW4

Q_CAP_C0402-100NF,50V,10%,X7R,A  I45  PC1198
   1 SW_PVCCFA_EHV_FIVRA_CPU1_BOOT4_      A @S9S_MB_2U_LIB.S9S_MB_2U(SCH_1):SW_PVCCFA_EHV_FIVRA_CPU1_BOOT4_R
   2 SW_PVCCFA_EHV_FIVRA_CPU1_BOOTR4      B @S9S_MB_2U_LIB.S9S_MB_2U(SCH_1):SW_PVCCFA_EHV_FIVRA_CPU1_BOOTR4

Q_CAPP_THLF-560UF,2.5V,20%,OSCA  I55  PC1201
   1 PVCCFA_EHV_FIVRA_CPU1      A @S9S_MB_2U_LIB.S9S_MB_2U(SCH_1):PVCCFA_EHV_FIVRA_CPU1
   2    GND      B @S9S_MB_2U_LIB.S9S_MB_2U(SCH_1):GND

Q_CAP_C0402-1UF,16V,10%,X6S,CHA  I56  PC1204_P1_3
   1 PVCCFA_EHV_FIVRA_CPU1      A @S9S_MB_2U_LIB.S9S_MB_2U(SCH_1):PVCCFA_EHV_FIVRA_CPU1
   2    GND      B @S9S_MB_2U_LIB.S9S_MB_2U(SCH_1):GND

Q_CAPP_THLF-560UF,2.5V,20%,OSCA  I67  PC1203
   1 PVCCFA_EHV_FIVRA_CPU1      A @S9S_MB_2U_LIB.S9S_MB_2U(SCH_1):PVCCFA_EHV_FIVRA_CPU1
   2    GND      B @S9S_MB_2U_LIB.S9S_MB_2U(SCH_1):GND

Q_CAP_C0805-22UF,4V,20%,X6S,CHA  I68  PC1208_P1_3
   1 PVCCFA_EHV_FIVRA_CPU1      A @S9S_MB_2U_LIB.S9S_MB_2U(SCH_1):PVCCFA_EHV_FIVRA_CPU1
   2    GND      B @S9S_MB_2U_LIB.S9S_MB_2U(SCH_1):GND

Q_CAP_C0805-22UF,16V,20%,X6S,CA  I77  PC1682
   1 SW_P12V_PVCCFA_EHV_FIVRA_CPU1_R      A @S9S_MB_2U_LIB.S9S_MB_2U(SCH_1):SW_P12V_PVCCFA_EHV_FIVRA_CPU1_R
   2    GND      B @S9S_MB_2U_LIB.S9S_MB_2U(SCH_1):GND

Q_CAP_0402-3300PF,50V,10%,X7R,A  I38  PC1193_P1_3
   1 SW_P12V_PVCCFA_EHV_FIVRA_CPU1_R      A @S9S_MB_2U_LIB.S9S_MB_2U(SCH_1):SW_P12V_PVCCFA_EHV_FIVRA_CPU1_R
   2    GND      B @S9S_MB_2U_LIB.S9S_MB_2U(SCH_1):GND

Q_CAP_C0805-22UF,16V,20%,X6S,CA  I41  PC1199_P1_3
   1 SW_P12V_PVCCFA_EHV_FIVRA_CPU1_R      A @S9S_MB_2U_LIB.S9S_MB_2U(SCH_1):SW_P12V_PVCCFA_EHV_FIVRA_CPU1_R
   2    GND      B @S9S_MB_2U_LIB.S9S_MB_2U(SCH_1):GND

Q_INDUCTOR_SMLF-130NH/106A,INDA  I57  PL12
   2 PVCCFA_EHV_FIVRA_CPU1      2 @S9S_MB_2U_LIB.S9S_MB_2U(SCH_1):PVCCFA_EHV_FIVRA_CPU1
   1 SW_PVCCFA_EHV_FIVRA_CPU1_SW3      1 @S9S_MB_2U_LIB.S9S_MB_2U(SCH_1):SW_PVCCFA_EHV_FIVRA_CPU1_SW3

ISL99390FRZTR5935-ISL99390FRZ-A  I15  PU78_P1_4
  34 PVCCFA_EHV_FIVRA_CPU1_PWM4    PWM @S9S_MB_2U_LIB.S9S_MB_2U(SCH_1):PVCCFA_EHV_FIVRA_CPU1_PWM4
  39 PVCCIN_CPU1_VREF  REFIN @S9S_MB_2U_LIB.S9S_MB_2U(SCH_1):PVCCIN_CPU1_VREF
   3 PVCCFA_EHV_FIVRA_CPU1_VDD4    VCC @S9S_MB_2U_LIB.S9S_MB_2U(SCH_1):PVCCFA_EHV_FIVRA_CPU1_VDD4
   2    GND   AGND @S9S_MB_2U_LIB.S9S_MB_2U(SCH_1):GND
  33 SW_PVCCFA_EHV_FIVRA_CPU1_BOOT4   BOOT @S9S_MB_2U_LIB.S9S_MB_2U(SCH_1):SW_PVCCFA_EHV_FIVRA_CPU1_BOOT4
25_29 SW_P12V_PVCCFA_EHV_FIVRA_CPU1_L   VIN1 @S9S_MB_2U_LIB.S9S_MB_2U(SCH_1):SW_P12V_PVCCFA_EHV_FIVRA_CPU1_L
  32 SW_PVCCFA_EHV_FIVRA_CPU1_BOOTR4  PHASE @S9S_MB_2U_LIB.S9S_MB_2U(SCH_1):SW_PVCCFA_EHV_FIVRA_CPU1_BOOTR4
   4 PVCCFA_EHV_FIVRA_CPU1_PVCC2   PVCC @S9S_MB_2U_LIB.S9S_MB_2U(SCH_1):PVCCFA_EHV_FIVRA_CPU1_PVCC2
  36 PVCCFA_EHV_FIVRA_CPU1_BTSEN TOUT_FLT @S9S_MB_2U_LIB.S9S_MB_2U(SCH_1):PVCCFA_EHV_FIVRA_CPU1_BTSEN
  38 PVCCFA_EHV_FIVRA_CPU1_IMON4   IOUT @S9S_MB_2U_LIB.S9S_MB_2U(SCH_1):PVCCFA_EHV_FIVRA_CPU1_IMON4
  37 PVCCFA_EHV_FIVRA_CPU1_LSET4   LSET @S9S_MB_2U_LIB.S9S_MB_2U(SCH_1):PVCCFA_EHV_FIVRA_CPU1_LSET4
10_19 SW_PVCCFA_EHV_FIVRA_CPU1_SW4     SW @S9S_MB_2U_LIB.S9S_MB_2U(SCH_1):SW_PVCCFA_EHV_FIVRA_CPU1_SW4
   5    GND  PGND1 @S9S_MB_2U_LIB.S9S_MB_2U(SCH_1):GND
  30 SW_P12V_PVCCFA_EHV_FIVRA_CPU1_L   VIN2 @S9S_MB_2U_LIB.S9S_MB_2U(SCH_1):SW_P12V_PVCCFA_EHV_FIVRA_CPU1_L
   1 PVCCFA_EHV_FIVRA_CPU1_VOS4    VOS @S9S_MB_2U_LIB.S9S_MB_2U(SCH_1):PVCCFA_EHV_FIVRA_CPU1_VOS4
  40    GND  PGND3 @S9S_MB_2U_LIB.S9S_MB_2U(SCH_1):GND
  35 PVCCFA_EHV_FIVRA_CPU1_VDD4     EN @S9S_MB_2U_LIB.S9S_MB_2U(SCH_1):PVCCFA_EHV_FIVRA_CPU1_VDD4
  31     NC    DNC     NC
   6     NC    GL1     NC
  41     NC    GL2     NC
7_9-20_24    GND  PGND2 @S9S_MB_2U_LIB.S9S_MB_2U(SCH_1):GND

Q_RES_0402LF-2.2,1%,1/16W,CHIPA  I18  PR1307
   1 PVCCFA_EHV_FIVRA_CPU1_PVCC2      A @S9S_MB_2U_LIB.S9S_MB_2U(SCH_1):PVCCFA_EHV_FIVRA_CPU1_PVCC2
   2 PVCCFA_EHV_FIVRA_CPU1_VDD4      B @S9S_MB_2U_LIB.S9S_MB_2U(SCH_1):PVCCFA_EHV_FIVRA_CPU1_VDD4

Q_CAP_C0402-2.2UF,10V,10%,X6S,A  I27  PC1191
   1 PVCCFA_EHV_FIVRA_CPU1_VDD3      A @S9S_MB_2U_LIB.S9S_MB_2U(SCH_1):PVCCFA_EHV_FIVRA_CPU1_VDD3
   2    GND      B @S9S_MB_2U_LIB.S9S_MB_2U(SCH_1):GND

Q_CAP_C0805-22UF,16V,20%,X6S,CA  I37  PC1202_P1_4
   1 SW_P12V_PVCCFA_EHV_FIVRA_CPU1_L      A @S9S_MB_2U_LIB.S9S_MB_2U(SCH_1):SW_P12V_PVCCFA_EHV_FIVRA_CPU1_L
   2    GND      B @S9S_MB_2U_LIB.S9S_MB_2U(SCH_1):GND

Q_CAP_C0402-1UF,16V,10%,X6S,CHA  I39  PC1195_P1_3
   1 SW_P12V_PVCCFA_EHV_FIVRA_CPU1_R      A @S9S_MB_2U_LIB.S9S_MB_2U(SCH_1):SW_P12V_PVCCFA_EHV_FIVRA_CPU1_R
   2    GND      B @S9S_MB_2U_LIB.S9S_MB_2U(SCH_1):GND

Q_CAP_C0805-22UF,16V,20%,X6S,CA  I42  PC1201_P1_3
   1 SW_P12V_PVCCFA_EHV_FIVRA_CPU1_R      A @S9S_MB_2U_LIB.S9S_MB_2U(SCH_1):SW_P12V_PVCCFA_EHV_FIVRA_CPU1_R
   2    GND      B @S9S_MB_2U_LIB.S9S_MB_2U(SCH_1):GND

Q_INDUCTOR_SMLF-100NH/16A,IND,A  I64  PL14
   2 SW_P12V_PVCCFA_EHV_FIVRA_CPU1_R      2 @S9S_MB_2U_LIB.S9S_MB_2U(SCH_1):SW_P12V_PVCCFA_EHV_FIVRA_CPU1_R
   1 P12V_AUX      1 @S9S_MB_2U_LIB.S9S_MB_2U(SCH_1):P12V_AUX

Q_CAP_C0805-22UF,4V,20%,X6S,CHA  I66  PC1206_P1_3
   1 PVCCFA_EHV_FIVRA_CPU1      A @S9S_MB_2U_LIB.S9S_MB_2U(SCH_1):PVCCFA_EHV_FIVRA_CPU1
   2    GND      B @S9S_MB_2U_LIB.S9S_MB_2U(SCH_1):GND

Q_CAP_C0805-22UF,16V,20%,X6S,CA  I80  PC1684
   1 SW_P12V_PVCCFA_EHV_FIVRA_CPU1_R      A @S9S_MB_2U_LIB.S9S_MB_2U(SCH_1):SW_P12V_PVCCFA_EHV_FIVRA_CPU1_R
   2    GND      B @S9S_MB_2U_LIB.S9S_MB_2U(SCH_1):GND

Q_CAP_0402-0.1UF,25V,10%,X7R,CA  I23  PC1369
   1    GND      A @S9S_MB_2U_LIB.S9S_MB_2U(SCH_1):GND
   2 PVCCIN_CPU1_VREF      B @S9S_MB_2U_LIB.S9S_MB_2U(SCH_1):PVCCIN_CPU1_VREF

ISL99390FRZTR5935-ISL99390FRZ-A  I24  PU77_P1_3
  34 PVCCFA_EHV_FIVRA_CPU1_PWM3    PWM @S9S_MB_2U_LIB.S9S_MB_2U(SCH_1):PVCCFA_EHV_FIVRA_CPU1_PWM3
  39 PVCCIN_CPU1_VREF  REFIN @S9S_MB_2U_LIB.S9S_MB_2U(SCH_1):PVCCIN_CPU1_VREF
   3 PVCCFA_EHV_FIVRA_CPU1_VDD3    VCC @S9S_MB_2U_LIB.S9S_MB_2U(SCH_1):PVCCFA_EHV_FIVRA_CPU1_VDD3
   2    GND   AGND @S9S_MB_2U_LIB.S9S_MB_2U(SCH_1):GND
  33 SW_PVCCFA_EHV_FIVRA_CPU1_BOOT3   BOOT @S9S_MB_2U_LIB.S9S_MB_2U(SCH_1):SW_PVCCFA_EHV_FIVRA_CPU1_BOOT3
25_29 SW_P12V_PVCCFA_EHV_FIVRA_CPU1_R   VIN1 @S9S_MB_2U_LIB.S9S_MB_2U(SCH_1):SW_P12V_PVCCFA_EHV_FIVRA_CPU1_R
  32 SW_PVCCFA_EHV_FIVRA_CPU1_BOOTR3  PHASE @S9S_MB_2U_LIB.S9S_MB_2U(SCH_1):SW_PVCCFA_EHV_FIVRA_CPU1_BOOTR3
   4 PVCCFA_EHV_FIVRA_CPU1_PVCC1   PVCC @S9S_MB_2U_LIB.S9S_MB_2U(SCH_1):PVCCFA_EHV_FIVRA_CPU1_PVCC1
  36 PVCCFA_EHV_FIVRA_CPU1_BTSEN TOUT_FLT @S9S_MB_2U_LIB.S9S_MB_2U(SCH_1):PVCCFA_EHV_FIVRA_CPU1_BTSEN
  38 PVCCFA_EHV_FIVRA_CPU1_IMON3   IOUT @S9S_MB_2U_LIB.S9S_MB_2U(SCH_1):PVCCFA_EHV_FIVRA_CPU1_IMON3
  37 PVCCFA_EHV_FIVRA_CPU1_LSET3   LSET @S9S_MB_2U_LIB.S9S_MB_2U(SCH_1):PVCCFA_EHV_FIVRA_CPU1_LSET3
10_19 SW_PVCCFA_EHV_FIVRA_CPU1_SW3     SW @S9S_MB_2U_LIB.S9S_MB_2U(SCH_1):SW_PVCCFA_EHV_FIVRA_CPU1_SW3
   5    GND  PGND1 @S9S_MB_2U_LIB.S9S_MB_2U(SCH_1):GND
  30 SW_P12V_PVCCFA_EHV_FIVRA_CPU1_R   VIN2 @S9S_MB_2U_LIB.S9S_MB_2U(SCH_1):SW_P12V_PVCCFA_EHV_FIVRA_CPU1_R
   1 PVCCFA_EHV_FIVRA_CPU1_VOS3    VOS @S9S_MB_2U_LIB.S9S_MB_2U(SCH_1):PVCCFA_EHV_FIVRA_CPU1_VOS3
  40    GND  PGND3 @S9S_MB_2U_LIB.S9S_MB_2U(SCH_1):GND
  35 PVCCFA_EHV_FIVRA_CPU1_VDD3     EN @S9S_MB_2U_LIB.S9S_MB_2U(SCH_1):PVCCFA_EHV_FIVRA_CPU1_VDD3
  31     NC    DNC     NC
   6     NC    GL1     NC
  41     NC    GL2     NC
7_9-20_24    GND  PGND2 @S9S_MB_2U_LIB.S9S_MB_2U(SCH_1):GND

Q_CAP_C0402-2.2UF,10V,10%,X6S,A  I31  PC1244_P1_3
   1 PVCCFA_EHV_FIVRA_CPU1_PVCC1      A @S9S_MB_2U_LIB.S9S_MB_2U(SCH_1):PVCCFA_EHV_FIVRA_CPU1_PVCC1
   2    GND      B @S9S_MB_2U_LIB.S9S_MB_2U(SCH_1):GND

Q_CAP_C0402-1UF,16V,10%,X6S,CHA  I35  PC1196_P1_4
   1 SW_P12V_PVCCFA_EHV_FIVRA_CPU1_L      A @S9S_MB_2U_LIB.S9S_MB_2U(SCH_1):SW_P12V_PVCCFA_EHV_FIVRA_CPU1_L
   2    GND      B @S9S_MB_2U_LIB.S9S_MB_2U(SCH_1):GND

Q_CAP_C0805-22UF,4V,20%,X6S,CHA  I50  PC1209_P1_4
   1 PVCCFA_EHV_FIVRA_CPU1      A @S9S_MB_2U_LIB.S9S_MB_2U(SCH_1):PVCCFA_EHV_FIVRA_CPU1
   2    GND      B @S9S_MB_2U_LIB.S9S_MB_2U(SCH_1):GND

Q_CAP_C0805-22UF,16V,20%,X6S,CA  I52  PC727_P1_4
   1 SW_P12V_PVCCFA_EHV_FIVRA_CPU1_L      A @S9S_MB_2U_LIB.S9S_MB_2U(SCH_1):SW_P12V_PVCCFA_EHV_FIVRA_CPU1_L
   2    GND      B @S9S_MB_2U_LIB.S9S_MB_2U(SCH_1):GND

Q_RES_0402LF-0,5%,1/16W,CHIP,CA  I54  PR1333
   1 PVCCFA_EHV_FIVRA_CPU1_VOS3      A @S9S_MB_2U_LIB.S9S_MB_2U(SCH_1):PVCCFA_EHV_FIVRA_CPU1_VOS3
   2 PVCCFA_EHV_FIVRA_CPU1      B @S9S_MB_2U_LIB.S9S_MB_2U(SCH_1):PVCCFA_EHV_FIVRA_CPU1

Q_CAPP_THLF-560UF,2.5V,20%,OSCA  I70  PC1204
   1 PVCCFA_EHV_FIVRA_CPU1      A @S9S_MB_2U_LIB.S9S_MB_2U(SCH_1):PVCCFA_EHV_FIVRA_CPU1
   2    GND      B @S9S_MB_2U_LIB.S9S_MB_2U(SCH_1):GND

Q_CAPP_SMLF-330UF,2.5V,+10/-35B  I72  PC1205
   1 PVCCFA_EHV_FIVRA_CPU1      A @S9S_MB_2U_LIB.S9S_MB_2U(SCH_1):PVCCFA_EHV_FIVRA_CPU1
   2    GND      B @S9S_MB_2U_LIB.S9S_MB_2U(SCH_1):GND

Q_RES_0402LF-8.87K,1%,1/16W,EMA  I5  PR1305
   1 PVCCFA_EHV_FIVRA_CPU1_LSET3      A @S9S_MB_2U_LIB.S9S_MB_2U(SCH_1):PVCCFA_EHV_FIVRA_CPU1_LSET3
   2    GND      B @S9S_MB_2U_LIB.S9S_MB_2U(SCH_1):GND

Q_CAP_C0402-2.2UF,10V,10%,X6S,A  I12  PC1192
   1 PVCCFA_EHV_FIVRA_CPU1_VDD4      A @S9S_MB_2U_LIB.S9S_MB_2U(SCH_1):PVCCFA_EHV_FIVRA_CPU1_VDD4
   2    GND      B @S9S_MB_2U_LIB.S9S_MB_2U(SCH_1):GND

Q_CAP_0402-0.1UF,25V,10%,X7R,CA  I13  PC1370
   1    GND      A @S9S_MB_2U_LIB.S9S_MB_2U(SCH_1):GND
   2 PVCCIN_CPU1_VREF      B @S9S_MB_2U_LIB.S9S_MB_2U(SCH_1):PVCCIN_CPU1_VREF

Q_RES_0402LF-3.3,1%,1/16W,CHIPA  I17  PR1803
   1 SW_PVCCFA_EHV_FIVRA_CPU1_BOOT4      A @S9S_MB_2U_LIB.S9S_MB_2U(SCH_1):SW_PVCCFA_EHV_FIVRA_CPU1_BOOT4
   2 SW_PVCCFA_EHV_FIVRA_CPU1_BOOT4_      B @S9S_MB_2U_LIB.S9S_MB_2U(SCH_1):SW_PVCCFA_EHV_FIVRA_CPU1_BOOT4_R

Q_CAP_C0402-2.2UF,10V,10%,X6S,A  I20  PC1245_P1_4
   1 PVCCFA_EHV_FIVRA_CPU1_PVCC2      A @S9S_MB_2U_LIB.S9S_MB_2U(SCH_1):PVCCFA_EHV_FIVRA_CPU1_PVCC2
   2    GND      B @S9S_MB_2U_LIB.S9S_MB_2U(SCH_1):GND

Q_RES_0402LF-2.2,1%,1/16W,CHIPA  I29  PR1306
   1 PVCCFA_EHV_FIVRA_CPU1_PVCC1      A @S9S_MB_2U_LIB.S9S_MB_2U(SCH_1):PVCCFA_EHV_FIVRA_CPU1_PVCC1
   2 PVCCFA_EHV_FIVRA_CPU1_VDD3      B @S9S_MB_2U_LIB.S9S_MB_2U(SCH_1):PVCCFA_EHV_FIVRA_CPU1_VDD3

Q_RES_0402LF-0,5%,1/16W,CHIP,CA  I43  PR1334
   1 PVCCFA_EHV_FIVRA_CPU1_VOS4      A @S9S_MB_2U_LIB.S9S_MB_2U(SCH_1):PVCCFA_EHV_FIVRA_CPU1_VOS4
   2 PVCCFA_EHV_FIVRA_CPU1      B @S9S_MB_2U_LIB.S9S_MB_2U(SCH_1):PVCCFA_EHV_FIVRA_CPU1

Q_CAP_C0402-100NF,50V,10%,X7R,A  I47  PC1203_P1_4
   1 PVCCFA_EHV_FIVRA_CPU1      A @S9S_MB_2U_LIB.S9S_MB_2U(SCH_1):PVCCFA_EHV_FIVRA_CPU1
   2    GND      B @S9S_MB_2U_LIB.S9S_MB_2U(SCH_1):GND

Q_CAP_C0805-22UF,4V,20%,X6S,CHA  I48  PC1207_P1_4
   1 PVCCFA_EHV_FIVRA_CPU1      A @S9S_MB_2U_LIB.S9S_MB_2U(SCH_1):PVCCFA_EHV_FIVRA_CPU1
   2    GND      B @S9S_MB_2U_LIB.S9S_MB_2U(SCH_1):GND

Q_CAP_C0402-100NF,50V,10%,X7R,A  I58  PC1197
   1 SW_PVCCFA_EHV_FIVRA_CPU1_BOOT3_      A @S9S_MB_2U_LIB.S9S_MB_2U(SCH_1):SW_PVCCFA_EHV_FIVRA_CPU1_BOOT3_R
   2 SW_PVCCFA_EHV_FIVRA_CPU1_BOOTR3      B @S9S_MB_2U_LIB.S9S_MB_2U(SCH_1):SW_PVCCFA_EHV_FIVRA_CPU1_BOOTR3

Q_CAP_C0805-22UF,16V,20%,X6S,CA  I60  PC726_P1_3
   1 SW_P12V_PVCCFA_EHV_FIVRA_CPU1_R      A @S9S_MB_2U_LIB.S9S_MB_2U(SCH_1):SW_P12V_PVCCFA_EHV_FIVRA_CPU1_R
   2    GND      B @S9S_MB_2U_LIB.S9S_MB_2U(SCH_1):GND

Q_CAP_C0402-100NF,50V,10%,X7R,A  I62  PC1658
   1 P12V_AUX      A @S9S_MB_2U_LIB.S9S_MB_2U(SCH_1):P12V_AUX
   2    GND      B @S9S_MB_2U_LIB.S9S_MB_2U(SCH_1):GND

Q_CAPP_SMLF-330UF,2.5V,+10/-35B  I73  PC2171
   1 PVCCFA_EHV_FIVRA_CPU1      A @S9S_MB_2U_LIB.S9S_MB_2U(SCH_1):PVCCFA_EHV_FIVRA_CPU1
   2    GND      B @S9S_MB_2U_LIB.S9S_MB_2U(SCH_1):GND

Q_CAP_C0805-22UF,16V,20%,X6S,CA  I75  PC1681
   1 SW_P12V_PVCCFA_EHV_FIVRA_CPU1_R      A @S9S_MB_2U_LIB.S9S_MB_2U(SCH_1):SW_P12V_PVCCFA_EHV_FIVRA_CPU1_R
   2    GND      B @S9S_MB_2U_LIB.S9S_MB_2U(SCH_1):GND

Q_CAP_C0805-22UF,16V,20%,X6S,CA  I78  PC1683
   1 SW_P12V_PVCCFA_EHV_FIVRA_CPU1_R      A @S9S_MB_2U_LIB.S9S_MB_2U(SCH_1):SW_P12V_PVCCFA_EHV_FIVRA_CPU1_R
   2    GND      B @S9S_MB_2U_LIB.S9S_MB_2U(SCH_1):GND

Q_CAPP_THLF-270UF,16V,20%,OSCOA  I81  PC1210
   1 SW_P12V_PVCCFA_EHV_FIVRA_CPU1_R      A @S9S_MB_2U_LIB.S9S_MB_2U(SCH_1):SW_P12V_PVCCFA_EHV_FIVRA_CPU1_R
   2    GND      B @S9S_MB_2U_LIB.S9S_MB_2U(SCH_1):GND


DRAWING: @S9S_MB_2U_LIB.S9S_MB_2U(SCH_1):PAGE278 

Q_RES_0402LF-0,5%,1/16W,EMPTY,A  I22  PR260
   1 P12V_AUX      A @S9S_MB_2U_LIB.S9S_MB_2U(SCH_1):P12V_AUX
   2 PVCCINFAON_CPU1_CSPIN      B @S9S_MB_2U_LIB.S9S_MB_2U(SCH_1):PVCCINFAON_CPU1_CSPIN

Q_RES_0402LF-0,5%,1/16W,CHIP,CA  I26  PR275
   1 PVCCINFAON_CPU1_CSPIN      A @S9S_MB_2U_LIB.S9S_MB_2U(SCH_1):PVCCINFAON_CPU1_CSPIN
   2    GND      B @S9S_MB_2U_LIB.S9S_MB_2U(SCH_1):GND

Q_CAP_0402-3300PF,50V,10%,X7R,A  I51  PC469
   1 SH_PVCCFA_EHV_CPU1_R      A @S9S_MB_2U_LIB.S9S_MB_2U(SCH_1):SH_PVCCFA_EHV_CPU1_R
   2 VSENSE_PVCCFA_EHV_CPU1_DN      B @S9S_MB_2U_LIB.S9S_MB_2U(SCH_1):VSENSE_PVCCFA_EHV_CPU1_DN

Q_RES_0402LF-0,5%,1/16W,CHIP,CA  I52  PR274
   1 SH_PVCCFA_EHV_CPU1      A @S9S_MB_2U_LIB.S9S_MB_2U(SCH_1):SH_PVCCFA_EHV_CPU1
   2 SH_PVCCFA_EHV_CPU1_R      B @S9S_MB_2U_LIB.S9S_MB_2U(SCH_1):SH_PVCCFA_EHV_CPU1_R

Q_SHORT_SM-EMPTY,SHORT6  I54  PJ50
   1 VSENSE_PVCCINFAON_CPU1_DP      1 @S9S_MB_2U_LIB.S9S_MB_2U(SCH_1):VSENSE_PVCCINFAON_CPU1_DP
   2 SH_PVCCINFAON_CPU1      2 @S9S_MB_2U_LIB.S9S_MB_2U(SCH_1):SH_PVCCINFAON_CPU1

Q_RES_0402LF-0,5%,1/16W,CHIP,CA  I57  R2563
   1 SMB_VR_3V3AUX_SDA_R      A @S9S_MB_2U_LIB.S9S_MB_2U(SCH_1):SMB_VR_3V3AUX_SDA_R
   2 SMB_DIO_PVCCINFAON_CPU1      B @S9S_MB_2U_LIB.S9S_MB_2U(SCH_1):SMB_DIO_PVCCINFAON_CPU1

Q_RES_0402LF-0,5%,1/16W,CHIP,CA  I59  R2561
   1 SVID_ALERT0_CPU1_R_N      A @S9S_MB_2U_LIB.S9S_MB_2U(SCH_1):SVID_ALERT0_CPU1_R_N
   2 SVID_ALERT_PVCCINFAON_CPU1_R      B @S9S_MB_2U_LIB.S9S_MB_2U(SCH_1):SVID_ALERT_PVCCINFAON_CPU1_R

Q_RES_0402LF-150,1%,1/16W,CHIPA  I61  R2559
   1 SVID_CLK0_CPU1_R      A @S9S_MB_2U_LIB.S9S_MB_2U(SCH_1):SVID_CLK0_CPU1_R
   2 SVID_CLK_PVCCINFAON_CPU1_R      B @S9S_MB_2U_LIB.S9S_MB_2U(SCH_1):SVID_CLK_PVCCINFAON_CPU1_R

Q_RES_0402LF-49.9,1%,1/16W,EMPA  I15  R2345
   1 PVNN_TERM_CPU1      A @S9S_MB_2U_LIB.S9S_MB_2U(SCH_1):PVNN_TERM_CPU1
   2 SVID_CLK0_CPU1_R      B @S9S_MB_2U_LIB.S9S_MB_2U(SCH_1):SVID_CLK0_CPU1_R

Q_RES_0402LF-0,5%,1/16W,CHIP,CA  I31  R2570
   1 FM_PVCCFA_EHV_CPU1_EN      A @S9S_MB_2U_LIB.S9S_MB_2U(SCH_1):FM_PVCCFA_EHV_CPU1_EN
   2 PVCCFA_EHV_CPU1_EN_R      B @S9S_MB_2U_LIB.S9S_MB_2U(SCH_1):PVCCFA_EHV_CPU1_EN_R

Q_CAP_0402-3300PF,50V,10%,X7R,A  I53  PC468
   1 SH_PVCCINFAON_CPU1_R      A @S9S_MB_2U_LIB.S9S_MB_2U(SCH_1):SH_PVCCINFAON_CPU1_R
   2 VSENSE_PVCCINFAON_CPU1_DN      B @S9S_MB_2U_LIB.S9S_MB_2U(SCH_1):VSENSE_PVCCINFAON_CPU1_DN

Q_RES_0402LF-100,1%,1/16W,CHIPA  I55  PR568
   1 VSENSE_PVCCINFAON_CPU1_DP      A @S9S_MB_2U_LIB.S9S_MB_2U(SCH_1):VSENSE_PVCCINFAON_CPU1_DP
   2 PVCCINFAON_CPU1      B @S9S_MB_2U_LIB.S9S_MB_2U(SCH_1):PVCCINFAON_CPU1

Q_RES_0402LF-0,5%,1/16W,CHIP,CA  I60  R2560
   1 SVID_DIO0_CPU1_R      A @S9S_MB_2U_LIB.S9S_MB_2U(SCH_1):SVID_DIO0_CPU1_R
   2 SVID_DIO_PVCCINFAON_CPU1_R      B @S9S_MB_2U_LIB.S9S_MB_2U(SCH_1):SVID_DIO_PVCCINFAON_CPU1_R

Q_RES_0402LF-0,5%,1/16W,CHIP,CA  I62  PR273
   1 SH_PVCCINFAON_CPU1      A @S9S_MB_2U_LIB.S9S_MB_2U(SCH_1):SH_PVCCINFAON_CPU1
   2 SH_PVCCINFAON_CPU1_R      B @S9S_MB_2U_LIB.S9S_MB_2U(SCH_1):SH_PVCCINFAON_CPU1_R

Q_CAP_0402-470PF,50V,10%,X7R,TA  I66  PC475
   1 PVCCINFAON_CPU1_ATSEN      A @S9S_MB_2U_LIB.S9S_MB_2U(SCH_1):PVCCINFAON_CPU1_ATSEN
   2    GND      B @S9S_MB_2U_LIB.S9S_MB_2U(SCH_1):GND

Q_RES_0402LF-1K,1%,1/16W,CHIP,A  I73  R2573
   1 P3V3_AUX      A @S9S_MB_2U_LIB.S9S_MB_2U(SCH_1):P3V3_AUX
   2 IRQ_PVCCFA_CPU1_VRHOT_R_N      B @S9S_MB_2U_LIB.S9S_MB_2U(SCH_1):IRQ_PVCCFA_CPU1_VRHOT_R_N

Q_CAP_0402-1000PF,50V,5%,EMPTYA  I32  C2453
   1 PWRGD_PVCCFA_EHV_CPU1_R      A @S9S_MB_2U_LIB.S9S_MB_2U(SCH_1):PWRGD_PVCCFA_EHV_CPU1_R
   2    GND      B @S9S_MB_2U_LIB.S9S_MB_2U(SCH_1):GND

Q_CAP_0402-1000PF,50V,5%,X7R,TA  I33  C2452
   1 PVCCFA_EHV_CPU1_EN_R      A @S9S_MB_2U_LIB.S9S_MB_2U(SCH_1):PVCCFA_EHV_CPU1_EN_R
   2    GND      B @S9S_MB_2U_LIB.S9S_MB_2U(SCH_1):GND

Q_RES_0402LF-100,1%,1/16W,EMPTA  I14  R2354
   1 PVNN_TERM_CPU1      A @S9S_MB_2U_LIB.S9S_MB_2U(SCH_1):PVNN_TERM_CPU1
   2 SVID_DIO0_CPU1_R      B @S9S_MB_2U_LIB.S9S_MB_2U(SCH_1):SVID_DIO0_CPU1_R

Q_RES_0402LF-0,5%,1/16W,CHIP,CA  I21  PR261
   1 P12V_AUX      A @S9S_MB_2U_LIB.S9S_MB_2U(SCH_1):P12V_AUX
   2 PVCCINFAON_CPU1_VIN_CSNIN      B @S9S_MB_2U_LIB.S9S_MB_2U(SCH_1):PVCCINFAON_CPU1_VIN_CSNIN

Q_RES_0402LF-28K,1%,1/16W,EMPTA  I23  PR258
   1 PVCCINFAON_CPU1_VREF      A @S9S_MB_2U_LIB.S9S_MB_2U(SCH_1):PVCCINFAON_CPU1_VREF
   2 PVCCINFAON_CPU1_ADDR      B @S9S_MB_2U_LIB.S9S_MB_2U(SCH_1):PVCCINFAON_CPU1_ADDR

Q_CAP_0402-0.1UF,25V,10%,EMPTYA  I28  PC467
   1 PVCCINFAON_CPU1_CSPIN      A @S9S_MB_2U_LIB.S9S_MB_2U(SCH_1):PVCCINFAON_CPU1_CSPIN
   2    GND      B @S9S_MB_2U_LIB.S9S_MB_2U(SCH_1):GND

Q_SHORT_SM-EMPTY,SHORT6  I44  PJ51
   1 VSENSE_PVCCFA_EHV_CPU1_DP      1 @S9S_MB_2U_LIB.S9S_MB_2U(SCH_1):VSENSE_PVCCFA_EHV_CPU1_DP
   2 SH_PVCCFA_EHV_CPU1      2 @S9S_MB_2U_LIB.S9S_MB_2U(SCH_1):SH_PVCCFA_EHV_CPU1

Q_CAP_0402-470PF,50V,10%,X7R,TA  I69  PC1292
   1 PVCCFA_EHV_CPU1_BTSEN      A @S9S_MB_2U_LIB.S9S_MB_2U(SCH_1):PVCCFA_EHV_CPU1_BTSEN
   2    GND      B @S9S_MB_2U_LIB.S9S_MB_2U(SCH_1):GND

Q_RES_0402LF-0,5%,1/16W,CHIP,CA  I78  PR4246
   1 NC_PVCCINFAON_CPU1_ACSP7      A @S9S_MB_2U_LIB.S9S_MB_2U(SCH_1):NC_PVCCINFAON_CPU1_ACSP7
   2    GND      B @S9S_MB_2U_LIB.S9S_MB_2U(SCH_1):GND

Q_RES_0402LF-0,5%,1/16W,CHIP,CA  I79  PR4245
   1 NC_PVCCINFAON_CPU1_ACSP6      A @S9S_MB_2U_LIB.S9S_MB_2U(SCH_1):NC_PVCCINFAON_CPU1_ACSP6
   2    GND      B @S9S_MB_2U_LIB.S9S_MB_2U(SCH_1):GND

Q_RES_0402LF-0,5%,1/16W,CHIP,CA  I80  PR4244
   1 NC_PVCCINFAON_CPU1_ACSP5      A @S9S_MB_2U_LIB.S9S_MB_2U(SCH_1):NC_PVCCINFAON_CPU1_ACSP5
   2    GND      B @S9S_MB_2U_LIB.S9S_MB_2U(SCH_1):GND

Q_RES_0402LF-0,5%,1/16W,CHIP,CA  I81  PR4243
   1 NC_PVCCINFAON_CPU1_ACSP4      A @S9S_MB_2U_LIB.S9S_MB_2U(SCH_1):NC_PVCCINFAON_CPU1_ACSP4
   2    GND      B @S9S_MB_2U_LIB.S9S_MB_2U(SCH_1):GND

Q_CAP_C0402-100NF,50V,10%,EMPTA  I93  PC476
   1 PVCCINFAON_CPU1_VCC      A @S9S_MB_2U_LIB.S9S_MB_2U(SCH_1):PVCCINFAON_CPU1_VCC
   2    GND      B @S9S_MB_2U_LIB.S9S_MB_2U(SCH_1):GND

Q_CAP_C0402-1UF,16V,10%,X6S,CHA  I97  PC478
   1 PVCCINFAON_CPU1_VCC      A @S9S_MB_2U_LIB.S9S_MB_2U(SCH_1):PVCCINFAON_CPU1_VCC
   2    GND      B @S9S_MB_2U_LIB.S9S_MB_2U(SCH_1):GND

Q_RES_0402LF-0,5%,1/16W,CHIP,CA  I103  R4781
   1 PWRGD_PVCCINFAON_CPU1      A @S9S_MB_2U_LIB.S9S_MB_2U(SCH_1):PWRGD_PVCCINFAON_CPU1
   2 PWRGD_PVCCINFAON_CPU1_R      B @S9S_MB_2U_LIB.S9S_MB_2U(SCH_1):PWRGD_PVCCINFAON_CPU1_R

Q_RES_0402LF-0,5%,1/16W,CHIP,CA  I29  R2572
   1 PWRGD_PVCCFA_EHV_CPU1      A @S9S_MB_2U_LIB.S9S_MB_2U(SCH_1):PWRGD_PVCCFA_EHV_CPU1
   2 PWRGD_PVCCFA_EHV_CPU1_R      B @S9S_MB_2U_LIB.S9S_MB_2U(SCH_1):PWRGD_PVCCFA_EHV_CPU1_R

Q_RES_0402LF-1K,1%,1/16W,CHIP,A  I30  R2571
   1 P3V3_AUX      A @S9S_MB_2U_LIB.S9S_MB_2U(SCH_1):P3V3_AUX
   2 PWRGD_PVCCFA_EHV_CPU1_R      B @S9S_MB_2U_LIB.S9S_MB_2U(SCH_1):PWRGD_PVCCFA_EHV_CPU1_R

Q_RES_0402LF-1K,1%,1/16W,EMPTYA  I35  PR276
   1 PVCCINFAON_CPU1_VIN_CSNIN      A @S9S_MB_2U_LIB.S9S_MB_2U(SCH_1):PVCCINFAON_CPU1_VIN_CSNIN
   2    GND      B @S9S_MB_2U_LIB.S9S_MB_2U(SCH_1):GND

Q_CAP_0402-0.1UF,25V,10%,X7R,CA  I36  PC474
   1 PVCCINFAON_CPU1_VIN_CSNIN      A @S9S_MB_2U_LIB.S9S_MB_2U(SCH_1):PVCCINFAON_CPU1_VIN_CSNIN
   2    GND      B @S9S_MB_2U_LIB.S9S_MB_2U(SCH_1):GND

ISL69260IRAZT-ISL69260IRAZ-T,SA  I38  PU22
  23 PVCCINFAON_CPU1_ACSP1    CS7 @S9S_MB_2U_LIB.S9S_MB_2U(SCH_1):PVCCINFAON_CPU1_ACSP1
  39 PVCCINFAON_CPU1_VCC    VCC @S9S_MB_2U_LIB.S9S_MB_2U(SCH_1):PVCCINFAON_CPU1_VCC
  20 PVCCFA_EHV_CPU1_EN_R    EN1 @S9S_MB_2U_LIB.S9S_MB_2U(SCH_1):PVCCFA_EHV_CPU1_EN_R
  10 SMB_CLK_PVCCINFAON_CPU1  PMSCL @S9S_MB_2U_LIB.S9S_MB_2U(SCH_1):SMB_CLK_PVCCINFAON_CPU1
  18 SVID_DIO_PVCCINFAON_CPU1_R SVDATA @S9S_MB_2U_LIB.S9S_MB_2U(SCH_1):SVID_DIO_PVCCINFAON_CPU1_R
  24 PVCCINFAON_CPU1_ACSP2    CS6 @S9S_MB_2U_LIB.S9S_MB_2U(SCH_1):PVCCINFAON_CPU1_ACSP2
  19 SVID_ALERT_PVCCINFAON_CPU1_R NSVALERT# @S9S_MB_2U_LIB.S9S_MB_2U(SCH_1):SVID_ALERT_PVCCINFAON_CPU1_R
  14 IRQ_PVCCFA_CPU1_VRHOT_N NVRHOT# @S9S_MB_2U_LIB.S9S_MB_2U(SCH_1):IRQ_PVCCFA_CPU1_VRHOT_N
  25 NC_PVCCINFAON_CPU1_ACSP3    CS5 @S9S_MB_2U_LIB.S9S_MB_2U(SCH_1):NC_PVCCINFAON_CPU1_ACSP3
  26 NC_PVCCINFAON_CPU1_ACSP4    CS4 @S9S_MB_2U_LIB.S9S_MB_2U(SCH_1):NC_PVCCINFAON_CPU1_ACSP4
  16 PWRGD_PVCCFA_EHV_CPU1_R    PG1 @S9S_MB_2U_LIB.S9S_MB_2U(SCH_1):PWRGD_PVCCFA_EHV_CPU1_R
  17 SVID_CLK_PVCCINFAON_CPU1_R  SVCLK @S9S_MB_2U_LIB.S9S_MB_2U(SCH_1):SVID_CLK_PVCCINFAON_CPU1_R
  11 NC_PVCCINFAON_CPU1_SMB_ALERT NPMALERT# @S9S_MB_2U_LIB.S9S_MB_2U(SCH_1):NC_PVCCINFAON_CPU1_SMB_ALERT
  13 PVCCINFAON_CPU1_EN_R    EN0 @S9S_MB_2U_LIB.S9S_MB_2U(SCH_1):PVCCINFAON_CPU1_EN_R
  22 VSENSE_PVCCINFAON_CPU1_DN  RGND0 @S9S_MB_2U_LIB.S9S_MB_2U(SCH_1):VSENSE_PVCCINFAON_CPU1_DN
   9 SMB_DIO_PVCCINFAON_CPU1  PMSDA @S9S_MB_2U_LIB.S9S_MB_2U(SCH_1):SMB_DIO_PVCCINFAON_CPU1
   5 NC_PVCCINFAON_CPU1_APWM4   PWM4 @S9S_MB_2U_LIB.S9S_MB_2U(SCH_1):NC_PVCCINFAON_CPU1_APWM4
   6 NC_PVCCINFAON_CPU1_APWM3   PWM5 @S9S_MB_2U_LIB.S9S_MB_2U(SCH_1):NC_PVCCINFAON_CPU1_APWM3
  21 SH_PVCCINFAON_CPU1_R  VSEN0 @S9S_MB_2U_LIB.S9S_MB_2U(SCH_1):SH_PVCCINFAON_CPU1_R
   2 NC_PVCCINFAON_CPU1_APWM7   PWM1 @S9S_MB_2U_LIB.S9S_MB_2U(SCH_1):NC_PVCCINFAON_CPU1_APWM7
  12 PWRGD_PVCCINFAON_CPU1_R    PG0 @S9S_MB_2U_LIB.S9S_MB_2U(SCH_1):PWRGD_PVCCINFAON_CPU1_R
   7 PVCCINFAON_CPU1_APWM2   PWM6 @S9S_MB_2U_LIB.S9S_MB_2U(SCH_1):PVCCINFAON_CPU1_APWM2
  40 PVCCINFAON_CPU1_VREF   VCCS @S9S_MB_2U_LIB.S9S_MB_2U(SCH_1):PVCCINFAON_CPU1_VREF
  37 PVCCINFAON_CPU1_CSPIN VMON||IINSEN||VSYS||ISYS @S9S_MB_2U_LIB.S9S_MB_2U(SCH_1):PVCCINFAON_CPU1_CSPIN
  38 PVCCINFAON_CPU1_VIN_CSNIN VINSEN||VSYS @S9S_MB_2U_LIB.S9S_MB_2U(SCH_1):PVCCINFAON_CPU1_VIN_CSNIN
  36 PVCCFA_EHV_CPU1_BTSEN TEMP1||ISYS @S9S_MB_2U_LIB.S9S_MB_2U(SCH_1):PVCCFA_EHV_CPU1_BTSEN
  15 PVCCINFAON_CPU1_PIN_ALERT NPINALERT#||NPSYSCRIT# @S9S_MB_2U_LIB.S9S_MB_2U(SCH_1):PVCCINFAON_CPU1_PIN_ALERT
  32 SH_PVCCFA_EHV_CPU1_R  VSEN1 @S9S_MB_2U_LIB.S9S_MB_2U(SCH_1):SH_PVCCFA_EHV_CPU1_R
  31 VSENSE_PVCCFA_EHV_CPU1_DN  RGND1 @S9S_MB_2U_LIB.S9S_MB_2U(SCH_1):VSENSE_PVCCFA_EHV_CPU1_DN
  29 NC_PVCCINFAON_CPU1_ACSP7    CS1 @S9S_MB_2U_LIB.S9S_MB_2U(SCH_1):NC_PVCCINFAON_CPU1_ACSP7
   8 PVCCINFAON_CPU1_APWM1   PWM7 @S9S_MB_2U_LIB.S9S_MB_2U(SCH_1):PVCCINFAON_CPU1_APWM1
   4 NC_PVCCINFAON_CPU1_APWM5   PWM3 @S9S_MB_2U_LIB.S9S_MB_2U(SCH_1):NC_PVCCINFAON_CPU1_APWM5
  27 NC_PVCCINFAON_CPU1_ACSP5    CS3 @S9S_MB_2U_LIB.S9S_MB_2U(SCH_1):NC_PVCCINFAON_CPU1_ACSP5
   3 NC_PVCCINFAON_CPU1_APWM6   PWM2 @S9S_MB_2U_LIB.S9S_MB_2U(SCH_1):NC_PVCCINFAON_CPU1_APWM6
  28 NC_PVCCINFAON_CPU1_ACSP6    CS2 @S9S_MB_2U_LIB.S9S_MB_2U(SCH_1):NC_PVCCINFAON_CPU1_ACSP6
  33 PVCCINFAON_CPU1_VR_FAULT    CFP @S9S_MB_2U_LIB.S9S_MB_2U(SCH_1):PVCCINFAON_CPU1_VR_FAULT
  TH    GND TH_GND @S9S_MB_2U_LIB.S9S_MB_2U(SCH_1):GND
  34 PVCCINFAON_CPU1_ADDR ADDR_CFG @S9S_MB_2U_LIB.S9S_MB_2U(SCH_1):PVCCINFAON_CPU1_ADDR
  35 PVCCINFAON_CPU1_ATSEN  TEMP0 @S9S_MB_2U_LIB.S9S_MB_2U(SCH_1):PVCCINFAON_CPU1_ATSEN
   1 PVCCFA_EHV_CPU1_BPWM1   PWM0 @S9S_MB_2U_LIB.S9S_MB_2U(SCH_1):PVCCFA_EHV_CPU1_BPWM1
  30 PVCCFA_EHV_CPU1_BCSP1    CS0 @S9S_MB_2U_LIB.S9S_MB_2U(SCH_1):PVCCFA_EHV_CPU1_BCSP1

Q_RES_0402LF-100,1%,1/16W,CHIPA  I41  PR567
   1 VSENSE_PVCCFA_EHV_CPU1_DN      A @S9S_MB_2U_LIB.S9S_MB_2U(SCH_1):VSENSE_PVCCFA_EHV_CPU1_DN
   2    GND      B @S9S_MB_2U_LIB.S9S_MB_2U(SCH_1):GND

Q_RES_0402LF-100,1%,1/16W,CHIPA  I45  PR569
   1 VSENSE_PVCCFA_EHV_CPU1_DP      A @S9S_MB_2U_LIB.S9S_MB_2U(SCH_1):VSENSE_PVCCFA_EHV_CPU1_DP
   2 PVCCFA_EHV_CPU1      B @S9S_MB_2U_LIB.S9S_MB_2U(SCH_1):PVCCFA_EHV_CPU1

Q_RES_0402LF-100,1%,1/16W,CHIPA  I46  PR566
   1 VSENSE_PVCCINFAON_CPU1_DN      A @S9S_MB_2U_LIB.S9S_MB_2U(SCH_1):VSENSE_PVCCINFAON_CPU1_DN
   2    GND      B @S9S_MB_2U_LIB.S9S_MB_2U(SCH_1):GND

Q_RES_0402LF-1K,1%,1/16W,CHIP,A  I49  R2569
   1 P3V3_AUX      A @S9S_MB_2U_LIB.S9S_MB_2U(SCH_1):P3V3_AUX
   2 PVCCINFAON_CPU1_PIN_ALERT      B @S9S_MB_2U_LIB.S9S_MB_2U(SCH_1):PVCCINFAON_CPU1_PIN_ALERT

Q_RES_0402LF-1K,1%,1/16W,CHIP,A  I50  R2568
   1 P3V3_AUX      A @S9S_MB_2U_LIB.S9S_MB_2U(SCH_1):P3V3_AUX
   2 PVCCINFAON_CPU1_VR_FAULT      B @S9S_MB_2U_LIB.S9S_MB_2U(SCH_1):PVCCINFAON_CPU1_VR_FAULT

Q_RES_0402LF-0,5%,1/16W,CHIP,CA  I58  R4594
   1 SMB_VR_3V3AUX_SCL_R      A @S9S_MB_2U_LIB.S9S_MB_2U(SCH_1):SMB_VR_3V3AUX_SCL_R
   2 SMB_CLK_PVCCINFAON_CPU1      B @S9S_MB_2U_LIB.S9S_MB_2U(SCH_1):SMB_CLK_PVCCINFAON_CPU1

Q_CAP_0402-1000PF,50V,5%,X7R,TA  I63  C2451
   1 PVCCINFAON_CPU1_EN_R      A @S9S_MB_2U_LIB.S9S_MB_2U(SCH_1):PVCCINFAON_CPU1_EN_R
   2    GND      B @S9S_MB_2U_LIB.S9S_MB_2U(SCH_1):GND

Q_RES_0402LF-10K,1%,1/16W,EMPTA  I67  PR665
   1 PVCCINFAON_CPU1_ATSEN      A @S9S_MB_2U_LIB.S9S_MB_2U(SCH_1):PVCCINFAON_CPU1_ATSEN
   2    GND      B @S9S_MB_2U_LIB.S9S_MB_2U(SCH_1):GND

Q_RES_0402LF-0,5%,1/16W,CHIP,CA  I70  R2574
   1 IRQ_PVCCFA_CPU1_VRHOT_N      A @S9S_MB_2U_LIB.S9S_MB_2U(SCH_1):IRQ_PVCCFA_CPU1_VRHOT_N
   2 IRQ_PVCCFA_CPU1_VRHOT_R_N      B @S9S_MB_2U_LIB.S9S_MB_2U(SCH_1):IRQ_PVCCFA_CPU1_VRHOT_R_N

Q_RES_0402LF-10K,1%,1/16W,EMPTA  I75  PR667
   1 PVCCFA_EHV_CPU1_BTSEN      A @S9S_MB_2U_LIB.S9S_MB_2U(SCH_1):PVCCFA_EHV_CPU1_BTSEN
   2    GND      B @S9S_MB_2U_LIB.S9S_MB_2U(SCH_1):GND

Q_RES_0402LF-0,5%,1/16W,CHIP,CA  I89  PR4242
   1 NC_PVCCINFAON_CPU1_ACSP3      A @S9S_MB_2U_LIB.S9S_MB_2U(SCH_1):NC_PVCCINFAON_CPU1_ACSP3
   2    GND      B @S9S_MB_2U_LIB.S9S_MB_2U(SCH_1):GND

Q_CAP_C0402-10UF,6.3V,20%,X6S,B  I92  PC477
   1 PVCCINFAON_CPU1_VREF      A @S9S_MB_2U_LIB.S9S_MB_2U(SCH_1):PVCCINFAON_CPU1_VREF
   2    GND      B @S9S_MB_2U_LIB.S9S_MB_2U(SCH_1):GND

Q_CAP_C0402-1UF,16V,10%,X6S,CHA  I96  PC1193
   1 PVCCINFAON_CPU1_VREF      A @S9S_MB_2U_LIB.S9S_MB_2U(SCH_1):PVCCINFAON_CPU1_VREF
   2    GND      B @S9S_MB_2U_LIB.S9S_MB_2U(SCH_1):GND

Q_RES_0402LF-0,5%,1/16W,CHIP,CA  I104  R2558
   1 FM_PVCCINFAON_CPU1_EN      A @S9S_MB_2U_LIB.S9S_MB_2U(SCH_1):FM_PVCCINFAON_CPU1_EN
   2 PVCCINFAON_CPU1_EN_R      B @S9S_MB_2U_LIB.S9S_MB_2U(SCH_1):PVCCINFAON_CPU1_EN_R

Q_RES_0402LF-1K,1%,1/16W,CHIP,A  I105  R2556
   1 P3V3_AUX      A @S9S_MB_2U_LIB.S9S_MB_2U(SCH_1):P3V3_AUX
   2 PWRGD_PVCCINFAON_CPU1_R      B @S9S_MB_2U_LIB.S9S_MB_2U(SCH_1):PWRGD_PVCCINFAON_CPU1_R

Q_CAP_0402-1000PF,50V,5%,EMPTYA  I106  C2450
   1 PWRGD_PVCCINFAON_CPU1_R      A @S9S_MB_2U_LIB.S9S_MB_2U(SCH_1):PWRGD_PVCCINFAON_CPU1_R
   2    GND      B @S9S_MB_2U_LIB.S9S_MB_2U(SCH_1):GND

Q_RES_0402LF-1,1%,1/16W,CHIP,CA  I108  PR283
   1 PVCCINFAON_CPU1_VCC      A @S9S_MB_2U_LIB.S9S_MB_2U(SCH_1):PVCCINFAON_CPU1_VCC
   2 P3V3_AUX      B @S9S_MB_2U_LIB.S9S_MB_2U(SCH_1):P3V3_AUX

Q_RES_0402LF-8.45K,1%,1/16W,CHA  I110  PR259
   1 PVCCINFAON_CPU1_ADDR      A @S9S_MB_2U_LIB.S9S_MB_2U(SCH_1):PVCCINFAON_CPU1_ADDR
   2    GND      B @S9S_MB_2U_LIB.S9S_MB_2U(SCH_1):GND

Q_CAP_0402-0.1UF,25V,10%,EMPTYA  I111  PC2367
   1 PVCCINFAON_CPU1_VCC      A @S9S_MB_2U_LIB.S9S_MB_2U(SCH_1):PVCCINFAON_CPU1_VCC
   2    GND      B @S9S_MB_2U_LIB.S9S_MB_2U(SCH_1):GND


DRAWING: @S9S_MB_2U_LIB.S9S_MB_2U(SCH_1):PAGE279 

Q_RES_0402LF-2.2,1%,1/16W,CHIPA  I11  PR255
   1 PVCCFA_EHV_CPU1_PVCC      A @S9S_MB_2U_LIB.S9S_MB_2U(SCH_1):PVCCFA_EHV_CPU1_PVCC
   2 PVCCINFAON_CPU1_VDD2      B @S9S_MB_2U_LIB.S9S_MB_2U(SCH_1):PVCCINFAON_CPU1_VDD2

Q_CAP_C0805-22UF,4V,20%,X6S,CHA  I33  PC458_P1_2
   1 PVCCINFAON_CPU1      A @S9S_MB_2U_LIB.S9S_MB_2U(SCH_1):PVCCINFAON_CPU1
   2    GND      B @S9S_MB_2U_LIB.S9S_MB_2U(SCH_1):GND

Q_RES_0402LF-499,1%,1/16W,CHIPA  I34  PR4247
   1 PVCCINFAON_CPU1      A @S9S_MB_2U_LIB.S9S_MB_2U(SCH_1):PVCCINFAON_CPU1
   2    GND      B @S9S_MB_2U_LIB.S9S_MB_2U(SCH_1):GND

Q_CAP_0402-3300PF,50V,10%,X7R,A  I36  PC443_P1_2
   1 SW_P12V_PVCCINFAON_CPU1_FLT      A @S9S_MB_2U_LIB.S9S_MB_2U(SCH_1):SW_P12V_PVCCINFAON_CPU1_FLT
   2    GND      B @S9S_MB_2U_LIB.S9S_MB_2U(SCH_1):GND

ISL99390FRZTR5935-ISL99390FRZ-A  I38  PU50_P1_1
  34 PVCCINFAON_CPU1_APWM1    PWM @S9S_MB_2U_LIB.S9S_MB_2U(SCH_1):PVCCINFAON_CPU1_APWM1
  39 PVCCINFAON_CPU1_VREF  REFIN @S9S_MB_2U_LIB.S9S_MB_2U(SCH_1):PVCCINFAON_CPU1_VREF
   3 PVCCINFAON_CPU1_VDD1    VCC @S9S_MB_2U_LIB.S9S_MB_2U(SCH_1):PVCCINFAON_CPU1_VDD1
   2    GND   AGND @S9S_MB_2U_LIB.S9S_MB_2U(SCH_1):GND
  33 SW_PVCCINFAON_CPU1_BOOT1   BOOT @S9S_MB_2U_LIB.S9S_MB_2U(SCH_1):SW_PVCCINFAON_CPU1_BOOT1
25_29 SW_P12V_PVCCINFAON_CPU1_FLT   VIN1 @S9S_MB_2U_LIB.S9S_MB_2U(SCH_1):SW_P12V_PVCCINFAON_CPU1_FLT
  32 SW_PVCCINFAON_CPU1_BOOTR1  PHASE @S9S_MB_2U_LIB.S9S_MB_2U(SCH_1):SW_PVCCINFAON_CPU1_BOOTR1
   4 PVCCFA_EHV_CPU1_PVCC   PVCC @S9S_MB_2U_LIB.S9S_MB_2U(SCH_1):PVCCFA_EHV_CPU1_PVCC
  36 PVCCINFAON_CPU1_ATSEN TOUT_FLT @S9S_MB_2U_LIB.S9S_MB_2U(SCH_1):PVCCINFAON_CPU1_ATSEN
  38 PVCCINFAON_CPU1_ACSP1   IOUT @S9S_MB_2U_LIB.S9S_MB_2U(SCH_1):PVCCINFAON_CPU1_ACSP1
  37 PVCCINFAON_CPU1_LSET1   LSET @S9S_MB_2U_LIB.S9S_MB_2U(SCH_1):PVCCINFAON_CPU1_LSET1
10_19 SW_PVCCINFAON_CPU1_SW1     SW @S9S_MB_2U_LIB.S9S_MB_2U(SCH_1):SW_PVCCINFAON_CPU1_SW1
   5    GND  PGND1 @S9S_MB_2U_LIB.S9S_MB_2U(SCH_1):GND
  30 SW_P12V_PVCCINFAON_CPU1_FLT   VIN2 @S9S_MB_2U_LIB.S9S_MB_2U(SCH_1):SW_P12V_PVCCINFAON_CPU1_FLT
   1 PVCCINFAON_CPU1_VOS1    VOS @S9S_MB_2U_LIB.S9S_MB_2U(SCH_1):PVCCINFAON_CPU1_VOS1
  40    GND  PGND3 @S9S_MB_2U_LIB.S9S_MB_2U(SCH_1):GND
  35 PVCCINFAON_CPU1_VDD1     EN @S9S_MB_2U_LIB.S9S_MB_2U(SCH_1):PVCCINFAON_CPU1_VDD1
  31     NC    DNC     NC
   6     NC    GL1     NC
  41     NC    GL2     NC
7_9-20_24    GND  PGND2 @S9S_MB_2U_LIB.S9S_MB_2U(SCH_1):GND

Q_CAP_C0402-1UF,16V,10%,X6S,CHA  I41  PC444_P1_1
   1 SW_P12V_PVCCINFAON_CPU1_FLT      A @S9S_MB_2U_LIB.S9S_MB_2U(SCH_1):SW_P12V_PVCCINFAON_CPU1_FLT
   2    GND      B @S9S_MB_2U_LIB.S9S_MB_2U(SCH_1):GND

Q_CAP_C0805-22UF,16V,20%,X6S,CA  I43  PC449_P1_2
   1 SW_P12V_PVCCINFAON_CPU1_FLT      A @S9S_MB_2U_LIB.S9S_MB_2U(SCH_1):SW_P12V_PVCCINFAON_CPU1_FLT
   2    GND      B @S9S_MB_2U_LIB.S9S_MB_2U(SCH_1):GND

Q_CAP_C0805-22UF,16V,20%,X6S,CA  I51  PC448_P1_1
   1 SW_P12V_PVCCINFAON_CPU1_FLT      A @S9S_MB_2U_LIB.S9S_MB_2U(SCH_1):SW_P12V_PVCCINFAON_CPU1_FLT
   2    GND      B @S9S_MB_2U_LIB.S9S_MB_2U(SCH_1):GND

Q_CAP_C0402-100NF,50V,10%,X7R,A  I52  PC446
   1 SW_PVCCINFAON_CPU1_BOOT1_R      A @S9S_MB_2U_LIB.S9S_MB_2U(SCH_1):SW_PVCCINFAON_CPU1_BOOT1_R
   2 SW_PVCCINFAON_CPU1_BOOTR1      B @S9S_MB_2U_LIB.S9S_MB_2U(SCH_1):SW_PVCCINFAON_CPU1_BOOTR1

Q_CAPP_THLF-560UF,2.5V,20%,OSCA  I59  PC1593
   1 PVCCINFAON_CPU1      A @S9S_MB_2U_LIB.S9S_MB_2U(SCH_1):PVCCINFAON_CPU1
   2    GND      B @S9S_MB_2U_LIB.S9S_MB_2U(SCH_1):GND

Q_CAPP_SMLF-330UF,2V,35%,SPCAPA  I62  PC1594
   1 PVCCINFAON_CPU1      A @S9S_MB_2U_LIB.S9S_MB_2U(SCH_1):PVCCINFAON_CPU1
   2    GND      B @S9S_MB_2U_LIB.S9S_MB_2U(SCH_1):GND

Q_CAP_C0402-100NF,50V,10%,X7R,A  I68  PC1659
   1 P12V_AUX      A @S9S_MB_2U_LIB.S9S_MB_2U(SCH_1):P12V_AUX
   2    GND      B @S9S_MB_2U_LIB.S9S_MB_2U(SCH_1):GND

Q_CAPP_THLF-270UF,16V,20%,OSCOA  I69  PC460
   1 SW_P12V_PVCCINFAON_CPU1_FLT      A @S9S_MB_2U_LIB.S9S_MB_2U(SCH_1):SW_P12V_PVCCINFAON_CPU1_FLT
   2    GND      B @S9S_MB_2U_LIB.S9S_MB_2U(SCH_1):GND

Q_RES_0402LF-8.87K,1%,1/16W,EMA  I16  PR1726
   1 PVCCINFAON_CPU1_LSET1      A @S9S_MB_2U_LIB.S9S_MB_2U(SCH_1):PVCCINFAON_CPU1_LSET1
   2    GND      B @S9S_MB_2U_LIB.S9S_MB_2U(SCH_1):GND

Q_RES_0402LF-2.2,1%,1/16W,CHIPA  I25  PR254
   1 PVCCFA_EHV_CPU1_PVCC      A @S9S_MB_2U_LIB.S9S_MB_2U(SCH_1):PVCCFA_EHV_CPU1_PVCC
   2 PVCCINFAON_CPU1_VDD1      B @S9S_MB_2U_LIB.S9S_MB_2U(SCH_1):PVCCINFAON_CPU1_VDD1

ISL99390FRZTR5935-ISL99390FRZ-A  I29  PU51_P1_2
  34 PVCCINFAON_CPU1_APWM2    PWM @S9S_MB_2U_LIB.S9S_MB_2U(SCH_1):PVCCINFAON_CPU1_APWM2
  39 PVCCINFAON_CPU1_VREF  REFIN @S9S_MB_2U_LIB.S9S_MB_2U(SCH_1):PVCCINFAON_CPU1_VREF
   3 PVCCINFAON_CPU1_VDD2    VCC @S9S_MB_2U_LIB.S9S_MB_2U(SCH_1):PVCCINFAON_CPU1_VDD2
   2    GND   AGND @S9S_MB_2U_LIB.S9S_MB_2U(SCH_1):GND
  33 SW_PVCCINFAON_CPU1_BOOT2   BOOT @S9S_MB_2U_LIB.S9S_MB_2U(SCH_1):SW_PVCCINFAON_CPU1_BOOT2
25_29 SW_P12V_PVCCINFAON_CPU1_FLT   VIN1 @S9S_MB_2U_LIB.S9S_MB_2U(SCH_1):SW_P12V_PVCCINFAON_CPU1_FLT
  32 SW_PVCCINFAON_CPU1_BOOTR2  PHASE @S9S_MB_2U_LIB.S9S_MB_2U(SCH_1):SW_PVCCINFAON_CPU1_BOOTR2
   4 PVCCFA_EHV_CPU1_PVCC   PVCC @S9S_MB_2U_LIB.S9S_MB_2U(SCH_1):PVCCFA_EHV_CPU1_PVCC
  36 PVCCINFAON_CPU1_ATSEN TOUT_FLT @S9S_MB_2U_LIB.S9S_MB_2U(SCH_1):PVCCINFAON_CPU1_ATSEN
  38 PVCCINFAON_CPU1_ACSP2   IOUT @S9S_MB_2U_LIB.S9S_MB_2U(SCH_1):PVCCINFAON_CPU1_ACSP2
  37 PVCCINFAON_CPU1_LSET2   LSET @S9S_MB_2U_LIB.S9S_MB_2U(SCH_1):PVCCINFAON_CPU1_LSET2
10_19 SW_PVCCINFAON_CPU1_SW2     SW @S9S_MB_2U_LIB.S9S_MB_2U(SCH_1):SW_PVCCINFAON_CPU1_SW2
   5    GND  PGND1 @S9S_MB_2U_LIB.S9S_MB_2U(SCH_1):GND
  30 SW_P12V_PVCCINFAON_CPU1_FLT   VIN2 @S9S_MB_2U_LIB.S9S_MB_2U(SCH_1):SW_P12V_PVCCINFAON_CPU1_FLT
   1 PVCCINFAON_CPU1_VOS2    VOS @S9S_MB_2U_LIB.S9S_MB_2U(SCH_1):PVCCINFAON_CPU1_VOS2
  40    GND  PGND3 @S9S_MB_2U_LIB.S9S_MB_2U(SCH_1):GND
  35 PVCCINFAON_CPU1_VDD2     EN @S9S_MB_2U_LIB.S9S_MB_2U(SCH_1):PVCCINFAON_CPU1_VDD2
  31     NC    DNC     NC
   6     NC    GL1     NC
  41     NC    GL2     NC
7_9-20_24    GND  PGND2 @S9S_MB_2U_LIB.S9S_MB_2U(SCH_1):GND

Q_CAP_C0805-22UF,4V,20%,X6S,CHA  I32  PC456_P1_2
   1 PVCCINFAON_CPU1      A @S9S_MB_2U_LIB.S9S_MB_2U(SCH_1):PVCCINFAON_CPU1
   2    GND      B @S9S_MB_2U_LIB.S9S_MB_2U(SCH_1):GND

Q_CAP_C0402-1UF,16V,10%,X6S,CHA  I37  PC445_P1_2
   1 SW_P12V_PVCCINFAON_CPU1_FLT      A @S9S_MB_2U_LIB.S9S_MB_2U(SCH_1):SW_P12V_PVCCINFAON_CPU1_FLT
   2    GND      B @S9S_MB_2U_LIB.S9S_MB_2U(SCH_1):GND

Q_RES_0402LF-3.3,1%,1/16W,CHIPA  I42  PR1795
   1 SW_PVCCINFAON_CPU1_BOOT2      A @S9S_MB_2U_LIB.S9S_MB_2U(SCH_1):SW_PVCCINFAON_CPU1_BOOT2
   2 SW_PVCCINFAON_CPU1_BOOT2_R      B @S9S_MB_2U_LIB.S9S_MB_2U(SCH_1):SW_PVCCINFAON_CPU1_BOOT2_R

Q_CAP_C0402-100NF,50V,10%,X7R,A  I44  PC447
   1 SW_PVCCINFAON_CPU1_BOOT2_R      A @S9S_MB_2U_LIB.S9S_MB_2U(SCH_1):SW_PVCCINFAON_CPU1_BOOT2_R
   2 SW_PVCCINFAON_CPU1_BOOTR2      B @S9S_MB_2U_LIB.S9S_MB_2U(SCH_1):SW_PVCCINFAON_CPU1_BOOTR2

Q_CAP_C0805-22UF,16V,20%,X6S,CA  I45  PC451_P1_2
   1 SW_P12V_PVCCINFAON_CPU1_FLT      A @S9S_MB_2U_LIB.S9S_MB_2U(SCH_1):SW_P12V_PVCCINFAON_CPU1_FLT
   2    GND      B @S9S_MB_2U_LIB.S9S_MB_2U(SCH_1):GND

Q_INDUCTOR_SMLF-120NH/69A,IND,A  I46  PL22
   2 PVCCINFAON_CPU1      2 @S9S_MB_2U_LIB.S9S_MB_2U(SCH_1):PVCCINFAON_CPU1
   1 SW_PVCCINFAON_CPU1_SW2      1 @S9S_MB_2U_LIB.S9S_MB_2U(SCH_1):SW_PVCCINFAON_CPU1_SW2

Q_CAP_C0805-22UF,16V,20%,X6S,CA  I53  PC450_P1_1
   1 SW_P12V_PVCCINFAON_CPU1_FLT      A @S9S_MB_2U_LIB.S9S_MB_2U(SCH_1):SW_P12V_PVCCINFAON_CPU1_FLT
   2    GND      B @S9S_MB_2U_LIB.S9S_MB_2U(SCH_1):GND

Q_CAPP_THLF-560UF,2.5V,20%,OSCA  I60  PC1595
   1 PVCCINFAON_CPU1      A @S9S_MB_2U_LIB.S9S_MB_2U(SCH_1):PVCCINFAON_CPU1
   2    GND      B @S9S_MB_2U_LIB.S9S_MB_2U(SCH_1):GND

Q_CAPP_SMLF-330UF,2V,35%,SPCAPA  I61  PC1588
   1 PVCCINFAON_CPU1      A @S9S_MB_2U_LIB.S9S_MB_2U(SCH_1):PVCCINFAON_CPU1
   2    GND      B @S9S_MB_2U_LIB.S9S_MB_2U(SCH_1):GND

Q_CAP_C0805-22UF,4V,20%,X6S,CHA  I63  PC455_P1_1
   1 PVCCINFAON_CPU1      A @S9S_MB_2U_LIB.S9S_MB_2U(SCH_1):PVCCINFAON_CPU1
   2    GND      B @S9S_MB_2U_LIB.S9S_MB_2U(SCH_1):GND

Q_CAPP_THLF-270UF,16V,20%,OSCOA  I70  PC461
   1 SW_P12V_PVCCINFAON_CPU1_FLT      A @S9S_MB_2U_LIB.S9S_MB_2U(SCH_1):SW_P12V_PVCCINFAON_CPU1_FLT
   2    GND      B @S9S_MB_2U_LIB.S9S_MB_2U(SCH_1):GND

Q_CAP_C0402-2.2UF,10V,10%,X6S,A  I10  PC441
   1 PVCCINFAON_CPU1_VDD2      A @S9S_MB_2U_LIB.S9S_MB_2U(SCH_1):PVCCINFAON_CPU1_VDD2
   2    GND      B @S9S_MB_2U_LIB.S9S_MB_2U(SCH_1):GND

Q_CAP_C0402-2.2UF,10V,10%,X6S,A  I24  PC440
   1 PVCCINFAON_CPU1_VDD1      A @S9S_MB_2U_LIB.S9S_MB_2U(SCH_1):PVCCINFAON_CPU1_VDD1
   2    GND      B @S9S_MB_2U_LIB.S9S_MB_2U(SCH_1):GND

Q_RES_0402LF-0,5%,1/16W,CHIP,CA  I31  PR1797
   1 PVCCINFAON_CPU1_VOS2      A @S9S_MB_2U_LIB.S9S_MB_2U(SCH_1):PVCCINFAON_CPU1_VOS2
   2 PVCCINFAON_CPU1      B @S9S_MB_2U_LIB.S9S_MB_2U(SCH_1):PVCCINFAON_CPU1

Q_CAP_0402-3300PF,50V,10%,X7R,A  I40  PC442_P1_1
   1 SW_P12V_PVCCINFAON_CPU1_FLT      A @S9S_MB_2U_LIB.S9S_MB_2U(SCH_1):SW_P12V_PVCCINFAON_CPU1_FLT
   2    GND      B @S9S_MB_2U_LIB.S9S_MB_2U(SCH_1):GND

Q_RES_0402LF-0,5%,1/16W,CHIP,CA  I49  PR1796
   1 PVCCINFAON_CPU1_VOS1      A @S9S_MB_2U_LIB.S9S_MB_2U(SCH_1):PVCCINFAON_CPU1_VOS1
   2 PVCCINFAON_CPU1      B @S9S_MB_2U_LIB.S9S_MB_2U(SCH_1):PVCCINFAON_CPU1

Q_RES_0402LF-3.3,1%,1/16W,CHIPA  I50  PR1794
   1 SW_PVCCINFAON_CPU1_BOOT1      A @S9S_MB_2U_LIB.S9S_MB_2U(SCH_1):SW_PVCCINFAON_CPU1_BOOT1
   2 SW_PVCCINFAON_CPU1_BOOT1_R      B @S9S_MB_2U_LIB.S9S_MB_2U(SCH_1):SW_PVCCINFAON_CPU1_BOOT1_R

Q_INDUCTOR_SMLF-120NH/69A,IND,A  I54  PL21
   2 PVCCINFAON_CPU1      2 @S9S_MB_2U_LIB.S9S_MB_2U(SCH_1):PVCCINFAON_CPU1
   1 SW_PVCCINFAON_CPU1_SW1      1 @S9S_MB_2U_LIB.S9S_MB_2U(SCH_1):SW_PVCCINFAON_CPU1_SW1

Q_RES_0402LF-8.87K,1%,1/16W,EMA  I3  PR1727
   1 PVCCINFAON_CPU1_LSET2      A @S9S_MB_2U_LIB.S9S_MB_2U(SCH_1):PVCCINFAON_CPU1_LSET2
   2    GND      B @S9S_MB_2U_LIB.S9S_MB_2U(SCH_1):GND

Q_CAP_0402-0.1UF,25V,10%,X7R,CA  I6  PC1365
   1    GND      A @S9S_MB_2U_LIB.S9S_MB_2U(SCH_1):GND
   2 PVCCINFAON_CPU1_VREF      B @S9S_MB_2U_LIB.S9S_MB_2U(SCH_1):PVCCINFAON_CPU1_VREF

Q_CAP_C0402-2.2UF,10V,10%,X6S,A  I13  PC2949
   1 PVCCFA_EHV_CPU1_PVCC      A @S9S_MB_2U_LIB.S9S_MB_2U(SCH_1):PVCCFA_EHV_CPU1_PVCC
   2    GND      B @S9S_MB_2U_LIB.S9S_MB_2U(SCH_1):GND

Q_CAP_0402-0.1UF,25V,10%,X7R,CA  I20  PC1364
   1    GND      A @S9S_MB_2U_LIB.S9S_MB_2U(SCH_1):GND
   2 PVCCINFAON_CPU1_VREF      B @S9S_MB_2U_LIB.S9S_MB_2U(SCH_1):PVCCINFAON_CPU1_VREF

Q_CAP_C0402-2.2UF,10V,10%,X6S,A  I26  PC2950
   1 PVCCFA_EHV_CPU1_PVCC      A @S9S_MB_2U_LIB.S9S_MB_2U(SCH_1):PVCCFA_EHV_CPU1_PVCC
   2    GND      B @S9S_MB_2U_LIB.S9S_MB_2U(SCH_1):GND

Q_CAP_C0402-100NF,50V,10%,X7R,A  I55  PC452_P1_1
   1 PVCCINFAON_CPU1      A @S9S_MB_2U_LIB.S9S_MB_2U(SCH_1):PVCCINFAON_CPU1
   2    GND      B @S9S_MB_2U_LIB.S9S_MB_2U(SCH_1):GND

Q_CAP_C0805-22UF,4V,20%,X6S,CHA  I65  PC457_P1_1
   1 PVCCINFAON_CPU1      A @S9S_MB_2U_LIB.S9S_MB_2U(SCH_1):PVCCINFAON_CPU1
   2    GND      B @S9S_MB_2U_LIB.S9S_MB_2U(SCH_1):GND

Q_CAPP_THLF-560UF,2.5V,20%,OSCA  I71  PC1596
   1 PVCCINFAON_CPU1      A @S9S_MB_2U_LIB.S9S_MB_2U(SCH_1):PVCCINFAON_CPU1
   2    GND      B @S9S_MB_2U_LIB.S9S_MB_2U(SCH_1):GND

Q_INDUCTOR_SMLF-100NH/16A,IND,A  I78  PL23
   2 SW_P12V_PVCCINFAON_CPU1_FLT      2 @S9S_MB_2U_LIB.S9S_MB_2U(SCH_1):SW_P12V_PVCCINFAON_CPU1_FLT
   1 P12V_AUX      1 @S9S_MB_2U_LIB.S9S_MB_2U(SCH_1):P12V_AUX


DRAWING: @S9S_MB_2U_LIB.S9S_MB_2U(SCH_1):PAGE280 

RAA2213404GNPHB0-RAA2213404GNPA  I14  PU49
  21 PVCCFA_EHV_CPU1_BPWM1    PWM @S9S_MB_2U_LIB.S9S_MB_2U(SCH_1):PVCCFA_EHV_CPU1_BPWM1
  24 PVCCINFAON_CPU1_VREF  REFIN @S9S_MB_2U_LIB.S9S_MB_2U(SCH_1):PVCCINFAON_CPU1_VREF
  23    GND   GND2 @S9S_MB_2U_LIB.S9S_MB_2U(SCH_1):GND
  20 SW_PVCCFA_EHV_CPU1_BOOT1   BOOT @S9S_MB_2U_LIB.S9S_MB_2U(SCH_1):SW_PVCCFA_EHV_CPU1_BOOT1
16_18-28 SW_P12V_PVCCINFAON_CPU1_FLT    VIN @S9S_MB_2U_LIB.S9S_MB_2U(SCH_1):SW_P12V_PVCCINFAON_CPU1_FLT
  19 SW_PVCCFA_EHV_CPU1_BOOTR1  PHASE @S9S_MB_2U_LIB.S9S_MB_2U(SCH_1):SW_PVCCFA_EHV_CPU1_BOOTR1
   4 PVCCFA_EHV_CPU1_VDD1    VCC @S9S_MB_2U_LIB.S9S_MB_2U(SCH_1):PVCCFA_EHV_CPU1_VDD1
   1 PVCCFA_EHV_CPU1_BTSEN   TMON @S9S_MB_2U_LIB.S9S_MB_2U(SCH_1):PVCCFA_EHV_CPU1_BTSEN
  25 PVCCFA_EHV_CPU1_BCSP1   IMON @S9S_MB_2U_LIB.S9S_MB_2U(SCH_1):PVCCFA_EHV_CPU1_BCSP1
6_7-13_15-29    GND   GND1 @S9S_MB_2U_LIB.S9S_MB_2U(SCH_1):GND
  27     NC    GL2     NC
8_12 SW_PVCCFA_EHV_CPU1_SW1     SW @S9S_MB_2U_LIB.S9S_MB_2U(SCH_1):SW_PVCCFA_EHV_CPU1_SW1
   2 PVCCFA_EHV_CPU1_FAULT FAULT# @S9S_MB_2U_LIB.S9S_MB_2U(SCH_1):PVCCFA_EHV_CPU1_FAULT
  26    GND   GND3 @S9S_MB_2U_LIB.S9S_MB_2U(SCH_1):GND
  22 PVCCFA_EHV_CPU1_NC2    NC1 @S9S_MB_2U_LIB.S9S_MB_2U(SCH_1):PVCCFA_EHV_CPU1_NC2
   5 PVCCFA_EHV_CPU1_LSET1    GL1 @S9S_MB_2U_LIB.S9S_MB_2U(SCH_1):PVCCFA_EHV_CPU1_LSET1
   3 PVCCFA_EHV_CPU1_NC1 LGCTRL @S9S_MB_2U_LIB.S9S_MB_2U(SCH_1):PVCCFA_EHV_CPU1_NC1

Q_CAP_C0402-100NF,50V,10%,X7R,A  I22  PC431
   1 SW_PVCCFA_EHV_CPU1_BOOT1_R      A @S9S_MB_2U_LIB.S9S_MB_2U(SCH_1):SW_PVCCFA_EHV_CPU1_BOOT1_R
   2 SW_PVCCFA_EHV_CPU1_BOOTR1      B @S9S_MB_2U_LIB.S9S_MB_2U(SCH_1):SW_PVCCFA_EHV_CPU1_BOOTR1

Q_INDUCTOR_SMLF-300NH/33A,IND,A  I23  PL20
   2 PVCCFA_EHV_CPU1      2 @S9S_MB_2U_LIB.S9S_MB_2U(SCH_1):PVCCFA_EHV_CPU1
   1 SW_PVCCFA_EHV_CPU1_SW1      1 @S9S_MB_2U_LIB.S9S_MB_2U(SCH_1):SW_PVCCFA_EHV_CPU1_SW1

Q_CAP_0402-3300PF,50V,10%,X7R,A  I24  PC429
   1 SW_P12V_PVCCINFAON_CPU1_FLT      A @S9S_MB_2U_LIB.S9S_MB_2U(SCH_1):SW_P12V_PVCCINFAON_CPU1_FLT
   2    GND      B @S9S_MB_2U_LIB.S9S_MB_2U(SCH_1):GND

Q_RES_0402LF-3.3,1%,1/16W,CHIPA  I25  PR1798
   1 SW_PVCCFA_EHV_CPU1_BOOT1      A @S9S_MB_2U_LIB.S9S_MB_2U(SCH_1):SW_PVCCFA_EHV_CPU1_BOOT1
   2 SW_PVCCFA_EHV_CPU1_BOOT1_R      B @S9S_MB_2U_LIB.S9S_MB_2U(SCH_1):SW_PVCCFA_EHV_CPU1_BOOT1_R

Q_CAP_C0805-22UF,16V,20%,X6S,CA  I27  PC432
   1 SW_P12V_PVCCINFAON_CPU1_FLT      A @S9S_MB_2U_LIB.S9S_MB_2U(SCH_1):SW_P12V_PVCCINFAON_CPU1_FLT
   2    GND      B @S9S_MB_2U_LIB.S9S_MB_2U(SCH_1):GND

Q_CAP_C0805-22UF,4V,20%,X6S,CHA  I30  PC435
   1 PVCCFA_EHV_CPU1      A @S9S_MB_2U_LIB.S9S_MB_2U(SCH_1):PVCCFA_EHV_CPU1
   2    GND      B @S9S_MB_2U_LIB.S9S_MB_2U(SCH_1):GND

Q_CAP_C0805-22UF,4V,20%,X6S,CHA  I31  PC437
   1 PVCCFA_EHV_CPU1      A @S9S_MB_2U_LIB.S9S_MB_2U(SCH_1):PVCCFA_EHV_CPU1
   2    GND      B @S9S_MB_2U_LIB.S9S_MB_2U(SCH_1):GND

Q_RES_0402LF-0,5%,1/16W,CHIP,CA  I4  PR678
   1    P5V      A @S9S_MB_2U_LIB.S9S_MB_2U(SCH_1):P5V
   2 PVCCFA_EHV_CPU1_PVCC      B @S9S_MB_2U_LIB.S9S_MB_2U(SCH_1):PVCCFA_EHV_CPU1_PVCC

Q_RES_0402LF-2.2,1%,1/16W,CHIPA  I15  PR250
   1 PVCCFA_EHV_CPU1_PVCC      A @S9S_MB_2U_LIB.S9S_MB_2U(SCH_1):PVCCFA_EHV_CPU1_PVCC
   2 PVCCFA_EHV_CPU1_VDD1      B @S9S_MB_2U_LIB.S9S_MB_2U(SCH_1):PVCCFA_EHV_CPU1_VDD1

Q_CAP_C0402-1UF,16V,10%,X6S,CHA  I26  PC430
   1 SW_P12V_PVCCINFAON_CPU1_FLT      A @S9S_MB_2U_LIB.S9S_MB_2U(SCH_1):SW_P12V_PVCCINFAON_CPU1_FLT
   2    GND      B @S9S_MB_2U_LIB.S9S_MB_2U(SCH_1):GND

Q_CAP_C0805-22UF,16V,20%,X6S,CA  I28  PC433
   1 SW_P12V_PVCCINFAON_CPU1_FLT      A @S9S_MB_2U_LIB.S9S_MB_2U(SCH_1):SW_P12V_PVCCINFAON_CPU1_FLT
   2    GND      B @S9S_MB_2U_LIB.S9S_MB_2U(SCH_1):GND

Q_CAP_C0402-100NF,50V,10%,X7R,A  I29  PC434
   1 PVCCFA_EHV_CPU1      A @S9S_MB_2U_LIB.S9S_MB_2U(SCH_1):PVCCFA_EHV_CPU1
   2    GND      B @S9S_MB_2U_LIB.S9S_MB_2U(SCH_1):GND

Q_CAP_0402-0.1UF,25V,10%,X7R,CA  I9  PC1366
   1    GND      A @S9S_MB_2U_LIB.S9S_MB_2U(SCH_1):GND
   2 PVCCINFAON_CPU1_VREF      B @S9S_MB_2U_LIB.S9S_MB_2U(SCH_1):PVCCINFAON_CPU1_VREF

Q_CAPP_THLF-560UF,2.5V,20%,OSCA  I32  PC2199
   1 PVCCFA_EHV_CPU1      A @S9S_MB_2U_LIB.S9S_MB_2U(SCH_1):PVCCFA_EHV_CPU1
   2    GND      B @S9S_MB_2U_LIB.S9S_MB_2U(SCH_1):GND

Q_RES_0402LF-8.87K,1%,1/16W,EMA  I1  PR1728
   1 PVCCFA_EHV_CPU1_LSET1      A @S9S_MB_2U_LIB.S9S_MB_2U(SCH_1):PVCCFA_EHV_CPU1_LSET1
   2    GND      B @S9S_MB_2U_LIB.S9S_MB_2U(SCH_1):GND

Q_CAP_C0402-2.2UF,10V,10%,X6S,A  I11  PC428
   1 PVCCFA_EHV_CPU1_VDD1      A @S9S_MB_2U_LIB.S9S_MB_2U(SCH_1):PVCCFA_EHV_CPU1_VDD1
   2    GND      B @S9S_MB_2U_LIB.S9S_MB_2U(SCH_1):GND

Q_RES_0402LF-0,5%,1/16W,EMPTY,A  I13  PR4248
   1 PVCCFA_EHV_CPU1_NC2      A @S9S_MB_2U_LIB.S9S_MB_2U(SCH_1):PVCCFA_EHV_CPU1_NC2
   2 PVCCFA_EHV_CPU1_VDD1      B @S9S_MB_2U_LIB.S9S_MB_2U(SCH_1):PVCCFA_EHV_CPU1_VDD1

Q_RES_0402LF-0,5%,1/16W,EMPTY,A  I16  PR699
   1   P3V3      A @S9S_MB_2U_LIB.S9S_MB_2U(SCH_1):P3V3
   2 PVCCFA_EHV_CPU1_PVCC      B @S9S_MB_2U_LIB.S9S_MB_2U(SCH_1):PVCCFA_EHV_CPU1_PVCC

Q_RES_0402LF-0,5%,1/16W,EMPTY,A  I18  PR4249
   1 PVCCFA_EHV_CPU1_FAULT      A @S9S_MB_2U_LIB.S9S_MB_2U(SCH_1):PVCCFA_EHV_CPU1_FAULT
   2    GND      B @S9S_MB_2U_LIB.S9S_MB_2U(SCH_1):GND

Q_RES_0402LF-0,5%,1/16W,CHIP,CA  I20  PR1799
   1 PVCCFA_EHV_CPU1_NC1      A @S9S_MB_2U_LIB.S9S_MB_2U(SCH_1):PVCCFA_EHV_CPU1_NC1
   2 PVCCFA_EHV_CPU1_VDD1      B @S9S_MB_2U_LIB.S9S_MB_2U(SCH_1):PVCCFA_EHV_CPU1_VDD1

Q_CAPP_SMLF-330UF,2.5V,+10/-35B  I33  PC1930
   1 PVCCFA_EHV_CPU1      A @S9S_MB_2U_LIB.S9S_MB_2U(SCH_1):PVCCFA_EHV_CPU1
   2    GND      B @S9S_MB_2U_LIB.S9S_MB_2U(SCH_1):GND

Q_RES_0402LF-499,1%,1/16W,CHIPA  I37  PR4250
   1 PVCCFA_EHV_CPU1      A @S9S_MB_2U_LIB.S9S_MB_2U(SCH_1):PVCCFA_EHV_CPU1
   2    GND      B @S9S_MB_2U_LIB.S9S_MB_2U(SCH_1):GND


DRAWING: @S9S_MB_2U_LIB.S9S_MB_2U(SCH_1):PAGE283 

Q_CAP_0402-0.1UF,25V,10%,X7R,CA  I8  PC1371
   1    GND      A @S9S_MB_2U_LIB.S9S_MB_2U(SCH_1):GND
   2 PVCCD_HV_CPU1_VREF      B @S9S_MB_2U_LIB.S9S_MB_2U(SCH_1):PVCCD_HV_CPU1_VREF

Q_CAP_C0402-2.2UF,10V,10%,X6S,A  I18  PC2951
   1 PVCCFA_EHV_CPU1_PVCC      A @S9S_MB_2U_LIB.S9S_MB_2U(SCH_1):PVCCFA_EHV_CPU1_PVCC
   2    GND      B @S9S_MB_2U_LIB.S9S_MB_2U(SCH_1):GND

Q_CAP_0402-3300PF,50V,10%,X7R,A  I20  PC374
   1 SW_P12V_PVCCINFAON_CPU1_FLT      A @S9S_MB_2U_LIB.S9S_MB_2U(SCH_1):SW_P12V_PVCCINFAON_CPU1_FLT
   2    GND      B @S9S_MB_2U_LIB.S9S_MB_2U(SCH_1):GND

Q_RES_0402LF-3.3,1%,1/16W,CHIPA  I21  PR1804
   1 SW_PVCCD_HV_CPU1_BOOT1      A @S9S_MB_2U_LIB.S9S_MB_2U(SCH_1):SW_PVCCD_HV_CPU1_BOOT1
   2 SW_PVCCD_HV_CPU1_BOOT1_R      B @S9S_MB_2U_LIB.S9S_MB_2U(SCH_1):SW_PVCCD_HV_CPU1_BOOT1_R

Q_CAP_C0805-22UF,16V,20%,X6S,CA  I23  PC377
   1 SW_P12V_PVCCINFAON_CPU1_FLT      A @S9S_MB_2U_LIB.S9S_MB_2U(SCH_1):SW_P12V_PVCCINFAON_CPU1_FLT
   2    GND      B @S9S_MB_2U_LIB.S9S_MB_2U(SCH_1):GND

Q_CAP_C0402-100NF,50V,10%,X7R,A  I27  PC379
   1 PVCCD_HV_CPU1      A @S9S_MB_2U_LIB.S9S_MB_2U(SCH_1):PVCCD_HV_CPU1
   2    GND      B @S9S_MB_2U_LIB.S9S_MB_2U(SCH_1):GND

Q_CAP_C0805-22UF,4V,20%,X6S,CHA  I28  PC381
   1 PVCCD_HV_CPU1      A @S9S_MB_2U_LIB.S9S_MB_2U(SCH_1):PVCCD_HV_CPU1
   2    GND      B @S9S_MB_2U_LIB.S9S_MB_2U(SCH_1):GND

Q_RES_0402LF-0,5%,1/16W,CHIP,CA  I12  PR1805
   1 PVCCD_HV_CPU1_VOS      A @S9S_MB_2U_LIB.S9S_MB_2U(SCH_1):PVCCD_HV_CPU1_VOS
   2 PVCCD_HV_CPU1      B @S9S_MB_2U_LIB.S9S_MB_2U(SCH_1):PVCCD_HV_CPU1

Q_CAP_C0402-1UF,16V,10%,X6S,CHA  I22  PC375
   1 SW_P12V_PVCCINFAON_CPU1_FLT      A @S9S_MB_2U_LIB.S9S_MB_2U(SCH_1):SW_P12V_PVCCINFAON_CPU1_FLT
   2    GND      B @S9S_MB_2U_LIB.S9S_MB_2U(SCH_1):GND

Q_INDUCTOR_SMLF-120NH/69A,IND,A  I14  PL17
   2 PVCCD_HV_CPU1      2 @S9S_MB_2U_LIB.S9S_MB_2U(SCH_1):PVCCD_HV_CPU1
   1 SW_PVCCD_HV_CPU1_SW1      1 @S9S_MB_2U_LIB.S9S_MB_2U(SCH_1):SW_PVCCD_HV_CPU1_SW1

Q_CAP_C0402-2.2UF,10V,10%,X6S,A  I15  PC373
   1 PVCCD_HV_CPU1_VDD1      A @S9S_MB_2U_LIB.S9S_MB_2U(SCH_1):PVCCD_HV_CPU1_VDD1
   2    GND      B @S9S_MB_2U_LIB.S9S_MB_2U(SCH_1):GND

Q_CAP_C0805-22UF,4V,20%,X6S,CHA  I29  PC382
   1 PVCCD_HV_CPU1      A @S9S_MB_2U_LIB.S9S_MB_2U(SCH_1):PVCCD_HV_CPU1
   2    GND      B @S9S_MB_2U_LIB.S9S_MB_2U(SCH_1):GND

Q_RES_0402LF-8.87K,1%,1/16W,EMA  I3  PR1746
   1 PVCCD_HV_CPU1_LSET1      A @S9S_MB_2U_LIB.S9S_MB_2U(SCH_1):PVCCD_HV_CPU1_LSET1
   2    GND      B @S9S_MB_2U_LIB.S9S_MB_2U(SCH_1):GND

ISL99390FRZTR5935-ISL99390FRZ-A  I10  PU17
  34 PVCCD_HV_CPU1_APWM1    PWM @S9S_MB_2U_LIB.S9S_MB_2U(SCH_1):PVCCD_HV_CPU1_APWM1
  39 PVCCD_HV_CPU1_VREF  REFIN @S9S_MB_2U_LIB.S9S_MB_2U(SCH_1):PVCCD_HV_CPU1_VREF
   3 PVCCD_HV_CPU1_VDD1    VCC @S9S_MB_2U_LIB.S9S_MB_2U(SCH_1):PVCCD_HV_CPU1_VDD1
   2    GND   AGND @S9S_MB_2U_LIB.S9S_MB_2U(SCH_1):GND
  33 SW_PVCCD_HV_CPU1_BOOT1   BOOT @S9S_MB_2U_LIB.S9S_MB_2U(SCH_1):SW_PVCCD_HV_CPU1_BOOT1
25_29 SW_P12V_PVCCINFAON_CPU1_FLT   VIN1 @S9S_MB_2U_LIB.S9S_MB_2U(SCH_1):SW_P12V_PVCCINFAON_CPU1_FLT
  32 SW_PVCCD_HV_CPU1_BOOTR1  PHASE @S9S_MB_2U_LIB.S9S_MB_2U(SCH_1):SW_PVCCD_HV_CPU1_BOOTR1
   4 PVCCFA_EHV_CPU1_PVCC   PVCC @S9S_MB_2U_LIB.S9S_MB_2U(SCH_1):PVCCFA_EHV_CPU1_PVCC
  36 PVCCD_HV_CPU1_ATSEN TOUT_FLT @S9S_MB_2U_LIB.S9S_MB_2U(SCH_1):PVCCD_HV_CPU1_ATSEN
  38 PVCCD_HV_CPU1_ACSP1   IOUT @S9S_MB_2U_LIB.S9S_MB_2U(SCH_1):PVCCD_HV_CPU1_ACSP1
  37 PVCCD_HV_CPU1_LSET1   LSET @S9S_MB_2U_LIB.S9S_MB_2U(SCH_1):PVCCD_HV_CPU1_LSET1
10_19 SW_PVCCD_HV_CPU1_SW1     SW @S9S_MB_2U_LIB.S9S_MB_2U(SCH_1):SW_PVCCD_HV_CPU1_SW1
   5    GND  PGND1 @S9S_MB_2U_LIB.S9S_MB_2U(SCH_1):GND
  30 SW_P12V_PVCCINFAON_CPU1_FLT   VIN2 @S9S_MB_2U_LIB.S9S_MB_2U(SCH_1):SW_P12V_PVCCINFAON_CPU1_FLT
   1 PVCCD_HV_CPU1_VOS    VOS @S9S_MB_2U_LIB.S9S_MB_2U(SCH_1):PVCCD_HV_CPU1_VOS
  40    GND  PGND3 @S9S_MB_2U_LIB.S9S_MB_2U(SCH_1):GND
  35 PVCCD_HV_CPU1_VDD1     EN @S9S_MB_2U_LIB.S9S_MB_2U(SCH_1):PVCCD_HV_CPU1_VDD1
  31     NC    DNC     NC
   6     NC    GL1     NC
  41     NC    GL2     NC
7_9-20_24    GND  PGND2 @S9S_MB_2U_LIB.S9S_MB_2U(SCH_1):GND

Q_RES_0402LF-2.2,1%,1/16W,CHIPA  I16  PR200
   1 PVCCFA_EHV_CPU1_PVCC      A @S9S_MB_2U_LIB.S9S_MB_2U(SCH_1):PVCCFA_EHV_CPU1_PVCC
   2 PVCCD_HV_CPU1_VDD1      B @S9S_MB_2U_LIB.S9S_MB_2U(SCH_1):PVCCD_HV_CPU1_VDD1

Q_CAP_C0805-22UF,4V,20%,X6S,CHA  I30  PC2
   1 PVCCD_HV_CPU1      A @S9S_MB_2U_LIB.S9S_MB_2U(SCH_1):PVCCD_HV_CPU1
   2    GND      B @S9S_MB_2U_LIB.S9S_MB_2U(SCH_1):GND

Q_CAPP_THLF-560UF,2.5V,20%,OSCA  I32  PC385
   1 PVCCD_HV_CPU1      A @S9S_MB_2U_LIB.S9S_MB_2U(SCH_1):PVCCD_HV_CPU1
   2    GND      B @S9S_MB_2U_LIB.S9S_MB_2U(SCH_1):GND

Q_CAP_C0402-100NF,50V,10%,X7R,A  I13  PC376
   1 SW_PVCCD_HV_CPU1_BOOT1_R      A @S9S_MB_2U_LIB.S9S_MB_2U(SCH_1):SW_PVCCD_HV_CPU1_BOOT1_R
   2 SW_PVCCD_HV_CPU1_BOOTR1      B @S9S_MB_2U_LIB.S9S_MB_2U(SCH_1):SW_PVCCD_HV_CPU1_BOOTR1

Q_CAP_C0805-22UF,16V,20%,X6S,CA  I24  PC378
   1 SW_P12V_PVCCINFAON_CPU1_FLT      A @S9S_MB_2U_LIB.S9S_MB_2U(SCH_1):SW_P12V_PVCCINFAON_CPU1_FLT
   2    GND      B @S9S_MB_2U_LIB.S9S_MB_2U(SCH_1):GND

Q_CAPP_SMLF-330UF,2V,35%,SPCAPA  I25  PC1940
   1 PVCCD_HV_CPU1      A @S9S_MB_2U_LIB.S9S_MB_2U(SCH_1):PVCCD_HV_CPU1
   2    GND      B @S9S_MB_2U_LIB.S9S_MB_2U(SCH_1):GND

Q_CAPP_THLF-560UF,2.5V,20%,OSCA  I26  PC384
   1 PVCCD_HV_CPU1      A @S9S_MB_2U_LIB.S9S_MB_2U(SCH_1):PVCCD_HV_CPU1
   2    GND      B @S9S_MB_2U_LIB.S9S_MB_2U(SCH_1):GND

Q_RES_0402LF-499,1%,1/16W,CHIPA  I35  PR4258
   1 PVCCD_HV_CPU1      A @S9S_MB_2U_LIB.S9S_MB_2U(SCH_1):PVCCD_HV_CPU1
   2    GND      B @S9S_MB_2U_LIB.S9S_MB_2U(SCH_1):GND


DRAWING: @S9S_MB_2U_LIB.S9S_MB_2U(SCH_1):PAGE285 

Q_CAP_C0805-22UF,16V,20%,X6S,CA  I15  PC1260
   1 SW_P12V_PVCCIN_CPU1_FLT      A @S9S_MB_2U_LIB.S9S_MB_2U(SCH_1):SW_P12V_PVCCIN_CPU1_FLT
   2    GND      B @S9S_MB_2U_LIB.S9S_MB_2U(SCH_1):GND

Q_RES_0402LF-30.1K,1%,1/16W,CHA  I18  PR3336
   1 PVPP_HBM_CPU1_MODE      A @S9S_MB_2U_LIB.S9S_MB_2U(SCH_1):PVPP_HBM_CPU1_MODE
   2    GND      B @S9S_MB_2U_LIB.S9S_MB_2U(SCH_1):GND

Q_RES_0402LF-26.1K,0.1%,1/16W,A  I30  PR2381
   1 PVPP_HBM_CPU1_FB      A @S9S_MB_2U_LIB.S9S_MB_2U(SCH_1):PVPP_HBM_CPU1_FB
   2 FM_HBM_VPP_SEL_CPU1_D      B @S9S_MB_2U_LIB.S9S_MB_2U(SCH_1):FM_HBM_VPP_SEL_CPU1_D

Q_CAP_0402-0.01UF,25V,10%,X7R,A  I32  PC2282
   1 SH_PVPP_HBM_CPU1_P      A @S9S_MB_2U_LIB.S9S_MB_2U(SCH_1):SH_PVPP_HBM_CPU1_P
   2 SH_PVPP_HBM_CPU1_N      B @S9S_MB_2U_LIB.S9S_MB_2U(SCH_1):SH_PVPP_HBM_CPU1_N

Q_CAP_0402-1000PF,50V,5%,X7R,TA  I36  C2460
   1 PWRGD_PVPP_HBM_CPU1_R      A @S9S_MB_2U_LIB.S9S_MB_2U(SCH_1):PWRGD_PVPP_HBM_CPU1_R
   2    GND      B @S9S_MB_2U_LIB.S9S_MB_2U(SCH_1):GND

Q_CAP_C0402-1UF,16V,10%,X6S,CHA  I17  PC1262
   1 SW_P12V_PVCCIN_CPU1_FLT      A @S9S_MB_2U_LIB.S9S_MB_2U(SCH_1):SW_P12V_PVCCIN_CPU1_FLT
   2    GND      B @S9S_MB_2U_LIB.S9S_MB_2U(SCH_1):GND

Q_RES_0402LF-10K,1%,1/16W,CHIPA  I27  R2583
   1 P3V3_AUX      A @S9S_MB_2U_LIB.S9S_MB_2U(SCH_1):P3V3_AUX
   2 PWRGD_PVPP_HBM_CPU1_R      B @S9S_MB_2U_LIB.S9S_MB_2U(SCH_1):PWRGD_PVPP_HBM_CPU1_R

Q_RES_0402LF-11.3K,0.1%,1/16W,A  I28  PR1314
   1 PVPP_HBM_CPU1_FB      A @S9S_MB_2U_LIB.S9S_MB_2U(SCH_1):PVPP_HBM_CPU1_FB
   2 SH_PVPP_HBM_CPU1_N      B @S9S_MB_2U_LIB.S9S_MB_2U(SCH_1):SH_PVPP_HBM_CPU1_N

Q_INDUCTOR_SMLF-0.68UH,IND,CV+A  I33  PL119
   2 PVPP_HBM_CPU1      2 @S9S_MB_2U_LIB.S9S_MB_2U(SCH_1):PVPP_HBM_CPU1
   1 SW_PVPP_HBM_CPU1_SW      1 @S9S_MB_2U_LIB.S9S_MB_2U(SCH_1):SW_PVPP_HBM_CPU1_SW

Q_RES_0402LF-38.3K,0.1%,1/16W,A  I34  PR1340
   1 PVPP_HBM_CPU1_FB      A @S9S_MB_2U_LIB.S9S_MB_2U(SCH_1):PVPP_HBM_CPU1_FB
   2 SH_PVPP_HBM_CPU1_P      B @S9S_MB_2U_LIB.S9S_MB_2U(SCH_1):SH_PVPP_HBM_CPU1_P

Q_SHORT_SM-EMPTY,SHORT6  I44  PJ67
   1 SH_PVPP_HBM_CPU1_N      1 @S9S_MB_2U_LIB.S9S_MB_2U(SCH_1):SH_PVPP_HBM_CPU1_N
   2    GND      2 @S9S_MB_2U_LIB.S9S_MB_2U(SCH_1):GND

Q_CAP_0402-1000PF,50V,5%,EMPTYA  I11  C2445
   1 FM_PVPP_HBM_CPU1_EN      A @S9S_MB_2U_LIB.S9S_MB_2U(SCH_1):FM_PVPP_HBM_CPU1_EN
   2    GND      B @S9S_MB_2U_LIB.S9S_MB_2U(SCH_1):GND

Q_RES_0402LF-2K,1%,1/16W,CHIP,A  I13  R2374
   1 FM_PVPP_HBM_CPU1_EN      A @S9S_MB_2U_LIB.S9S_MB_2U(SCH_1):FM_PVPP_HBM_CPU1_EN
   2    GND      B @S9S_MB_2U_LIB.S9S_MB_2U(SCH_1):GND

RS53318LR-RS53318LR,SMLF,IC,ALA  I25  PU80
  10 SW_P12V_PVCCIN_CPU1_FLT   VIN1 @S9S_MB_2U_LIB.S9S_MB_2U(SCH_1):SW_P12V_PVCCIN_CPU1_FLT
   9 PWRGD_PVPP_HBM_CPU1_R  PGOOD @S9S_MB_2U_LIB.S9S_MB_2U(SCH_1):PWRGD_PVPP_HBM_CPU1_R
11_18    GND   PGND @S9S_MB_2U_LIB.S9S_MB_2U(SCH_1):GND
   8 FM_PVPP_HBM_CPU1_EN     EN @S9S_MB_2U_LIB.S9S_MB_2U(SCH_1):FM_PVPP_HBM_CPU1_EN
   1 SW_PVPP_HBM_CPU1_BST    BST @S9S_MB_2U_LIB.S9S_MB_2U(SCH_1):SW_PVPP_HBM_CPU1_BST
   7 PVPP_HBM_CPU1_FB     FB @S9S_MB_2U_LIB.S9S_MB_2U(SCH_1):PVPP_HBM_CPU1_FB
   2    GND   AGND @S9S_MB_2U_LIB.S9S_MB_2U(SCH_1):GND
  19 PVPP_HBM_CPU1_VCC    VCC @S9S_MB_2U_LIB.S9S_MB_2U(SCH_1):PVPP_HBM_CPU1_VCC
   6 SH_PVPP_HBM_CPU1_N    RTN @S9S_MB_2U_LIB.S9S_MB_2U(SCH_1):SH_PVPP_HBM_CPU1_N
  20 SW_PVPP_HBM_CPU1_SW     SW @S9S_MB_2U_LIB.S9S_MB_2U(SCH_1):SW_PVPP_HBM_CPU1_SW
   5 PVPP_HBM_CPU1_REF    REF @S9S_MB_2U_LIB.S9S_MB_2U(SCH_1):PVPP_HBM_CPU1_REF
   4 PVPP_HBM_CPU1_MODE   MODE @S9S_MB_2U_LIB.S9S_MB_2U(SCH_1):PVPP_HBM_CPU1_MODE
   3 PVPP_HBM_CPU1_CS     CS @S9S_MB_2U_LIB.S9S_MB_2U(SCH_1):PVPP_HBM_CPU1_CS
  21 SW_P12V_PVCCIN_CPU1_FLT   VIN2 @S9S_MB_2U_LIB.S9S_MB_2U(SCH_1):SW_P12V_PVCCIN_CPU1_FLT

Q_RES_0402LF-0,5%,1/16W,CHIP,CA  I37  R2380
   1 PWRGD_PVPP_HBM_CPU1_R      A @S9S_MB_2U_LIB.S9S_MB_2U(SCH_1):PWRGD_PVPP_HBM_CPU1_R
   2 PWRGD_PVPP_HBM_CPU1      B @S9S_MB_2U_LIB.S9S_MB_2U(SCH_1):PWRGD_PVPP_HBM_CPU1

Q_RES_0402LF-0,5%,1/16W,CHIP,CA  I3  PR1338
   1 P3V3_AUX      A @S9S_MB_2U_LIB.S9S_MB_2U(SCH_1):P3V3_AUX
   2 PVPP_HBM_CPU1_VCC      B @S9S_MB_2U_LIB.S9S_MB_2U(SCH_1):PVPP_HBM_CPU1_VCC

Q_RES_0402LF-9.76K,1%,1/16W,CHA  I10  PR1339
   1 PVPP_HBM_CPU1_CS      A @S9S_MB_2U_LIB.S9S_MB_2U(SCH_1):PVPP_HBM_CPU1_CS
   2    GND      B @S9S_MB_2U_LIB.S9S_MB_2U(SCH_1):GND

Q_CAP_C0805-22UF,16V,20%,X6S,CA  I16  PC1261
   1 SW_P12V_PVCCIN_CPU1_FLT      A @S9S_MB_2U_LIB.S9S_MB_2U(SCH_1):SW_P12V_PVCCIN_CPU1_FLT
   2    GND      B @S9S_MB_2U_LIB.S9S_MB_2U(SCH_1):GND

Q_CAP_0402-0.1UF,25V,10%,X7R,CA  I24  PC1264
   1 PVPP_HBM_CPU1_REF      A @S9S_MB_2U_LIB.S9S_MB_2U(SCH_1):PVPP_HBM_CPU1_REF
   2 SH_PVPP_HBM_CPU1_N      B @S9S_MB_2U_LIB.S9S_MB_2U(SCH_1):SH_PVPP_HBM_CPU1_N

Q_CAP_C0805-22UF,4V,20%,X6S,CHA  I41  PC1269
   1 PVPP_HBM_CPU1      A @S9S_MB_2U_LIB.S9S_MB_2U(SCH_1):PVPP_HBM_CPU1
   2    GND      B @S9S_MB_2U_LIB.S9S_MB_2U(SCH_1):GND

Q_SHORT_SM-EMPTY,SHORT6  I46  PJ66
   1 SH_PVPP_HBM_CPU1_P      1 @S9S_MB_2U_LIB.S9S_MB_2U(SCH_1):SH_PVPP_HBM_CPU1_P
   2 PVPP_HBM_CPU1      2 @S9S_MB_2U_LIB.S9S_MB_2U(SCH_1):PVPP_HBM_CPU1

Q_CAP_C0402-1UF,25V,10%,X6S,CHA  I1  PC644
   1 PVPP_HBM_CPU1_VCC      A @S9S_MB_2U_LIB.S9S_MB_2U(SCH_1):PVPP_HBM_CPU1_VCC
   2    GND      B @S9S_MB_2U_LIB.S9S_MB_2U(SCH_1):GND

Q_CAP_C0805-22UF,16V,20%,X6S,CA  I8  PC1259
   1 SW_P12V_PVCCIN_CPU1_FLT      A @S9S_MB_2U_LIB.S9S_MB_2U(SCH_1):SW_P12V_PVCCIN_CPU1_FLT
   2    GND      B @S9S_MB_2U_LIB.S9S_MB_2U(SCH_1):GND

Q_RES_0402LF-10K,1%,1/16W,EMPTA  I14  R2367
   1 P3V3_AUX      A @S9S_MB_2U_LIB.S9S_MB_2U(SCH_1):P3V3_AUX
   2 FM_PVPP_HBM_CPU1_EN      B @S9S_MB_2U_LIB.S9S_MB_2U(SCH_1):FM_PVPP_HBM_CPU1_EN

Q_CAP_0402-0.022UF,16V,10%,X7RA  I23  PC2002
   1 PVPP_HBM_CPU1_REF      A @S9S_MB_2U_LIB.S9S_MB_2U(SCH_1):PVPP_HBM_CPU1_REF
   2    GND      B @S9S_MB_2U_LIB.S9S_MB_2U(SCH_1):GND

Q_CAP_C0402-0.22UF,25V,10%,X7RA  I26  PC1265
   1 SW_PVPP_HBM_CPU1_BST      A @S9S_MB_2U_LIB.S9S_MB_2U(SCH_1):SW_PVPP_HBM_CPU1_BST
   2 SW_PVPP_HBM_CPU1_SW      B @S9S_MB_2U_LIB.S9S_MB_2U(SCH_1):SW_PVPP_HBM_CPU1_SW

MOSFET_N_SMLF-BSS138K,BSS138K,B  I29  PU174
   G FM_HBM2_HBM3_VPP_SEL   GATE @S9S_MB_2U_LIB.S9S_MB_2U(SCH_1):FM_HBM2_HBM3_VPP_SEL
   D FM_HBM_VPP_SEL_CPU1_D  DRAIN @S9S_MB_2U_LIB.S9S_MB_2U(SCH_1):FM_HBM_VPP_SEL_CPU1_D
   S SH_PVPP_HBM_CPU1_N SOURCE @S9S_MB_2U_LIB.S9S_MB_2U(SCH_1):SH_PVPP_HBM_CPU1_N

Q_CAP_0402-680PF,50V,10%,X7R,TA  I35  PC1266
   1 PVPP_HBM_CPU1_FB      A @S9S_MB_2U_LIB.S9S_MB_2U(SCH_1):PVPP_HBM_CPU1_FB
   2 SH_PVPP_HBM_CPU1_P      B @S9S_MB_2U_LIB.S9S_MB_2U(SCH_1):SH_PVPP_HBM_CPU1_P

Q_CAP_0402-0.1UF,25V,10%,X7R,CA  I39  PC1267
   1 PVPP_HBM_CPU1      A @S9S_MB_2U_LIB.S9S_MB_2U(SCH_1):PVPP_HBM_CPU1
   2    GND      B @S9S_MB_2U_LIB.S9S_MB_2U(SCH_1):GND

Q_CAP_C0805-22UF,4V,20%,X6S,CHA  I40  PC1268
   1 PVPP_HBM_CPU1      A @S9S_MB_2U_LIB.S9S_MB_2U(SCH_1):PVPP_HBM_CPU1
   2    GND      B @S9S_MB_2U_LIB.S9S_MB_2U(SCH_1):GND

Q_CAP_C0805-22UF,4V,20%,X6S,CHA  I47  PC1270
   1 PVPP_HBM_CPU1      A @S9S_MB_2U_LIB.S9S_MB_2U(SCH_1):PVPP_HBM_CPU1
   2    GND      B @S9S_MB_2U_LIB.S9S_MB_2U(SCH_1):GND

Q_CAPP_THLF-560UF,6.3V,20%,OSCA  I49  PC1771
   1 PVPP_HBM_CPU1      A @S9S_MB_2U_LIB.S9S_MB_2U(SCH_1):PVPP_HBM_CPU1
   2    GND      B @S9S_MB_2U_LIB.S9S_MB_2U(SCH_1):GND


DRAWING: @S9S_MB_2U_LIB.S9S_MB_2U(SCH_1):PAGE287 

PICOPROBE_BXA-DELTA-L 4.0,SMLFA  I8  J68
   2 DELTA_L_85_5INCH_IN4_DN    2_N @S9S_MB_2U_LIB.S9S_MB_2U(SCH_1):DELTA_L_85_5INCH_IN4_DN
   3 DELTA_L_GND_1    3_G @S9S_MB_2U_LIB.S9S_MB_2U(SCH_1):DELTA_L_GND_1
   1 DELTA_L_85_5INCH_IN4_DP    1_P @S9S_MB_2U_LIB.S9S_MB_2U(SCH_1):DELTA_L_85_5INCH_IN4_DP

PICOPROBE_BXA-DELTA-L 4.0,SMLFA  I11  J67
   2 DELTA_L_85_5INCH_IN3_DN    2_N @S9S_MB_2U_LIB.S9S_MB_2U(SCH_1):DELTA_L_85_5INCH_IN3_DN
   3 DELTA_L_GND_1    3_G @S9S_MB_2U_LIB.S9S_MB_2U(SCH_1):DELTA_L_GND_1
   1 DELTA_L_85_5INCH_IN3_DP    1_P @S9S_MB_2U_LIB.S9S_MB_2U(SCH_1):DELTA_L_85_5INCH_IN3_DP

PICOPROBE_BXA-DELTA-L 4.0,SMLFA  I12  J66
   2 DELTA_L_85_5INCH_IN2_DN    2_N @S9S_MB_2U_LIB.S9S_MB_2U(SCH_1):DELTA_L_85_5INCH_IN2_DN
   3 DELTA_L_GND_1    3_G @S9S_MB_2U_LIB.S9S_MB_2U(SCH_1):DELTA_L_GND_1
   1 DELTA_L_85_5INCH_IN2_DP    1_P @S9S_MB_2U_LIB.S9S_MB_2U(SCH_1):DELTA_L_85_5INCH_IN2_DP

PICOPROBE_BXA-DELTA-L 4.0,SMLFA  I19  J74
   2 DELTA_L_85_5INCH_IN4_DP    2_N @S9S_MB_2U_LIB.S9S_MB_2U(SCH_1):DELTA_L_85_5INCH_IN4_DP
   3 DELTA_L_GND_1    3_G @S9S_MB_2U_LIB.S9S_MB_2U(SCH_1):DELTA_L_GND_1
   1 DELTA_L_85_5INCH_IN4_DN    1_P @S9S_MB_2U_LIB.S9S_MB_2U(SCH_1):DELTA_L_85_5INCH_IN4_DN

PICOPROBE_BXA-DELTA-L 4.0,SMLFA  I21  J72
   2 DELTA_L_85_5INCH_IN2_DP    2_N @S9S_MB_2U_LIB.S9S_MB_2U(SCH_1):DELTA_L_85_5INCH_IN2_DP
   3 DELTA_L_GND_1    3_G @S9S_MB_2U_LIB.S9S_MB_2U(SCH_1):DELTA_L_GND_1
   1 DELTA_L_85_5INCH_IN2_DN    1_P @S9S_MB_2U_LIB.S9S_MB_2U(SCH_1):DELTA_L_85_5INCH_IN2_DN

PICOPROBE_BXA-DELTA-L 4.0,SMLFA  I23  J70
   2 DELTA_L_85_5INCH_BOT_DP    2_N @S9S_MB_2U_LIB.S9S_MB_2U(SCH_1):DELTA_L_85_5INCH_BOT_DP
   3 DELTA_L_GND_1    3_G @S9S_MB_2U_LIB.S9S_MB_2U(SCH_1):DELTA_L_GND_1
   1 DELTA_L_85_5INCH_BOT_DN    1_P @S9S_MB_2U_LIB.S9S_MB_2U(SCH_1):DELTA_L_85_5INCH_BOT_DN

PICOPROBE_BXA-DELTA-L 4.0,SMLFA  I30  J118
   2 DELTA_L_85_10INCH_IN5_DN    2_N @S9S_MB_2U_LIB.S9S_MB_2U(SCH_1):DELTA_L_85_10INCH_IN5_DN
   3 DELTA_L_GND_1    3_G @S9S_MB_2U_LIB.S9S_MB_2U(SCH_1):DELTA_L_GND_1
   1 DELTA_L_85_10INCH_IN5_DP    1_P @S9S_MB_2U_LIB.S9S_MB_2U(SCH_1):DELTA_L_85_10INCH_IN5_DP

PICOPROBE_BXA-DELTA-L 4.0,SMLFA  I31  J121
   2 DELTA_L_85_10INCH_IN6_DP    2_N @S9S_MB_2U_LIB.S9S_MB_2U(SCH_1):DELTA_L_85_10INCH_IN6_DP
   3 DELTA_L_GND_1    3_G @S9S_MB_2U_LIB.S9S_MB_2U(SCH_1):DELTA_L_GND_1
   1 DELTA_L_85_10INCH_IN6_DN    1_P @S9S_MB_2U_LIB.S9S_MB_2U(SCH_1):DELTA_L_85_10INCH_IN6_DN

PICOPROBE_BXA-DELTA-L 4.0,SMLFA  I32  J120
   2 DELTA_L_85_10INCH_IN5_DP    2_N @S9S_MB_2U_LIB.S9S_MB_2U(SCH_1):DELTA_L_85_10INCH_IN5_DP
   3 DELTA_L_GND_1    3_G @S9S_MB_2U_LIB.S9S_MB_2U(SCH_1):DELTA_L_GND_1
   1 DELTA_L_85_10INCH_IN5_DN    1_P @S9S_MB_2U_LIB.S9S_MB_2U(SCH_1):DELTA_L_85_10INCH_IN5_DN

PICOPROBE_BXA-DELTA-L 4.0,SMLFA  I39  J80
   2 DELTA_L_85_10INCH_IN4_DN    2_N @S9S_MB_2U_LIB.S9S_MB_2U(SCH_1):DELTA_L_85_10INCH_IN4_DN
   3 DELTA_L_GND_1    3_G @S9S_MB_2U_LIB.S9S_MB_2U(SCH_1):DELTA_L_GND_1
   1 DELTA_L_85_10INCH_IN4_DP    1_P @S9S_MB_2U_LIB.S9S_MB_2U(SCH_1):DELTA_L_85_10INCH_IN4_DP

PICOPROBE_BXA-DELTA-L 4.0,SMLFA  I43  J78
   2 DELTA_L_85_10INCH_IN2_DN    2_N @S9S_MB_2U_LIB.S9S_MB_2U(SCH_1):DELTA_L_85_10INCH_IN2_DN
   3 DELTA_L_GND_1    3_G @S9S_MB_2U_LIB.S9S_MB_2U(SCH_1):DELTA_L_GND_1
   1 DELTA_L_85_10INCH_IN2_DP    1_P @S9S_MB_2U_LIB.S9S_MB_2U(SCH_1):DELTA_L_85_10INCH_IN2_DP

PICOPROBE_BXA-DELTA-L 4.0,SMLFA  I52  J75
   2 DELTA_L_85_10INCH_TOP_DN    2_N @S9S_MB_2U_LIB.S9S_MB_2U(SCH_1):DELTA_L_85_10INCH_TOP_DN
   3 DELTA_L_GND_1    3_G @S9S_MB_2U_LIB.S9S_MB_2U(SCH_1):DELTA_L_GND_1
   1 DELTA_L_85_10INCH_TOP_DP    1_P @S9S_MB_2U_LIB.S9S_MB_2U(SCH_1):DELTA_L_85_10INCH_TOP_DP

PICOPROBE_BXA-DELTA-L 4.0,SMLFA  I53  J86
   2 DELTA_L_85_10INCH_IN4_DP    2_N @S9S_MB_2U_LIB.S9S_MB_2U(SCH_1):DELTA_L_85_10INCH_IN4_DP
   3 DELTA_L_GND_1    3_G @S9S_MB_2U_LIB.S9S_MB_2U(SCH_1):DELTA_L_GND_1
   1 DELTA_L_85_10INCH_IN4_DN    1_P @S9S_MB_2U_LIB.S9S_MB_2U(SCH_1):DELTA_L_85_10INCH_IN4_DN

PICOPROBE_BXA-DELTA-L 4.0,SMLFA  I55  J84
   2 DELTA_L_85_10INCH_IN2_DP    2_N @S9S_MB_2U_LIB.S9S_MB_2U(SCH_1):DELTA_L_85_10INCH_IN2_DP
   3 DELTA_L_GND_1    3_G @S9S_MB_2U_LIB.S9S_MB_2U(SCH_1):DELTA_L_GND_1
   1 DELTA_L_85_10INCH_IN2_DN    1_P @S9S_MB_2U_LIB.S9S_MB_2U(SCH_1):DELTA_L_85_10INCH_IN2_DN

PICOPROBE_BXA-DELTA-L 4.0,SMLFA  I57  J82
   2 DELTA_L_85_10INCH_BOT_DP    2_N @S9S_MB_2U_LIB.S9S_MB_2U(SCH_1):DELTA_L_85_10INCH_BOT_DP
   3 DELTA_L_GND_1    3_G @S9S_MB_2U_LIB.S9S_MB_2U(SCH_1):DELTA_L_GND_1
   1 DELTA_L_85_10INCH_BOT_DN    1_P @S9S_MB_2U_LIB.S9S_MB_2U(SCH_1):DELTA_L_85_10INCH_BOT_DN

PICOPROBE_BXA-DELTA-L 4.0,SMLFA  I3  J115
   2 DELTA_L_85_5INCH_IN6_DN    2_N @S9S_MB_2U_LIB.S9S_MB_2U(SCH_1):DELTA_L_85_5INCH_IN6_DN
   3 DELTA_L_GND_1    3_G @S9S_MB_2U_LIB.S9S_MB_2U(SCH_1):DELTA_L_GND_1
   1 DELTA_L_85_5INCH_IN6_DP    1_P @S9S_MB_2U_LIB.S9S_MB_2U(SCH_1):DELTA_L_85_5INCH_IN6_DP

PICOPROBE_BXA-DELTA-L 4.0,SMLFA  I4  J114
   2 DELTA_L_85_5INCH_IN5_DN    2_N @S9S_MB_2U_LIB.S9S_MB_2U(SCH_1):DELTA_L_85_5INCH_IN5_DN
   3 DELTA_L_GND_1    3_G @S9S_MB_2U_LIB.S9S_MB_2U(SCH_1):DELTA_L_GND_1
   1 DELTA_L_85_5INCH_IN5_DP    1_P @S9S_MB_2U_LIB.S9S_MB_2U(SCH_1):DELTA_L_85_5INCH_IN5_DP

PICOPROBE_BXA-DELTA-L 4.0,SMLFA  I5  J117
   2 DELTA_L_85_5INCH_IN6_DP    2_N @S9S_MB_2U_LIB.S9S_MB_2U(SCH_1):DELTA_L_85_5INCH_IN6_DP
   3 DELTA_L_GND_1    3_G @S9S_MB_2U_LIB.S9S_MB_2U(SCH_1):DELTA_L_GND_1
   1 DELTA_L_85_5INCH_IN6_DN    1_P @S9S_MB_2U_LIB.S9S_MB_2U(SCH_1):DELTA_L_85_5INCH_IN6_DN

PICOPROBE_BXA-DELTA-L 4.0,SMLFA  I6  J116
   2 DELTA_L_85_5INCH_IN5_DP    2_N @S9S_MB_2U_LIB.S9S_MB_2U(SCH_1):DELTA_L_85_5INCH_IN5_DP
   3 DELTA_L_GND_1    3_G @S9S_MB_2U_LIB.S9S_MB_2U(SCH_1):DELTA_L_GND_1
   1 DELTA_L_85_5INCH_IN5_DN    1_P @S9S_MB_2U_LIB.S9S_MB_2U(SCH_1):DELTA_L_85_5INCH_IN5_DN

PICOPROBE_BXA-DELTA-L 4.0,SMLFA  I14  J65
   2 DELTA_L_85_5INCH_IN1_DN    2_N @S9S_MB_2U_LIB.S9S_MB_2U(SCH_1):DELTA_L_85_5INCH_IN1_DN
   3 DELTA_L_GND_1    3_G @S9S_MB_2U_LIB.S9S_MB_2U(SCH_1):DELTA_L_GND_1
   1 DELTA_L_85_5INCH_IN1_DP    1_P @S9S_MB_2U_LIB.S9S_MB_2U(SCH_1):DELTA_L_85_5INCH_IN1_DP

PICOPROBE_BXA-DELTA-L 4.0,SMLFA  I17  J64
   2 DELTA_L_85_5INCH_BOT_DN    2_N @S9S_MB_2U_LIB.S9S_MB_2U(SCH_1):DELTA_L_85_5INCH_BOT_DN
   3 DELTA_L_GND_1    3_G @S9S_MB_2U_LIB.S9S_MB_2U(SCH_1):DELTA_L_GND_1
   1 DELTA_L_85_5INCH_BOT_DP    1_P @S9S_MB_2U_LIB.S9S_MB_2U(SCH_1):DELTA_L_85_5INCH_BOT_DP

PICOPROBE_BXA-DELTA-L 4.0,SMLFA  I18  J63
   2 DELTA_L_85_5INCH_TOP_DN    2_N @S9S_MB_2U_LIB.S9S_MB_2U(SCH_1):DELTA_L_85_5INCH_TOP_DN
   3 DELTA_L_GND_1    3_G @S9S_MB_2U_LIB.S9S_MB_2U(SCH_1):DELTA_L_GND_1
   1 DELTA_L_85_5INCH_TOP_DP    1_P @S9S_MB_2U_LIB.S9S_MB_2U(SCH_1):DELTA_L_85_5INCH_TOP_DP

PICOPROBE_BXA-DELTA-L 4.0,SMLFA  I20  J73
   2 DELTA_L_85_5INCH_IN3_DP    2_N @S9S_MB_2U_LIB.S9S_MB_2U(SCH_1):DELTA_L_85_5INCH_IN3_DP
   3 DELTA_L_GND_1    3_G @S9S_MB_2U_LIB.S9S_MB_2U(SCH_1):DELTA_L_GND_1
   1 DELTA_L_85_5INCH_IN3_DN    1_P @S9S_MB_2U_LIB.S9S_MB_2U(SCH_1):DELTA_L_85_5INCH_IN3_DN

PICOPROBE_BXA-DELTA-L 4.0,SMLFA  I22  J71
   2 DELTA_L_85_5INCH_IN1_DP    2_N @S9S_MB_2U_LIB.S9S_MB_2U(SCH_1):DELTA_L_85_5INCH_IN1_DP
   3 DELTA_L_GND_1    3_G @S9S_MB_2U_LIB.S9S_MB_2U(SCH_1):DELTA_L_GND_1
   1 DELTA_L_85_5INCH_IN1_DN    1_P @S9S_MB_2U_LIB.S9S_MB_2U(SCH_1):DELTA_L_85_5INCH_IN1_DN

PICOPROBE_BXA-DELTA-L 4.0,SMLFA  I24  J69
   2 DELTA_L_85_5INCH_TOP_DP    2_N @S9S_MB_2U_LIB.S9S_MB_2U(SCH_1):DELTA_L_85_5INCH_TOP_DP
   3 DELTA_L_GND_1    3_G @S9S_MB_2U_LIB.S9S_MB_2U(SCH_1):DELTA_L_GND_1
   1 DELTA_L_85_5INCH_TOP_DN    1_P @S9S_MB_2U_LIB.S9S_MB_2U(SCH_1):DELTA_L_85_5INCH_TOP_DN

PICOPROBE_BXA-DELTA-L 4.0,SMLFA  I28  J119
   2 DELTA_L_85_10INCH_IN6_DN    2_N @S9S_MB_2U_LIB.S9S_MB_2U(SCH_1):DELTA_L_85_10INCH_IN6_DN
   3 DELTA_L_GND_1    3_G @S9S_MB_2U_LIB.S9S_MB_2U(SCH_1):DELTA_L_GND_1
   1 DELTA_L_85_10INCH_IN6_DP    1_P @S9S_MB_2U_LIB.S9S_MB_2U(SCH_1):DELTA_L_85_10INCH_IN6_DP

PICOPROBE_BXA-DELTA-L 4.0,SMLFA  I42  J79
   2 DELTA_L_85_10INCH_IN3_DN    2_N @S9S_MB_2U_LIB.S9S_MB_2U(SCH_1):DELTA_L_85_10INCH_IN3_DN
   3 DELTA_L_GND_1    3_G @S9S_MB_2U_LIB.S9S_MB_2U(SCH_1):DELTA_L_GND_1
   1 DELTA_L_85_10INCH_IN3_DP    1_P @S9S_MB_2U_LIB.S9S_MB_2U(SCH_1):DELTA_L_85_10INCH_IN3_DP

PICOPROBE_BXA-DELTA-L 4.0,SMLFA  I48  J77
   2 DELTA_L_85_10INCH_IN1_DN    2_N @S9S_MB_2U_LIB.S9S_MB_2U(SCH_1):DELTA_L_85_10INCH_IN1_DN
   3 DELTA_L_GND_1    3_G @S9S_MB_2U_LIB.S9S_MB_2U(SCH_1):DELTA_L_GND_1
   1 DELTA_L_85_10INCH_IN1_DP    1_P @S9S_MB_2U_LIB.S9S_MB_2U(SCH_1):DELTA_L_85_10INCH_IN1_DP

PICOPROBE_BXA-DELTA-L 4.0,SMLFA  I51  J76
   2 DELTA_L_85_10INCH_BOT_DN    2_N @S9S_MB_2U_LIB.S9S_MB_2U(SCH_1):DELTA_L_85_10INCH_BOT_DN
   3 DELTA_L_GND_1    3_G @S9S_MB_2U_LIB.S9S_MB_2U(SCH_1):DELTA_L_GND_1
   1 DELTA_L_85_10INCH_BOT_DP    1_P @S9S_MB_2U_LIB.S9S_MB_2U(SCH_1):DELTA_L_85_10INCH_BOT_DP

PICOPROBE_BXA-DELTA-L 4.0,SMLFA  I54  J85
   2 DELTA_L_85_10INCH_IN3_DP    2_N @S9S_MB_2U_LIB.S9S_MB_2U(SCH_1):DELTA_L_85_10INCH_IN3_DP
   3 DELTA_L_GND_1    3_G @S9S_MB_2U_LIB.S9S_MB_2U(SCH_1):DELTA_L_GND_1
   1 DELTA_L_85_10INCH_IN3_DN    1_P @S9S_MB_2U_LIB.S9S_MB_2U(SCH_1):DELTA_L_85_10INCH_IN3_DN

PICOPROBE_BXA-DELTA-L 4.0,SMLFA  I56  J83
   2 DELTA_L_85_10INCH_IN1_DP    2_N @S9S_MB_2U_LIB.S9S_MB_2U(SCH_1):DELTA_L_85_10INCH_IN1_DP
   3 DELTA_L_GND_1    3_G @S9S_MB_2U_LIB.S9S_MB_2U(SCH_1):DELTA_L_GND_1
   1 DELTA_L_85_10INCH_IN1_DN    1_P @S9S_MB_2U_LIB.S9S_MB_2U(SCH_1):DELTA_L_85_10INCH_IN1_DN

PICOPROBE_BXA-DELTA-L 4.0,SMLFA  I58  J81
   2 DELTA_L_85_10INCH_TOP_DP    2_N @S9S_MB_2U_LIB.S9S_MB_2U(SCH_1):DELTA_L_85_10INCH_TOP_DP
   3 DELTA_L_GND_1    3_G @S9S_MB_2U_LIB.S9S_MB_2U(SCH_1):DELTA_L_GND_1
   1 DELTA_L_85_10INCH_TOP_DN    1_P @S9S_MB_2U_LIB.S9S_MB_2U(SCH_1):DELTA_L_85_10INCH_TOP_DN


DRAWING: @S9S_MB_2U_LIB.S9S_MB_2U(SCH_1):PAGE288 

TP_TDR_4P_FTS_TH-TP_TDR_4P_DIPA  I3  X19
   2 T1_GND     P1 @S9S_MB_2U_LIB.S9S_MB_2U(SCH_1):T1_GND
   3 T1_GND     P2 @S9S_MB_2U_LIB.S9S_MB_2U(SCH_1):T1_GND
   1 TDR_DIFF_100_TOP_DN     S1 @S9S_MB_2U_LIB.S9S_MB_2U(SCH_1):TDR_DIFF_100_TOP_DN
   4 TDR_DIFF_100_TOP_DP     S2 @S9S_MB_2U_LIB.S9S_MB_2U(SCH_1):TDR_DIFF_100_TOP_DP

TP_TDR_4P_FTS_TH-TP_TDR_4P_DIPA  I4  X20
   2 T1_GND     P1 @S9S_MB_2U_LIB.S9S_MB_2U(SCH_1):T1_GND
   3 T1_GND     P2 @S9S_MB_2U_LIB.S9S_MB_2U(SCH_1):T1_GND
   1 TDR_DIFF_100_IN1_DN     S1 @S9S_MB_2U_LIB.S9S_MB_2U(SCH_1):TDR_DIFF_100_IN1_DN
   4 TDR_DIFF_100_IN1_DP     S2 @S9S_MB_2U_LIB.S9S_MB_2U(SCH_1):TDR_DIFF_100_IN1_DP

TP_TDR_4P_FTS_TH-TP_TDR_4P_DIPA  I8  X22
   2 T1_GND     P1 @S9S_MB_2U_LIB.S9S_MB_2U(SCH_1):T1_GND
   3 T1_GND     P2 @S9S_MB_2U_LIB.S9S_MB_2U(SCH_1):T1_GND
   1 TDR_DIFF_100_IN3_DN     S1 @S9S_MB_2U_LIB.S9S_MB_2U(SCH_1):TDR_DIFF_100_IN3_DN
   4 TDR_DIFF_100_IN3_DP     S2 @S9S_MB_2U_LIB.S9S_MB_2U(SCH_1):TDR_DIFF_100_IN3_DP

TP_TDR_4P_FTS_TH-TP_TDR_4P_DIPA  I9  X21
   2 T1_GND     P1 @S9S_MB_2U_LIB.S9S_MB_2U(SCH_1):T1_GND
   3 T1_GND     P2 @S9S_MB_2U_LIB.S9S_MB_2U(SCH_1):T1_GND
   1 TDR_DIFF_100_IN2_DN     S1 @S9S_MB_2U_LIB.S9S_MB_2U(SCH_1):TDR_DIFF_100_IN2_DN
   4 TDR_DIFF_100_IN2_DP     S2 @S9S_MB_2U_LIB.S9S_MB_2U(SCH_1):TDR_DIFF_100_IN2_DP

TP_TDR_4P_FTS_TH-TP_TDR_4P_DIPA  I10  X23
   2 T1_GND     P1 @S9S_MB_2U_LIB.S9S_MB_2U(SCH_1):T1_GND
   3 T1_GND     P2 @S9S_MB_2U_LIB.S9S_MB_2U(SCH_1):T1_GND
   1 TDR_DIFF_100_IN4_DN     S1 @S9S_MB_2U_LIB.S9S_MB_2U(SCH_1):TDR_DIFF_100_IN4_DN
   4 TDR_DIFF_100_IN4_DP     S2 @S9S_MB_2U_LIB.S9S_MB_2U(SCH_1):TDR_DIFF_100_IN4_DP

TP_TDR_4P_FTS_TH-TP_TDR_4P_DIPA  I11  X13
   2 T1_GND     P1 @S9S_MB_2U_LIB.S9S_MB_2U(SCH_1):T1_GND
   3 T1_GND     P2 @S9S_MB_2U_LIB.S9S_MB_2U(SCH_1):T1_GND
   1 TDR_DIFF_100_TOP_DP     S1 @S9S_MB_2U_LIB.S9S_MB_2U(SCH_1):TDR_DIFF_100_TOP_DP
   4 TDR_DIFF_100_TOP_DN     S2 @S9S_MB_2U_LIB.S9S_MB_2U(SCH_1):TDR_DIFF_100_TOP_DN

TP_TDR_4P_FTS_TH-TP_TDR_4P_DIPA  I12  X14
   2 T1_GND     P1 @S9S_MB_2U_LIB.S9S_MB_2U(SCH_1):T1_GND
   3 T1_GND     P2 @S9S_MB_2U_LIB.S9S_MB_2U(SCH_1):T1_GND
   1 TDR_DIFF_100_IN1_DP     S1 @S9S_MB_2U_LIB.S9S_MB_2U(SCH_1):TDR_DIFF_100_IN1_DP
   4 TDR_DIFF_100_IN1_DN     S2 @S9S_MB_2U_LIB.S9S_MB_2U(SCH_1):TDR_DIFF_100_IN1_DN

TP_TDR_4P_FTS_TH-TP_TDR_4P_DIPA  I17  X15
   2 T1_GND     P1 @S9S_MB_2U_LIB.S9S_MB_2U(SCH_1):T1_GND
   3 T1_GND     P2 @S9S_MB_2U_LIB.S9S_MB_2U(SCH_1):T1_GND
   1 TDR_DIFF_100_IN2_DP     S1 @S9S_MB_2U_LIB.S9S_MB_2U(SCH_1):TDR_DIFF_100_IN2_DP
   4 TDR_DIFF_100_IN2_DN     S2 @S9S_MB_2U_LIB.S9S_MB_2U(SCH_1):TDR_DIFF_100_IN2_DN

TP_TDR_4P_FTS_TH-TP_TDR_4P_DIPA  I18  X16
   2 T1_GND     P1 @S9S_MB_2U_LIB.S9S_MB_2U(SCH_1):T1_GND
   3 T1_GND     P2 @S9S_MB_2U_LIB.S9S_MB_2U(SCH_1):T1_GND
   1 TDR_DIFF_100_IN3_DP     S1 @S9S_MB_2U_LIB.S9S_MB_2U(SCH_1):TDR_DIFF_100_IN3_DP
   4 TDR_DIFF_100_IN3_DN     S2 @S9S_MB_2U_LIB.S9S_MB_2U(SCH_1):TDR_DIFF_100_IN3_DN

TP_TDR_4P_FTS_TH-TP_TDR_4P_DIPA  I19  X17
   2 T1_GND     P1 @S9S_MB_2U_LIB.S9S_MB_2U(SCH_1):T1_GND
   3 T1_GND     P2 @S9S_MB_2U_LIB.S9S_MB_2U(SCH_1):T1_GND
   1 TDR_DIFF_100_IN4_DP     S1 @S9S_MB_2U_LIB.S9S_MB_2U(SCH_1):TDR_DIFF_100_IN4_DP
   4 TDR_DIFF_100_IN4_DN     S2 @S9S_MB_2U_LIB.S9S_MB_2U(SCH_1):TDR_DIFF_100_IN4_DN

TP_TDR_4P_FTS_TH-TP_TDR_4P_DIPA  I26  X7
   2 T1_GND     P1 @S9S_MB_2U_LIB.S9S_MB_2U(SCH_1):T1_GND
   3 T1_GND     P2 @S9S_MB_2U_LIB.S9S_MB_2U(SCH_1):T1_GND
   1 TDR_DIFF_85_TOP_DN     S1 @S9S_MB_2U_LIB.S9S_MB_2U(SCH_1):TDR_DIFF_85_TOP_DN
   4 TDR_DIFF_85_TOP_DP     S2 @S9S_MB_2U_LIB.S9S_MB_2U(SCH_1):TDR_DIFF_85_TOP_DP

TP_TDR_4P_FTS_TH-TP_TDR_4P_DIPA  I27  X8
   2 T1_GND     P1 @S9S_MB_2U_LIB.S9S_MB_2U(SCH_1):T1_GND
   3 T1_GND     P2 @S9S_MB_2U_LIB.S9S_MB_2U(SCH_1):T1_GND
   1 TDR_DIFF_85_IN1_DN     S1 @S9S_MB_2U_LIB.S9S_MB_2U(SCH_1):TDR_DIFF_85_IN1_DN
   4 TDR_DIFF_85_IN1_DP     S2 @S9S_MB_2U_LIB.S9S_MB_2U(SCH_1):TDR_DIFF_85_IN1_DP

TP_TDR_4P_FTS_TH-TP_TDR_4P_DIPA  I28  X1
   2 T1_GND     P1 @S9S_MB_2U_LIB.S9S_MB_2U(SCH_1):T1_GND
   3 T1_GND     P2 @S9S_MB_2U_LIB.S9S_MB_2U(SCH_1):T1_GND
   1 TDR_DIFF_85_TOP_DP     S1 @S9S_MB_2U_LIB.S9S_MB_2U(SCH_1):TDR_DIFF_85_TOP_DP
   4 TDR_DIFF_85_TOP_DN     S2 @S9S_MB_2U_LIB.S9S_MB_2U(SCH_1):TDR_DIFF_85_TOP_DN

TP_TDR_4P_FTS_TH-TP_TDR_4P_DIPA  I30  X2
   2 T1_GND     P1 @S9S_MB_2U_LIB.S9S_MB_2U(SCH_1):T1_GND
   3 T1_GND     P2 @S9S_MB_2U_LIB.S9S_MB_2U(SCH_1):T1_GND
   1 TDR_DIFF_85_IN1_DP     S1 @S9S_MB_2U_LIB.S9S_MB_2U(SCH_1):TDR_DIFF_85_IN1_DP
   4 TDR_DIFF_85_IN1_DN     S2 @S9S_MB_2U_LIB.S9S_MB_2U(SCH_1):TDR_DIFF_85_IN1_DN

TP_TDR_4P_FTS_TH-TP_TDR_4P_DIPA  I32  X9
   2 T1_GND     P1 @S9S_MB_2U_LIB.S9S_MB_2U(SCH_1):T1_GND
   3 T1_GND     P2 @S9S_MB_2U_LIB.S9S_MB_2U(SCH_1):T1_GND
   1 TDR_DIFF_85_IN2_DN     S1 @S9S_MB_2U_LIB.S9S_MB_2U(SCH_1):TDR_DIFF_85_IN2_DN
   4 TDR_DIFF_85_IN2_DP     S2 @S9S_MB_2U_LIB.S9S_MB_2U(SCH_1):TDR_DIFF_85_IN2_DP

TP_TDR_4P_FTS_TH-TP_TDR_4P_DIPA  I33  X10
   2 T1_GND     P1 @S9S_MB_2U_LIB.S9S_MB_2U(SCH_1):T1_GND
   3 T1_GND     P2 @S9S_MB_2U_LIB.S9S_MB_2U(SCH_1):T1_GND
   1 TDR_DIFF_85_IN3_DN     S1 @S9S_MB_2U_LIB.S9S_MB_2U(SCH_1):TDR_DIFF_85_IN3_DN
   4 TDR_DIFF_85_IN3_DP     S2 @S9S_MB_2U_LIB.S9S_MB_2U(SCH_1):TDR_DIFF_85_IN3_DP

TP_TDR_4P_FTS_TH-TP_TDR_4P_DIPA  I34  X11
   2 T1_GND     P1 @S9S_MB_2U_LIB.S9S_MB_2U(SCH_1):T1_GND
   3 T1_GND     P2 @S9S_MB_2U_LIB.S9S_MB_2U(SCH_1):T1_GND
   1 TDR_DIFF_85_IN4_DN     S1 @S9S_MB_2U_LIB.S9S_MB_2U(SCH_1):TDR_DIFF_85_IN4_DN
   4 TDR_DIFF_85_IN4_DP     S2 @S9S_MB_2U_LIB.S9S_MB_2U(SCH_1):TDR_DIFF_85_IN4_DP

TP_TDR_4P_FTS_TH-TP_TDR_4P_DIPA  I35  X3
   2 T1_GND     P1 @S9S_MB_2U_LIB.S9S_MB_2U(SCH_1):T1_GND
   3 T1_GND     P2 @S9S_MB_2U_LIB.S9S_MB_2U(SCH_1):T1_GND
   1 TDR_DIFF_85_IN2_DP     S1 @S9S_MB_2U_LIB.S9S_MB_2U(SCH_1):TDR_DIFF_85_IN2_DP
   4 TDR_DIFF_85_IN2_DN     S2 @S9S_MB_2U_LIB.S9S_MB_2U(SCH_1):TDR_DIFF_85_IN2_DN

TP_TDR_4P_FTS_TH-TP_TDR_4P_DIPA  I37  X4
   2 T1_GND     P1 @S9S_MB_2U_LIB.S9S_MB_2U(SCH_1):T1_GND
   3 T1_GND     P2 @S9S_MB_2U_LIB.S9S_MB_2U(SCH_1):T1_GND
   1 TDR_DIFF_85_IN3_DP     S1 @S9S_MB_2U_LIB.S9S_MB_2U(SCH_1):TDR_DIFF_85_IN3_DP
   4 TDR_DIFF_85_IN3_DN     S2 @S9S_MB_2U_LIB.S9S_MB_2U(SCH_1):TDR_DIFF_85_IN3_DN

TP_TDR_4P_FTS_TH-TP_TDR_4P_DIPA  I39  X5
   2 T1_GND     P1 @S9S_MB_2U_LIB.S9S_MB_2U(SCH_1):T1_GND
   3 T1_GND     P2 @S9S_MB_2U_LIB.S9S_MB_2U(SCH_1):T1_GND
   1 TDR_DIFF_85_IN4_DP     S1 @S9S_MB_2U_LIB.S9S_MB_2U(SCH_1):TDR_DIFF_85_IN4_DP
   4 TDR_DIFF_85_IN4_DN     S2 @S9S_MB_2U_LIB.S9S_MB_2U(SCH_1):TDR_DIFF_85_IN4_DN

TP_TDR_4P_FTS_TH-TP_TDR_4P_DIPA  I42  X24
   2 T1_GND     P1 @S9S_MB_2U_LIB.S9S_MB_2U(SCH_1):T1_GND
   3 T1_GND     P2 @S9S_MB_2U_LIB.S9S_MB_2U(SCH_1):T1_GND
   1 TDR_DIFF_100_BOT_DN     S1 @S9S_MB_2U_LIB.S9S_MB_2U(SCH_1):TDR_DIFF_100_BOT_DN
   4 TDR_DIFF_100_BOT_DP     S2 @S9S_MB_2U_LIB.S9S_MB_2U(SCH_1):TDR_DIFF_100_BOT_DP

TP_TDR_4P_FTS_TH-TP_TDR_4P_DIPA  I43  X18
   2 T1_GND     P1 @S9S_MB_2U_LIB.S9S_MB_2U(SCH_1):T1_GND
   3 T1_GND     P2 @S9S_MB_2U_LIB.S9S_MB_2U(SCH_1):T1_GND
   1 TDR_DIFF_100_BOT_DP     S1 @S9S_MB_2U_LIB.S9S_MB_2U(SCH_1):TDR_DIFF_100_BOT_DP
   4 TDR_DIFF_100_BOT_DN     S2 @S9S_MB_2U_LIB.S9S_MB_2U(SCH_1):TDR_DIFF_100_BOT_DN

TP_TDR_4P_FTS_TH-TP_TDR_4P_DIPA  I46  X12
   2 T1_GND     P1 @S9S_MB_2U_LIB.S9S_MB_2U(SCH_1):T1_GND
   3 T1_GND     P2 @S9S_MB_2U_LIB.S9S_MB_2U(SCH_1):T1_GND
   1 TDR_DIFF_85_BOT_DN     S1 @S9S_MB_2U_LIB.S9S_MB_2U(SCH_1):TDR_DIFF_85_BOT_DN
   4 TDR_DIFF_85_BOT_DP     S2 @S9S_MB_2U_LIB.S9S_MB_2U(SCH_1):TDR_DIFF_85_BOT_DP

TP_TDR_4P_FTS_TH-TP_TDR_4P_DIPA  I47  X6
   2 T1_GND     P1 @S9S_MB_2U_LIB.S9S_MB_2U(SCH_1):T1_GND
   3 T1_GND     P2 @S9S_MB_2U_LIB.S9S_MB_2U(SCH_1):T1_GND
   1 TDR_DIFF_85_BOT_DP     S1 @S9S_MB_2U_LIB.S9S_MB_2U(SCH_1):TDR_DIFF_85_BOT_DP
   4 TDR_DIFF_85_BOT_DN     S2 @S9S_MB_2U_LIB.S9S_MB_2U(SCH_1):TDR_DIFF_85_BOT_DN

TDR_3P_TH2-EMPTY,N_A  I49  DB7
   1 T1_GND    GND @S9S_MB_2U_LIB.S9S_MB_2U(SCH_1):T1_GND
   2 TDR_SE_50_OHM_TOP    IO1 @S9S_MB_2U_LIB.S9S_MB_2U(SCH_1):TDR_SE_50_OHM_TOP
   3 TDR_SE_50_OHM_TOP    IO2 @S9S_MB_2U_LIB.S9S_MB_2U(SCH_1):TDR_SE_50_OHM_TOP

TDR_3P_TH2-EMPTY,N_A  I51  DB8
   1 T1_GND    GND @S9S_MB_2U_LIB.S9S_MB_2U(SCH_1):T1_GND
   2 TDR_SE_50_OHM_IN1    IO1 @S9S_MB_2U_LIB.S9S_MB_2U(SCH_1):TDR_SE_50_OHM_IN1
   3 TDR_SE_50_OHM_IN1    IO2 @S9S_MB_2U_LIB.S9S_MB_2U(SCH_1):TDR_SE_50_OHM_IN1

TDR_3P_TH2-EMPTY,N_A  I53  DB9
   1 T1_GND    GND @S9S_MB_2U_LIB.S9S_MB_2U(SCH_1):T1_GND
   2 TDR_SE_50_OHM_IN2    IO1 @S9S_MB_2U_LIB.S9S_MB_2U(SCH_1):TDR_SE_50_OHM_IN2
   3 TDR_SE_50_OHM_IN2    IO2 @S9S_MB_2U_LIB.S9S_MB_2U(SCH_1):TDR_SE_50_OHM_IN2

TDR_3P_TH2-EMPTY,N_A  I55  DB10
   1 T1_GND    GND @S9S_MB_2U_LIB.S9S_MB_2U(SCH_1):T1_GND
   2 TDR_SE_50_OHM_IN3    IO1 @S9S_MB_2U_LIB.S9S_MB_2U(SCH_1):TDR_SE_50_OHM_IN3
   3 TDR_SE_50_OHM_IN3    IO2 @S9S_MB_2U_LIB.S9S_MB_2U(SCH_1):TDR_SE_50_OHM_IN3

TDR_3P_TH2-EMPTY,N_A  I57  DB11
   1 T1_GND    GND @S9S_MB_2U_LIB.S9S_MB_2U(SCH_1):T1_GND
   2 TDR_SE_50_OHM_IN4    IO1 @S9S_MB_2U_LIB.S9S_MB_2U(SCH_1):TDR_SE_50_OHM_IN4
   3 TDR_SE_50_OHM_IN4    IO2 @S9S_MB_2U_LIB.S9S_MB_2U(SCH_1):TDR_SE_50_OHM_IN4

TDR_3P_TH2-EMPTY,N_A  I60  DB12
   1 T1_GND    GND @S9S_MB_2U_LIB.S9S_MB_2U(SCH_1):T1_GND
   2 TDR_SE_50_OHM_BOT    IO1 @S9S_MB_2U_LIB.S9S_MB_2U(SCH_1):TDR_SE_50_OHM_BOT
   3 TDR_SE_50_OHM_BOT    IO2 @S9S_MB_2U_LIB.S9S_MB_2U(SCH_1):TDR_SE_50_OHM_BOT

TDR_3P_TH2-EMPTY,N_A  I61  DB1
   1 T1_GND    GND @S9S_MB_2U_LIB.S9S_MB_2U(SCH_1):T1_GND
   2 TDR_SE_40_OHM_TOP    IO1 @S9S_MB_2U_LIB.S9S_MB_2U(SCH_1):TDR_SE_40_OHM_TOP
   3 TDR_SE_40_OHM_TOP    IO2 @S9S_MB_2U_LIB.S9S_MB_2U(SCH_1):TDR_SE_40_OHM_TOP

TDR_3P_TH2-EMPTY,N_A  I62  DB2
   1 T1_GND    GND @S9S_MB_2U_LIB.S9S_MB_2U(SCH_1):T1_GND
   2 TDR_SE_40_OHM_IN1    IO1 @S9S_MB_2U_LIB.S9S_MB_2U(SCH_1):TDR_SE_40_OHM_IN1
   3 TDR_SE_40_OHM_IN1    IO2 @S9S_MB_2U_LIB.S9S_MB_2U(SCH_1):TDR_SE_40_OHM_IN1

TDR_3P_TH2-EMPTY,N_A  I63  DB3
   1 T1_GND    GND @S9S_MB_2U_LIB.S9S_MB_2U(SCH_1):T1_GND
   2 TDR_SE_40_OHM_IN2    IO1 @S9S_MB_2U_LIB.S9S_MB_2U(SCH_1):TDR_SE_40_OHM_IN2
   3 TDR_SE_40_OHM_IN2    IO2 @S9S_MB_2U_LIB.S9S_MB_2U(SCH_1):TDR_SE_40_OHM_IN2

TDR_3P_TH2-EMPTY,N_A  I67  DB4
   1 T1_GND    GND @S9S_MB_2U_LIB.S9S_MB_2U(SCH_1):T1_GND
   2 TDR_SE_40_OHM_IN3    IO1 @S9S_MB_2U_LIB.S9S_MB_2U(SCH_1):TDR_SE_40_OHM_IN3
   3 TDR_SE_40_OHM_IN3    IO2 @S9S_MB_2U_LIB.S9S_MB_2U(SCH_1):TDR_SE_40_OHM_IN3

TDR_3P_TH2-EMPTY,N_A  I68  DB5
   1 T1_GND    GND @S9S_MB_2U_LIB.S9S_MB_2U(SCH_1):T1_GND
   2 TDR_SE_40_OHM_IN4    IO1 @S9S_MB_2U_LIB.S9S_MB_2U(SCH_1):TDR_SE_40_OHM_IN4
   3 TDR_SE_40_OHM_IN4    IO2 @S9S_MB_2U_LIB.S9S_MB_2U(SCH_1):TDR_SE_40_OHM_IN4

TDR_3P_TH2-EMPTY,N_A  I69  DB6
   1 T1_GND    GND @S9S_MB_2U_LIB.S9S_MB_2U(SCH_1):T1_GND
   2 TDR_SE_40_OHM_BOT    IO1 @S9S_MB_2U_LIB.S9S_MB_2U(SCH_1):TDR_SE_40_OHM_BOT
   3 TDR_SE_40_OHM_BOT    IO2 @S9S_MB_2U_LIB.S9S_MB_2U(SCH_1):TDR_SE_40_OHM_BOT

TDR_3P_TH2-EMPTY,N_A  I96  DB14
   1 T1_GND    GND @S9S_MB_2U_LIB.S9S_MB_2U(SCH_1):T1_GND
   2 TDR_SE_40_OHM_IN6    IO1 @S9S_MB_2U_LIB.S9S_MB_2U(SCH_1):TDR_SE_40_OHM_IN6
   3 TDR_SE_40_OHM_IN6    IO2 @S9S_MB_2U_LIB.S9S_MB_2U(SCH_1):TDR_SE_40_OHM_IN6

TDR_3P_TH2-EMPTY,N_A  I97  DB15
   1 T1_GND    GND @S9S_MB_2U_LIB.S9S_MB_2U(SCH_1):T1_GND
   2 TDR_SE_50_OHM_IN5    IO1 @S9S_MB_2U_LIB.S9S_MB_2U(SCH_1):TDR_SE_50_OHM_IN5
   3 TDR_SE_50_OHM_IN5    IO2 @S9S_MB_2U_LIB.S9S_MB_2U(SCH_1):TDR_SE_50_OHM_IN5

TDR_3P_TH2-EMPTY,N_A  I99  DB16
   1 T1_GND    GND @S9S_MB_2U_LIB.S9S_MB_2U(SCH_1):T1_GND
   2 TDR_SE_50_OHM_IN6    IO1 @S9S_MB_2U_LIB.S9S_MB_2U(SCH_1):TDR_SE_50_OHM_IN6
   3 TDR_SE_50_OHM_IN6    IO2 @S9S_MB_2U_LIB.S9S_MB_2U(SCH_1):TDR_SE_50_OHM_IN6

TDR_3P_TH2-EMPTY,N_A  I101  DB13
   1 T1_GND    GND @S9S_MB_2U_LIB.S9S_MB_2U(SCH_1):T1_GND
   2 TDR_SE_40_OHM_IN5    IO1 @S9S_MB_2U_LIB.S9S_MB_2U(SCH_1):TDR_SE_40_OHM_IN5
   3 TDR_SE_40_OHM_IN5    IO2 @S9S_MB_2U_LIB.S9S_MB_2U(SCH_1):TDR_SE_40_OHM_IN5

TP_TDR_4P_FTS_TH-TP_TDR_4P_DIPA  I106  X27
   2 T1_GND     P1 @S9S_MB_2U_LIB.S9S_MB_2U(SCH_1):T1_GND
   3 T1_GND     P2 @S9S_MB_2U_LIB.S9S_MB_2U(SCH_1):T1_GND
   1 TDR_DIFF_85_IN5_DN     S1 @S9S_MB_2U_LIB.S9S_MB_2U(SCH_1):TDR_DIFF_85_IN5_DN
   4 TDR_DIFF_85_IN5_DP     S2 @S9S_MB_2U_LIB.S9S_MB_2U(SCH_1):TDR_DIFF_85_IN5_DP

TP_TDR_4P_FTS_TH-TP_TDR_4P_DIPA  I107  X28
   2 T1_GND     P1 @S9S_MB_2U_LIB.S9S_MB_2U(SCH_1):T1_GND
   3 T1_GND     P2 @S9S_MB_2U_LIB.S9S_MB_2U(SCH_1):T1_GND
   1 TDR_DIFF_85_IN6_DN     S1 @S9S_MB_2U_LIB.S9S_MB_2U(SCH_1):TDR_DIFF_85_IN6_DN
   4 TDR_DIFF_85_IN6_DP     S2 @S9S_MB_2U_LIB.S9S_MB_2U(SCH_1):TDR_DIFF_85_IN6_DP

TP_TDR_4P_FTS_TH-TP_TDR_4P_DIPA  I108  X25
   2 T1_GND     P1 @S9S_MB_2U_LIB.S9S_MB_2U(SCH_1):T1_GND
   3 T1_GND     P2 @S9S_MB_2U_LIB.S9S_MB_2U(SCH_1):T1_GND
   1 TDR_DIFF_85_IN5_DP     S1 @S9S_MB_2U_LIB.S9S_MB_2U(SCH_1):TDR_DIFF_85_IN5_DP
   4 TDR_DIFF_85_IN5_DN     S2 @S9S_MB_2U_LIB.S9S_MB_2U(SCH_1):TDR_DIFF_85_IN5_DN

TP_TDR_4P_FTS_TH-TP_TDR_4P_DIPA  I110  X26
   2 T1_GND     P1 @S9S_MB_2U_LIB.S9S_MB_2U(SCH_1):T1_GND
   3 T1_GND     P2 @S9S_MB_2U_LIB.S9S_MB_2U(SCH_1):T1_GND
   1 TDR_DIFF_85_IN6_DP     S1 @S9S_MB_2U_LIB.S9S_MB_2U(SCH_1):TDR_DIFF_85_IN6_DP
   4 TDR_DIFF_85_IN6_DN     S2 @S9S_MB_2U_LIB.S9S_MB_2U(SCH_1):TDR_DIFF_85_IN6_DN

TP_TDR_4P_FTS_TH-TP_TDR_4P_DIPA  I112  X31
   2 T1_GND     P1 @S9S_MB_2U_LIB.S9S_MB_2U(SCH_1):T1_GND
   3 T1_GND     P2 @S9S_MB_2U_LIB.S9S_MB_2U(SCH_1):T1_GND
   1 TDR_DIFF_100_IN5_DN     S1 @S9S_MB_2U_LIB.S9S_MB_2U(SCH_1):TDR_DIFF_100_IN5_DN
   4 TDR_DIFF_100_IN5_DP     S2 @S9S_MB_2U_LIB.S9S_MB_2U(SCH_1):TDR_DIFF_100_IN5_DP

TP_TDR_4P_FTS_TH-TP_TDR_4P_DIPA  I115  X32
   2 T1_GND     P1 @S9S_MB_2U_LIB.S9S_MB_2U(SCH_1):T1_GND
   3 T1_GND     P2 @S9S_MB_2U_LIB.S9S_MB_2U(SCH_1):T1_GND
   1 TDR_DIFF_100_IN6_DN     S1 @S9S_MB_2U_LIB.S9S_MB_2U(SCH_1):TDR_DIFF_100_IN6_DN
   4 TDR_DIFF_100_IN6_DP     S2 @S9S_MB_2U_LIB.S9S_MB_2U(SCH_1):TDR_DIFF_100_IN6_DP

TP_TDR_4P_FTS_TH-TP_TDR_4P_DIPA  I116  X29
   2 T1_GND     P1 @S9S_MB_2U_LIB.S9S_MB_2U(SCH_1):T1_GND
   3 T1_GND     P2 @S9S_MB_2U_LIB.S9S_MB_2U(SCH_1):T1_GND
   1 TDR_DIFF_100_IN5_DP     S1 @S9S_MB_2U_LIB.S9S_MB_2U(SCH_1):TDR_DIFF_100_IN5_DP
   4 TDR_DIFF_100_IN5_DN     S2 @S9S_MB_2U_LIB.S9S_MB_2U(SCH_1):TDR_DIFF_100_IN5_DN

TP_TDR_4P_FTS_TH-TP_TDR_4P_DIPA  I117  X30
   2 T1_GND     P1 @S9S_MB_2U_LIB.S9S_MB_2U(SCH_1):T1_GND
   3 T1_GND     P2 @S9S_MB_2U_LIB.S9S_MB_2U(SCH_1):T1_GND
   1 TDR_DIFF_100_IN6_DP     S1 @S9S_MB_2U_LIB.S9S_MB_2U(SCH_1):TDR_DIFF_100_IN6_DP
   4 TDR_DIFF_100_IN6_DN     S2 @S9S_MB_2U_LIB.S9S_MB_2U(SCH_1):TDR_DIFF_100_IN6_DN


DRAWING: @S9S_MB_2U_LIB.S9S_MB_2U(SCH_1):PAGE289 

HOLE_TH-EMPTY,DUMMY50  I7  H30
   1     NC      1     NC

HOLE_TH-EMPTY,DUMMY50  I8  H29
   1     NC      1     NC

HOLE_TH-EMPTY,TMP-Q_HOLE78  I9  H38
   1     NC      1     NC

HOLE_TH-EMPTY,TMP-Q_HOLE78  I10  H36
   1     NC      1     NC

HOLE_TH-EMPTY,DUMMY50  I11  H28
   1     NC      1     NC

HOLE_TH-EMPTY,DUMMY50  I12  H27
   1     NC      1     NC

HOLE_TH-EMPTY,HOLE1187  I18  H76
   1    GND      1 @S9S_MB_2U_LIB.S9S_MB_2U(SCH_1):GND

HOLE_TH-EMPTY,HOLE1079  I19  H26
   1     NC      1     NC

HOLE_TH-EMPTY,HOLE1079  I20  H24
   1     NC      1     NC

HOLE_TH-EMPTY,HOLE1079  I21  H22
   1     NC      1     NC

HOLE_TH-EMPTY,HOLE1248  I54  H32
   1    GND      1 @S9S_MB_2U_LIB.S9S_MB_2U(SCH_1):GND

HOLE_TH-EMPTY,HOLE1248  I56  H31
   1    GND      1 @S9S_MB_2U_LIB.S9S_MB_2U(SCH_1):GND

HOLE_TH-EMPTY,HOLE1247  I57  H75
   1     NC      1     NC

HOLE_TH-EMPTY,HOLE1247  I58  H74
   1     NC      1     NC

HOLE_TH-EMPTY,HOLE1079  I60  H20
   1     NC      1     NC

HOLE_TH-EMPTY,HOLE1079  I61  H18
   1     NC      1     NC

HOLE_TH-EMPTY,HOLE1079  I63  H16
   1     NC      1     NC

HOLE_TH-EMPTY,HOLE1079  I64  H25
   1     NC      1     NC

HOLE_TH-EMPTY,HOLE1079  I72  H23
   1     NC      1     NC

HOLE_TH-EMPTY,HOLE1079  I73  H21
   1     NC      1     NC

HOLE_TH-EMPTY,HOLE1079  I74  H19
   1     NC      1     NC

HOLE_TH-EMPTY,HOLE1079  I75  H17
   1     NC      1     NC

HOLE_TH-EMPTY,HOLE1079  I83  H15
   1     NC      1     NC

HOLE_TH-EMPTY,HOLE1187  I87  H77
   1    GND      1 @S9S_MB_2U_LIB.S9S_MB_2U(SCH_1):GND

HOLE_TH-EMPTY,HOLE596  I147  H91
   1    GND      1 @S9S_MB_2U_LIB.S9S_MB_2U(SCH_1):GND

HOLE_TH-EMPTY,HOLE596  I149  H97
   1    GND      1 @S9S_MB_2U_LIB.S9S_MB_2U(SCH_1):GND

HOLE_TH-EMPTY,HOLE596  I155  H99
   1    GND      1 @S9S_MB_2U_LIB.S9S_MB_2U(SCH_1):GND

HOLE_TH-EMPTY,HOLE596  I158  H102
   1    GND      1 @S9S_MB_2U_LIB.S9S_MB_2U(SCH_1):GND

HOLE_TH-EMPTY,HOLE596  I160  H98
   1    GND      1 @S9S_MB_2U_LIB.S9S_MB_2U(SCH_1):GND

HOLE_TH-EMPTY,HOLE596  I166  H92
   1    GND      1 @S9S_MB_2U_LIB.S9S_MB_2U(SCH_1):GND

HOLE_TH-EMPTY,HOLE596  I168  H87
   1    GND      1 @S9S_MB_2U_LIB.S9S_MB_2U(SCH_1):GND

HOLE_TH-EMPTY,HOLE596  I175  H104
   1    GND      1 @S9S_MB_2U_LIB.S9S_MB_2U(SCH_1):GND

HOLE_TH-EMPTY,HOLE596  I140  H86
   1    GND      1 @S9S_MB_2U_LIB.S9S_MB_2U(SCH_1):GND

HOLE_TH-EMPTY,HOLE596  I144  H88
   1    GND      1 @S9S_MB_2U_LIB.S9S_MB_2U(SCH_1):GND

HOLE_TH-EMPTY,HOLE596  I148  H93
   1    GND      1 @S9S_MB_2U_LIB.S9S_MB_2U(SCH_1):GND

HOLE_TH-EMPTY,HOLE596  I150  H95
   1    GND      1 @S9S_MB_2U_LIB.S9S_MB_2U(SCH_1):GND

HOLE_TH-EMPTY,HOLE596  I154  H101
   1    GND      1 @S9S_MB_2U_LIB.S9S_MB_2U(SCH_1):GND

HOLE_TH-EMPTY,HOLE596  I159  H100
   1    GND      1 @S9S_MB_2U_LIB.S9S_MB_2U(SCH_1):GND

HOLE_TH-EMPTY,HOLE596  I161  H96
   1    GND      1 @S9S_MB_2U_LIB.S9S_MB_2U(SCH_1):GND

HOLE_TH-EMPTY,HOLE596  I165  H94
   1    GND      1 @S9S_MB_2U_LIB.S9S_MB_2U(SCH_1):GND

HOLE_TH-EMPTY,HOLE596  I167  H89
   1    GND      1 @S9S_MB_2U_LIB.S9S_MB_2U(SCH_1):GND

HOLE_TH-EMPTY,HOLE596  I174  H103
   1    GND      1 @S9S_MB_2U_LIB.S9S_MB_2U(SCH_1):GND

HOLE_TH-EMPTY,HOLE596  I190  H106
   1    GND      1 @S9S_MB_2U_LIB.S9S_MB_2U(SCH_1):GND

HOLE_TH-EMPTY,HOLE596  I192  H105
   1    GND      1 @S9S_MB_2U_LIB.S9S_MB_2U(SCH_1):GND

GND_HOLE_TH-EMPTY,GND_HOLE514  I202  H115
   3    GND   GND3 @S9S_MB_2U_LIB.S9S_MB_2U(SCH_1):GND
   2    GND   GND2 @S9S_MB_2U_LIB.S9S_MB_2U(SCH_1):GND
   9    GND   GND9 @S9S_MB_2U_LIB.S9S_MB_2U(SCH_1):GND
   8    GND   GND8 @S9S_MB_2U_LIB.S9S_MB_2U(SCH_1):GND
   7    GND   GND7 @S9S_MB_2U_LIB.S9S_MB_2U(SCH_1):GND
   6    GND   GND6 @S9S_MB_2U_LIB.S9S_MB_2U(SCH_1):GND
   5    GND   GND5 @S9S_MB_2U_LIB.S9S_MB_2U(SCH_1):GND
   4    GND   GND4 @S9S_MB_2U_LIB.S9S_MB_2U(SCH_1):GND

GND_HOLE_TH-EMPTY,GND_HOLE140  I204  H111
   3    GND   GND3 @S9S_MB_2U_LIB.S9S_MB_2U(SCH_1):GND
   2    GND   GND2 @S9S_MB_2U_LIB.S9S_MB_2U(SCH_1):GND
   9    GND   GND9 @S9S_MB_2U_LIB.S9S_MB_2U(SCH_1):GND
   8    GND   GND8 @S9S_MB_2U_LIB.S9S_MB_2U(SCH_1):GND
   7    GND   GND7 @S9S_MB_2U_LIB.S9S_MB_2U(SCH_1):GND
   6    GND   GND6 @S9S_MB_2U_LIB.S9S_MB_2U(SCH_1):GND
   5    GND   GND5 @S9S_MB_2U_LIB.S9S_MB_2U(SCH_1):GND
   4    GND   GND4 @S9S_MB_2U_LIB.S9S_MB_2U(SCH_1):GND

GND_HOLE_TH-EMPTY,GND_HOLE140  I207  H112
   3    GND   GND3 @S9S_MB_2U_LIB.S9S_MB_2U(SCH_1):GND
   2    GND   GND2 @S9S_MB_2U_LIB.S9S_MB_2U(SCH_1):GND
   9    GND   GND9 @S9S_MB_2U_LIB.S9S_MB_2U(SCH_1):GND
   8    GND   GND8 @S9S_MB_2U_LIB.S9S_MB_2U(SCH_1):GND
   7    GND   GND7 @S9S_MB_2U_LIB.S9S_MB_2U(SCH_1):GND
   6    GND   GND6 @S9S_MB_2U_LIB.S9S_MB_2U(SCH_1):GND
   5    GND   GND5 @S9S_MB_2U_LIB.S9S_MB_2U(SCH_1):GND
   4    GND   GND4 @S9S_MB_2U_LIB.S9S_MB_2U(SCH_1):GND

HOLE_TH-EMPTY,SP_HOLE1199  I216  H44
   1    GND      1 @S9S_MB_2U_LIB.S9S_MB_2U(SCH_1):GND

HOLE_TH-EMPTY,SP_HOLE1199  I217  H45
   1    GND      1 @S9S_MB_2U_LIB.S9S_MB_2U(SCH_1):GND

HOLE_TH-EMPTY,SP_HOLE1199  I218  H47
   1    GND      1 @S9S_MB_2U_LIB.S9S_MB_2U(SCH_1):GND

HOLE_TH-EMPTY,SP_HOLE1199  I219  H49
   1    GND      1 @S9S_MB_2U_LIB.S9S_MB_2U(SCH_1):GND

HOLE_TH-EMPTY,TMP-C_T2I_ALEX_1A  I224  H120
   1     NC      1     NC

HOLE_TH-EMPTY,TMP-C_T2I_ALEX_1A  I225  H122
   1     NC      1     NC

HOLE_TH-EMPTY,TMP-C_T2I_ALEX_1A  I226  H124
   1     NC      1     NC

HOLE_TH-EMPTY,TMP-C_T2I_ALEX_1A  I227  H126
   1     NC      1     NC

HOLE_TH-EMPTY,TMP-C_T2I_ALEX_1A  I228  H127
   1     NC      1     NC

HOLE_TH-EMPTY,TMP-C_T2I_ALEX_1A  I229  H125
   1     NC      1     NC

HOLE_TH-EMPTY,HOLE596  I232  H128
   1    GND      1 @S9S_MB_2U_LIB.S9S_MB_2U(SCH_1):GND

CONN1_10165288101LF-CONN1_1016A  I238  J122
SCR_H1     NC    NC1     NC

CONN1_10165288101LF-CONN1_1016A  I239  J123
SCR_H1     NC    NC1     NC

GND_HOLE_TH-EMPTY,TMP-QGND_HOLA  I247  H113
   3    GND   GND3 @S9S_MB_2U_LIB.S9S_MB_2U(SCH_1):GND
   2    GND   GND2 @S9S_MB_2U_LIB.S9S_MB_2U(SCH_1):GND
   9    GND   GND9 @S9S_MB_2U_LIB.S9S_MB_2U(SCH_1):GND
   8    GND   GND8 @S9S_MB_2U_LIB.S9S_MB_2U(SCH_1):GND
   7    GND   GND7 @S9S_MB_2U_LIB.S9S_MB_2U(SCH_1):GND
   6    GND   GND6 @S9S_MB_2U_LIB.S9S_MB_2U(SCH_1):GND
   5    GND   GND5 @S9S_MB_2U_LIB.S9S_MB_2U(SCH_1):GND
   4    GND   GND4 @S9S_MB_2U_LIB.S9S_MB_2U(SCH_1):GND

GND_HOLE_TH-EMPTY,TMP-QGND_HOLA  I248  H114
   3    GND   GND3 @S9S_MB_2U_LIB.S9S_MB_2U(SCH_1):GND
   2    GND   GND2 @S9S_MB_2U_LIB.S9S_MB_2U(SCH_1):GND
   9    GND   GND9 @S9S_MB_2U_LIB.S9S_MB_2U(SCH_1):GND
   8    GND   GND8 @S9S_MB_2U_LIB.S9S_MB_2U(SCH_1):GND
   7    GND   GND7 @S9S_MB_2U_LIB.S9S_MB_2U(SCH_1):GND
   6    GND   GND6 @S9S_MB_2U_LIB.S9S_MB_2U(SCH_1):GND
   5    GND   GND5 @S9S_MB_2U_LIB.S9S_MB_2U(SCH_1):GND
   4    GND   GND4 @S9S_MB_2U_LIB.S9S_MB_2U(SCH_1):GND

HOLE_TH-EMPTY,HOLE1195  I249  H129
   1    GND      1 @S9S_MB_2U_LIB.S9S_MB_2U(SCH_1):GND

HOLE_TH-EMPTY,HOLE372  I254  H90
   1     NC      1     NC


DRAWING: @S9S_MB_2U_LIB.S9S_MB_2U(SCH_1):PAGE290 

ME_DUMMY_SYMBOL-PICKUP_SMDC20,A  I9  ME4
ME_DUMMY_SYMBOL-PICKUP_SMDC20,A  I10  ME2
ME_DUMMY_SYMBOL-PICKUP_SMDC20,A  I11  ME3
ME_DUMMY_SYMBOL-PICKUP_SMDC20,A  I12  ME15
ME_DUMMY_SYMBOL-PICKUP_SMDC20,A  I13  ME13
ME_DUMMY_SYMBOL-PICKUP_SMDC20,A  I14  ME11
ME_DUMMY_SYMBOL-PICKUP_SMDC20,A  I15  ME12
ME_DUMMY_SYMBOL-PICKUP_SMDC20,A  I16  ME14
DUMMY_SYMBOL-BATTERY_SYMBOL,MEA  I17  DM13
   1     NC      1     NC

ME_DUMMY_SYMBOL-PICKUP_SMDC20,A  I18  ME9
ME_DUMMY_SYMBOL-PICKUP_SMDC20,A  I19  ME10
DUMMY_SYMBOL-MECHANIC_SYMBOL,MA  I23  DM9
   1     NC      1     NC

TP_TP_BOM ONLY-NA,TP12_BOM  I40  U1_BL
   1     NC     TP     NC

TP_TP_BOM ONLY-NA,TP12_BOM  I41  U2_BL
   1     NC     TP     NC

TP_TP_BOM ONLY-NA,TP12_BOM  I42  U2_BP
   1     NC     TP     NC

TP_TP_BOM ONLY-NA,TP12_BOM  I43  U1_BP
   1     NC     TP     NC

TP_TP_BOM ONLY-NA,TP12_BOM  I45  U2_DC
   1     NC     TP     NC

TP_TP_BOM ONLY-NA,TP12_BOM  I47  U1_DC
   1     NC     TP     NC

ME_DUMMY_SYMBOL-QUANTA_LOGO_7XA  I62  ME17
ME_DUMMY_SYMBOL-WEEE,MECH,EMPTA  I63  ME18
ME_DUMMY_SYMBOL-PB-E1_SMALL,MEA  I64  ME20
ME_DUMMY_SYMBOL-PCB_VENDOR_LOGA  I65  ME21
TP_TP_BOM ONLY-NA,TP12_BOM  I69  J90_CON
   1     NC     TP     NC

TP_TP_BOM ONLY-NA,TP12_BOM  I70  JP4003_12
   1     NC     TP     NC

TP_TP_BOM ONLY-NA,TP12_BOM  I71  JP15_23
   1     NC     TP     NC

TP_TP_BOM ONLY-NA,TP12_BOM  I72  JP16_23
   1     NC     TP     NC

ME_DUMMY_SYMBOL-SNLABEL_27X6,MA  I73  ME22
ME_DUMMY_SYMBOL-CBS_3X558-8,MEA  I74  ME27
ME_DUMMY_SYMBOL-EFI BIOS LABELA  I75  ME28
ME_DUMMY_SYMBOL-SNLABEL_15X5,MA  I76  ME29

DRAWING: @S9S_MB_2U_LIB.S9S_MB_2U(SCH_1):PAGE150 

Q_RES_0402LF-4.7K,1%,1/16W,CHIA  I2  R410
   1 OCP_SFF_ID0      A @S9S_MB_2U_LIB.S9S_MB_2U(SCH_1):OCP_SFF_ID0
   2    GND      B @S9S_MB_2U_LIB.S9S_MB_2U(SCH_1):GND

Q_RES_0402LF-4.7K,1%,1/16W,CHIA  I4  R415
   1 OCP_SFF_ID1      A @S9S_MB_2U_LIB.S9S_MB_2U(SCH_1):OCP_SFF_ID1
   2    GND      B @S9S_MB_2U_LIB.S9S_MB_2U(SCH_1):GND

Q_RES_0402LF-4.7K,1%,1/16W,EMPA  I5  R409
   1 P3V3_OCP_SFF      A @S9S_MB_2U_LIB.S9S_MB_2U(SCH_1):P3V3_OCP_SFF
   2 OCP_SFF_ID0      B @S9S_MB_2U_LIB.S9S_MB_2U(SCH_1):OCP_SFF_ID0

Q_RES_0402LF-4.7K,1%,1/16W,EMPA  I6  R414
   1 P3V3_OCP_SFF      A @S9S_MB_2U_LIB.S9S_MB_2U(SCH_1):P3V3_OCP_SFF
   2 OCP_SFF_ID1      B @S9S_MB_2U_LIB.S9S_MB_2U(SCH_1):OCP_SFF_ID1

Q_RES_0402LF-100K,1%,1/16W,CHIA  I35  R3132
   1    GND      A @S9S_MB_2U_LIB.S9S_MB_2U(SCH_1):GND
   2 FM_OCP_SFF_PWR_GOOD      B @S9S_MB_2U_LIB.S9S_MB_2U(SCH_1):FM_OCP_SFF_PWR_GOOD

Q_RES_0402LF-10K,1%,1/16W,CHIPA  I36  R1930
   1    GND      A @S9S_MB_2U_LIB.S9S_MB_2U(SCH_1):GND
   2 OCP_SFF_MAIN_PWR_EN      B @S9S_MB_2U_LIB.S9S_MB_2U(SCH_1):OCP_SFF_MAIN_PWR_EN

Q_RES_0402LF-10K,1%,1/16W,CHIPA  I37  R1929
   1    GND      A @S9S_MB_2U_LIB.S9S_MB_2U(SCH_1):GND
   2 OCP_SFF_AUX_PWR_EN      B @S9S_MB_2U_LIB.S9S_MB_2U(SCH_1):OCP_SFF_AUX_PWR_EN

Q_RES_0402LF-0,5%,1/16W,CHIP,CA  I51  R1671
   1 OCP_SFF_AUX_PWR_EN      A @S9S_MB_2U_LIB.S9S_MB_2U(SCH_1):OCP_SFF_AUX_PWR_EN
   2 OCP_SFF_AUX_PWR_EN_R      B @S9S_MB_2U_LIB.S9S_MB_2U(SCH_1):OCP_SFF_AUX_PWR_EN_R

Q_RES_0402LF-0,5%,1/16W,CHIP,CA  I52  R418
   1 OCP_SFF_ISO_BIF2_EN      A @S9S_MB_2U_LIB.S9S_MB_2U(SCH_1):OCP_SFF_ISO_BIF2_EN
   2 OCP_SFF_BIF2_R_N      B @S9S_MB_2U_LIB.S9S_MB_2U(SCH_1):OCP_SFF_BIF2_R_N

Q_RES_0402LF-0,5%,1/16W,CHIP,CA  I53  R417
   1 OCP_SFF_ISO_BIF1_EN      A @S9S_MB_2U_LIB.S9S_MB_2U(SCH_1):OCP_SFF_ISO_BIF1_EN
   2 OCP_SFF_BIF1_R_N      B @S9S_MB_2U_LIB.S9S_MB_2U(SCH_1):OCP_SFF_BIF1_R_N

Q_RES_0402LF-0,5%,1/16W,CHIP,CA  I54  R416
   1 OCP_SFF_ISO_BIF0_EN      A @S9S_MB_2U_LIB.S9S_MB_2U(SCH_1):OCP_SFF_ISO_BIF0_EN
   2 OCP_SFF_BIF0_R_N      B @S9S_MB_2U_LIB.S9S_MB_2U(SCH_1):OCP_SFF_BIF0_R_N

Q_RES_0402LF-0,5%,1/16W,CHIP,CA  I58  R429
   1 OCP_SFF_MAIN_PWR_EN      A @S9S_MB_2U_LIB.S9S_MB_2U(SCH_1):OCP_SFF_MAIN_PWR_EN
   2 OCP_SFF_MAIN_PWR_EN_R      B @S9S_MB_2U_LIB.S9S_MB_2U(SCH_1):OCP_SFF_MAIN_PWR_EN_R

Q_CAP_C0805-22UF,16V,20%,X6S,CB  I89  C1213
   1 P12V_OCP_SFF      A @S9S_MB_2U_LIB.S9S_MB_2U(SCH_1):P12V_OCP_SFF
   2    GND      B @S9S_MB_2U_LIB.S9S_MB_2U(SCH_1):GND

Q_CAP_C0805-22UF,16V,20%,X6S,CB  I90  C1232
   1 P12V_OCP_SFF      A @S9S_MB_2U_LIB.S9S_MB_2U(SCH_1):P12V_OCP_SFF
   2    GND      B @S9S_MB_2U_LIB.S9S_MB_2U(SCH_1):GND

Q_CAP_0402-0.1UF,25V,10%,X7R,CA  I91  C1233
   1 P12V_OCP_SFF      A @S9S_MB_2U_LIB.S9S_MB_2U(SCH_1):P12V_OCP_SFF
   2    GND      B @S9S_MB_2U_LIB.S9S_MB_2U(SCH_1):GND

Q_CAP_0402-0.1UF,25V,10%,X7R,CA  I110  C1234
   1 P12V_OCP_SFF      A @S9S_MB_2U_LIB.S9S_MB_2U(SCH_1):P12V_OCP_SFF
   2    GND      B @S9S_MB_2U_LIB.S9S_MB_2U(SCH_1):GND

Q_CAP_0402-0.1UF,25V,10%,X7R,CA  I111  C1235
   1 P12V_OCP_SFF      A @S9S_MB_2U_LIB.S9S_MB_2U(SCH_1):P12V_OCP_SFF
   2    GND      B @S9S_MB_2U_LIB.S9S_MB_2U(SCH_1):GND

Q_CAP_0402-0.1UF,25V,10%,X7R,CA  I113  C1236
   1 P12V_OCP_SFF      A @S9S_MB_2U_LIB.S9S_MB_2U(SCH_1):P12V_OCP_SFF
   2    GND      B @S9S_MB_2U_LIB.S9S_MB_2U(SCH_1):GND

Q_CAP_0402-0.1UF,25V,10%,X7R,CA  I114  C1237
   1 P3V3_OCP_SFF      A @S9S_MB_2U_LIB.S9S_MB_2U(SCH_1):P3V3_OCP_SFF
   2    GND      B @S9S_MB_2U_LIB.S9S_MB_2U(SCH_1):GND

Q_CAP_0402-0.1UF,25V,10%,X7R,CA  I115  C1238
   1 P3V3_OCP_SFF      A @S9S_MB_2U_LIB.S9S_MB_2U(SCH_1):P3V3_OCP_SFF
   2    GND      B @S9S_MB_2U_LIB.S9S_MB_2U(SCH_1):GND

Q_CAP_0402-0.1UF,25V,10%,X7R,CA  I116  C1239
   1 P3V3_OCP_SFF      A @S9S_MB_2U_LIB.S9S_MB_2U(SCH_1):P3V3_OCP_SFF
   2    GND      B @S9S_MB_2U_LIB.S9S_MB_2U(SCH_1):GND

Q_RES_0402LF-0,5%,1/16W,CHIP,CA  I118  R444
   1 OCP_SFF_USB2_3_DN      A @S9S_MB_2U_LIB.S9S_MB_2U(SCH_1):OCP_SFF_USB2_3_DN
   2 USB2_3_DN      B @S9S_MB_2U_LIB.S9S_MB_2U(SCH_1):USB2_3_DN

Q_RES_0402LF-0,5%,1/16W,CHIP,CA  I119  R445
   1 OCP_SFF_USB2_3_DP      A @S9S_MB_2U_LIB.S9S_MB_2U(SCH_1):OCP_SFF_USB2_3_DP
   2 USB2_3_DP      B @S9S_MB_2U_LIB.S9S_MB_2U(SCH_1):USB2_3_DP

Q_RES_0402LF-100,1%,1/16W,CHIPA  I149  R1895
   1 OCP_SFF_PRSNTA_R_N      A @S9S_MB_2U_LIB.S9S_MB_2U(SCH_1):OCP_SFF_PRSNTA_R_N
   2    GND      B @S9S_MB_2U_LIB.S9S_MB_2U(SCH_1):GND

Q_RES_0402LF-33.2,1%,1/16W,CHIA  I151  R424
   1 SMB_OCP_SFF_3V3AUX_BUF_R_SCL      A @S9S_MB_2U_LIB.S9S_MB_2U(SCH_1):SMB_OCP_SFF_3V3AUX_BUF_R_SCL
   2 SMB_OCP_SFF_3V3AUX_BUF_SCL      B @S9S_MB_2U_LIB.S9S_MB_2U(SCH_1):SMB_OCP_SFF_3V3AUX_BUF_SCL

Q_CAP_0402-0.1UF,25V,10%,X7R,CA  I168  C1240
   1 P3V3_OCP_SFF      A @S9S_MB_2U_LIB.S9S_MB_2U(SCH_1):P3V3_OCP_SFF
   2    GND      B @S9S_MB_2U_LIB.S9S_MB_2U(SCH_1):GND

SCONN168_ME1016810202011-SCONNA  I199  J37
 OB1 FM_OCP_SFF_PWR_GOOD NIC_PWR_GOOD @S9S_MB_2U_LIB.S9S_MB_2U(SCH_1):FM_OCP_SFF_PWR_GOOD
 OB2 OCP_SFF_MAIN_PWR_EN_R MAIN_PWR_EN @S9S_MB_2U_LIB.S9S_MB_2U(SCH_1):OCP_SFF_MAIN_PWR_EN_R
 OB3 SGPIO_OCP_SFF_LD_N    LD# @S9S_MB_2U_LIB.S9S_MB_2U(SCH_1):SGPIO_OCP_SFF_LD_N
 OB4 SGPIO_OCP_SFF_DATAIN DATA_IN @S9S_MB_2U_LIB.S9S_MB_2U(SCH_1):SGPIO_OCP_SFF_DATAIN
 OB5 SGPIO_OCP_SFF_DATAOUT DATA_OUT @S9S_MB_2U_LIB.S9S_MB_2U(SCH_1):SGPIO_OCP_SFF_DATAOUT
 OB6 SGPIO_OCP_SFF_CLK    CLK @S9S_MB_2U_LIB.S9S_MB_2U(SCH_1):SGPIO_OCP_SFF_CLK
 OB7 OCP_SFF_ID0 SLOT_ID0 @S9S_MB_2U_LIB.S9S_MB_2U(SCH_1):OCP_SFF_ID0
 OB8 NCSI_OCP_SFF_RXD1 RBT_RXD1 @S9S_MB_2U_LIB.S9S_MB_2U(SCH_1):NCSI_OCP_SFF_RXD1
 OB9 NCSI_OCP_SFF_RXD0 RBT_RXD0 @S9S_MB_2U_LIB.S9S_MB_2U(SCH_1):NCSI_OCP_SFF_RXD0
OB10    GND GND_OB10 @S9S_MB_2U_LIB.S9S_MB_2U(SCH_1):GND
OB11 CLK_100M_OCP_SFF_2_DN REFCLKN2 @S9S_MB_2U_LIB.S9S_MB_2U(SCH_1):CLK_100M_OCP_SFF_2_DN
OB12 CLK_100M_OCP_SFF_2_DP REFCLKP2 @S9S_MB_2U_LIB.S9S_MB_2U(SCH_1):CLK_100M_OCP_SFF_2_DP
OB13    GND GND_OB13 @S9S_MB_2U_LIB.S9S_MB_2U(SCH_1):GND
OB14 NCSI_OCP_SFF_CRS_DV RBT_CRS_DV @S9S_MB_2U_LIB.S9S_MB_2U(SCH_1):NCSI_OCP_SFF_CRS_DV
  B1 P12V_OCP_SFF +12V_EDGE_B1 @S9S_MB_2U_LIB.S9S_MB_2U(SCH_1):P12V_OCP_SFF
  B2 P12V_OCP_SFF +12V_EDGE_B2 @S9S_MB_2U_LIB.S9S_MB_2U(SCH_1):P12V_OCP_SFF
  B3 P12V_OCP_SFF +12V_EDGE_B3 @S9S_MB_2U_LIB.S9S_MB_2U(SCH_1):P12V_OCP_SFF
  B4 P12V_OCP_SFF +12V_EDGE_B4 @S9S_MB_2U_LIB.S9S_MB_2U(SCH_1):P12V_OCP_SFF
  B5 P12V_OCP_SFF +12V_EDGE_B5 @S9S_MB_2U_LIB.S9S_MB_2U(SCH_1):P12V_OCP_SFF
  B6 P12V_OCP_SFF +12V_EDGE_B6 @S9S_MB_2U_LIB.S9S_MB_2U(SCH_1):P12V_OCP_SFF
  B7 OCP_SFF_BIF0_R_N  BIF0# @S9S_MB_2U_LIB.S9S_MB_2U(SCH_1):OCP_SFF_BIF0_R_N
  B8 OCP_SFF_BIF1_R_N  BIF1# @S9S_MB_2U_LIB.S9S_MB_2U(SCH_1):OCP_SFF_BIF1_R_N
  B9 OCP_SFF_BIF2_R_N  BIF2# @S9S_MB_2U_LIB.S9S_MB_2U(SCH_1):OCP_SFF_BIF2_R_N
 B10 RST_PERST0_OCP_SFF_N PERST0# @S9S_MB_2U_LIB.S9S_MB_2U(SCH_1):RST_PERST0_OCP_SFF_N
 B11 P3V3_OCP_SFF +3.3V_EDGE @S9S_MB_2U_LIB.S9S_MB_2U(SCH_1):P3V3_OCP_SFF
 B12 OCP_SFF_AUX_PWR_EN_R AUX_PWR_EN @S9S_MB_2U_LIB.S9S_MB_2U(SCH_1):OCP_SFF_AUX_PWR_EN_R
 B13    GND GND_B13 @S9S_MB_2U_LIB.S9S_MB_2U(SCH_1):GND
 B14 CLK_100M_OCP_SFF_0_DN REFCLKN0 @S9S_MB_2U_LIB.S9S_MB_2U(SCH_1):CLK_100M_OCP_SFF_0_DN
 B15 CLK_100M_OCP_SFF_0_DP REFCLKP0 @S9S_MB_2U_LIB.S9S_MB_2U(SCH_1):CLK_100M_OCP_SFF_0_DP
 B16    GND GND_B16 @S9S_MB_2U_LIB.S9S_MB_2U(SCH_1):GND
 B17 P5E_CPU0_PE1_TX_C_DN<0>  PETN0 @S9S_MB_2U_LIB.S9S_MB_2U(SCH_1):P5E_CPU0_PE1_TX_C_DN(0)
 B18 P5E_CPU0_PE1_TX_C_DP<0>  PETP0 @S9S_MB_2U_LIB.S9S_MB_2U(SCH_1):P5E_CPU0_PE1_TX_C_DP(0)
 B19    GND GND_B19 @S9S_MB_2U_LIB.S9S_MB_2U(SCH_1):GND
 B20 P5E_CPU0_PE1_TX_C_DN<1>  PETN1 @S9S_MB_2U_LIB.S9S_MB_2U(SCH_1):P5E_CPU0_PE1_TX_C_DN(1)
 B21 P5E_CPU0_PE1_TX_C_DP<1>  PETP1 @S9S_MB_2U_LIB.S9S_MB_2U(SCH_1):P5E_CPU0_PE1_TX_C_DP(1)
 B22    GND GND_B22 @S9S_MB_2U_LIB.S9S_MB_2U(SCH_1):GND
 B23 P5E_CPU0_PE1_TX_C_DP<2>  PETN2 @S9S_MB_2U_LIB.S9S_MB_2U(SCH_1):P5E_CPU0_PE1_TX_C_DP(2)
 B24 P5E_CPU0_PE1_TX_C_DN<2>  PETP2 @S9S_MB_2U_LIB.S9S_MB_2U(SCH_1):P5E_CPU0_PE1_TX_C_DN(2)
 B25    GND GND_B25 @S9S_MB_2U_LIB.S9S_MB_2U(SCH_1):GND
 B26 P5E_CPU0_PE1_TX_C_DN<3>  PETN3 @S9S_MB_2U_LIB.S9S_MB_2U(SCH_1):P5E_CPU0_PE1_TX_C_DN(3)
 B27 P5E_CPU0_PE1_TX_C_DP<3>  PETP3 @S9S_MB_2U_LIB.S9S_MB_2U(SCH_1):P5E_CPU0_PE1_TX_C_DP(3)
 B28    GND GND_B28 @S9S_MB_2U_LIB.S9S_MB_2U(SCH_1):GND
 B29    GND GND_B29 @S9S_MB_2U_LIB.S9S_MB_2U(SCH_1):GND
 B30 P5E_CPU0_PE1_TX_C_DP<4>  PETN4 @S9S_MB_2U_LIB.S9S_MB_2U(SCH_1):P5E_CPU0_PE1_TX_C_DP(4)
 B31 P5E_CPU0_PE1_TX_C_DN<4>  PETP4 @S9S_MB_2U_LIB.S9S_MB_2U(SCH_1):P5E_CPU0_PE1_TX_C_DN(4)
 B32    GND GND_B32 @S9S_MB_2U_LIB.S9S_MB_2U(SCH_1):GND
 B33 P5E_CPU0_PE1_TX_C_DN<5>  PETN5 @S9S_MB_2U_LIB.S9S_MB_2U(SCH_1):P5E_CPU0_PE1_TX_C_DN(5)
 B34 P5E_CPU0_PE1_TX_C_DP<5>  PETP5 @S9S_MB_2U_LIB.S9S_MB_2U(SCH_1):P5E_CPU0_PE1_TX_C_DP(5)
 B35    GND GND_B35 @S9S_MB_2U_LIB.S9S_MB_2U(SCH_1):GND
 B36 P5E_CPU0_PE1_TX_C_DP<6>  PETN6 @S9S_MB_2U_LIB.S9S_MB_2U(SCH_1):P5E_CPU0_PE1_TX_C_DP(6)
 B37 P5E_CPU0_PE1_TX_C_DN<6>  PETP6 @S9S_MB_2U_LIB.S9S_MB_2U(SCH_1):P5E_CPU0_PE1_TX_C_DN(6)
 B38    GND GND_B38 @S9S_MB_2U_LIB.S9S_MB_2U(SCH_1):GND
 B39 P5E_CPU0_PE1_TX_C_DN<7>  PETN7 @S9S_MB_2U_LIB.S9S_MB_2U(SCH_1):P5E_CPU0_PE1_TX_C_DN(7)
 B40 P5E_CPU0_PE1_TX_C_DP<7>  PETP7 @S9S_MB_2U_LIB.S9S_MB_2U(SCH_1):P5E_CPU0_PE1_TX_C_DP(7)
 B41    GND GND_B41 @S9S_MB_2U_LIB.S9S_MB_2U(SCH_1):GND
 B42 OCP_SFF_PRSNT0_R_N PRSNTB0# @S9S_MB_2U_LIB.S9S_MB_2U(SCH_1):OCP_SFF_PRSNT0_R_N
 B43    GND GND_B43 @S9S_MB_2U_LIB.S9S_MB_2U(SCH_1):GND
 B44 P5E_CPU0_PE1_TX_C_DP<8>  PETN8 @S9S_MB_2U_LIB.S9S_MB_2U(SCH_1):P5E_CPU0_PE1_TX_C_DP(8)
 B45 P5E_CPU0_PE1_TX_C_DN<8>  PETP8 @S9S_MB_2U_LIB.S9S_MB_2U(SCH_1):P5E_CPU0_PE1_TX_C_DN(8)
 B46    GND GND_B46 @S9S_MB_2U_LIB.S9S_MB_2U(SCH_1):GND
 B47 P5E_CPU0_PE1_TX_C_DN<9>  PETN9 @S9S_MB_2U_LIB.S9S_MB_2U(SCH_1):P5E_CPU0_PE1_TX_C_DN(9)
 B48 P5E_CPU0_PE1_TX_C_DP<9>  PETP9 @S9S_MB_2U_LIB.S9S_MB_2U(SCH_1):P5E_CPU0_PE1_TX_C_DP(9)
 B49    GND GND_B49 @S9S_MB_2U_LIB.S9S_MB_2U(SCH_1):GND
 B50 P5E_CPU0_PE1_TX_C_DP<10> PETN10 @S9S_MB_2U_LIB.S9S_MB_2U(SCH_1):P5E_CPU0_PE1_TX_C_DP(10)
 B51 P5E_CPU0_PE1_TX_C_DN<10> PETP10 @S9S_MB_2U_LIB.S9S_MB_2U(SCH_1):P5E_CPU0_PE1_TX_C_DN(10)
 B52    GND GND_B52 @S9S_MB_2U_LIB.S9S_MB_2U(SCH_1):GND
 B53 P5E_CPU0_PE1_TX_C_DN<11> PETN11 @S9S_MB_2U_LIB.S9S_MB_2U(SCH_1):P5E_CPU0_PE1_TX_C_DN(11)
 B54 P5E_CPU0_PE1_TX_C_DP<11> PETP11 @S9S_MB_2U_LIB.S9S_MB_2U(SCH_1):P5E_CPU0_PE1_TX_C_DP(11)
 B55    GND GND_B55 @S9S_MB_2U_LIB.S9S_MB_2U(SCH_1):GND
 B56 P5E_CPU0_PE1_TX_C_DP<12> PETN12 @S9S_MB_2U_LIB.S9S_MB_2U(SCH_1):P5E_CPU0_PE1_TX_C_DP(12)
 OA1 RST_PERST2_OCP_SFF_N PERST2# @S9S_MB_2U_LIB.S9S_MB_2U(SCH_1):RST_PERST2_OCP_SFF_N
 OA2 RST_PERST3_OCP_SFF_N PERST3# @S9S_MB_2U_LIB.S9S_MB_2U(SCH_1):RST_PERST3_OCP_SFF_N
 OA3 IRQ_LVC3_OCP_SFF_WAKE_N  WAKE# @S9S_MB_2U_LIB.S9S_MB_2U(SCH_1):IRQ_LVC3_OCP_SFF_WAKE_N
 OA4 OCP_SFF_ISO1_RBT_ARB_IN RBT_ARB_IN @S9S_MB_2U_LIB.S9S_MB_2U(SCH_1):OCP_SFF_ISO1_RBT_ARB_IN
 OA5 OCP_SFF_ISO2_RBT_ARB_OUT RBT_ARB_OUT @S9S_MB_2U_LIB.S9S_MB_2U(SCH_1):OCP_SFF_ISO2_RBT_ARB_OUT
 OA6 OCP_SFF_ID1 SLOT_ID1 @S9S_MB_2U_LIB.S9S_MB_2U(SCH_1):OCP_SFF_ID1
 OA7 NCSI_OCP_SFF_TX_EN RBT_TX_EN @S9S_MB_2U_LIB.S9S_MB_2U(SCH_1):NCSI_OCP_SFF_TX_EN
 OA8 NCSI_OCP_SFF_TXD1 RBT_TXD1 @S9S_MB_2U_LIB.S9S_MB_2U(SCH_1):NCSI_OCP_SFF_TXD1
 OA9 NCSI_OCP_SFF_TXD0 RBT_TXD0 @S9S_MB_2U_LIB.S9S_MB_2U(SCH_1):NCSI_OCP_SFF_TXD0
OA10    GND GND_OA10 @S9S_MB_2U_LIB.S9S_MB_2U(SCH_1):GND
OA11 CLK_100M_OCP_SFF_3_DN REFCLKN3 @S9S_MB_2U_LIB.S9S_MB_2U(SCH_1):CLK_100M_OCP_SFF_3_DN
OA12 CLK_100M_OCP_SFF_3_DP REFCLKP3 @S9S_MB_2U_LIB.S9S_MB_2U(SCH_1):CLK_100M_OCP_SFF_3_DP
OA13    GND GND_OA13 @S9S_MB_2U_LIB.S9S_MB_2U(SCH_1):GND
OA14 CLK_50M_NCSI_OCP_SFF_ISO RBT_CLK_IN @S9S_MB_2U_LIB.S9S_MB_2U(SCH_1):CLK_50M_NCSI_OCP_SFF_ISO
  A1    GND GND_A1 @S9S_MB_2U_LIB.S9S_MB_2U(SCH_1):GND
  A2    GND GND_A2 @S9S_MB_2U_LIB.S9S_MB_2U(SCH_1):GND
  A3    GND GND_A3 @S9S_MB_2U_LIB.S9S_MB_2U(SCH_1):GND
  A4    GND GND_A4 @S9S_MB_2U_LIB.S9S_MB_2U(SCH_1):GND
  A5    GND GND_A5 @S9S_MB_2U_LIB.S9S_MB_2U(SCH_1):GND
  A6    GND GND_A6 @S9S_MB_2U_LIB.S9S_MB_2U(SCH_1):GND
  A7 SMB_OCP_SFF_3V3AUX_BUF_R_SCL  SMCLK @S9S_MB_2U_LIB.S9S_MB_2U(SCH_1):SMB_OCP_SFF_3V3AUX_BUF_R_SCL
  A8 SMB_OCP_SFF_3V3AUX_BUF_R_SDA  SMDAT @S9S_MB_2U_LIB.S9S_MB_2U(SCH_1):SMB_OCP_SFF_3V3AUX_BUF_R_SDA
  A9 RST_SMB_OCP_SFF_N SMRST# @S9S_MB_2U_LIB.S9S_MB_2U(SCH_1):RST_SMB_OCP_SFF_N
 A10 OCP_SFF_PRSNTA_R_N PRSNTA# @S9S_MB_2U_LIB.S9S_MB_2U(SCH_1):OCP_SFF_PRSNTA_R_N
 A11 RST_PERST1_OCP_SFF_N PERST1# @S9S_MB_2U_LIB.S9S_MB_2U(SCH_1):RST_PERST1_OCP_SFF_N
 A12 OCP_SFF_PRSNT2_R_N PRSNTB2# @S9S_MB_2U_LIB.S9S_MB_2U(SCH_1):OCP_SFF_PRSNT2_R_N
 A13    GND GND_A13 @S9S_MB_2U_LIB.S9S_MB_2U(SCH_1):GND
 A14 CLK_100M_OCP_SFF_1_DN REFCLKN1 @S9S_MB_2U_LIB.S9S_MB_2U(SCH_1):CLK_100M_OCP_SFF_1_DN
 A15 CLK_100M_OCP_SFF_1_DP REFCLKP1 @S9S_MB_2U_LIB.S9S_MB_2U(SCH_1):CLK_100M_OCP_SFF_1_DP
 A16    GND GND_A16 @S9S_MB_2U_LIB.S9S_MB_2U(SCH_1):GND
 A17 P5E_CPU0_PE1_RX_DN<0>  PERN0 @S9S_MB_2U_LIB.S9S_MB_2U(SCH_1):P5E_CPU0_PE1_RX_DN(0)
 A18 P5E_CPU0_PE1_RX_DP<0>  PERP0 @S9S_MB_2U_LIB.S9S_MB_2U(SCH_1):P5E_CPU0_PE1_RX_DP(0)
 A19    GND GND_A19 @S9S_MB_2U_LIB.S9S_MB_2U(SCH_1):GND
 A20 P5E_CPU0_PE1_RX_DP<1>  PERN1 @S9S_MB_2U_LIB.S9S_MB_2U(SCH_1):P5E_CPU0_PE1_RX_DP(1)
 A21 P5E_CPU0_PE1_RX_DN<1>  PERP1 @S9S_MB_2U_LIB.S9S_MB_2U(SCH_1):P5E_CPU0_PE1_RX_DN(1)
 A22    GND GND_A22 @S9S_MB_2U_LIB.S9S_MB_2U(SCH_1):GND
 A23 P5E_CPU0_PE1_RX_DP<2>  PERN2 @S9S_MB_2U_LIB.S9S_MB_2U(SCH_1):P5E_CPU0_PE1_RX_DP(2)
 A24 P5E_CPU0_PE1_RX_DN<2>  PERP2 @S9S_MB_2U_LIB.S9S_MB_2U(SCH_1):P5E_CPU0_PE1_RX_DN(2)
 A25    GND GND_A25 @S9S_MB_2U_LIB.S9S_MB_2U(SCH_1):GND
 A26 P5E_CPU0_PE1_RX_DP<3>  PERN3 @S9S_MB_2U_LIB.S9S_MB_2U(SCH_1):P5E_CPU0_PE1_RX_DP(3)
 A27 P5E_CPU0_PE1_RX_DN<3>  PERP3 @S9S_MB_2U_LIB.S9S_MB_2U(SCH_1):P5E_CPU0_PE1_RX_DN(3)
 A28    GND GND_A28 @S9S_MB_2U_LIB.S9S_MB_2U(SCH_1):GND
 A29    GND GND_A29 @S9S_MB_2U_LIB.S9S_MB_2U(SCH_1):GND
 A30 P5E_CPU0_PE1_RX_DP<4>  PERN4 @S9S_MB_2U_LIB.S9S_MB_2U(SCH_1):P5E_CPU0_PE1_RX_DP(4)
 A31 P5E_CPU0_PE1_RX_DN<4>  PERP4 @S9S_MB_2U_LIB.S9S_MB_2U(SCH_1):P5E_CPU0_PE1_RX_DN(4)
 A32    GND GND_A32 @S9S_MB_2U_LIB.S9S_MB_2U(SCH_1):GND
 A33 P5E_CPU0_PE1_RX_DP<5>  PERN5 @S9S_MB_2U_LIB.S9S_MB_2U(SCH_1):P5E_CPU0_PE1_RX_DP(5)
 A34 P5E_CPU0_PE1_RX_DN<5>  PERP5 @S9S_MB_2U_LIB.S9S_MB_2U(SCH_1):P5E_CPU0_PE1_RX_DN(5)
 A35    GND GND_A35 @S9S_MB_2U_LIB.S9S_MB_2U(SCH_1):GND
 A36 P5E_CPU0_PE1_RX_DP<6>  PERN6 @S9S_MB_2U_LIB.S9S_MB_2U(SCH_1):P5E_CPU0_PE1_RX_DP(6)
 A37 P5E_CPU0_PE1_RX_DN<6>  PERP6 @S9S_MB_2U_LIB.S9S_MB_2U(SCH_1):P5E_CPU0_PE1_RX_DN(6)
 A38    GND GND_A38 @S9S_MB_2U_LIB.S9S_MB_2U(SCH_1):GND
 A39 P5E_CPU0_PE1_RX_DP<7>  PERN7 @S9S_MB_2U_LIB.S9S_MB_2U(SCH_1):P5E_CPU0_PE1_RX_DP(7)
 A40 P5E_CPU0_PE1_RX_DN<7>  PERP7 @S9S_MB_2U_LIB.S9S_MB_2U(SCH_1):P5E_CPU0_PE1_RX_DN(7)
 A41    GND GND_A41 @S9S_MB_2U_LIB.S9S_MB_2U(SCH_1):GND
 A42 OCP_SFF_PRSNT1_R_N PRSNTB1# @S9S_MB_2U_LIB.S9S_MB_2U(SCH_1):OCP_SFF_PRSNT1_R_N
 A43    GND GND_A43 @S9S_MB_2U_LIB.S9S_MB_2U(SCH_1):GND
 A44 P5E_CPU0_PE1_RX_DP<8>  PERN8 @S9S_MB_2U_LIB.S9S_MB_2U(SCH_1):P5E_CPU0_PE1_RX_DP(8)
 A45 P5E_CPU0_PE1_RX_DN<8>  PERP8 @S9S_MB_2U_LIB.S9S_MB_2U(SCH_1):P5E_CPU0_PE1_RX_DN(8)
 A46    GND GND_A46 @S9S_MB_2U_LIB.S9S_MB_2U(SCH_1):GND
 A47 P5E_CPU0_PE1_RX_DP<9>  PERN9 @S9S_MB_2U_LIB.S9S_MB_2U(SCH_1):P5E_CPU0_PE1_RX_DP(9)
 A48 P5E_CPU0_PE1_RX_DN<9>  PERP9 @S9S_MB_2U_LIB.S9S_MB_2U(SCH_1):P5E_CPU0_PE1_RX_DN(9)
 A49    GND GND_A49 @S9S_MB_2U_LIB.S9S_MB_2U(SCH_1):GND
 A50 P5E_CPU0_PE1_RX_DP<10> PERN10 @S9S_MB_2U_LIB.S9S_MB_2U(SCH_1):P5E_CPU0_PE1_RX_DP(10)
 A51 P5E_CPU0_PE1_RX_DN<10> PERP10 @S9S_MB_2U_LIB.S9S_MB_2U(SCH_1):P5E_CPU0_PE1_RX_DN(10)
 A52    GND GND_A52 @S9S_MB_2U_LIB.S9S_MB_2U(SCH_1):GND
 A53 P5E_CPU0_PE1_RX_DP<11> PERN11 @S9S_MB_2U_LIB.S9S_MB_2U(SCH_1):P5E_CPU0_PE1_RX_DP(11)
 A54 P5E_CPU0_PE1_RX_DN<11> PERP11 @S9S_MB_2U_LIB.S9S_MB_2U(SCH_1):P5E_CPU0_PE1_RX_DN(11)
 A55    GND GND_A55 @S9S_MB_2U_LIB.S9S_MB_2U(SCH_1):GND
 A56 P5E_CPU0_PE1_RX_DP<12> PERN12 @S9S_MB_2U_LIB.S9S_MB_2U(SCH_1):P5E_CPU0_PE1_RX_DP(12)
 A57 P5E_CPU0_PE1_RX_DN<12> PERP12 @S9S_MB_2U_LIB.S9S_MB_2U(SCH_1):P5E_CPU0_PE1_RX_DN(12)
 A58    GND GND_A58 @S9S_MB_2U_LIB.S9S_MB_2U(SCH_1):GND
 A59 P5E_CPU0_PE1_RX_DP<13> PERN13 @S9S_MB_2U_LIB.S9S_MB_2U(SCH_1):P5E_CPU0_PE1_RX_DP(13)
 A60 P5E_CPU0_PE1_RX_DN<13> PERP13 @S9S_MB_2U_LIB.S9S_MB_2U(SCH_1):P5E_CPU0_PE1_RX_DN(13)
 A61    GND GND_A61 @S9S_MB_2U_LIB.S9S_MB_2U(SCH_1):GND
 A62 P5E_CPU0_PE1_RX_DP<14> PERN14 @S9S_MB_2U_LIB.S9S_MB_2U(SCH_1):P5E_CPU0_PE1_RX_DP(14)
 A63 P5E_CPU0_PE1_RX_DN<14> PERP14 @S9S_MB_2U_LIB.S9S_MB_2U(SCH_1):P5E_CPU0_PE1_RX_DN(14)
 A64    GND GND_A64 @S9S_MB_2U_LIB.S9S_MB_2U(SCH_1):GND
 A65 P5E_CPU0_PE1_RX_DP<15> PERN15 @S9S_MB_2U_LIB.S9S_MB_2U(SCH_1):P5E_CPU0_PE1_RX_DP(15)
 A66 P5E_CPU0_PE1_RX_DN<15> PERP15 @S9S_MB_2U_LIB.S9S_MB_2U(SCH_1):P5E_CPU0_PE1_RX_DN(15)
 A67    GND GND_A67 @S9S_MB_2U_LIB.S9S_MB_2U(SCH_1):GND
 A68 OCP_SFF_USB2_3_DN USB_DATN @S9S_MB_2U_LIB.S9S_MB_2U(SCH_1):OCP_SFF_USB2_3_DN
 A69 OCP_SFF_USB2_3_DP USB_DATP @S9S_MB_2U_LIB.S9S_MB_2U(SCH_1):OCP_SFF_USB2_3_DP
 A70 OCP_SFF_PWRBRK_N PWRBRK0# @S9S_MB_2U_LIB.S9S_MB_2U(SCH_1):OCP_SFF_PWRBRK_N
 B57 P5E_CPU0_PE1_TX_C_DN<12> PETP12 @S9S_MB_2U_LIB.S9S_MB_2U(SCH_1):P5E_CPU0_PE1_TX_C_DN(12)
 B58    GND GND_B58 @S9S_MB_2U_LIB.S9S_MB_2U(SCH_1):GND
 B59 P5E_CPU0_PE1_TX_C_DN<13> PETN13 @S9S_MB_2U_LIB.S9S_MB_2U(SCH_1):P5E_CPU0_PE1_TX_C_DN(13)
 B60 P5E_CPU0_PE1_TX_C_DP<13> PETP13 @S9S_MB_2U_LIB.S9S_MB_2U(SCH_1):P5E_CPU0_PE1_TX_C_DP(13)
 B61    GND GND_B61 @S9S_MB_2U_LIB.S9S_MB_2U(SCH_1):GND
 B62 P5E_CPU0_PE1_TX_C_DP<14> PETN14 @S9S_MB_2U_LIB.S9S_MB_2U(SCH_1):P5E_CPU0_PE1_TX_C_DP(14)
 B63 P5E_CPU0_PE1_TX_C_DN<14> PETP14 @S9S_MB_2U_LIB.S9S_MB_2U(SCH_1):P5E_CPU0_PE1_TX_C_DN(14)
 B64    GND GND_B64 @S9S_MB_2U_LIB.S9S_MB_2U(SCH_1):GND
 B65 P5E_CPU0_PE1_TX_C_DN<15> PETN15 @S9S_MB_2U_LIB.S9S_MB_2U(SCH_1):P5E_CPU0_PE1_TX_C_DN(15)
 B66 P5E_CPU0_PE1_TX_C_DP<15> PETP15 @S9S_MB_2U_LIB.S9S_MB_2U(SCH_1):P5E_CPU0_PE1_TX_C_DP(15)
 B67    GND GND_B67 @S9S_MB_2U_LIB.S9S_MB_2U(SCH_1):GND
 B68 TP_OCP_SFF_B68 RFU1_NC_B68 @S9S_MB_2U_LIB.S9S_MB_2U(SCH_1):TP_OCP_SFF_B68
 B69 TP_OCP_SFF_B69 RFU1_NC_B69 @S9S_MB_2U_LIB.S9S_MB_2U(SCH_1):TP_OCP_SFF_B69
 B70 OCP_SFF_PRSNT3_R_N PRSNTB3# @S9S_MB_2U_LIB.S9S_MB_2U(SCH_1):OCP_SFF_PRSNT3_R_N
  G1    GND     G1 @S9S_MB_2U_LIB.S9S_MB_2U(SCH_1):GND
  G2    GND     G2 @S9S_MB_2U_LIB.S9S_MB_2U(SCH_1):GND
  G3    GND     G3 @S9S_MB_2U_LIB.S9S_MB_2U(SCH_1):GND
  G4    GND     G4 @S9S_MB_2U_LIB.S9S_MB_2U(SCH_1):GND
  G5    GND     G5 @S9S_MB_2U_LIB.S9S_MB_2U(SCH_1):GND

Q_RES_0402LF-1K,1%,1/16W,CHIP,A  I212  R423
   1 SGPIO_OCP_SFF_CLK      A @S9S_MB_2U_LIB.S9S_MB_2U(SCH_1):SGPIO_OCP_SFF_CLK
   2 P3V3_OCP_SFF      B @S9S_MB_2U_LIB.S9S_MB_2U(SCH_1):P3V3_OCP_SFF

Q_RES_0402LF-10K,1%,1/16W,CHIPA  I215  R422
   1 SGPIO_OCP_SFF_DATAOUT      A @S9S_MB_2U_LIB.S9S_MB_2U(SCH_1):SGPIO_OCP_SFF_DATAOUT
   2    GND      B @S9S_MB_2U_LIB.S9S_MB_2U(SCH_1):GND

Q_RES_0402LF-10K,1%,1/16W,CHIPA  I217  R421
   1 SGPIO_OCP_SFF_DATAIN      A @S9S_MB_2U_LIB.S9S_MB_2U(SCH_1):SGPIO_OCP_SFF_DATAIN
   2 P3V3_OCP_SFF      B @S9S_MB_2U_LIB.S9S_MB_2U(SCH_1):P3V3_OCP_SFF

Q_RES_0402LF-1K,1%,1/16W,CHIP,A  I218  R420
   1 SGPIO_OCP_SFF_LD_N      A @S9S_MB_2U_LIB.S9S_MB_2U(SCH_1):SGPIO_OCP_SFF_LD_N
   2 P3V3_OCP_SFF      B @S9S_MB_2U_LIB.S9S_MB_2U(SCH_1):P3V3_OCP_SFF

Q_RES_0402LF-200,1%,1/16W,CHIPA  I220  R425
   1 SMB_OCP_SFF_3V3AUX_BUF_R_SDA      A @S9S_MB_2U_LIB.S9S_MB_2U(SCH_1):SMB_OCP_SFF_3V3AUX_BUF_R_SDA
   2 SMB_OCP_SFF_3V3AUX_BUF_SDA      B @S9S_MB_2U_LIB.S9S_MB_2U(SCH_1):SMB_OCP_SFF_3V3AUX_BUF_SDA


DRAWING: @S9S_MB_2U_LIB.S9S_MB_2U(SCH_1):PAGE148 

CONN112_10137002101LF-CONN112_A  I74  J111
  A8    GND     A8 @S9S_MB_2U_LIB.S9S_MB_2U(SCH_1):GND
  A7 GPU_FPGA_RST_R_BUF_N     A7 @S9S_MB_2U_LIB.S9S_MB_2U(SCH_1):GPU_FPGA_RST_R_BUF_N
  A6    GND     A6 @S9S_MB_2U_LIB.S9S_MB_2U(SCH_1):GND
  A5 GPU_PEX_STRAP0     A5 @S9S_MB_2U_LIB.S9S_MB_2U(SCH_1):GPU_PEX_STRAP0
  B8 P5E_CPU1_PE0_RX_DN<0>     B8 @S9S_MB_2U_LIB.S9S_MB_2U(SCH_1):P5E_CPU1_PE0_RX_DN(0)
  B7    GND     B7 @S9S_MB_2U_LIB.S9S_MB_2U(SCH_1):GND
  B6 P5E_CPU1_PE0_RX_DN<2>     B6 @S9S_MB_2U_LIB.S9S_MB_2U(SCH_1):P5E_CPU1_PE0_RX_DN(2)
  B5    GND     B5 @S9S_MB_2U_LIB.S9S_MB_2U(SCH_1):GND
  C8 P5E_CPU1_PE0_RX_DP<0>     C8 @S9S_MB_2U_LIB.S9S_MB_2U(SCH_1):P5E_CPU1_PE0_RX_DP(0)
  C7 P5E_CPU1_PE0_RX_DP<1>     C7 @S9S_MB_2U_LIB.S9S_MB_2U(SCH_1):P5E_CPU1_PE0_RX_DP(1)
  C6 P5E_CPU1_PE0_RX_DP<2>     C6 @S9S_MB_2U_LIB.S9S_MB_2U(SCH_1):P5E_CPU1_PE0_RX_DP(2)
  C5 P5E_CPU1_PE0_RX_DP<3>     C5 @S9S_MB_2U_LIB.S9S_MB_2U(SCH_1):P5E_CPU1_PE0_RX_DP(3)
  D8    GND     D8 @S9S_MB_2U_LIB.S9S_MB_2U(SCH_1):GND
  D7 P5E_CPU1_PE0_RX_DN<1>     D7 @S9S_MB_2U_LIB.S9S_MB_2U(SCH_1):P5E_CPU1_PE0_RX_DN(1)
  D6    GND     D6 @S9S_MB_2U_LIB.S9S_MB_2U(SCH_1):GND
  D5 P5E_CPU1_PE0_RX_DN<3>     D5 @S9S_MB_2U_LIB.S9S_MB_2U(SCH_1):P5E_CPU1_PE0_RX_DN(3)
  E8 P5E_CPU1_PE4_RX_DP<15>     E8 @S9S_MB_2U_LIB.S9S_MB_2U(SCH_1):P5E_CPU1_PE4_RX_DP(15)
  E7    GND     E7 @S9S_MB_2U_LIB.S9S_MB_2U(SCH_1):GND
  E6 P5E_CPU1_PE4_RX_DP<13>     E6 @S9S_MB_2U_LIB.S9S_MB_2U(SCH_1):P5E_CPU1_PE4_RX_DP(13)
  E5    GND     E5 @S9S_MB_2U_LIB.S9S_MB_2U(SCH_1):GND
  F8 P5E_CPU1_PE4_RX_DN<15>     F8 @S9S_MB_2U_LIB.S9S_MB_2U(SCH_1):P5E_CPU1_PE4_RX_DN(15)
  F7 P5E_CPU1_PE4_RX_DN<14>     F7 @S9S_MB_2U_LIB.S9S_MB_2U(SCH_1):P5E_CPU1_PE4_RX_DN(14)
  F6 P5E_CPU1_PE4_RX_DN<13>     F6 @S9S_MB_2U_LIB.S9S_MB_2U(SCH_1):P5E_CPU1_PE4_RX_DN(13)
  F5 P5E_CPU1_PE4_RX_DN<12>     F5 @S9S_MB_2U_LIB.S9S_MB_2U(SCH_1):P5E_CPU1_PE4_RX_DN(12)
  G8    GND     G8 @S9S_MB_2U_LIB.S9S_MB_2U(SCH_1):GND
  G7 P5E_CPU1_PE4_RX_DP<14>     G7 @S9S_MB_2U_LIB.S9S_MB_2U(SCH_1):P5E_CPU1_PE4_RX_DP(14)
  G6    GND     G6 @S9S_MB_2U_LIB.S9S_MB_2U(SCH_1):GND
  G5 P5E_CPU1_PE4_RX_DP<12>     G5 @S9S_MB_2U_LIB.S9S_MB_2U(SCH_1):P5E_CPU1_PE4_RX_DP(12)
  H8 P5E_CPU1_PE0_TX_C_DN<0>     H8 @S9S_MB_2U_LIB.S9S_MB_2U(SCH_1):P5E_CPU1_PE0_TX_C_DN(0)
  H7    GND     H7 @S9S_MB_2U_LIB.S9S_MB_2U(SCH_1):GND
  H6 P5E_CPU1_PE0_TX_C_DN<2>     H6 @S9S_MB_2U_LIB.S9S_MB_2U(SCH_1):P5E_CPU1_PE0_TX_C_DN(2)
  H5    GND     H5 @S9S_MB_2U_LIB.S9S_MB_2U(SCH_1):GND
  I8 P5E_CPU1_PE0_TX_C_DP<0>     I8 @S9S_MB_2U_LIB.S9S_MB_2U(SCH_1):P5E_CPU1_PE0_TX_C_DP(0)
  I7 P5E_CPU1_PE0_TX_C_DN<1>     I7 @S9S_MB_2U_LIB.S9S_MB_2U(SCH_1):P5E_CPU1_PE0_TX_C_DN(1)
  I6 P5E_CPU1_PE0_TX_C_DP<2>     I6 @S9S_MB_2U_LIB.S9S_MB_2U(SCH_1):P5E_CPU1_PE0_TX_C_DP(2)
  I5 P5E_CPU1_PE0_TX_C_DN<3>     I5 @S9S_MB_2U_LIB.S9S_MB_2U(SCH_1):P5E_CPU1_PE0_TX_C_DN(3)
  J8    GND     J8 @S9S_MB_2U_LIB.S9S_MB_2U(SCH_1):GND
  J7 P5E_CPU1_PE0_TX_C_DP<1>     J7 @S9S_MB_2U_LIB.S9S_MB_2U(SCH_1):P5E_CPU1_PE0_TX_C_DP(1)
  J6    GND     J6 @S9S_MB_2U_LIB.S9S_MB_2U(SCH_1):GND
  J5 P5E_CPU1_PE0_TX_C_DP<3>     J5 @S9S_MB_2U_LIB.S9S_MB_2U(SCH_1):P5E_CPU1_PE0_TX_C_DP(3)
  K8 P5E_CPU1_PE4_TX_C_DN<15>     K8 @S9S_MB_2U_LIB.S9S_MB_2U(SCH_1):P5E_CPU1_PE4_TX_C_DN(15)
  K7    GND     K7 @S9S_MB_2U_LIB.S9S_MB_2U(SCH_1):GND
  K6 P5E_CPU1_PE4_TX_C_DN<13>     K6 @S9S_MB_2U_LIB.S9S_MB_2U(SCH_1):P5E_CPU1_PE4_TX_C_DN(13)
  K5    GND     K5 @S9S_MB_2U_LIB.S9S_MB_2U(SCH_1):GND
  L8 P5E_CPU1_PE4_TX_C_DP<15>     L8 @S9S_MB_2U_LIB.S9S_MB_2U(SCH_1):P5E_CPU1_PE4_TX_C_DP(15)
  L7 P5E_CPU1_PE4_TX_C_DN<14>     L7 @S9S_MB_2U_LIB.S9S_MB_2U(SCH_1):P5E_CPU1_PE4_TX_C_DN(14)
  L6 P5E_CPU1_PE4_TX_C_DP<13>     L6 @S9S_MB_2U_LIB.S9S_MB_2U(SCH_1):P5E_CPU1_PE4_TX_C_DP(13)
  L5 P5E_CPU1_PE4_TX_C_DN<12>     L5 @S9S_MB_2U_LIB.S9S_MB_2U(SCH_1):P5E_CPU1_PE4_TX_C_DN(12)
  M5 P5E_CPU1_PE4_TX_C_DP<12>     M5 @S9S_MB_2U_LIB.S9S_MB_2U(SCH_1):P5E_CPU1_PE4_TX_C_DP(12)
  N5    GND     N5 @S9S_MB_2U_LIB.S9S_MB_2U(SCH_1):GND
  M6    GND     M6 @S9S_MB_2U_LIB.S9S_MB_2U(SCH_1):GND
  N6 FM_GPU_PWRGD     N6 @S9S_MB_2U_LIB.S9S_MB_2U(SCH_1):FM_GPU_PWRGD
  M7 P5E_CPU1_PE4_TX_C_DP<14>     M7 @S9S_MB_2U_LIB.S9S_MB_2U(SCH_1):P5E_CPU1_PE4_TX_C_DP(14)
  N7    GND     N7 @S9S_MB_2U_LIB.S9S_MB_2U(SCH_1):GND
  M8    GND     M8 @S9S_MB_2U_LIB.S9S_MB_2U(SCH_1):GND
  N8 GPU_BASE_ID1     N8 @S9S_MB_2U_LIB.S9S_MB_2U(SCH_1):GPU_BASE_ID1

CONN112_10137002101LF-CONN112_A  I75  J111
  A4    GND     A4 @S9S_MB_2U_LIB.S9S_MB_2U(SCH_1):GND
  A3 GPU_BASE_ID0     A3 @S9S_MB_2U_LIB.S9S_MB_2U(SCH_1):GPU_BASE_ID0
  A2    GND     A2 @S9S_MB_2U_LIB.S9S_MB_2U(SCH_1):GND
  A1 GPU_PEX_STRAP1     A1 @S9S_MB_2U_LIB.S9S_MB_2U(SCH_1):GPU_PEX_STRAP1
  B4 P5E_CPU1_PE0_RX_DN<4>     B4 @S9S_MB_2U_LIB.S9S_MB_2U(SCH_1):P5E_CPU1_PE0_RX_DN(4)
  B3    GND     B3 @S9S_MB_2U_LIB.S9S_MB_2U(SCH_1):GND
  B2 P5E_CPU1_PE0_RX_DN<6>     B2 @S9S_MB_2U_LIB.S9S_MB_2U(SCH_1):P5E_CPU1_PE0_RX_DN(6)
  B1    GND     B1 @S9S_MB_2U_LIB.S9S_MB_2U(SCH_1):GND
  C4 P5E_CPU1_PE0_RX_DP<4>     C4 @S9S_MB_2U_LIB.S9S_MB_2U(SCH_1):P5E_CPU1_PE0_RX_DP(4)
  C3 P5E_CPU1_PE0_RX_DN<5>     C3 @S9S_MB_2U_LIB.S9S_MB_2U(SCH_1):P5E_CPU1_PE0_RX_DN(5)
  C2 P5E_CPU1_PE0_RX_DP<6>     C2 @S9S_MB_2U_LIB.S9S_MB_2U(SCH_1):P5E_CPU1_PE0_RX_DP(6)
  C1 P5E_CPU1_PE0_RX_DN<7>     C1 @S9S_MB_2U_LIB.S9S_MB_2U(SCH_1):P5E_CPU1_PE0_RX_DN(7)
  D4    GND     D4 @S9S_MB_2U_LIB.S9S_MB_2U(SCH_1):GND
  D3 P5E_CPU1_PE0_RX_DP<5>     D3 @S9S_MB_2U_LIB.S9S_MB_2U(SCH_1):P5E_CPU1_PE0_RX_DP(5)
  D2    GND     D2 @S9S_MB_2U_LIB.S9S_MB_2U(SCH_1):GND
  D1 P5E_CPU1_PE0_RX_DP<7>     D1 @S9S_MB_2U_LIB.S9S_MB_2U(SCH_1):P5E_CPU1_PE0_RX_DP(7)
  E4 P5E_CPU1_PE4_RX_DP<11>     E4 @S9S_MB_2U_LIB.S9S_MB_2U(SCH_1):P5E_CPU1_PE4_RX_DP(11)
  E3    GND     E3 @S9S_MB_2U_LIB.S9S_MB_2U(SCH_1):GND
  E2 P5E_CPU1_PE4_RX_DP<9>     E2 @S9S_MB_2U_LIB.S9S_MB_2U(SCH_1):P5E_CPU1_PE4_RX_DP(9)
  E1    GND     E1 @S9S_MB_2U_LIB.S9S_MB_2U(SCH_1):GND
  F4 P5E_CPU1_PE4_RX_DN<11>     F4 @S9S_MB_2U_LIB.S9S_MB_2U(SCH_1):P5E_CPU1_PE4_RX_DN(11)
  F3 P5E_CPU1_PE4_RX_DN<10>     F3 @S9S_MB_2U_LIB.S9S_MB_2U(SCH_1):P5E_CPU1_PE4_RX_DN(10)
  F2 P5E_CPU1_PE4_RX_DN<9>     F2 @S9S_MB_2U_LIB.S9S_MB_2U(SCH_1):P5E_CPU1_PE4_RX_DN(9)
  F1 P5E_CPU1_PE4_RX_DN<8>     F1 @S9S_MB_2U_LIB.S9S_MB_2U(SCH_1):P5E_CPU1_PE4_RX_DN(8)
  G4    GND     G4 @S9S_MB_2U_LIB.S9S_MB_2U(SCH_1):GND
  G3 P5E_CPU1_PE4_RX_DP<10>     G3 @S9S_MB_2U_LIB.S9S_MB_2U(SCH_1):P5E_CPU1_PE4_RX_DP(10)
  G2    GND     G2 @S9S_MB_2U_LIB.S9S_MB_2U(SCH_1):GND
  G1 P5E_CPU1_PE4_RX_DP<8>     G1 @S9S_MB_2U_LIB.S9S_MB_2U(SCH_1):P5E_CPU1_PE4_RX_DP(8)
  H4 P5E_CPU1_PE0_TX_C_DN<4>     H4 @S9S_MB_2U_LIB.S9S_MB_2U(SCH_1):P5E_CPU1_PE0_TX_C_DN(4)
  H3    GND     H3 @S9S_MB_2U_LIB.S9S_MB_2U(SCH_1):GND
  H2 P5E_CPU1_PE0_TX_C_DN<6>     H2 @S9S_MB_2U_LIB.S9S_MB_2U(SCH_1):P5E_CPU1_PE0_TX_C_DN(6)
  H1    GND     H1 @S9S_MB_2U_LIB.S9S_MB_2U(SCH_1):GND
  I4 P5E_CPU1_PE0_TX_C_DP<4>     I4 @S9S_MB_2U_LIB.S9S_MB_2U(SCH_1):P5E_CPU1_PE0_TX_C_DP(4)
  I3 P5E_CPU1_PE0_TX_C_DN<5>     I3 @S9S_MB_2U_LIB.S9S_MB_2U(SCH_1):P5E_CPU1_PE0_TX_C_DN(5)
  I2 P5E_CPU1_PE0_TX_C_DP<6>     I2 @S9S_MB_2U_LIB.S9S_MB_2U(SCH_1):P5E_CPU1_PE0_TX_C_DP(6)
  I1 P5E_CPU1_PE0_TX_C_DN<7>     I1 @S9S_MB_2U_LIB.S9S_MB_2U(SCH_1):P5E_CPU1_PE0_TX_C_DN(7)
  J4    GND     J4 @S9S_MB_2U_LIB.S9S_MB_2U(SCH_1):GND
  J3 P5E_CPU1_PE0_TX_C_DP<5>     J3 @S9S_MB_2U_LIB.S9S_MB_2U(SCH_1):P5E_CPU1_PE0_TX_C_DP(5)
  J2    GND     J2 @S9S_MB_2U_LIB.S9S_MB_2U(SCH_1):GND
  J1 P5E_CPU1_PE0_TX_C_DP<7>     J1 @S9S_MB_2U_LIB.S9S_MB_2U(SCH_1):P5E_CPU1_PE0_TX_C_DP(7)
  K4 P5E_CPU1_PE4_TX_C_DP<11>     K4 @S9S_MB_2U_LIB.S9S_MB_2U(SCH_1):P5E_CPU1_PE4_TX_C_DP(11)
  K3    GND     K3 @S9S_MB_2U_LIB.S9S_MB_2U(SCH_1):GND
  K2 P5E_CPU1_PE4_TX_C_DN<9>     K2 @S9S_MB_2U_LIB.S9S_MB_2U(SCH_1):P5E_CPU1_PE4_TX_C_DN(9)
  K1    GND     K1 @S9S_MB_2U_LIB.S9S_MB_2U(SCH_1):GND
  L4 P5E_CPU1_PE4_TX_C_DN<11>     L4 @S9S_MB_2U_LIB.S9S_MB_2U(SCH_1):P5E_CPU1_PE4_TX_C_DN(11)
  L3 P5E_CPU1_PE4_TX_C_DN<10>     L3 @S9S_MB_2U_LIB.S9S_MB_2U(SCH_1):P5E_CPU1_PE4_TX_C_DN(10)
  L2 P5E_CPU1_PE4_TX_C_DP<9>     L2 @S9S_MB_2U_LIB.S9S_MB_2U(SCH_1):P5E_CPU1_PE4_TX_C_DP(9)
  L1 P5E_CPU1_PE4_TX_C_DN<8>     L1 @S9S_MB_2U_LIB.S9S_MB_2U(SCH_1):P5E_CPU1_PE4_TX_C_DN(8)
  M1 P5E_CPU1_PE4_TX_C_DP<8>     M1 @S9S_MB_2U_LIB.S9S_MB_2U(SCH_1):P5E_CPU1_PE4_TX_C_DP(8)
  N1    GND     N1 @S9S_MB_2U_LIB.S9S_MB_2U(SCH_1):GND
  M2    GND     M2 @S9S_MB_2U_LIB.S9S_MB_2U(SCH_1):GND
  N2 GPU_PRSNT_N     N2 @S9S_MB_2U_LIB.S9S_MB_2U(SCH_1):GPU_PRSNT_N
  M3 P5E_CPU1_PE4_TX_C_DP<10>     M3 @S9S_MB_2U_LIB.S9S_MB_2U(SCH_1):P5E_CPU1_PE4_TX_C_DP(10)
  N3    GND     N3 @S9S_MB_2U_LIB.S9S_MB_2U(SCH_1):GND
  M4    GND     M4 @S9S_MB_2U_LIB.S9S_MB_2U(SCH_1):GND
  N4 FM_GPU_PWR_EN_R_BUF     N4 @S9S_MB_2U_LIB.S9S_MB_2U(SCH_1):FM_GPU_PWR_EN_R_BUF


DRAWING: @S9S_MB_2U_LIB.S9S_MB_2U(SCH_1):PAGE149 

CONN160_10131762101LF-CONN160_A  I75  J112
  A8    GND     A8 @S9S_MB_2U_LIB.S9S_MB_2U(SCH_1):GND
  A7 PRSNT_SWB_N     A7 @S9S_MB_2U_LIB.S9S_MB_2U(SCH_1):PRSNT_SWB_N
  A6    GND     A6 @S9S_MB_2U_LIB.S9S_MB_2U(SCH_1):GND
  A5 RST_PERST_1_SWB_BUF_N     A5 @S9S_MB_2U_LIB.S9S_MB_2U(SCH_1):RST_PERST_1_SWB_BUF_N
  B8 P5E_CPU1_PE0_RX_DN<8>     B8 @S9S_MB_2U_LIB.S9S_MB_2U(SCH_1):P5E_CPU1_PE0_RX_DN(8)
  B7    GND     B7 @S9S_MB_2U_LIB.S9S_MB_2U(SCH_1):GND
  B6 P5E_CPU1_PE0_RX_DN<10>     B6 @S9S_MB_2U_LIB.S9S_MB_2U(SCH_1):P5E_CPU1_PE0_RX_DN(10)
  B5    GND     B5 @S9S_MB_2U_LIB.S9S_MB_2U(SCH_1):GND
  C8 P5E_CPU1_PE0_RX_DP<8>     C8 @S9S_MB_2U_LIB.S9S_MB_2U(SCH_1):P5E_CPU1_PE0_RX_DP(8)
  C7 P5E_CPU1_PE0_RX_DN<9>     C7 @S9S_MB_2U_LIB.S9S_MB_2U(SCH_1):P5E_CPU1_PE0_RX_DN(9)
  C6 P5E_CPU1_PE0_RX_DP<10>     C6 @S9S_MB_2U_LIB.S9S_MB_2U(SCH_1):P5E_CPU1_PE0_RX_DP(10)
  C5 P5E_CPU1_PE0_RX_DP<11>     C5 @S9S_MB_2U_LIB.S9S_MB_2U(SCH_1):P5E_CPU1_PE0_RX_DP(11)
  D8    GND     D8 @S9S_MB_2U_LIB.S9S_MB_2U(SCH_1):GND
  D7 P5E_CPU1_PE0_RX_DP<9>     D7 @S9S_MB_2U_LIB.S9S_MB_2U(SCH_1):P5E_CPU1_PE0_RX_DP(9)
  D6    GND     D6 @S9S_MB_2U_LIB.S9S_MB_2U(SCH_1):GND
  D5 P5E_CPU1_PE0_RX_DN<11>     D5 @S9S_MB_2U_LIB.S9S_MB_2U(SCH_1):P5E_CPU1_PE0_RX_DN(11)
  E8 P5E_CPU1_PE4_RX_DP<7>     E8 @S9S_MB_2U_LIB.S9S_MB_2U(SCH_1):P5E_CPU1_PE4_RX_DP(7)
  E7    GND     E7 @S9S_MB_2U_LIB.S9S_MB_2U(SCH_1):GND
  E6 P5E_CPU1_PE4_RX_DP<5>     E6 @S9S_MB_2U_LIB.S9S_MB_2U(SCH_1):P5E_CPU1_PE4_RX_DP(5)
  E5    GND     E5 @S9S_MB_2U_LIB.S9S_MB_2U(SCH_1):GND
  F8 P5E_CPU1_PE4_RX_DN<7>     F8 @S9S_MB_2U_LIB.S9S_MB_2U(SCH_1):P5E_CPU1_PE4_RX_DN(7)
  F7 P5E_CPU1_PE4_RX_DN<6>     F7 @S9S_MB_2U_LIB.S9S_MB_2U(SCH_1):P5E_CPU1_PE4_RX_DN(6)
  F6 P5E_CPU1_PE4_RX_DN<5>     F6 @S9S_MB_2U_LIB.S9S_MB_2U(SCH_1):P5E_CPU1_PE4_RX_DN(5)
  F5 P5E_CPU1_PE4_RX_DN<4>     F5 @S9S_MB_2U_LIB.S9S_MB_2U(SCH_1):P5E_CPU1_PE4_RX_DN(4)
  G8    GND     G8 @S9S_MB_2U_LIB.S9S_MB_2U(SCH_1):GND
  G7 P5E_CPU1_PE4_RX_DP<6>     G7 @S9S_MB_2U_LIB.S9S_MB_2U(SCH_1):P5E_CPU1_PE4_RX_DP(6)
  G6    GND     G6 @S9S_MB_2U_LIB.S9S_MB_2U(SCH_1):GND
  G5 P5E_CPU1_PE4_RX_DP<4>     G5 @S9S_MB_2U_LIB.S9S_MB_2U(SCH_1):P5E_CPU1_PE4_RX_DP(4)
  H8 P5E_CPU1_PE0_TX_C_DN<8>     H8 @S9S_MB_2U_LIB.S9S_MB_2U(SCH_1):P5E_CPU1_PE0_TX_C_DN(8)
  H7    GND     H7 @S9S_MB_2U_LIB.S9S_MB_2U(SCH_1):GND
  H6 P5E_CPU1_PE0_TX_C_DN<10>     H6 @S9S_MB_2U_LIB.S9S_MB_2U(SCH_1):P5E_CPU1_PE0_TX_C_DN(10)
  H5    GND     H5 @S9S_MB_2U_LIB.S9S_MB_2U(SCH_1):GND
  I8 P5E_CPU1_PE0_TX_C_DP<8>     I8 @S9S_MB_2U_LIB.S9S_MB_2U(SCH_1):P5E_CPU1_PE0_TX_C_DP(8)
  I7 P5E_CPU1_PE0_TX_C_DN<9>     I7 @S9S_MB_2U_LIB.S9S_MB_2U(SCH_1):P5E_CPU1_PE0_TX_C_DN(9)
  I6 P5E_CPU1_PE0_TX_C_DP<10>     I6 @S9S_MB_2U_LIB.S9S_MB_2U(SCH_1):P5E_CPU1_PE0_TX_C_DP(10)
  I5 P5E_CPU1_PE0_TX_C_DN<11>     I5 @S9S_MB_2U_LIB.S9S_MB_2U(SCH_1):P5E_CPU1_PE0_TX_C_DN(11)
  J8    GND     J8 @S9S_MB_2U_LIB.S9S_MB_2U(SCH_1):GND
  J7 P5E_CPU1_PE0_TX_C_DP<9>     J7 @S9S_MB_2U_LIB.S9S_MB_2U(SCH_1):P5E_CPU1_PE0_TX_C_DP(9)
  J6    GND     J6 @S9S_MB_2U_LIB.S9S_MB_2U(SCH_1):GND
  J5 P5E_CPU1_PE0_TX_C_DP<11>     J5 @S9S_MB_2U_LIB.S9S_MB_2U(SCH_1):P5E_CPU1_PE0_TX_C_DP(11)
  K8 P5E_CPU1_PE4_TX_C_DN<7>     K8 @S9S_MB_2U_LIB.S9S_MB_2U(SCH_1):P5E_CPU1_PE4_TX_C_DN(7)
  K7    GND     K7 @S9S_MB_2U_LIB.S9S_MB_2U(SCH_1):GND
  K6 P5E_CPU1_PE4_TX_C_DN<5>     K6 @S9S_MB_2U_LIB.S9S_MB_2U(SCH_1):P5E_CPU1_PE4_TX_C_DN(5)
  K5    GND     K5 @S9S_MB_2U_LIB.S9S_MB_2U(SCH_1):GND
  L8 P5E_CPU1_PE4_TX_C_DP<7>     L8 @S9S_MB_2U_LIB.S9S_MB_2U(SCH_1):P5E_CPU1_PE4_TX_C_DP(7)
  L7 P5E_CPU1_PE4_TX_C_DN<6>     L7 @S9S_MB_2U_LIB.S9S_MB_2U(SCH_1):P5E_CPU1_PE4_TX_C_DN(6)
  L6 P5E_CPU1_PE4_TX_C_DP<5>     L6 @S9S_MB_2U_LIB.S9S_MB_2U(SCH_1):P5E_CPU1_PE4_TX_C_DP(5)
  L5 P5E_CPU1_PE4_TX_C_DN<4>     L5 @S9S_MB_2U_LIB.S9S_MB_2U(SCH_1):P5E_CPU1_PE4_TX_C_DN(4)
  M5 P5E_CPU1_PE4_TX_C_DP<4>     M5 @S9S_MB_2U_LIB.S9S_MB_2U(SCH_1):P5E_CPU1_PE4_TX_C_DP(4)
  N5    GND     N5 @S9S_MB_2U_LIB.S9S_MB_2U(SCH_1):GND
  M6    GND     M6 @S9S_MB_2U_LIB.S9S_MB_2U(SCH_1):GND
  N6 P2E_MB_BMC_RX_DN<0>     N6 @S9S_MB_2U_LIB.S9S_MB_2U(SCH_1):P2E_MB_BMC_RX_DN(0)
  M7 P5E_CPU1_PE4_TX_C_DP<6>     M7 @S9S_MB_2U_LIB.S9S_MB_2U(SCH_1):P5E_CPU1_PE4_TX_C_DP(6)
  N7    GND     N7 @S9S_MB_2U_LIB.S9S_MB_2U(SCH_1):GND
  M8    GND     M8 @S9S_MB_2U_LIB.S9S_MB_2U(SCH_1):GND
  N8 P3E_PCH_NVS_RX_DN<0>     N8 @S9S_MB_2U_LIB.S9S_MB_2U(SCH_1):P3E_PCH_NVS_RX_DN(0)
  O5 NC_J112_O5     O5 @S9S_MB_2U_LIB.S9S_MB_2U(SCH_1):NC_J112_O5
  P5 NC_J112_P5     P5 @S9S_MB_2U_LIB.S9S_MB_2U(SCH_1):NC_J112_P5
  Q5    GND     Q5 @S9S_MB_2U_LIB.S9S_MB_2U(SCH_1):GND
  R5 NC_J112_R5     R5 @S9S_MB_2U_LIB.S9S_MB_2U(SCH_1):NC_J112_R5
  S5 NC_J112_S5     S5 @S9S_MB_2U_LIB.S9S_MB_2U(SCH_1):NC_J112_S5
  T5    GND     T5 @S9S_MB_2U_LIB.S9S_MB_2U(SCH_1):GND
  O6 P2E_MB_BMC_RX_DP<0>     O6 @S9S_MB_2U_LIB.S9S_MB_2U(SCH_1):P2E_MB_BMC_RX_DP(0)
  P6    GND     P6 @S9S_MB_2U_LIB.S9S_MB_2U(SCH_1):GND
  Q6 P2E_MB_BMC_TX_BUF_C_DN<0>     Q6 @S9S_MB_2U_LIB.S9S_MB_2U(SCH_1):P2E_MB_BMC_TX_BUF_C_DN(0)
  R6 P2E_MB_BMC_TX_BUF_C_DP<0>     R6 @S9S_MB_2U_LIB.S9S_MB_2U(SCH_1):P2E_MB_BMC_TX_BUF_C_DP(0)
  S6    GND     S6 @S9S_MB_2U_LIB.S9S_MB_2U(SCH_1):GND
  T6 GPU_FPGA_THERM_OVERT_N     T6 @S9S_MB_2U_LIB.S9S_MB_2U(SCH_1):GPU_FPGA_THERM_OVERT_N
  O7 P3E_PCH_NVS_RX_DN<1>     O7 @S9S_MB_2U_LIB.S9S_MB_2U(SCH_1):P3E_PCH_NVS_RX_DN(1)
  P7 P3E_PCH_NVS_RX_DP<1>     P7 @S9S_MB_2U_LIB.S9S_MB_2U(SCH_1):P3E_PCH_NVS_RX_DP(1)
  Q7    GND     Q7 @S9S_MB_2U_LIB.S9S_MB_2U(SCH_1):GND
  R7 P3E_PCH_NVS_TX_C_DN<1>     R7 @S9S_MB_2U_LIB.S9S_MB_2U(SCH_1):P3E_PCH_NVS_TX_C_DN(1)
  S7 P3E_PCH_NVS_TX_C_DP<1>     S7 @S9S_MB_2U_LIB.S9S_MB_2U(SCH_1):P3E_PCH_NVS_TX_C_DP(1)
  T7    GND     T7 @S9S_MB_2U_LIB.S9S_MB_2U(SCH_1):GND
  O8 P3E_PCH_NVS_RX_DP<0>     O8 @S9S_MB_2U_LIB.S9S_MB_2U(SCH_1):P3E_PCH_NVS_RX_DP(0)
  P8    GND     P8 @S9S_MB_2U_LIB.S9S_MB_2U(SCH_1):GND
  Q8 P3E_PCH_NVS_TX_C_DN<0>     Q8 @S9S_MB_2U_LIB.S9S_MB_2U(SCH_1):P3E_PCH_NVS_TX_C_DN(0)
  R8 P3E_PCH_NVS_TX_C_DP<0>     R8 @S9S_MB_2U_LIB.S9S_MB_2U(SCH_1):P3E_PCH_NVS_TX_C_DP(0)
  S8    GND     S8 @S9S_MB_2U_LIB.S9S_MB_2U(SCH_1):GND
  T8 RST_PERST_0_SWB_BUF_N     T8 @S9S_MB_2U_LIB.S9S_MB_2U(SCH_1):RST_PERST_0_SWB_BUF_N

CONN160_10131762101LF-CONN160_A  I76  J112
  A4    GND     A4 @S9S_MB_2U_LIB.S9S_MB_2U(SCH_1):GND
  A3 HGX_DETECT_N_ISO     A3 @S9S_MB_2U_LIB.S9S_MB_2U(SCH_1):HGX_DETECT_N_ISO
  A2    GND     A2 @S9S_MB_2U_LIB.S9S_MB_2U(SCH_1):GND
  A1 RST_PERST_2_SWB_BUF_N     A1 @S9S_MB_2U_LIB.S9S_MB_2U(SCH_1):RST_PERST_2_SWB_BUF_N
  B4 P5E_CPU1_PE0_RX_DN<12>     B4 @S9S_MB_2U_LIB.S9S_MB_2U(SCH_1):P5E_CPU1_PE0_RX_DN(12)
  B3    GND     B3 @S9S_MB_2U_LIB.S9S_MB_2U(SCH_1):GND
  B2 P5E_CPU1_PE0_RX_DN<14>     B2 @S9S_MB_2U_LIB.S9S_MB_2U(SCH_1):P5E_CPU1_PE0_RX_DN(14)
  B1    GND     B1 @S9S_MB_2U_LIB.S9S_MB_2U(SCH_1):GND
  C4 P5E_CPU1_PE0_RX_DP<12>     C4 @S9S_MB_2U_LIB.S9S_MB_2U(SCH_1):P5E_CPU1_PE0_RX_DP(12)
  C3 P5E_CPU1_PE0_RX_DN<13>     C3 @S9S_MB_2U_LIB.S9S_MB_2U(SCH_1):P5E_CPU1_PE0_RX_DN(13)
  C2 P5E_CPU1_PE0_RX_DP<14>     C2 @S9S_MB_2U_LIB.S9S_MB_2U(SCH_1):P5E_CPU1_PE0_RX_DP(14)
  C1 P5E_CPU1_PE0_RX_DN<15>     C1 @S9S_MB_2U_LIB.S9S_MB_2U(SCH_1):P5E_CPU1_PE0_RX_DN(15)
  D4    GND     D4 @S9S_MB_2U_LIB.S9S_MB_2U(SCH_1):GND
  D3 P5E_CPU1_PE0_RX_DP<13>     D3 @S9S_MB_2U_LIB.S9S_MB_2U(SCH_1):P5E_CPU1_PE0_RX_DP(13)
  D2    GND     D2 @S9S_MB_2U_LIB.S9S_MB_2U(SCH_1):GND
  D1 P5E_CPU1_PE0_RX_DP<15>     D1 @S9S_MB_2U_LIB.S9S_MB_2U(SCH_1):P5E_CPU1_PE0_RX_DP(15)
  E4 P5E_CPU1_PE4_RX_DP<3>     E4 @S9S_MB_2U_LIB.S9S_MB_2U(SCH_1):P5E_CPU1_PE4_RX_DP(3)
  E3    GND     E3 @S9S_MB_2U_LIB.S9S_MB_2U(SCH_1):GND
  E2 P5E_CPU1_PE4_RX_DP<1>     E2 @S9S_MB_2U_LIB.S9S_MB_2U(SCH_1):P5E_CPU1_PE4_RX_DP(1)
  E1    GND     E1 @S9S_MB_2U_LIB.S9S_MB_2U(SCH_1):GND
  F4 P5E_CPU1_PE4_RX_DN<3>     F4 @S9S_MB_2U_LIB.S9S_MB_2U(SCH_1):P5E_CPU1_PE4_RX_DN(3)
  F3 P5E_CPU1_PE4_RX_DN<2>     F3 @S9S_MB_2U_LIB.S9S_MB_2U(SCH_1):P5E_CPU1_PE4_RX_DN(2)
  F2 P5E_CPU1_PE4_RX_DN<1>     F2 @S9S_MB_2U_LIB.S9S_MB_2U(SCH_1):P5E_CPU1_PE4_RX_DN(1)
  F1 P5E_CPU1_PE4_RX_DN<0>     F1 @S9S_MB_2U_LIB.S9S_MB_2U(SCH_1):P5E_CPU1_PE4_RX_DN(0)
  G4    GND     G4 @S9S_MB_2U_LIB.S9S_MB_2U(SCH_1):GND
  G3 P5E_CPU1_PE4_RX_DP<2>     G3 @S9S_MB_2U_LIB.S9S_MB_2U(SCH_1):P5E_CPU1_PE4_RX_DP(2)
  G2    GND     G2 @S9S_MB_2U_LIB.S9S_MB_2U(SCH_1):GND
  G1 P5E_CPU1_PE4_RX_DP<0>     G1 @S9S_MB_2U_LIB.S9S_MB_2U(SCH_1):P5E_CPU1_PE4_RX_DP(0)
  H4 P5E_CPU1_PE0_TX_C_DN<12>     H4 @S9S_MB_2U_LIB.S9S_MB_2U(SCH_1):P5E_CPU1_PE0_TX_C_DN(12)
  H3    GND     H3 @S9S_MB_2U_LIB.S9S_MB_2U(SCH_1):GND
  H2 P5E_CPU1_PE0_TX_C_DN<14>     H2 @S9S_MB_2U_LIB.S9S_MB_2U(SCH_1):P5E_CPU1_PE0_TX_C_DN(14)
  H1    GND     H1 @S9S_MB_2U_LIB.S9S_MB_2U(SCH_1):GND
  I4 P5E_CPU1_PE0_TX_C_DP<12>     I4 @S9S_MB_2U_LIB.S9S_MB_2U(SCH_1):P5E_CPU1_PE0_TX_C_DP(12)
  I3 P5E_CPU1_PE0_TX_C_DN<13>     I3 @S9S_MB_2U_LIB.S9S_MB_2U(SCH_1):P5E_CPU1_PE0_TX_C_DN(13)
  I2 P5E_CPU1_PE0_TX_C_DP<14>     I2 @S9S_MB_2U_LIB.S9S_MB_2U(SCH_1):P5E_CPU1_PE0_TX_C_DP(14)
  I1 P5E_CPU1_PE0_TX_C_DN<15>     I1 @S9S_MB_2U_LIB.S9S_MB_2U(SCH_1):P5E_CPU1_PE0_TX_C_DN(15)
  J4    GND     J4 @S9S_MB_2U_LIB.S9S_MB_2U(SCH_1):GND
  J3 P5E_CPU1_PE0_TX_C_DP<13>     J3 @S9S_MB_2U_LIB.S9S_MB_2U(SCH_1):P5E_CPU1_PE0_TX_C_DP(13)
  J2    GND     J2 @S9S_MB_2U_LIB.S9S_MB_2U(SCH_1):GND
  J1 P5E_CPU1_PE0_TX_C_DP<15>     J1 @S9S_MB_2U_LIB.S9S_MB_2U(SCH_1):P5E_CPU1_PE0_TX_C_DP(15)
  K4 P5E_CPU1_PE4_TX_C_DN<3>     K4 @S9S_MB_2U_LIB.S9S_MB_2U(SCH_1):P5E_CPU1_PE4_TX_C_DN(3)
  K3    GND     K3 @S9S_MB_2U_LIB.S9S_MB_2U(SCH_1):GND
  K2 P5E_CPU1_PE4_TX_C_DP<1>     K2 @S9S_MB_2U_LIB.S9S_MB_2U(SCH_1):P5E_CPU1_PE4_TX_C_DP(1)
  K1    GND     K1 @S9S_MB_2U_LIB.S9S_MB_2U(SCH_1):GND
  L4 P5E_CPU1_PE4_TX_C_DP<3>     L4 @S9S_MB_2U_LIB.S9S_MB_2U(SCH_1):P5E_CPU1_PE4_TX_C_DP(3)
  L3 P5E_CPU1_PE4_TX_C_DN<2>     L3 @S9S_MB_2U_LIB.S9S_MB_2U(SCH_1):P5E_CPU1_PE4_TX_C_DN(2)
  L2 P5E_CPU1_PE4_TX_C_DN<1>     L2 @S9S_MB_2U_LIB.S9S_MB_2U(SCH_1):P5E_CPU1_PE4_TX_C_DN(1)
  L1 P5E_CPU1_PE4_TX_C_DN<0>     L1 @S9S_MB_2U_LIB.S9S_MB_2U(SCH_1):P5E_CPU1_PE4_TX_C_DN(0)
  M1 P5E_CPU1_PE4_TX_C_DP<0>     M1 @S9S_MB_2U_LIB.S9S_MB_2U(SCH_1):P5E_CPU1_PE4_TX_C_DP(0)
  N1    GND     N1 @S9S_MB_2U_LIB.S9S_MB_2U(SCH_1):GND
  M2    GND     M2 @S9S_MB_2U_LIB.S9S_MB_2U(SCH_1):GND
  N2 NC_J112_N2     N2 @S9S_MB_2U_LIB.S9S_MB_2U(SCH_1):NC_J112_N2
  M3 P5E_CPU1_PE4_TX_C_DP<2>     M3 @S9S_MB_2U_LIB.S9S_MB_2U(SCH_1):P5E_CPU1_PE4_TX_C_DP(2)
  N3    GND     N3 @S9S_MB_2U_LIB.S9S_MB_2U(SCH_1):GND
  M4    GND     M4 @S9S_MB_2U_LIB.S9S_MB_2U(SCH_1):GND
  N4 CLK_100M_GPU_1_DN     N4 @S9S_MB_2U_LIB.S9S_MB_2U(SCH_1):CLK_100M_GPU_1_DN
  O1 CLK_100M_GPU_2_DN     O1 @S9S_MB_2U_LIB.S9S_MB_2U(SCH_1):CLK_100M_GPU_2_DN
  P1 CLK_100M_GPU_2_DP     P1 @S9S_MB_2U_LIB.S9S_MB_2U(SCH_1):CLK_100M_GPU_2_DP
  Q1    GND     Q1 @S9S_MB_2U_LIB.S9S_MB_2U(SCH_1):GND
  R1 USB2_HUB_BUF_SWB_DN     R1 @S9S_MB_2U_LIB.S9S_MB_2U(SCH_1):USB2_HUB_BUF_SWB_DN
  S1 USB2_HUB_BUF_SWB_DP     S1 @S9S_MB_2U_LIB.S9S_MB_2U(SCH_1):USB2_HUB_BUF_SWB_DP
  T1    GND     T1 @S9S_MB_2U_LIB.S9S_MB_2U(SCH_1):GND
  O2 NC_J112_O2     O2 @S9S_MB_2U_LIB.S9S_MB_2U(SCH_1):NC_J112_O2
  P2    GND     P2 @S9S_MB_2U_LIB.S9S_MB_2U(SCH_1):GND
  Q2 CLK_100M_GPU_FPGA_DN     Q2 @S9S_MB_2U_LIB.S9S_MB_2U(SCH_1):CLK_100M_GPU_FPGA_DN
  R2 CLK_100M_GPU_FPGA_DP     R2 @S9S_MB_2U_LIB.S9S_MB_2U(SCH_1):CLK_100M_GPU_FPGA_DP
  S2    GND     S2 @S9S_MB_2U_LIB.S9S_MB_2U(SCH_1):GND
  T2 GPU_FPGA_READY     T2 @S9S_MB_2U_LIB.S9S_MB_2U(SCH_1):GPU_FPGA_READY
  O3 CLK_100M_SWB_DN     O3 @S9S_MB_2U_LIB.S9S_MB_2U(SCH_1):CLK_100M_SWB_DN
  P3 CLK_100M_SWB_DP     P3 @S9S_MB_2U_LIB.S9S_MB_2U(SCH_1):CLK_100M_SWB_DP
  Q3    GND     Q3 @S9S_MB_2U_LIB.S9S_MB_2U(SCH_1):GND
  R3 SMB_2_BMC_GPU_BUF_SCL     R3 @S9S_MB_2U_LIB.S9S_MB_2U(SCH_1):SMB_2_BMC_GPU_BUF_SCL
  S3 SMB_2_BMC_GPU_BUF_SDA     S3 @S9S_MB_2U_LIB.S9S_MB_2U(SCH_1):SMB_2_BMC_GPU_BUF_SDA
  T3    GND     T3 @S9S_MB_2U_LIB.S9S_MB_2U(SCH_1):GND
  O4 CLK_100M_GPU_1_DP     O4 @S9S_MB_2U_LIB.S9S_MB_2U(SCH_1):CLK_100M_GPU_1_DP
  P4    GND     P4 @S9S_MB_2U_LIB.S9S_MB_2U(SCH_1):GND
  Q4 SMB_1_BMC_GPU_BUF_SCL     Q4 @S9S_MB_2U_LIB.S9S_MB_2U(SCH_1):SMB_1_BMC_GPU_BUF_SCL
  R4 SMB_1_BMC_GPU_BUF_SDA     R4 @S9S_MB_2U_LIB.S9S_MB_2U(SCH_1):SMB_1_BMC_GPU_BUF_SDA
  S4    GND     S4 @S9S_MB_2U_LIB.S9S_MB_2U(SCH_1):GND
  T4 GPU_NVS_PWR_BRAKE_N_BUF     T4 @S9S_MB_2U_LIB.S9S_MB_2U(SCH_1):GPU_NVS_PWR_BRAKE_N_BUF


DRAWING: @S9S_MB_2U_LIB.S9S_MB_2U(SCH_1):PAGE142 

CONN112_10137002101LF-CONN112_A  I65  J105
  A4    GND     A4 @S9S_MB_2U_LIB.S9S_MB_2U(SCH_1):GND
  A3 GPU_WP_HW_CTRL_ISO     A3 @S9S_MB_2U_LIB.S9S_MB_2U(SCH_1):GPU_WP_HW_CTRL_ISO
  A2    GND     A2 @S9S_MB_2U_LIB.S9S_MB_2U(SCH_1):GND
  A1 GPU_3V3IO_RSVD4     A1 @S9S_MB_2U_LIB.S9S_MB_2U(SCH_1):GPU_3V3IO_RSVD4
  B4 P5E_CPU0_PE3_RX_DP<4>     B4 @S9S_MB_2U_LIB.S9S_MB_2U(SCH_1):P5E_CPU0_PE3_RX_DP(4)
  B3    GND     B3 @S9S_MB_2U_LIB.S9S_MB_2U(SCH_1):GND
  B2 P5E_CPU0_PE3_RX_DP<6>     B2 @S9S_MB_2U_LIB.S9S_MB_2U(SCH_1):P5E_CPU0_PE3_RX_DP(6)
  B1    GND     B1 @S9S_MB_2U_LIB.S9S_MB_2U(SCH_1):GND
  C4 P5E_CPU0_PE3_RX_DN<4>     C4 @S9S_MB_2U_LIB.S9S_MB_2U(SCH_1):P5E_CPU0_PE3_RX_DN(4)
  C3 P5E_CPU0_PE3_RX_DP<5>     C3 @S9S_MB_2U_LIB.S9S_MB_2U(SCH_1):P5E_CPU0_PE3_RX_DP(5)
  C2 P5E_CPU0_PE3_RX_DN<6>     C2 @S9S_MB_2U_LIB.S9S_MB_2U(SCH_1):P5E_CPU0_PE3_RX_DN(6)
  C1 P5E_CPU0_PE3_RX_DP<7>     C1 @S9S_MB_2U_LIB.S9S_MB_2U(SCH_1):P5E_CPU0_PE3_RX_DP(7)
  D4    GND     D4 @S9S_MB_2U_LIB.S9S_MB_2U(SCH_1):GND
  D3 P5E_CPU0_PE3_RX_DN<5>     D3 @S9S_MB_2U_LIB.S9S_MB_2U(SCH_1):P5E_CPU0_PE3_RX_DN(5)
  D2    GND     D2 @S9S_MB_2U_LIB.S9S_MB_2U(SCH_1):GND
  D1 P5E_CPU0_PE3_RX_DN<7>     D1 @S9S_MB_2U_LIB.S9S_MB_2U(SCH_1):P5E_CPU0_PE3_RX_DN(7)
  E4 P5E_CPU0_PE2_RX_DP<4>     E4 @S9S_MB_2U_LIB.S9S_MB_2U(SCH_1):P5E_CPU0_PE2_RX_DP(4)
  E3    GND     E3 @S9S_MB_2U_LIB.S9S_MB_2U(SCH_1):GND
  E2 P5E_CPU0_PE2_RX_DP<6>     E2 @S9S_MB_2U_LIB.S9S_MB_2U(SCH_1):P5E_CPU0_PE2_RX_DP(6)
  E1    GND     E1 @S9S_MB_2U_LIB.S9S_MB_2U(SCH_1):GND
  F4 P5E_CPU0_PE2_RX_DN<4>     F4 @S9S_MB_2U_LIB.S9S_MB_2U(SCH_1):P5E_CPU0_PE2_RX_DN(4)
  F3 P5E_CPU0_PE2_RX_DP<5>     F3 @S9S_MB_2U_LIB.S9S_MB_2U(SCH_1):P5E_CPU0_PE2_RX_DP(5)
  F2 P5E_CPU0_PE2_RX_DN<6>     F2 @S9S_MB_2U_LIB.S9S_MB_2U(SCH_1):P5E_CPU0_PE2_RX_DN(6)
  F1 P5E_CPU0_PE2_RX_DP<7>     F1 @S9S_MB_2U_LIB.S9S_MB_2U(SCH_1):P5E_CPU0_PE2_RX_DP(7)
  G4    GND     G4 @S9S_MB_2U_LIB.S9S_MB_2U(SCH_1):GND
  G3 P5E_CPU0_PE2_RX_DN<5>     G3 @S9S_MB_2U_LIB.S9S_MB_2U(SCH_1):P5E_CPU0_PE2_RX_DN(5)
  G2    GND     G2 @S9S_MB_2U_LIB.S9S_MB_2U(SCH_1):GND
  G1 P5E_CPU0_PE2_RX_DN<7>     G1 @S9S_MB_2U_LIB.S9S_MB_2U(SCH_1):P5E_CPU0_PE2_RX_DN(7)
  H4 P5E_CPU0_PE3_TX_C_DN<4>     H4 @S9S_MB_2U_LIB.S9S_MB_2U(SCH_1):P5E_CPU0_PE3_TX_C_DN(4)
  H3    GND     H3 @S9S_MB_2U_LIB.S9S_MB_2U(SCH_1):GND
  H2 P5E_CPU0_PE3_TX_C_DN<6>     H2 @S9S_MB_2U_LIB.S9S_MB_2U(SCH_1):P5E_CPU0_PE3_TX_C_DN(6)
  H1    GND     H1 @S9S_MB_2U_LIB.S9S_MB_2U(SCH_1):GND
  I4 P5E_CPU0_PE3_TX_C_DP<4>     I4 @S9S_MB_2U_LIB.S9S_MB_2U(SCH_1):P5E_CPU0_PE3_TX_C_DP(4)
  I3 P5E_CPU0_PE3_TX_C_DN<5>     I3 @S9S_MB_2U_LIB.S9S_MB_2U(SCH_1):P5E_CPU0_PE3_TX_C_DN(5)
  I2 P5E_CPU0_PE3_TX_C_DP<6>     I2 @S9S_MB_2U_LIB.S9S_MB_2U(SCH_1):P5E_CPU0_PE3_TX_C_DP(6)
  I1 P5E_CPU0_PE3_TX_C_DN<7>     I1 @S9S_MB_2U_LIB.S9S_MB_2U(SCH_1):P5E_CPU0_PE3_TX_C_DN(7)
  J4    GND     J4 @S9S_MB_2U_LIB.S9S_MB_2U(SCH_1):GND
  J3 P5E_CPU0_PE3_TX_C_DP<5>     J3 @S9S_MB_2U_LIB.S9S_MB_2U(SCH_1):P5E_CPU0_PE3_TX_C_DP(5)
  J2    GND     J2 @S9S_MB_2U_LIB.S9S_MB_2U(SCH_1):GND
  J1 P5E_CPU0_PE3_TX_C_DP<7>     J1 @S9S_MB_2U_LIB.S9S_MB_2U(SCH_1):P5E_CPU0_PE3_TX_C_DP(7)
  K4 P5E_CPU0_PE2_TX_C_DP<4>     K4 @S9S_MB_2U_LIB.S9S_MB_2U(SCH_1):P5E_CPU0_PE2_TX_C_DP(4)
  K3    GND     K3 @S9S_MB_2U_LIB.S9S_MB_2U(SCH_1):GND
  K2 P5E_CPU0_PE2_TX_C_DP<6>     K2 @S9S_MB_2U_LIB.S9S_MB_2U(SCH_1):P5E_CPU0_PE2_TX_C_DP(6)
  K1    GND     K1 @S9S_MB_2U_LIB.S9S_MB_2U(SCH_1):GND
  L4 P5E_CPU0_PE2_TX_C_DN<4>     L4 @S9S_MB_2U_LIB.S9S_MB_2U(SCH_1):P5E_CPU0_PE2_TX_C_DN(4)
  L3 P5E_CPU0_PE2_TX_C_DP<5>     L3 @S9S_MB_2U_LIB.S9S_MB_2U(SCH_1):P5E_CPU0_PE2_TX_C_DP(5)
  L2 P5E_CPU0_PE2_TX_C_DN<6>     L2 @S9S_MB_2U_LIB.S9S_MB_2U(SCH_1):P5E_CPU0_PE2_TX_C_DN(6)
  L1 P5E_CPU0_PE2_TX_C_DP<7>     L1 @S9S_MB_2U_LIB.S9S_MB_2U(SCH_1):P5E_CPU0_PE2_TX_C_DP(7)
  M1 P5E_CPU0_PE2_TX_C_DN<7>     M1 @S9S_MB_2U_LIB.S9S_MB_2U(SCH_1):P5E_CPU0_PE2_TX_C_DN(7)
  N1    GND     N1 @S9S_MB_2U_LIB.S9S_MB_2U(SCH_1):GND
  M2    GND     M2 @S9S_MB_2U_LIB.S9S_MB_2U(SCH_1):GND
  N2 FM_SWB_PWR_EN_R_BUF     N2 @S9S_MB_2U_LIB.S9S_MB_2U(SCH_1):FM_SWB_PWR_EN_R_BUF
  M3 P5E_CPU0_PE2_TX_C_DN<5>     M3 @S9S_MB_2U_LIB.S9S_MB_2U(SCH_1):P5E_CPU0_PE2_TX_C_DN(5)
  N3    GND     N3 @S9S_MB_2U_LIB.S9S_MB_2U(SCH_1):GND
  M4    GND     M4 @S9S_MB_2U_LIB.S9S_MB_2U(SCH_1):GND
  N4 FM_SWB_BIC_READY_N     N4 @S9S_MB_2U_LIB.S9S_MB_2U(SCH_1):FM_SWB_BIC_READY_N

CONN112_10137002101LF-CONN112_A  I68  J105
  A8    GND     A8 @S9S_MB_2U_LIB.S9S_MB_2U(SCH_1):GND
  A7 GPU_3V3IO_RSVD1     A7 @S9S_MB_2U_LIB.S9S_MB_2U(SCH_1):GPU_3V3IO_RSVD1
  A6    GND     A6 @S9S_MB_2U_LIB.S9S_MB_2U(SCH_1):GND
  A5 GPU_3V3IO_RSVD3     A5 @S9S_MB_2U_LIB.S9S_MB_2U(SCH_1):GPU_3V3IO_RSVD3
  B8 P5E_CPU0_PE3_RX_DP<0>     B8 @S9S_MB_2U_LIB.S9S_MB_2U(SCH_1):P5E_CPU0_PE3_RX_DP(0)
  B7    GND     B7 @S9S_MB_2U_LIB.S9S_MB_2U(SCH_1):GND
  B6 P5E_CPU0_PE3_RX_DN<2>     B6 @S9S_MB_2U_LIB.S9S_MB_2U(SCH_1):P5E_CPU0_PE3_RX_DN(2)
  B5    GND     B5 @S9S_MB_2U_LIB.S9S_MB_2U(SCH_1):GND
  C8 P5E_CPU0_PE3_RX_DN<0>     C8 @S9S_MB_2U_LIB.S9S_MB_2U(SCH_1):P5E_CPU0_PE3_RX_DN(0)
  C7 P5E_CPU0_PE3_RX_DN<1>     C7 @S9S_MB_2U_LIB.S9S_MB_2U(SCH_1):P5E_CPU0_PE3_RX_DN(1)
  C6 P5E_CPU0_PE3_RX_DP<2>     C6 @S9S_MB_2U_LIB.S9S_MB_2U(SCH_1):P5E_CPU0_PE3_RX_DP(2)
  C5 P5E_CPU0_PE3_RX_DN<3>     C5 @S9S_MB_2U_LIB.S9S_MB_2U(SCH_1):P5E_CPU0_PE3_RX_DN(3)
  D8    GND     D8 @S9S_MB_2U_LIB.S9S_MB_2U(SCH_1):GND
  D7 P5E_CPU0_PE3_RX_DP<1>     D7 @S9S_MB_2U_LIB.S9S_MB_2U(SCH_1):P5E_CPU0_PE3_RX_DP(1)
  D6    GND     D6 @S9S_MB_2U_LIB.S9S_MB_2U(SCH_1):GND
  D5 P5E_CPU0_PE3_RX_DP<3>     D5 @S9S_MB_2U_LIB.S9S_MB_2U(SCH_1):P5E_CPU0_PE3_RX_DP(3)
  E8 P5E_CPU0_PE2_RX_DP<0>     E8 @S9S_MB_2U_LIB.S9S_MB_2U(SCH_1):P5E_CPU0_PE2_RX_DP(0)
  E7    GND     E7 @S9S_MB_2U_LIB.S9S_MB_2U(SCH_1):GND
  E6 P5E_CPU0_PE2_RX_DP<2>     E6 @S9S_MB_2U_LIB.S9S_MB_2U(SCH_1):P5E_CPU0_PE2_RX_DP(2)
  E5    GND     E5 @S9S_MB_2U_LIB.S9S_MB_2U(SCH_1):GND
  F8 P5E_CPU0_PE2_RX_DN<0>     F8 @S9S_MB_2U_LIB.S9S_MB_2U(SCH_1):P5E_CPU0_PE2_RX_DN(0)
  F7 P5E_CPU0_PE2_RX_DP<1>     F7 @S9S_MB_2U_LIB.S9S_MB_2U(SCH_1):P5E_CPU0_PE2_RX_DP(1)
  F6 P5E_CPU0_PE2_RX_DN<2>     F6 @S9S_MB_2U_LIB.S9S_MB_2U(SCH_1):P5E_CPU0_PE2_RX_DN(2)
  F5 P5E_CPU0_PE2_RX_DP<3>     F5 @S9S_MB_2U_LIB.S9S_MB_2U(SCH_1):P5E_CPU0_PE2_RX_DP(3)
  G8    GND     G8 @S9S_MB_2U_LIB.S9S_MB_2U(SCH_1):GND
  G7 P5E_CPU0_PE2_RX_DN<1>     G7 @S9S_MB_2U_LIB.S9S_MB_2U(SCH_1):P5E_CPU0_PE2_RX_DN(1)
  G6    GND     G6 @S9S_MB_2U_LIB.S9S_MB_2U(SCH_1):GND
  G5 P5E_CPU0_PE2_RX_DN<3>     G5 @S9S_MB_2U_LIB.S9S_MB_2U(SCH_1):P5E_CPU0_PE2_RX_DN(3)
  H8 P5E_CPU0_PE3_TX_C_DP<0>     H8 @S9S_MB_2U_LIB.S9S_MB_2U(SCH_1):P5E_CPU0_PE3_TX_C_DP(0)
  H7    GND     H7 @S9S_MB_2U_LIB.S9S_MB_2U(SCH_1):GND
  H6 P5E_CPU0_PE3_TX_C_DN<2>     H6 @S9S_MB_2U_LIB.S9S_MB_2U(SCH_1):P5E_CPU0_PE3_TX_C_DN(2)
  H5    GND     H5 @S9S_MB_2U_LIB.S9S_MB_2U(SCH_1):GND
  I8 P5E_CPU0_PE3_TX_C_DN<0>     I8 @S9S_MB_2U_LIB.S9S_MB_2U(SCH_1):P5E_CPU0_PE3_TX_C_DN(0)
  I7 P5E_CPU0_PE3_TX_C_DN<1>     I7 @S9S_MB_2U_LIB.S9S_MB_2U(SCH_1):P5E_CPU0_PE3_TX_C_DN(1)
  I6 P5E_CPU0_PE3_TX_C_DP<2>     I6 @S9S_MB_2U_LIB.S9S_MB_2U(SCH_1):P5E_CPU0_PE3_TX_C_DP(2)
  I5 P5E_CPU0_PE3_TX_C_DN<3>     I5 @S9S_MB_2U_LIB.S9S_MB_2U(SCH_1):P5E_CPU0_PE3_TX_C_DN(3)
  J8    GND     J8 @S9S_MB_2U_LIB.S9S_MB_2U(SCH_1):GND
  J7 P5E_CPU0_PE3_TX_C_DP<1>     J7 @S9S_MB_2U_LIB.S9S_MB_2U(SCH_1):P5E_CPU0_PE3_TX_C_DP(1)
  J6    GND     J6 @S9S_MB_2U_LIB.S9S_MB_2U(SCH_1):GND
  J5 P5E_CPU0_PE3_TX_C_DP<3>     J5 @S9S_MB_2U_LIB.S9S_MB_2U(SCH_1):P5E_CPU0_PE3_TX_C_DP(3)
  K8 P5E_CPU0_PE2_TX_C_DP<0>     K8 @S9S_MB_2U_LIB.S9S_MB_2U(SCH_1):P5E_CPU0_PE2_TX_C_DP(0)
  K7    GND     K7 @S9S_MB_2U_LIB.S9S_MB_2U(SCH_1):GND
  K6 P5E_CPU0_PE2_TX_C_DP<2>     K6 @S9S_MB_2U_LIB.S9S_MB_2U(SCH_1):P5E_CPU0_PE2_TX_C_DP(2)
  K5    GND     K5 @S9S_MB_2U_LIB.S9S_MB_2U(SCH_1):GND
  L8 P5E_CPU0_PE2_TX_C_DN<0>     L8 @S9S_MB_2U_LIB.S9S_MB_2U(SCH_1):P5E_CPU0_PE2_TX_C_DN(0)
  L7 P5E_CPU0_PE2_TX_C_DP<1>     L7 @S9S_MB_2U_LIB.S9S_MB_2U(SCH_1):P5E_CPU0_PE2_TX_C_DP(1)
  L6 P5E_CPU0_PE2_TX_C_DN<2>     L6 @S9S_MB_2U_LIB.S9S_MB_2U(SCH_1):P5E_CPU0_PE2_TX_C_DN(2)
  L5 P5E_CPU0_PE2_TX_C_DP<3>     L5 @S9S_MB_2U_LIB.S9S_MB_2U(SCH_1):P5E_CPU0_PE2_TX_C_DP(3)
  M5 P5E_CPU0_PE2_TX_C_DN<3>     M5 @S9S_MB_2U_LIB.S9S_MB_2U(SCH_1):P5E_CPU0_PE2_TX_C_DN(3)
  N5    GND     N5 @S9S_MB_2U_LIB.S9S_MB_2U(SCH_1):GND
  M6    GND     M6 @S9S_MB_2U_LIB.S9S_MB_2U(SCH_1):GND
  N6 RST_SWB_BIC_BUF_N     N6 @S9S_MB_2U_LIB.S9S_MB_2U(SCH_1):RST_SWB_BIC_BUF_N
  M7 P5E_CPU0_PE2_TX_C_DN<1>     M7 @S9S_MB_2U_LIB.S9S_MB_2U(SCH_1):P5E_CPU0_PE2_TX_C_DN(1)
  N7    GND     N7 @S9S_MB_2U_LIB.S9S_MB_2U(SCH_1):GND
  M8    GND     M8 @S9S_MB_2U_LIB.S9S_MB_2U(SCH_1):GND
  N8 RST_BMC_FROM_SWB_N     N8 @S9S_MB_2U_LIB.S9S_MB_2U(SCH_1):RST_BMC_FROM_SWB_N


DRAWING: @S9S_MB_2U_LIB.S9S_MB_2U(SCH_1):PAGE144 

CONN112_10137002101LF-CONN112_A  I65  J106
  A4    GND     A4 @S9S_MB_2U_LIB.S9S_MB_2U(SCH_1):GND
  A3 FM_SWB_PWRGD     A3 @S9S_MB_2U_LIB.S9S_MB_2U(SCH_1):FM_SWB_PWRGD
  A2    GND     A2 @S9S_MB_2U_LIB.S9S_MB_2U(SCH_1):GND
  A1 PRSNT_CABLE_SWB_B1_N     A1 @S9S_MB_2U_LIB.S9S_MB_2U(SCH_1):PRSNT_CABLE_SWB_B1_N
  B4 P5E_CPU0_PE3_RX_DP<12>     B4 @S9S_MB_2U_LIB.S9S_MB_2U(SCH_1):P5E_CPU0_PE3_RX_DP(12)
  B3    GND     B3 @S9S_MB_2U_LIB.S9S_MB_2U(SCH_1):GND
  B2 P5E_CPU0_PE3_RX_DP<14>     B2 @S9S_MB_2U_LIB.S9S_MB_2U(SCH_1):P5E_CPU0_PE3_RX_DP(14)
  B1    GND     B1 @S9S_MB_2U_LIB.S9S_MB_2U(SCH_1):GND
  C4 P5E_CPU0_PE3_RX_DN<12>     C4 @S9S_MB_2U_LIB.S9S_MB_2U(SCH_1):P5E_CPU0_PE3_RX_DN(12)
  C3 P5E_CPU0_PE3_RX_DP<13>     C3 @S9S_MB_2U_LIB.S9S_MB_2U(SCH_1):P5E_CPU0_PE3_RX_DP(13)
  C2 P5E_CPU0_PE3_RX_DN<14>     C2 @S9S_MB_2U_LIB.S9S_MB_2U(SCH_1):P5E_CPU0_PE3_RX_DN(14)
  C1 P5E_CPU0_PE3_RX_DP<15>     C1 @S9S_MB_2U_LIB.S9S_MB_2U(SCH_1):P5E_CPU0_PE3_RX_DP(15)
  D4    GND     D4 @S9S_MB_2U_LIB.S9S_MB_2U(SCH_1):GND
  D3 P5E_CPU0_PE3_RX_DN<13>     D3 @S9S_MB_2U_LIB.S9S_MB_2U(SCH_1):P5E_CPU0_PE3_RX_DN(13)
  D2    GND     D2 @S9S_MB_2U_LIB.S9S_MB_2U(SCH_1):GND
  D1 P5E_CPU0_PE3_RX_DN<15>     D1 @S9S_MB_2U_LIB.S9S_MB_2U(SCH_1):P5E_CPU0_PE3_RX_DN(15)
  E4 P5E_CPU0_PE2_RX_DP<12>     E4 @S9S_MB_2U_LIB.S9S_MB_2U(SCH_1):P5E_CPU0_PE2_RX_DP(12)
  E3    GND     E3 @S9S_MB_2U_LIB.S9S_MB_2U(SCH_1):GND
  E2 P5E_CPU0_PE2_RX_DP<14>     E2 @S9S_MB_2U_LIB.S9S_MB_2U(SCH_1):P5E_CPU0_PE2_RX_DP(14)
  E1    GND     E1 @S9S_MB_2U_LIB.S9S_MB_2U(SCH_1):GND
  F4 P5E_CPU0_PE2_RX_DN<12>     F4 @S9S_MB_2U_LIB.S9S_MB_2U(SCH_1):P5E_CPU0_PE2_RX_DN(12)
  F3 P5E_CPU0_PE2_RX_DP<13>     F3 @S9S_MB_2U_LIB.S9S_MB_2U(SCH_1):P5E_CPU0_PE2_RX_DP(13)
  F2 P5E_CPU0_PE2_RX_DN<14>     F2 @S9S_MB_2U_LIB.S9S_MB_2U(SCH_1):P5E_CPU0_PE2_RX_DN(14)
  F1 P5E_CPU0_PE2_RX_DP<15>     F1 @S9S_MB_2U_LIB.S9S_MB_2U(SCH_1):P5E_CPU0_PE2_RX_DP(15)
  G4    GND     G4 @S9S_MB_2U_LIB.S9S_MB_2U(SCH_1):GND
  G3 P5E_CPU0_PE2_RX_DN<13>     G3 @S9S_MB_2U_LIB.S9S_MB_2U(SCH_1):P5E_CPU0_PE2_RX_DN(13)
  G2    GND     G2 @S9S_MB_2U_LIB.S9S_MB_2U(SCH_1):GND
  G1 P5E_CPU0_PE2_RX_DN<15>     G1 @S9S_MB_2U_LIB.S9S_MB_2U(SCH_1):P5E_CPU0_PE2_RX_DN(15)
  H4 P5E_CPU0_PE3_TX_C_DN<12>     H4 @S9S_MB_2U_LIB.S9S_MB_2U(SCH_1):P5E_CPU0_PE3_TX_C_DN(12)
  H3    GND     H3 @S9S_MB_2U_LIB.S9S_MB_2U(SCH_1):GND
  H2 P5E_CPU0_PE3_TX_C_DN<14>     H2 @S9S_MB_2U_LIB.S9S_MB_2U(SCH_1):P5E_CPU0_PE3_TX_C_DN(14)
  H1    GND     H1 @S9S_MB_2U_LIB.S9S_MB_2U(SCH_1):GND
  I4 P5E_CPU0_PE3_TX_C_DP<12>     I4 @S9S_MB_2U_LIB.S9S_MB_2U(SCH_1):P5E_CPU0_PE3_TX_C_DP(12)
  I3 P5E_CPU0_PE3_TX_C_DN<13>     I3 @S9S_MB_2U_LIB.S9S_MB_2U(SCH_1):P5E_CPU0_PE3_TX_C_DN(13)
  I2 P5E_CPU0_PE3_TX_C_DP<14>     I2 @S9S_MB_2U_LIB.S9S_MB_2U(SCH_1):P5E_CPU0_PE3_TX_C_DP(14)
  I1 P5E_CPU0_PE3_TX_C_DN<15>     I1 @S9S_MB_2U_LIB.S9S_MB_2U(SCH_1):P5E_CPU0_PE3_TX_C_DN(15)
  J4    GND     J4 @S9S_MB_2U_LIB.S9S_MB_2U(SCH_1):GND
  J3 P5E_CPU0_PE3_TX_C_DP<13>     J3 @S9S_MB_2U_LIB.S9S_MB_2U(SCH_1):P5E_CPU0_PE3_TX_C_DP(13)
  J2    GND     J2 @S9S_MB_2U_LIB.S9S_MB_2U(SCH_1):GND
  J1 P5E_CPU0_PE3_TX_C_DP<15>     J1 @S9S_MB_2U_LIB.S9S_MB_2U(SCH_1):P5E_CPU0_PE3_TX_C_DP(15)
  K4 P5E_CPU0_PE2_TX_C_DP<12>     K4 @S9S_MB_2U_LIB.S9S_MB_2U(SCH_1):P5E_CPU0_PE2_TX_C_DP(12)
  K3    GND     K3 @S9S_MB_2U_LIB.S9S_MB_2U(SCH_1):GND
  K2 P5E_CPU0_PE2_TX_C_DP<14>     K2 @S9S_MB_2U_LIB.S9S_MB_2U(SCH_1):P5E_CPU0_PE2_TX_C_DP(14)
  K1    GND     K1 @S9S_MB_2U_LIB.S9S_MB_2U(SCH_1):GND
  L4 P5E_CPU0_PE2_TX_C_DN<12>     L4 @S9S_MB_2U_LIB.S9S_MB_2U(SCH_1):P5E_CPU0_PE2_TX_C_DN(12)
  L3 P5E_CPU0_PE2_TX_C_DP<13>     L3 @S9S_MB_2U_LIB.S9S_MB_2U(SCH_1):P5E_CPU0_PE2_TX_C_DP(13)
  L2 P5E_CPU0_PE2_TX_C_DN<14>     L2 @S9S_MB_2U_LIB.S9S_MB_2U(SCH_1):P5E_CPU0_PE2_TX_C_DN(14)
  L1 P5E_CPU0_PE2_TX_C_DN<15>     L1 @S9S_MB_2U_LIB.S9S_MB_2U(SCH_1):P5E_CPU0_PE2_TX_C_DN(15)
  M1 P5E_CPU0_PE2_TX_C_DP<15>     M1 @S9S_MB_2U_LIB.S9S_MB_2U(SCH_1):P5E_CPU0_PE2_TX_C_DP(15)
  N1    GND     N1 @S9S_MB_2U_LIB.S9S_MB_2U(SCH_1):GND
  M2    GND     M2 @S9S_MB_2U_LIB.S9S_MB_2U(SCH_1):GND
  N2 I3C_BMC_SWB_BUF_SDA     N2 @S9S_MB_2U_LIB.S9S_MB_2U(SCH_1):I3C_BMC_SWB_BUF_SDA
  M3 P5E_CPU0_PE2_TX_C_DN<13>     M3 @S9S_MB_2U_LIB.S9S_MB_2U(SCH_1):P5E_CPU0_PE2_TX_C_DN(13)
  N3    GND     N3 @S9S_MB_2U_LIB.S9S_MB_2U(SCH_1):GND
  M4    GND     M4 @S9S_MB_2U_LIB.S9S_MB_2U(SCH_1):GND
  N4 I3C_BMC_SWB_BUF_SCL     N4 @S9S_MB_2U_LIB.S9S_MB_2U(SCH_1):I3C_BMC_SWB_BUF_SCL

CONN112_10137002101LF-CONN112_A  I68  J106
  A8    GND     A8 @S9S_MB_2U_LIB.S9S_MB_2U(SCH_1):GND
  A7 PRSNT_CABLE_GPU_A1_N     A7 @S9S_MB_2U_LIB.S9S_MB_2U(SCH_1):PRSNT_CABLE_GPU_A1_N
  A6    GND     A6 @S9S_MB_2U_LIB.S9S_MB_2U(SCH_1):GND
  A5 NC_J106_A5     A5 @S9S_MB_2U_LIB.S9S_MB_2U(SCH_1):NC_J106_A5
  B8 P5E_CPU0_PE3_RX_DN<8>     B8 @S9S_MB_2U_LIB.S9S_MB_2U(SCH_1):P5E_CPU0_PE3_RX_DN(8)
  B7    GND     B7 @S9S_MB_2U_LIB.S9S_MB_2U(SCH_1):GND
  B6 P5E_CPU0_PE3_RX_DN<10>     B6 @S9S_MB_2U_LIB.S9S_MB_2U(SCH_1):P5E_CPU0_PE3_RX_DN(10)
  B5    GND     B5 @S9S_MB_2U_LIB.S9S_MB_2U(SCH_1):GND
  C8 P5E_CPU0_PE3_RX_DP<8>     C8 @S9S_MB_2U_LIB.S9S_MB_2U(SCH_1):P5E_CPU0_PE3_RX_DP(8)
  C7 P5E_CPU0_PE3_RX_DN<9>     C7 @S9S_MB_2U_LIB.S9S_MB_2U(SCH_1):P5E_CPU0_PE3_RX_DN(9)
  C6 P5E_CPU0_PE3_RX_DP<10>     C6 @S9S_MB_2U_LIB.S9S_MB_2U(SCH_1):P5E_CPU0_PE3_RX_DP(10)
  C5 P5E_CPU0_PE3_RX_DN<11>     C5 @S9S_MB_2U_LIB.S9S_MB_2U(SCH_1):P5E_CPU0_PE3_RX_DN(11)
  D8    GND     D8 @S9S_MB_2U_LIB.S9S_MB_2U(SCH_1):GND
  D7 P5E_CPU0_PE3_RX_DP<9>     D7 @S9S_MB_2U_LIB.S9S_MB_2U(SCH_1):P5E_CPU0_PE3_RX_DP(9)
  D6    GND     D6 @S9S_MB_2U_LIB.S9S_MB_2U(SCH_1):GND
  D5 P5E_CPU0_PE3_RX_DP<11>     D5 @S9S_MB_2U_LIB.S9S_MB_2U(SCH_1):P5E_CPU0_PE3_RX_DP(11)
  E8 P5E_CPU0_PE2_RX_DP<8>     E8 @S9S_MB_2U_LIB.S9S_MB_2U(SCH_1):P5E_CPU0_PE2_RX_DP(8)
  E7    GND     E7 @S9S_MB_2U_LIB.S9S_MB_2U(SCH_1):GND
  E6 P5E_CPU0_PE2_RX_DP<10>     E6 @S9S_MB_2U_LIB.S9S_MB_2U(SCH_1):P5E_CPU0_PE2_RX_DP(10)
  E5    GND     E5 @S9S_MB_2U_LIB.S9S_MB_2U(SCH_1):GND
  F8 P5E_CPU0_PE2_RX_DN<8>     F8 @S9S_MB_2U_LIB.S9S_MB_2U(SCH_1):P5E_CPU0_PE2_RX_DN(8)
  F7 P5E_CPU0_PE2_RX_DP<9>     F7 @S9S_MB_2U_LIB.S9S_MB_2U(SCH_1):P5E_CPU0_PE2_RX_DP(9)
  F6 P5E_CPU0_PE2_RX_DN<10>     F6 @S9S_MB_2U_LIB.S9S_MB_2U(SCH_1):P5E_CPU0_PE2_RX_DN(10)
  F5 P5E_CPU0_PE2_RX_DP<11>     F5 @S9S_MB_2U_LIB.S9S_MB_2U(SCH_1):P5E_CPU0_PE2_RX_DP(11)
  G8    GND     G8 @S9S_MB_2U_LIB.S9S_MB_2U(SCH_1):GND
  G7 P5E_CPU0_PE2_RX_DN<9>     G7 @S9S_MB_2U_LIB.S9S_MB_2U(SCH_1):P5E_CPU0_PE2_RX_DN(9)
  G6    GND     G6 @S9S_MB_2U_LIB.S9S_MB_2U(SCH_1):GND
  G5 P5E_CPU0_PE2_RX_DN<11>     G5 @S9S_MB_2U_LIB.S9S_MB_2U(SCH_1):P5E_CPU0_PE2_RX_DN(11)
  H8 P5E_CPU0_PE3_TX_C_DN<8>     H8 @S9S_MB_2U_LIB.S9S_MB_2U(SCH_1):P5E_CPU0_PE3_TX_C_DN(8)
  H7    GND     H7 @S9S_MB_2U_LIB.S9S_MB_2U(SCH_1):GND
  H6 P5E_CPU0_PE3_TX_C_DN<10>     H6 @S9S_MB_2U_LIB.S9S_MB_2U(SCH_1):P5E_CPU0_PE3_TX_C_DN(10)
  H5    GND     H5 @S9S_MB_2U_LIB.S9S_MB_2U(SCH_1):GND
  I8 P5E_CPU0_PE3_TX_C_DP<8>     I8 @S9S_MB_2U_LIB.S9S_MB_2U(SCH_1):P5E_CPU0_PE3_TX_C_DP(8)
  I7 P5E_CPU0_PE3_TX_C_DN<9>     I7 @S9S_MB_2U_LIB.S9S_MB_2U(SCH_1):P5E_CPU0_PE3_TX_C_DN(9)
  I6 P5E_CPU0_PE3_TX_C_DP<10>     I6 @S9S_MB_2U_LIB.S9S_MB_2U(SCH_1):P5E_CPU0_PE3_TX_C_DP(10)
  I5 P5E_CPU0_PE3_TX_C_DN<11>     I5 @S9S_MB_2U_LIB.S9S_MB_2U(SCH_1):P5E_CPU0_PE3_TX_C_DN(11)
  J8    GND     J8 @S9S_MB_2U_LIB.S9S_MB_2U(SCH_1):GND
  J7 P5E_CPU0_PE3_TX_C_DP<9>     J7 @S9S_MB_2U_LIB.S9S_MB_2U(SCH_1):P5E_CPU0_PE3_TX_C_DP(9)
  J6    GND     J6 @S9S_MB_2U_LIB.S9S_MB_2U(SCH_1):GND
  J5 P5E_CPU0_PE3_TX_C_DP<11>     J5 @S9S_MB_2U_LIB.S9S_MB_2U(SCH_1):P5E_CPU0_PE3_TX_C_DP(11)
  K8 P5E_CPU0_PE2_TX_C_DP<8>     K8 @S9S_MB_2U_LIB.S9S_MB_2U(SCH_1):P5E_CPU0_PE2_TX_C_DP(8)
  K7    GND     K7 @S9S_MB_2U_LIB.S9S_MB_2U(SCH_1):GND
  K6 P5E_CPU0_PE2_TX_C_DP<10>     K6 @S9S_MB_2U_LIB.S9S_MB_2U(SCH_1):P5E_CPU0_PE2_TX_C_DP(10)
  K5    GND     K5 @S9S_MB_2U_LIB.S9S_MB_2U(SCH_1):GND
  L8 P5E_CPU0_PE2_TX_C_DN<8>     L8 @S9S_MB_2U_LIB.S9S_MB_2U(SCH_1):P5E_CPU0_PE2_TX_C_DN(8)
  L7 P5E_CPU0_PE2_TX_C_DP<9>     L7 @S9S_MB_2U_LIB.S9S_MB_2U(SCH_1):P5E_CPU0_PE2_TX_C_DP(9)
  L6 P5E_CPU0_PE2_TX_C_DN<10>     L6 @S9S_MB_2U_LIB.S9S_MB_2U(SCH_1):P5E_CPU0_PE2_TX_C_DN(10)
  L5 P5E_CPU0_PE2_TX_C_DP<11>     L5 @S9S_MB_2U_LIB.S9S_MB_2U(SCH_1):P5E_CPU0_PE2_TX_C_DP(11)
  M5 P5E_CPU0_PE2_TX_C_DN<11>     M5 @S9S_MB_2U_LIB.S9S_MB_2U(SCH_1):P5E_CPU0_PE2_TX_C_DN(11)
  N5    GND     N5 @S9S_MB_2U_LIB.S9S_MB_2U(SCH_1):GND
  M6    GND     M6 @S9S_MB_2U_LIB.S9S_MB_2U(SCH_1):GND
  N6 UART_BMC_BIC_RX     N6 @S9S_MB_2U_LIB.S9S_MB_2U(SCH_1):UART_BMC_BIC_RX
  M7 P5E_CPU0_PE2_TX_C_DN<9>     M7 @S9S_MB_2U_LIB.S9S_MB_2U(SCH_1):P5E_CPU0_PE2_TX_C_DN(9)
  N7    GND     N7 @S9S_MB_2U_LIB.S9S_MB_2U(SCH_1):GND
  M8    GND     M8 @S9S_MB_2U_LIB.S9S_MB_2U(SCH_1):GND
  N8 UART_BMC_BIC_TX     N8 @S9S_MB_2U_LIB.S9S_MB_2U(SCH_1):UART_BMC_BIC_TX


DRAWING: @S9S_MB_2U_LIB.S9S_MB_2U(SCH_1):PAGE222 

Q_RES_0402LF-0,5%,1/16W,EMPTY,A  I12  R2987
   1 SMB_2_BMC_GPU_R_SDA      A @S9S_MB_2U_LIB.S9S_MB_2U(SCH_1):SMB_2_BMC_GPU_R_SDA
   2 SMB_2_BMC_GPU_BUF_R_SDA      B @S9S_MB_2U_LIB.S9S_MB_2U(SCH_1):SMB_2_BMC_GPU_BUF_R_SDA

Q_RES_0402LF-10K,1%,1/16W,CHIPA  I16  R2666
   1 SMB_BMC_SWB_EN      A @S9S_MB_2U_LIB.S9S_MB_2U(SCH_1):SMB_BMC_SWB_EN
   2    GND      B @S9S_MB_2U_LIB.S9S_MB_2U(SCH_1):GND

Q_CAP_0402-0.1UF,25V,10%,EMPTYA  I34  C1708
   1 P3V3_AUX      A @S9S_MB_2U_LIB.S9S_MB_2U(SCH_1):P3V3_AUX
   2    GND      B @S9S_MB_2U_LIB.S9S_MB_2U(SCH_1):GND

Q_RES_0402LF-0,5%,1/16W,EMPTY,A  I38  R2893
   1 SMB_1_BMC_GPU_R_SCL      A @S9S_MB_2U_LIB.S9S_MB_2U(SCH_1):SMB_1_BMC_GPU_R_SCL
   2 SMB_1_BMC_GPU_BUF_R_SCL      B @S9S_MB_2U_LIB.S9S_MB_2U(SCH_1):SMB_1_BMC_GPU_BUF_R_SCL

Q_RES_0402LF-0,5%,1/16W,EMPTY,A  I54  R2724
   1 SMB_BMC_SWB_R_SDA      A @S9S_MB_2U_LIB.S9S_MB_2U(SCH_1):SMB_BMC_SWB_R_SDA
   2 SMB_BMC_SWB_BUF_R_SDA      B @S9S_MB_2U_LIB.S9S_MB_2U(SCH_1):SMB_BMC_SWB_BUF_R_SDA

Q_RES_0402LF-0,5%,1/16W,EMPTY,A  I55  R2705
   1 SMB_BMC_SWB_R_SCL      A @S9S_MB_2U_LIB.S9S_MB_2U(SCH_1):SMB_BMC_SWB_R_SCL
   2 SMB_BMC_SWB_BUF_R_SCL      B @S9S_MB_2U_LIB.S9S_MB_2U(SCH_1):SMB_BMC_SWB_BUF_R_SCL

Q_RES_0402LF-33.2,1%,1/16W,CHIA  I65  R2671
   1 SMB_BMC_SWB_BUF_R_SCL      A @S9S_MB_2U_LIB.S9S_MB_2U(SCH_1):SMB_BMC_SWB_BUF_R_SCL
   2 SMB_BMC_SWB_BUF_SCL      B @S9S_MB_2U_LIB.S9S_MB_2U(SCH_1):SMB_BMC_SWB_BUF_SCL

Q_CAP_0402-0.1UF,25V,10%,X7R,CA  I66  C1766
   1 P3V3_AUX      A @S9S_MB_2U_LIB.S9S_MB_2U(SCH_1):P3V3_AUX
   2    GND      B @S9S_MB_2U_LIB.S9S_MB_2U(SCH_1):GND

Q_RES_0402LF-33.2,1%,1/16W,CHIA  I72  R2675
   1 I3C_BMC_SWB_BUF_R_SCL      A @S9S_MB_2U_LIB.S9S_MB_2U(SCH_1):I3C_BMC_SWB_BUF_R_SCL
   2 I3C_BMC_SWB_BUF_SCL      B @S9S_MB_2U_LIB.S9S_MB_2U(SCH_1):I3C_BMC_SWB_BUF_SCL

Q_RES_0402LF-0,5%,1/16W,CHIP,CA  I7  R3108
   1 SMB_2_BMC_GPU_SDA      A @S9S_MB_2U_LIB.S9S_MB_2U(SCH_1):SMB_2_BMC_GPU_SDA
   2 SMB_2_BMC_GPU_R_SDA      B @S9S_MB_2U_LIB.S9S_MB_2U(SCH_1):SMB_2_BMC_GPU_R_SDA

Q_RES_0402LF-0,5%,1/16W,CHIP,CA  I8  R3107
   1 SMB_2_BMC_GPU_SCL      A @S9S_MB_2U_LIB.S9S_MB_2U(SCH_1):SMB_2_BMC_GPU_SCL
   2 SMB_2_BMC_GPU_R_SCL      B @S9S_MB_2U_LIB.S9S_MB_2U(SCH_1):SMB_2_BMC_GPU_R_SCL

Q_RES_0402LF-0,5%,1/16W,CHIP,CA  I9  R2992
   1 SMB_BMC_GPU_EN      A @S9S_MB_2U_LIB.S9S_MB_2U(SCH_1):SMB_BMC_GPU_EN
   2 SMB_BMC_GPU_EN_R3      B @S9S_MB_2U_LIB.S9S_MB_2U(SCH_1):SMB_BMC_GPU_EN_R3

LTC4307CMS8-LTC4307CMS8,SMLF,IA  I11  U200
   1 SMB_BMC_GPU_EN_R3 ENABLE @S9S_MB_2U_LIB.S9S_MB_2U(SCH_1):SMB_BMC_GPU_EN_R3
   3 SMB_2_BMC_GPU_R_SCL SCL_IN @S9S_MB_2U_LIB.S9S_MB_2U(SCH_1):SMB_2_BMC_GPU_R_SCL
   6 SMB_2_BMC_GPU_R_SDA SDA_IN @S9S_MB_2U_LIB.S9S_MB_2U(SCH_1):SMB_2_BMC_GPU_R_SDA
   2 SMB_2_BMC_GPU_BUF_R_SCL SCL_OUT @S9S_MB_2U_LIB.S9S_MB_2U(SCH_1):SMB_2_BMC_GPU_BUF_R_SCL
   7 SMB_2_BMC_GPU_BUF_R_SDA SDA_OUT @S9S_MB_2U_LIB.S9S_MB_2U(SCH_1):SMB_2_BMC_GPU_BUF_R_SDA
   5     NC  READY     NC
   4    GND    GND @S9S_MB_2U_LIB.S9S_MB_2U(SCH_1):GND
   8 P3V3_AUX    VCC @S9S_MB_2U_LIB.S9S_MB_2U(SCH_1):P3V3_AUX

Q_RES_0402LF-0,5%,1/16W,EMPTY,A  I13  R2986
   1 SMB_2_BMC_GPU_R_SCL      A @S9S_MB_2U_LIB.S9S_MB_2U(SCH_1):SMB_2_BMC_GPU_R_SCL
   2 SMB_2_BMC_GPU_BUF_R_SCL      B @S9S_MB_2U_LIB.S9S_MB_2U(SCH_1):SMB_2_BMC_GPU_BUF_R_SCL

Q_RES_0402LF-0,5%,1/16W,CHIP,CA  I17  R3111
   1 I3C_BMC_SWB_SDA      A @S9S_MB_2U_LIB.S9S_MB_2U(SCH_1):I3C_BMC_SWB_SDA
   2 I3C_BMC_SWB_R_SDA      B @S9S_MB_2U_LIB.S9S_MB_2U(SCH_1):I3C_BMC_SWB_R_SDA

Q_RES_0402LF-33.2,1%,1/16W,CHIA  I18  R3112
   1 I3C_BMC_SWB_SCL      A @S9S_MB_2U_LIB.S9S_MB_2U(SCH_1):I3C_BMC_SWB_SCL
   2 I3C_BMC_SWB_R_SCL      B @S9S_MB_2U_LIB.S9S_MB_2U(SCH_1):I3C_BMC_SWB_R_SCL

Q_RES_0402LF-0,5%,1/16W,CHIP,CA  I19  R2676
   1 SMB_BMC_SWB_EN      A @S9S_MB_2U_LIB.S9S_MB_2U(SCH_1):SMB_BMC_SWB_EN
   2 SMB_BMC_SWB_EN_R2      B @S9S_MB_2U_LIB.S9S_MB_2U(SCH_1):SMB_BMC_SWB_EN_R2

Q_CAP_0402-0.1UF,25V,10%,X7R,CA  I20  C1796
   1 P3V3_AUX      A @S9S_MB_2U_LIB.S9S_MB_2U(SCH_1):P3V3_AUX
   2    GND      B @S9S_MB_2U_LIB.S9S_MB_2U(SCH_1):GND

Q_RES_0402LF-54.9K,1%,1/16W,CHA  I23  R3521
   1 P3V3_AUX      A @S9S_MB_2U_LIB.S9S_MB_2U(SCH_1):P3V3_AUX
   2 SMB_2_BMC_GPU_BUF_R_SCL      B @S9S_MB_2U_LIB.S9S_MB_2U(SCH_1):SMB_2_BMC_GPU_BUF_R_SCL

Q_RES_0402LF-54.9K,1%,1/16W,CHA  I25  R3522
   1 P3V3_AUX      A @S9S_MB_2U_LIB.S9S_MB_2U(SCH_1):P3V3_AUX
   2 SMB_2_BMC_GPU_BUF_R_SDA      B @S9S_MB_2U_LIB.S9S_MB_2U(SCH_1):SMB_2_BMC_GPU_BUF_R_SDA

Q_RES_0402LF-33.2,1%,1/16W,CHIA  I26  R2990
   1 SMB_2_BMC_GPU_BUF_R_SCL      A @S9S_MB_2U_LIB.S9S_MB_2U(SCH_1):SMB_2_BMC_GPU_BUF_R_SCL
   2 SMB_2_BMC_GPU_BUF_SCL      B @S9S_MB_2U_LIB.S9S_MB_2U(SCH_1):SMB_2_BMC_GPU_BUF_SCL

Q_RES_0402LF-33.2,1%,1/16W,CHIA  I27  R2991
   1 SMB_2_BMC_GPU_BUF_R_SDA      A @S9S_MB_2U_LIB.S9S_MB_2U(SCH_1):SMB_2_BMC_GPU_BUF_R_SDA
   2 SMB_2_BMC_GPU_BUF_SDA      B @S9S_MB_2U_LIB.S9S_MB_2U(SCH_1):SMB_2_BMC_GPU_BUF_SDA

Q_RES_0402LF-0,5%,1/16W,CHIP,CA  I29  R2725
   1 I3C_BMC_SWB_R_SCL      A @S9S_MB_2U_LIB.S9S_MB_2U(SCH_1):I3C_BMC_SWB_R_SCL
   2 I3C_BMC_SWB_BUF_R_SCL      B @S9S_MB_2U_LIB.S9S_MB_2U(SCH_1):I3C_BMC_SWB_BUF_R_SCL

Q_RES_0402LF-0,5%,1/16W,CHIP,CA  I30  R2706
   1 I3C_BMC_SWB_R_SDA      A @S9S_MB_2U_LIB.S9S_MB_2U(SCH_1):I3C_BMC_SWB_R_SDA
   2 I3C_BMC_SWB_BUF_R_SDA      B @S9S_MB_2U_LIB.S9S_MB_2U(SCH_1):I3C_BMC_SWB_BUF_R_SDA

LTC4307CMS8-LTC4307CMS8,SMLF,EA  I31  U176
   1 SMB_BMC_SWB_EN_R2 ENABLE @S9S_MB_2U_LIB.S9S_MB_2U(SCH_1):SMB_BMC_SWB_EN_R2
   3 I3C_BMC_SWB_R_SCL SCL_IN @S9S_MB_2U_LIB.S9S_MB_2U(SCH_1):I3C_BMC_SWB_R_SCL
   6 I3C_BMC_SWB_R_SDA SDA_IN @S9S_MB_2U_LIB.S9S_MB_2U(SCH_1):I3C_BMC_SWB_R_SDA
   2 I3C_BMC_SWB_BUF_R_SCL SCL_OUT @S9S_MB_2U_LIB.S9S_MB_2U(SCH_1):I3C_BMC_SWB_BUF_R_SCL
   7 I3C_BMC_SWB_BUF_R_SDA SDA_OUT @S9S_MB_2U_LIB.S9S_MB_2U(SCH_1):I3C_BMC_SWB_BUF_R_SDA
   5     NC  READY     NC
   4    GND    GND @S9S_MB_2U_LIB.S9S_MB_2U(SCH_1):GND
   8 P3V3_AUX    VCC @S9S_MB_2U_LIB.S9S_MB_2U(SCH_1):P3V3_AUX

Q_RES_0402LF-0,5%,1/16W,EMPTY,A  I33  R2894
   1 SMB_1_BMC_GPU_R_SDA      A @S9S_MB_2U_LIB.S9S_MB_2U(SCH_1):SMB_1_BMC_GPU_R_SDA
   2 SMB_1_BMC_GPU_BUF_R_SDA      B @S9S_MB_2U_LIB.S9S_MB_2U(SCH_1):SMB_1_BMC_GPU_BUF_R_SDA

Q_RES_0402LF-0,5%,1/16W,CHIP,CA  I42  R3106
   1 SMB_BMC_SWB_SDA      A @S9S_MB_2U_LIB.S9S_MB_2U(SCH_1):SMB_BMC_SWB_SDA
   2 SMB_BMC_SWB_R_SDA      B @S9S_MB_2U_LIB.S9S_MB_2U(SCH_1):SMB_BMC_SWB_R_SDA

Q_RES_0402LF-0,5%,1/16W,CHIP,CA  I43  R3105
   1 SMB_BMC_SWB_SCL      A @S9S_MB_2U_LIB.S9S_MB_2U(SCH_1):SMB_BMC_SWB_SCL
   2 SMB_BMC_SWB_R_SCL      B @S9S_MB_2U_LIB.S9S_MB_2U(SCH_1):SMB_BMC_SWB_R_SCL

Q_RES_0402LF-0,5%,1/16W,CHIP,CA  I44  R2707
   1 SMB_BMC_SWB_EN      A @S9S_MB_2U_LIB.S9S_MB_2U(SCH_1):SMB_BMC_SWB_EN
   2 SMB_BMC_SWB_EN_R      B @S9S_MB_2U_LIB.S9S_MB_2U(SCH_1):SMB_BMC_SWB_EN_R

Q_RES_0402LF-10K,1%,1/16W,CHIPA  I48  R4603
   1 SMB_BMC_GPU_EN      A @S9S_MB_2U_LIB.S9S_MB_2U(SCH_1):SMB_BMC_GPU_EN
   2    GND      B @S9S_MB_2U_LIB.S9S_MB_2U(SCH_1):GND

LTC4307CMS8-LTC4307CMS8,SMLF,IA  I50  U175
   1 SMB_BMC_SWB_EN_R ENABLE @S9S_MB_2U_LIB.S9S_MB_2U(SCH_1):SMB_BMC_SWB_EN_R
   3 SMB_BMC_SWB_R_SCL SCL_IN @S9S_MB_2U_LIB.S9S_MB_2U(SCH_1):SMB_BMC_SWB_R_SCL
   6 SMB_BMC_SWB_R_SDA SDA_IN @S9S_MB_2U_LIB.S9S_MB_2U(SCH_1):SMB_BMC_SWB_R_SDA
   2 SMB_BMC_SWB_BUF_R_SCL SCL_OUT @S9S_MB_2U_LIB.S9S_MB_2U(SCH_1):SMB_BMC_SWB_BUF_R_SCL
   7 SMB_BMC_SWB_BUF_R_SDA SDA_OUT @S9S_MB_2U_LIB.S9S_MB_2U(SCH_1):SMB_BMC_SWB_BUF_R_SDA
   5     NC  READY     NC
   4    GND    GND @S9S_MB_2U_LIB.S9S_MB_2U(SCH_1):GND
   8 P3V3_AUX    VCC @S9S_MB_2U_LIB.S9S_MB_2U(SCH_1):P3V3_AUX

Q_RES_0402LF-0,5%,1/16W,CHIP,CA  I51  R3109
   1 SMB_1_BMC_GPU_SCL      A @S9S_MB_2U_LIB.S9S_MB_2U(SCH_1):SMB_1_BMC_GPU_SCL
   2 SMB_1_BMC_GPU_R_SCL      B @S9S_MB_2U_LIB.S9S_MB_2U(SCH_1):SMB_1_BMC_GPU_R_SCL

Q_RES_0402LF-0,5%,1/16W,CHIP,CA  I52  R3110
   1 SMB_1_BMC_GPU_SDA      A @S9S_MB_2U_LIB.S9S_MB_2U(SCH_1):SMB_1_BMC_GPU_SDA
   2 SMB_1_BMC_GPU_R_SDA      B @S9S_MB_2U_LIB.S9S_MB_2U(SCH_1):SMB_1_BMC_GPU_R_SDA

Q_RES_0402LF-0,5%,1/16W,CHIP,CA  I53  R2899
   1 SMB_BMC_GPU_EN      A @S9S_MB_2U_LIB.S9S_MB_2U(SCH_1):SMB_BMC_GPU_EN
   2 SMB_BMC_GPU_EN_R1      B @S9S_MB_2U_LIB.S9S_MB_2U(SCH_1):SMB_BMC_GPU_EN_R1

Q_CAP_0402-0.1UF,25V,10%,X7R,CA  I58  C1707
   1 P3V3_AUX      A @S9S_MB_2U_LIB.S9S_MB_2U(SCH_1):P3V3_AUX
   2    GND      B @S9S_MB_2U_LIB.S9S_MB_2U(SCH_1):GND

Q_RES_0402LF-10K,1%,1/16W,CHIPA  I59  R2667
   1 P3V3_AUX      A @S9S_MB_2U_LIB.S9S_MB_2U(SCH_1):P3V3_AUX
   2 SMB_BMC_SWB_BUF_R_SCL      B @S9S_MB_2U_LIB.S9S_MB_2U(SCH_1):SMB_BMC_SWB_BUF_R_SCL

Q_RES_0402LF-10K,1%,1/16W,CHIPA  I61  R2669
   1 P3V3_AUX      A @S9S_MB_2U_LIB.S9S_MB_2U(SCH_1):P3V3_AUX
   2 SMB_BMC_SWB_BUF_R_SDA      B @S9S_MB_2U_LIB.S9S_MB_2U(SCH_1):SMB_BMC_SWB_BUF_R_SDA

LTC4307CMS8-LTC4307CMS8,SMLF,IA  I63  U194
   1 SMB_BMC_GPU_EN_R1 ENABLE @S9S_MB_2U_LIB.S9S_MB_2U(SCH_1):SMB_BMC_GPU_EN_R1
   3 SMB_1_BMC_GPU_R_SCL SCL_IN @S9S_MB_2U_LIB.S9S_MB_2U(SCH_1):SMB_1_BMC_GPU_R_SCL
   6 SMB_1_BMC_GPU_R_SDA SDA_IN @S9S_MB_2U_LIB.S9S_MB_2U(SCH_1):SMB_1_BMC_GPU_R_SDA
   2 SMB_1_BMC_GPU_BUF_R_SCL SCL_OUT @S9S_MB_2U_LIB.S9S_MB_2U(SCH_1):SMB_1_BMC_GPU_BUF_R_SCL
   7 SMB_1_BMC_GPU_BUF_R_SDA SDA_OUT @S9S_MB_2U_LIB.S9S_MB_2U(SCH_1):SMB_1_BMC_GPU_BUF_R_SDA
   5     NC  READY     NC
   4    GND    GND @S9S_MB_2U_LIB.S9S_MB_2U(SCH_1):GND
   8 P3V3_AUX    VCC @S9S_MB_2U_LIB.S9S_MB_2U(SCH_1):P3V3_AUX

Q_RES_0402LF-33.2,1%,1/16W,CHIA  I64  R2672
   1 SMB_BMC_SWB_BUF_R_SDA      A @S9S_MB_2U_LIB.S9S_MB_2U(SCH_1):SMB_BMC_SWB_BUF_R_SDA
   2 SMB_BMC_SWB_BUF_SDA      B @S9S_MB_2U_LIB.S9S_MB_2U(SCH_1):SMB_BMC_SWB_BUF_SDA

Q_RES_0402LF-27.4,1%,1/16W,CHIA  I71  R2674
   1 I3C_BMC_SWB_BUF_R_SDA      A @S9S_MB_2U_LIB.S9S_MB_2U(SCH_1):I3C_BMC_SWB_BUF_R_SDA
   2 I3C_BMC_SWB_BUF_SDA      B @S9S_MB_2U_LIB.S9S_MB_2U(SCH_1):I3C_BMC_SWB_BUF_SDA

Q_RES_0402LF-4.7K,5%,1/16W,EMPA  I75  R2668
   1 P3V3_AUX      A @S9S_MB_2U_LIB.S9S_MB_2U(SCH_1):P3V3_AUX
   2 I3C_BMC_SWB_BUF_R_SDA      B @S9S_MB_2U_LIB.S9S_MB_2U(SCH_1):I3C_BMC_SWB_BUF_R_SDA

Q_RES_0402LF-4.7K,5%,1/16W,EMPA  I77  R2670
   1 P3V3_AUX      A @S9S_MB_2U_LIB.S9S_MB_2U(SCH_1):P3V3_AUX
   2 I3C_BMC_SWB_BUF_R_SCL      B @S9S_MB_2U_LIB.S9S_MB_2U(SCH_1):I3C_BMC_SWB_BUF_R_SCL

Q_RES_0402LF-33.2,1%,1/16W,CHIA  I78  R2897
   1 SMB_1_BMC_GPU_BUF_R_SCL      A @S9S_MB_2U_LIB.S9S_MB_2U(SCH_1):SMB_1_BMC_GPU_BUF_R_SCL
   2 SMB_1_BMC_GPU_BUF_SCL      B @S9S_MB_2U_LIB.S9S_MB_2U(SCH_1):SMB_1_BMC_GPU_BUF_SCL

Q_RES_0402LF-33.2,1%,1/16W,CHIA  I79  R2898
   1 SMB_1_BMC_GPU_BUF_R_SDA      A @S9S_MB_2U_LIB.S9S_MB_2U(SCH_1):SMB_1_BMC_GPU_BUF_R_SDA
   2 SMB_1_BMC_GPU_BUF_SDA      B @S9S_MB_2U_LIB.S9S_MB_2U(SCH_1):SMB_1_BMC_GPU_BUF_SDA

Q_RES_0402LF-54.9K,1%,1/16W,CHA  I80  R3523
   1 P3V3_AUX      A @S9S_MB_2U_LIB.S9S_MB_2U(SCH_1):P3V3_AUX
   2 SMB_1_BMC_GPU_BUF_R_SCL      B @S9S_MB_2U_LIB.S9S_MB_2U(SCH_1):SMB_1_BMC_GPU_BUF_R_SCL

Q_RES_0402LF-54.9K,1%,1/16W,CHA  I81  R3524
   1 P3V3_AUX      A @S9S_MB_2U_LIB.S9S_MB_2U(SCH_1):P3V3_AUX
   2 SMB_1_BMC_GPU_BUF_R_SDA      B @S9S_MB_2U_LIB.S9S_MB_2U(SCH_1):SMB_1_BMC_GPU_BUF_R_SDA


DRAWING: @S9S_MB_2U_LIB.S9S_MB_2U(SCH_1):PAGE145 

Q_RES_0402LF-4.7K,5%,1/16W,CHIA  I14  R2835
   1 P3V3_AUX      A @S9S_MB_2U_LIB.S9S_MB_2U(SCH_1):P3V3_AUX
   2 BIC_MONITER_N      B @S9S_MB_2U_LIB.S9S_MB_2U(SCH_1):BIC_MONITER_N

Q_RES_0402LF-4.7K,5%,1/16W,CHIA  I18  R2834
   1 P3V3_AUX      A @S9S_MB_2U_LIB.S9S_MB_2U(SCH_1):P3V3_AUX
   2 RST_BMC_FROM_SWB      B @S9S_MB_2U_LIB.S9S_MB_2U(SCH_1):RST_BMC_FROM_SWB

Q_RES_0402LF-4.7K,5%,1/16W,CHIA  I19  R2836
   1 P3V3_AUX      A @S9S_MB_2U_LIB.S9S_MB_2U(SCH_1):P3V3_AUX
   2 FM_SWB_BIC_READY      B @S9S_MB_2U_LIB.S9S_MB_2U(SCH_1):FM_SWB_BIC_READY

Q_RES_0402LF-4.7K,5%,1/16W,CHIA  I24  R2841
   1 P3V3_AUX      A @S9S_MB_2U_LIB.S9S_MB_2U(SCH_1):P3V3_AUX
   2 FM_SWB_PWRGD_N      B @S9S_MB_2U_LIB.S9S_MB_2U(SCH_1):FM_SWB_PWRGD_N

Q_RES_0402LF-4.7K,5%,1/16W,CHIA  I30  R2842
   1 P3V3_AUX      A @S9S_MB_2U_LIB.S9S_MB_2U(SCH_1):P3V3_AUX
   2 FM_GPU_PWRGD_N      B @S9S_MB_2U_LIB.S9S_MB_2U(SCH_1):FM_GPU_PWRGD_N

MOSFET_NCH_DUAL-PJT138K,SMLF,IA  I33  Q67
   1    GND     S1 @S9S_MB_2U_LIB.S9S_MB_2U(SCH_1):GND
   2 BIC_MONITER     G1 @S9S_MB_2U_LIB.S9S_MB_2U(SCH_1):BIC_MONITER
   6 BIC_MONITER_N     D1 @S9S_MB_2U_LIB.S9S_MB_2U(SCH_1):BIC_MONITER_N

MOSFET_NCH_DUAL-PJT138K,SMLF,IA  I35  Q70
   1    GND     S1 @S9S_MB_2U_LIB.S9S_MB_2U(SCH_1):GND
   2 FM_SWB_BIC_READY_N     G1 @S9S_MB_2U_LIB.S9S_MB_2U(SCH_1):FM_SWB_BIC_READY_N
   6 FM_SWB_BIC_READY     D1 @S9S_MB_2U_LIB.S9S_MB_2U(SCH_1):FM_SWB_BIC_READY

MOSFET_NCH_DUAL-PJT138K,SMLF,IA  I37  Q72
   1    GND     S1 @S9S_MB_2U_LIB.S9S_MB_2U(SCH_1):GND
   2 FM_GPU_PWRGD     G1 @S9S_MB_2U_LIB.S9S_MB_2U(SCH_1):FM_GPU_PWRGD
   6 FM_GPU_PWRGD_N     D1 @S9S_MB_2U_LIB.S9S_MB_2U(SCH_1):FM_GPU_PWRGD_N

Q_RES_0402LF-100K,1%,1/16W,EMPA  I56  R2831
   1 BIC_MONITER      A @S9S_MB_2U_LIB.S9S_MB_2U(SCH_1):BIC_MONITER
   2    GND      B @S9S_MB_2U_LIB.S9S_MB_2U(SCH_1):GND

Q_RES_0402LF-100K,1%,1/16W,EMPA  I58  R2829
   1 RST_BMC_FROM_SWB_N      A @S9S_MB_2U_LIB.S9S_MB_2U(SCH_1):RST_BMC_FROM_SWB_N
   2    GND      B @S9S_MB_2U_LIB.S9S_MB_2U(SCH_1):GND

Q_RES_0402LF-100K,1%,1/16W,EMPA  I60  R2833
   1 FM_SWB_BIC_READY_N      A @S9S_MB_2U_LIB.S9S_MB_2U(SCH_1):FM_SWB_BIC_READY_N
   2    GND      B @S9S_MB_2U_LIB.S9S_MB_2U(SCH_1):GND

Q_RES_0402LF-100K,1%,1/16W,CHIA  I62  R2838
   1 FM_SWB_PWRGD      A @S9S_MB_2U_LIB.S9S_MB_2U(SCH_1):FM_SWB_PWRGD
   2    GND      B @S9S_MB_2U_LIB.S9S_MB_2U(SCH_1):GND

Q_RES_0402LF-100K,1%,1/16W,CHIA  I66  R2828
   1 P3V3_AUX      A @S9S_MB_2U_LIB.S9S_MB_2U(SCH_1):P3V3_AUX
   2 RST_BMC_FROM_SWB_N      B @S9S_MB_2U_LIB.S9S_MB_2U(SCH_1):RST_BMC_FROM_SWB_N

Q_RES_0402LF-100K,1%,1/16W,CHIA  I67  R2832
   1 P3V3_AUX      A @S9S_MB_2U_LIB.S9S_MB_2U(SCH_1):P3V3_AUX
   2 FM_SWB_BIC_READY_N      B @S9S_MB_2U_LIB.S9S_MB_2U(SCH_1):FM_SWB_BIC_READY_N

Q_RES_0402LF-100K,1%,1/16W,CHIA  I68  R2830
   1 P3V3_AUX      A @S9S_MB_2U_LIB.S9S_MB_2U(SCH_1):P3V3_AUX
   2 BIC_MONITER      B @S9S_MB_2U_LIB.S9S_MB_2U(SCH_1):BIC_MONITER

Q_RES_0402LF-100K,1%,1/16W,EMPA  I80  R2837
   1 P3V3_AUX      A @S9S_MB_2U_LIB.S9S_MB_2U(SCH_1):P3V3_AUX
   2 FM_SWB_PWRGD      B @S9S_MB_2U_LIB.S9S_MB_2U(SCH_1):FM_SWB_PWRGD

MOSFET_NCH_DUAL-PJT138K,SMLF,IA  I82  Q67
   3 BIC_MONITER_ISO     D2 @S9S_MB_2U_LIB.S9S_MB_2U(SCH_1):BIC_MONITER_ISO
   5 BIC_MONITER_N     G2 @S9S_MB_2U_LIB.S9S_MB_2U(SCH_1):BIC_MONITER_N
   4    GND     S2 @S9S_MB_2U_LIB.S9S_MB_2U(SCH_1):GND

Q_RES_0402LF-4.7K,5%,1/16W,CHIA  I84  R2920
   1 P3V3_AUX      A @S9S_MB_2U_LIB.S9S_MB_2U(SCH_1):P3V3_AUX
   2 BIC_MONITER_ISO      B @S9S_MB_2U_LIB.S9S_MB_2U(SCH_1):BIC_MONITER_ISO

MOSFET_NCH_DUAL-PJT138K,SMLF,IA  I88  Q69
   3 RST_BMC_FROM_SWB_ISO_N     D2 @S9S_MB_2U_LIB.S9S_MB_2U(SCH_1):RST_BMC_FROM_SWB_ISO_N
   5 RST_BMC_FROM_SWB     G2 @S9S_MB_2U_LIB.S9S_MB_2U(SCH_1):RST_BMC_FROM_SWB
   4    GND     S2 @S9S_MB_2U_LIB.S9S_MB_2U(SCH_1):GND

Q_RES_0402LF-4.7K,5%,1/16W,CHIA  I91  R2919
   1 P3V3_AUX      A @S9S_MB_2U_LIB.S9S_MB_2U(SCH_1):P3V3_AUX
   2 RST_BMC_FROM_SWB_ISO_N      B @S9S_MB_2U_LIB.S9S_MB_2U(SCH_1):RST_BMC_FROM_SWB_ISO_N

Q_CAP_0402-1000PF,50V,5%,EMPTYA  I92  C1754
   1 FM_SWB_BIC_READY_ISO_N      A @S9S_MB_2U_LIB.S9S_MB_2U(SCH_1):FM_SWB_BIC_READY_ISO_N
   2    GND      B @S9S_MB_2U_LIB.S9S_MB_2U(SCH_1):GND

Q_RES_0402LF-4.7K,5%,1/16W,CHIA  I97  R2933
   1 P3V3_AUX      A @S9S_MB_2U_LIB.S9S_MB_2U(SCH_1):P3V3_AUX
   2 FM_SWB_BIC_READY_ISO_N      B @S9S_MB_2U_LIB.S9S_MB_2U(SCH_1):FM_SWB_BIC_READY_ISO_N

MOSFET_NCH_DUAL-PJT138K,SMLF,IA  I100  Q71
   3 FM_SWB_PWRGD_ISO     D2 @S9S_MB_2U_LIB.S9S_MB_2U(SCH_1):FM_SWB_PWRGD_ISO
   5 FM_SWB_PWRGD_N     G2 @S9S_MB_2U_LIB.S9S_MB_2U(SCH_1):FM_SWB_PWRGD_N
   4    GND     S2 @S9S_MB_2U_LIB.S9S_MB_2U(SCH_1):GND

Q_RES_0402LF-4.7K,5%,1/16W,CHIA  I101  R2934
   1 P3V3_AUX      A @S9S_MB_2U_LIB.S9S_MB_2U(SCH_1):P3V3_AUX
   2 FM_SWB_PWRGD_ISO      B @S9S_MB_2U_LIB.S9S_MB_2U(SCH_1):FM_SWB_PWRGD_ISO

Q_CAP_0402-1000PF,50V,5%,EMPTYA  I105  C1756
   1 FM_GPU_PWRGD_ISO      A @S9S_MB_2U_LIB.S9S_MB_2U(SCH_1):FM_GPU_PWRGD_ISO
   2    GND      B @S9S_MB_2U_LIB.S9S_MB_2U(SCH_1):GND

Q_RES_0402LF-4.7K,5%,1/16W,CHIA  I109  R2935
   1 P3V3_AUX      A @S9S_MB_2U_LIB.S9S_MB_2U(SCH_1):P3V3_AUX
   2 FM_GPU_PWRGD_ISO      B @S9S_MB_2U_LIB.S9S_MB_2U(SCH_1):FM_GPU_PWRGD_ISO

Q_CAP_0402-1000PF,50V,5%,EMPTYA  I111  C1774
   1 FM_SWB_PWRGD_ISO      A @S9S_MB_2U_LIB.S9S_MB_2U(SCH_1):FM_SWB_PWRGD_ISO
   2    GND      B @S9S_MB_2U_LIB.S9S_MB_2U(SCH_1):GND

Q_CAP_0402-1000PF,50V,5%,EMPTYA  I114  C1773
   1 BIC_MONITER_ISO      A @S9S_MB_2U_LIB.S9S_MB_2U(SCH_1):BIC_MONITER_ISO
   2    GND      B @S9S_MB_2U_LIB.S9S_MB_2U(SCH_1):GND

Q_CAP_0402-1000PF,50V,5%,EMPTYA  I116  C1772
   1 RST_BMC_FROM_SWB_ISO_N      A @S9S_MB_2U_LIB.S9S_MB_2U(SCH_1):RST_BMC_FROM_SWB_ISO_N
   2    GND      B @S9S_MB_2U_LIB.S9S_MB_2U(SCH_1):GND

MOSFET_NCH_DUAL-PJT138K,SMLF,IA  I117  Q69
   1    GND     S1 @S9S_MB_2U_LIB.S9S_MB_2U(SCH_1):GND
   2 RST_BMC_FROM_SWB_N     G1 @S9S_MB_2U_LIB.S9S_MB_2U(SCH_1):RST_BMC_FROM_SWB_N
   6 RST_BMC_FROM_SWB     D1 @S9S_MB_2U_LIB.S9S_MB_2U(SCH_1):RST_BMC_FROM_SWB

MOSFET_NCH_DUAL-PJT138K,SMLF,IA  I118  Q71
   1    GND     S1 @S9S_MB_2U_LIB.S9S_MB_2U(SCH_1):GND
   2 FM_SWB_PWRGD     G1 @S9S_MB_2U_LIB.S9S_MB_2U(SCH_1):FM_SWB_PWRGD
   6 FM_SWB_PWRGD_N     D1 @S9S_MB_2U_LIB.S9S_MB_2U(SCH_1):FM_SWB_PWRGD_N

MOSFET_NCH_DUAL-PJT138K,SMLF,IA  I119  Q72
   3 FM_GPU_PWRGD_ISO     D2 @S9S_MB_2U_LIB.S9S_MB_2U(SCH_1):FM_GPU_PWRGD_ISO
   5 FM_GPU_PWRGD_N     G2 @S9S_MB_2U_LIB.S9S_MB_2U(SCH_1):FM_GPU_PWRGD_N
   4    GND     S2 @S9S_MB_2U_LIB.S9S_MB_2U(SCH_1):GND

MOSFET_NCH_DUAL-PJT138K,SMLF,IA  I120  Q70
   3 FM_SWB_BIC_READY_ISO_N     D2 @S9S_MB_2U_LIB.S9S_MB_2U(SCH_1):FM_SWB_BIC_READY_ISO_N
   5 FM_SWB_BIC_READY     G2 @S9S_MB_2U_LIB.S9S_MB_2U(SCH_1):FM_SWB_BIC_READY
   4    GND     S2 @S9S_MB_2U_LIB.S9S_MB_2U(SCH_1):GND

MOSFET_NCH_DUAL-PJT138K,SMLF,IA  I121  Q74
   1    GND     S1 @S9S_MB_2U_LIB.S9S_MB_2U(SCH_1):GND
   2 FM_SMB_2_ALERT_GPU_N     G1 @S9S_MB_2U_LIB.S9S_MB_2U(SCH_1):FM_SMB_2_ALERT_GPU_N
   6 FM_SMB_2_ALERT_GPU     D1 @S9S_MB_2U_LIB.S9S_MB_2U(SCH_1):FM_SMB_2_ALERT_GPU

MOSFET_NCH_DUAL-PJT138K,SMLF,IA  I122  Q74
   3 FM_SMB_2_ALERT_GPU_ISO_N     D2 @S9S_MB_2U_LIB.S9S_MB_2U(SCH_1):FM_SMB_2_ALERT_GPU_ISO_N
   5 FM_SMB_2_ALERT_GPU     G2 @S9S_MB_2U_LIB.S9S_MB_2U(SCH_1):FM_SMB_2_ALERT_GPU
   4    GND     S2 @S9S_MB_2U_LIB.S9S_MB_2U(SCH_1):GND

Q_CAP_0402-1000PF,50V,5%,EMPTYA  I125  C1804
   1 FM_SMB_2_ALERT_GPU_ISO_N      A @S9S_MB_2U_LIB.S9S_MB_2U(SCH_1):FM_SMB_2_ALERT_GPU_ISO_N
   2    GND      B @S9S_MB_2U_LIB.S9S_MB_2U(SCH_1):GND

Q_RES_0402LF-4.7K,5%,1/16W,CHIA  I127  R3035
   1 P3V3_AUX      A @S9S_MB_2U_LIB.S9S_MB_2U(SCH_1):P3V3_AUX
   2 FM_SMB_2_ALERT_GPU_ISO_N      B @S9S_MB_2U_LIB.S9S_MB_2U(SCH_1):FM_SMB_2_ALERT_GPU_ISO_N

Q_RES_0402LF-4.7K,5%,1/16W,CHIA  I129  R3034
   1 P3V3_AUX      A @S9S_MB_2U_LIB.S9S_MB_2U(SCH_1):P3V3_AUX
   2 FM_SMB_2_ALERT_GPU      B @S9S_MB_2U_LIB.S9S_MB_2U(SCH_1):FM_SMB_2_ALERT_GPU

Q_RES_0402LF-100K,1%,1/16W,EMPA  I134  R3032
   1 FM_SMB_2_ALERT_GPU_N      A @S9S_MB_2U_LIB.S9S_MB_2U(SCH_1):FM_SMB_2_ALERT_GPU_N
   2    GND      B @S9S_MB_2U_LIB.S9S_MB_2U(SCH_1):GND

Q_RES_0402LF-100K,1%,1/16W,EMPA  I139  R3028
   1 FM_SMB_1_ALERT_GPU_N      A @S9S_MB_2U_LIB.S9S_MB_2U(SCH_1):FM_SMB_1_ALERT_GPU_N
   2    GND      B @S9S_MB_2U_LIB.S9S_MB_2U(SCH_1):GND

Q_RES_0402LF-4.7K,5%,1/16W,CHIA  I144  R3029
   1 P3V3_AUX      A @S9S_MB_2U_LIB.S9S_MB_2U(SCH_1):P3V3_AUX
   2 FM_SMB_1_ALERT_GPU      B @S9S_MB_2U_LIB.S9S_MB_2U(SCH_1):FM_SMB_1_ALERT_GPU

Q_RES_0402LF-4.7K,5%,1/16W,CHIA  I146  R3030
   1 P3V3_AUX      A @S9S_MB_2U_LIB.S9S_MB_2U(SCH_1):P3V3_AUX
   2 FM_SMB_1_ALERT_GPU_ISO_N      B @S9S_MB_2U_LIB.S9S_MB_2U(SCH_1):FM_SMB_1_ALERT_GPU_ISO_N

Q_CAP_0402-1000PF,50V,5%,EMPTYA  I148  C1802
   1 FM_SMB_1_ALERT_GPU_ISO_N      A @S9S_MB_2U_LIB.S9S_MB_2U(SCH_1):FM_SMB_1_ALERT_GPU_ISO_N
   2    GND      B @S9S_MB_2U_LIB.S9S_MB_2U(SCH_1):GND

MOSFET_NCH_DUAL-PJT138K,SMLF,IA  I151  Q75
   3 FM_SMB_1_ALERT_GPU_ISO_N     D2 @S9S_MB_2U_LIB.S9S_MB_2U(SCH_1):FM_SMB_1_ALERT_GPU_ISO_N
   5 FM_SMB_1_ALERT_GPU     G2 @S9S_MB_2U_LIB.S9S_MB_2U(SCH_1):FM_SMB_1_ALERT_GPU
   4    GND     S2 @S9S_MB_2U_LIB.S9S_MB_2U(SCH_1):GND

MOSFET_NCH_DUAL-PJT138K,SMLF,IA  I152  Q75
   1    GND     S1 @S9S_MB_2U_LIB.S9S_MB_2U(SCH_1):GND
   2 FM_SMB_1_ALERT_GPU_N     G1 @S9S_MB_2U_LIB.S9S_MB_2U(SCH_1):FM_SMB_1_ALERT_GPU_N
   6 FM_SMB_1_ALERT_GPU     D1 @S9S_MB_2U_LIB.S9S_MB_2U(SCH_1):FM_SMB_1_ALERT_GPU

MOSFET_NCH_DUAL-PJT138K,SMLF,IA  I159  Q96
   3 GPU_FPGA_READY_ISO     D2 @S9S_MB_2U_LIB.S9S_MB_2U(SCH_1):GPU_FPGA_READY_ISO
   5 GPU_FPGA_READY_N     G2 @S9S_MB_2U_LIB.S9S_MB_2U(SCH_1):GPU_FPGA_READY_N
   4    GND     S2 @S9S_MB_2U_LIB.S9S_MB_2U(SCH_1):GND

MOSFET_NCH_DUAL-PJT138K,SMLF,IA  I154  Q96
   1    GND     S1 @S9S_MB_2U_LIB.S9S_MB_2U(SCH_1):GND
   2 GPU_FPGA_READY     G1 @S9S_MB_2U_LIB.S9S_MB_2U(SCH_1):GPU_FPGA_READY
   6 GPU_FPGA_READY_N     D1 @S9S_MB_2U_LIB.S9S_MB_2U(SCH_1):GPU_FPGA_READY_N

Q_CAP_0402-1000PF,50V,5%,EMPTYA  I156  C1881
   1 GPU_FPGA_READY_ISO      A @S9S_MB_2U_LIB.S9S_MB_2U(SCH_1):GPU_FPGA_READY_ISO
   2    GND      B @S9S_MB_2U_LIB.S9S_MB_2U(SCH_1):GND

Q_RES_0402LF-4.7K,5%,1/16W,CHIA  I158  R3321
   1 P3V3_AUX      A @S9S_MB_2U_LIB.S9S_MB_2U(SCH_1):P3V3_AUX
   2 GPU_FPGA_READY_ISO      B @S9S_MB_2U_LIB.S9S_MB_2U(SCH_1):GPU_FPGA_READY_ISO

Q_RES_0402LF-4.7K,5%,1/16W,CHIA  I162  R3320
   1 P3V3_AUX      A @S9S_MB_2U_LIB.S9S_MB_2U(SCH_1):P3V3_AUX
   2 GPU_FPGA_READY_N      B @S9S_MB_2U_LIB.S9S_MB_2U(SCH_1):GPU_FPGA_READY_N

Q_RES_0402LF-100K,1%,1/16W,EMPA  I171  R3318
   1 P3V3_AUX      A @S9S_MB_2U_LIB.S9S_MB_2U(SCH_1):P3V3_AUX
   2 GPU_FPGA_READY      B @S9S_MB_2U_LIB.S9S_MB_2U(SCH_1):GPU_FPGA_READY

Q_RES_0402LF-54.9K,1%,1/16W,CHA  I172  R3511
   1 GPU_FPGA_READY      A @S9S_MB_2U_LIB.S9S_MB_2U(SCH_1):GPU_FPGA_READY
   2    GND      B @S9S_MB_2U_LIB.S9S_MB_2U(SCH_1):GND

Q_RES_0402LF-54.9K,1%,1/16W,CHA  I173  R3513
   1 FM_GPU_PWRGD      A @S9S_MB_2U_LIB.S9S_MB_2U(SCH_1):FM_GPU_PWRGD
   2    GND      B @S9S_MB_2U_LIB.S9S_MB_2U(SCH_1):GND

Q_RES_0402LF-100K,1%,1/16W,EMPA  I174  R3512
   1 P3V3_AUX      A @S9S_MB_2U_LIB.S9S_MB_2U(SCH_1):P3V3_AUX
   2 FM_GPU_PWRGD      B @S9S_MB_2U_LIB.S9S_MB_2U(SCH_1):FM_GPU_PWRGD

Q_RES_0402LF-54.9K,1%,1/16W,CHA  I175  R3514
   1 P3V3_AUX      A @S9S_MB_2U_LIB.S9S_MB_2U(SCH_1):P3V3_AUX
   2 FM_SMB_2_ALERT_GPU_N      B @S9S_MB_2U_LIB.S9S_MB_2U(SCH_1):FM_SMB_2_ALERT_GPU_N

Q_RES_0402LF-54.9K,1%,1/16W,CHA  I176  R3510
   1 P3V3_AUX      A @S9S_MB_2U_LIB.S9S_MB_2U(SCH_1):P3V3_AUX
   2 FM_SMB_1_ALERT_GPU_N      B @S9S_MB_2U_LIB.S9S_MB_2U(SCH_1):FM_SMB_1_ALERT_GPU_N


DRAWING: @S9S_MB_2U_LIB.S9S_MB_2U(SCH_1):PAGE214 

Q_RES_0402LF-0,5%,1/16W,CHIP,CA  I34  R2848
   1 RST_SWB_BIC_N      A @S9S_MB_2U_LIB.S9S_MB_2U(SCH_1):RST_SWB_BIC_N
   2 RST_SWB_BIC_R_N      B @S9S_MB_2U_LIB.S9S_MB_2U(SCH_1):RST_SWB_BIC_R_N

PCA9539RPW-PCA9539RPW,SMLF,IC,A  I66  U181
   1 PU_U181_INT    INT @S9S_MB_2U_LIB.S9S_MB_2U(SCH_1):PU_U181_INT
   2 TCA9539_0_ADD1     A1 @S9S_MB_2U_LIB.S9S_MB_2U(SCH_1):TCA9539_0_ADD1
   3 PU_RST_SMB_U181_N  RESET @S9S_MB_2U_LIB.S9S_MB_2U(SCH_1):PU_RST_SMB_U181_N
   4 RST_USB_HUB_N  IO0_0 @S9S_MB_2U_LIB.S9S_MB_2U(SCH_1):RST_USB_HUB_N
   5 RST_SWB_BIC_N  IO0_1 @S9S_MB_2U_LIB.S9S_MB_2U(SCH_1):RST_SWB_BIC_N
   6 TP_TCA9539_0_P0_2  IO0_2 @S9S_MB_2U_LIB.S9S_MB_2U(SCH_1):TP_TCA9539_0_P0_2
   7 TP_TCA9539_0_P0_3  IO0_3 @S9S_MB_2U_LIB.S9S_MB_2U(SCH_1):TP_TCA9539_0_P0_3
   8 PRSNT_SWB_ISO_R1_N  IO0_4 @S9S_MB_2U_LIB.S9S_MB_2U(SCH_1):PRSNT_SWB_ISO_R1_N
   9 GPU_PRSNT_N_ISO_R1  IO0_5 @S9S_MB_2U_LIB.S9S_MB_2U(SCH_1):GPU_PRSNT_N_ISO_R1
  10 PRSNT_CABLE_GPU_B3_ISO_R1_N  IO0_6 @S9S_MB_2U_LIB.S9S_MB_2U(SCH_1):PRSNT_CABLE_GPU_B3_ISO_R1_N
  11 PRSNT_CABLE_SWB_B2_ISO_R_N  IO0_7 @S9S_MB_2U_LIB.S9S_MB_2U(SCH_1):PRSNT_CABLE_SWB_B2_ISO_R_N
  12    GND    VSS @S9S_MB_2U_LIB.S9S_MB_2U(SCH_1):GND
  13 PRSNT_CABLE_GPU_A2_ISO_R1_N  IO1_0 @S9S_MB_2U_LIB.S9S_MB_2U(SCH_1):PRSNT_CABLE_GPU_A2_ISO_R1_N
  14 PRSNT_CABLE_SWB_B1_ISO_R_N  IO1_1 @S9S_MB_2U_LIB.S9S_MB_2U(SCH_1):PRSNT_CABLE_SWB_B1_ISO_R_N
  15 GPU_BASE_ID0_R  IO1_2 @S9S_MB_2U_LIB.S9S_MB_2U(SCH_1):GPU_BASE_ID0_R
  16 GPU_BASE_ID1_R  IO1_3 @S9S_MB_2U_LIB.S9S_MB_2U(SCH_1):GPU_BASE_ID1_R
  17 GPU_PEX_STRAP0_R  IO1_4 @S9S_MB_2U_LIB.S9S_MB_2U(SCH_1):GPU_PEX_STRAP0_R
  18 GPU_PEX_STRAP1_R  IO1_5 @S9S_MB_2U_LIB.S9S_MB_2U(SCH_1):GPU_PEX_STRAP1_R
  19 PRSNT_CABLE_GPU_A1_ISO_R1_N  IO1_6 @S9S_MB_2U_LIB.S9S_MB_2U(SCH_1):PRSNT_CABLE_GPU_A1_ISO_R1_N
  20 PRSNT_CABLE_GPU_A3_ISO_R_N  IO1_7 @S9S_MB_2U_LIB.S9S_MB_2U(SCH_1):PRSNT_CABLE_GPU_A3_ISO_R_N
  21 TCA9539_0_ADD0     A0 @S9S_MB_2U_LIB.S9S_MB_2U(SCH_1):TCA9539_0_ADD0
  22 SMB_IOEXP_3V3AUX_SCL_R1    SCL @S9S_MB_2U_LIB.S9S_MB_2U(SCH_1):SMB_IOEXP_3V3AUX_SCL_R1
  23 SMB_IOEXP_3V3AUX_SDA_R1    SDA @S9S_MB_2U_LIB.S9S_MB_2U(SCH_1):SMB_IOEXP_3V3AUX_SDA_R1
  24 P3V3_AUX    VDD @S9S_MB_2U_LIB.S9S_MB_2U(SCH_1):P3V3_AUX

Q_RES_0402LF-1K,1%,1/16W,EMPTYA  I74  R2695
   1 P3V3_AUX      A @S9S_MB_2U_LIB.S9S_MB_2U(SCH_1):P3V3_AUX
   2 TCA9539_0_ADD0      B @S9S_MB_2U_LIB.S9S_MB_2U(SCH_1):TCA9539_0_ADD0

Q_RES_0402LF-1K,1%,1/16W,CHIP,A  I75  R2696
   1 TCA9539_0_ADD0      A @S9S_MB_2U_LIB.S9S_MB_2U(SCH_1):TCA9539_0_ADD0
   2    GND      B @S9S_MB_2U_LIB.S9S_MB_2U(SCH_1):GND

Q_RES_0402LF-1K,1%,1/16W,EMPTYA  I76  R2693
   1 P3V3_AUX      A @S9S_MB_2U_LIB.S9S_MB_2U(SCH_1):P3V3_AUX
   2 TCA9539_0_ADD1      B @S9S_MB_2U_LIB.S9S_MB_2U(SCH_1):TCA9539_0_ADD1

Q_RES_0402LF-1K,1%,1/16W,CHIP,A  I77  R2694
   1 TCA9539_0_ADD1      A @S9S_MB_2U_LIB.S9S_MB_2U(SCH_1):TCA9539_0_ADD1
   2    GND      B @S9S_MB_2U_LIB.S9S_MB_2U(SCH_1):GND

Q_CAP_0402-0.1UF,25V,10%,X7R,CA  I87  C1713
   1 P3V3_AUX      A @S9S_MB_2U_LIB.S9S_MB_2U(SCH_1):P3V3_AUX
   2    GND      B @S9S_MB_2U_LIB.S9S_MB_2U(SCH_1):GND

Q_RES_0402LF-4.7K,5%,1/16W,EMPA  I90  R2923
   1 P3V3_AUX      A @S9S_MB_2U_LIB.S9S_MB_2U(SCH_1):P3V3_AUX
   2 PU_U181_INT      B @S9S_MB_2U_LIB.S9S_MB_2U(SCH_1):PU_U181_INT

Q_RES_0402LF-10K,1%,1/16W,EMPTA  I93  R2921
   1 P3V3_AUX      A @S9S_MB_2U_LIB.S9S_MB_2U(SCH_1):P3V3_AUX
   2 RST_SMB_SWITCH_N      B @S9S_MB_2U_LIB.S9S_MB_2U(SCH_1):RST_SMB_SWITCH_N

Q_RES_0402LF-0,5%,1/16W,CHIP,CA  I95  R2922
   1 RST_SMB_SWITCH_N      A @S9S_MB_2U_LIB.S9S_MB_2U(SCH_1):RST_SMB_SWITCH_N
   2 PU_RST_SMB_U181_N      B @S9S_MB_2U_LIB.S9S_MB_2U(SCH_1):PU_RST_SMB_U181_N

Q_RES_0402LF-0,5%,1/16W,CHIP,CA  I96  R2982
   1 SMB_IOEXP_3V3AUX_SCL      A @S9S_MB_2U_LIB.S9S_MB_2U(SCH_1):SMB_IOEXP_3V3AUX_SCL
   2 SMB_IOEXP_3V3AUX_SCL_R1      B @S9S_MB_2U_LIB.S9S_MB_2U(SCH_1):SMB_IOEXP_3V3AUX_SCL_R1

Q_RES_0402LF-0,5%,1/16W,CHIP,CA  I101  R2983
   1 SMB_IOEXP_3V3AUX_SDA      A @S9S_MB_2U_LIB.S9S_MB_2U(SCH_1):SMB_IOEXP_3V3AUX_SDA
   2 SMB_IOEXP_3V3AUX_SDA_R1      B @S9S_MB_2U_LIB.S9S_MB_2U(SCH_1):SMB_IOEXP_3V3AUX_SDA_R1

Q_RES_0402LF-0,5%,1/16W,CHIP,CA  I118  R3499
   1 GPU_BASE_ID1      A @S9S_MB_2U_LIB.S9S_MB_2U(SCH_1):GPU_BASE_ID1
   2 GPU_BASE_ID1_R      B @S9S_MB_2U_LIB.S9S_MB_2U(SCH_1):GPU_BASE_ID1_R

Q_RES_0402LF-0,5%,1/16W,CHIP,CA  I127  R3516
   1 GPU_BASE_ID0      A @S9S_MB_2U_LIB.S9S_MB_2U(SCH_1):GPU_BASE_ID0
   2 GPU_BASE_ID0_R      B @S9S_MB_2U_LIB.S9S_MB_2U(SCH_1):GPU_BASE_ID0_R

Q_RES_0402LF-0,5%,1/16W,CHIP,CA  I128  R3517
   1 GPU_PEX_STRAP1      A @S9S_MB_2U_LIB.S9S_MB_2U(SCH_1):GPU_PEX_STRAP1
   2 GPU_PEX_STRAP1_R      B @S9S_MB_2U_LIB.S9S_MB_2U(SCH_1):GPU_PEX_STRAP1_R

Q_RES_0402LF-0,5%,1/16W,CHIP,CA  I129  R3518
   1 GPU_PEX_STRAP0      A @S9S_MB_2U_LIB.S9S_MB_2U(SCH_1):GPU_PEX_STRAP0
   2 GPU_PEX_STRAP0_R      B @S9S_MB_2U_LIB.S9S_MB_2U(SCH_1):GPU_PEX_STRAP0_R

Q_RES_0402LF-0,5%,1/16W,CHIP,CA  I137  R4728
   1 PRSNT_SWB_ISO_N      A @S9S_MB_2U_LIB.S9S_MB_2U(SCH_1):PRSNT_SWB_ISO_N
   2 PRSNT_SWB_ISO_R1_N      B @S9S_MB_2U_LIB.S9S_MB_2U(SCH_1):PRSNT_SWB_ISO_R1_N

Q_RES_0402LF-0,5%,1/16W,CHIP,CA  I140  R4729
   1 GPU_PRSNT_N_ISO      A @S9S_MB_2U_LIB.S9S_MB_2U(SCH_1):GPU_PRSNT_N_ISO
   2 GPU_PRSNT_N_ISO_R1      B @S9S_MB_2U_LIB.S9S_MB_2U(SCH_1):GPU_PRSNT_N_ISO_R1

Q_RES_0402LF-0,5%,1/16W,CHIP,CA  I144  R4734
   1 PRSNT_CABLE_GPU_B3_ISO_N      A @S9S_MB_2U_LIB.S9S_MB_2U(SCH_1):PRSNT_CABLE_GPU_B3_ISO_N
   2 PRSNT_CABLE_GPU_B3_ISO_R1_N      B @S9S_MB_2U_LIB.S9S_MB_2U(SCH_1):PRSNT_CABLE_GPU_B3_ISO_R1_N

Q_RES_0402LF-0,5%,1/16W,CHIP,CA  I148  R4735
   1 PRSNT_CABLE_SWB_B2_ISO_N      A @S9S_MB_2U_LIB.S9S_MB_2U(SCH_1):PRSNT_CABLE_SWB_B2_ISO_N
   2 PRSNT_CABLE_SWB_B2_ISO_R_N      B @S9S_MB_2U_LIB.S9S_MB_2U(SCH_1):PRSNT_CABLE_SWB_B2_ISO_R_N

Q_RES_0402LF-0,5%,1/16W,CHIP,CA  I153  R4736
   1 PRSNT_CABLE_GPU_A2_ISO_N      A @S9S_MB_2U_LIB.S9S_MB_2U(SCH_1):PRSNT_CABLE_GPU_A2_ISO_N
   2 PRSNT_CABLE_GPU_A2_ISO_R1_N      B @S9S_MB_2U_LIB.S9S_MB_2U(SCH_1):PRSNT_CABLE_GPU_A2_ISO_R1_N

Q_RES_0402LF-0,5%,1/16W,CHIP,CA  I156  R4741
   1 PRSNT_CABLE_SWB_B1_ISO_N      A @S9S_MB_2U_LIB.S9S_MB_2U(SCH_1):PRSNT_CABLE_SWB_B1_ISO_N
   2 PRSNT_CABLE_SWB_B1_ISO_R_N      B @S9S_MB_2U_LIB.S9S_MB_2U(SCH_1):PRSNT_CABLE_SWB_B1_ISO_R_N

Q_RES_0402LF-0,5%,1/16W,CHIP,CA  I161  R4742
   1 PRSNT_CABLE_GPU_A1_ISO_N      A @S9S_MB_2U_LIB.S9S_MB_2U(SCH_1):PRSNT_CABLE_GPU_A1_ISO_N
   2 PRSNT_CABLE_GPU_A1_ISO_R1_N      B @S9S_MB_2U_LIB.S9S_MB_2U(SCH_1):PRSNT_CABLE_GPU_A1_ISO_R1_N

Q_RES_0402LF-0,5%,1/16W,CHIP,CA  I164  R4802
   1 PRSNT_CABLE_GPU_A3_ISO_N      A @S9S_MB_2U_LIB.S9S_MB_2U(SCH_1):PRSNT_CABLE_GPU_A3_ISO_N
   2 PRSNT_CABLE_GPU_A3_ISO_R_N      B @S9S_MB_2U_LIB.S9S_MB_2U(SCH_1):PRSNT_CABLE_GPU_A3_ISO_R_N


DRAWING: @S9S_MB_2U_LIB.S9S_MB_2U(SCH_1):PAGE140 

74LVC2G17GW-74LVC2G17GW,SMLF,IA  I65  U195
   5 P3V3_AUX    VCC @S9S_MB_2U_LIB.S9S_MB_2U(SCH_1):P3V3_AUX
   4 RST_SWB_BIC_BUF_R_N     B1 @S9S_MB_2U_LIB.S9S_MB_2U(SCH_1):RST_SWB_BIC_BUF_R_N
   2    GND    GND @S9S_MB_2U_LIB.S9S_MB_2U(SCH_1):GND
   1 BMC_MONITER_R     A0 @S9S_MB_2U_LIB.S9S_MB_2U(SCH_1):BMC_MONITER_R
   3 RST_SWB_BIC_R_N     A1 @S9S_MB_2U_LIB.S9S_MB_2U(SCH_1):RST_SWB_BIC_R_N
   6 BMC_MONITER_BUF_R     B0 @S9S_MB_2U_LIB.S9S_MB_2U(SCH_1):BMC_MONITER_BUF_R

Q_RES_0402LF-100K,1%,1/16W,EMPA  I68  R2815
   1 P3V3_AUX      A @S9S_MB_2U_LIB.S9S_MB_2U(SCH_1):P3V3_AUX
   2 BMC_MONITER_R      B @S9S_MB_2U_LIB.S9S_MB_2U(SCH_1):BMC_MONITER_R

Q_RES_0402LF-4.7K,5%,1/16W,EMPA  I78  R2820
   1 P3V3_AUX      A @S9S_MB_2U_LIB.S9S_MB_2U(SCH_1):P3V3_AUX
   2 BMC_MONITER_BUF_R      B @S9S_MB_2U_LIB.S9S_MB_2U(SCH_1):BMC_MONITER_BUF_R

Q_CAP_0402-0.1UF,25V,10%,X7R,CA  I89  C1769
   1 P3V3_AUX      A @S9S_MB_2U_LIB.S9S_MB_2U(SCH_1):P3V3_AUX
   2    GND      B @S9S_MB_2U_LIB.S9S_MB_2U(SCH_1):GND

Q_RES_0402LF-4.7K,5%,1/16W,CHIA  I92  R2915
   1 BMC_MONITER_R      A @S9S_MB_2U_LIB.S9S_MB_2U(SCH_1):BMC_MONITER_R
   2    GND      B @S9S_MB_2U_LIB.S9S_MB_2U(SCH_1):GND

Q_RES_0402LF-4.7K,5%,1/16W,EMPA  I93  R2916
   1 RST_SWB_BIC_R_N      A @S9S_MB_2U_LIB.S9S_MB_2U(SCH_1):RST_SWB_BIC_R_N
   2    GND      B @S9S_MB_2U_LIB.S9S_MB_2U(SCH_1):GND

Q_RES_0402LF-4.7K,5%,1/16W,CHIA  I121  R2926
   1 BMC_MONITER_BUF_R      A @S9S_MB_2U_LIB.S9S_MB_2U(SCH_1):BMC_MONITER_BUF_R
   2    GND      B @S9S_MB_2U_LIB.S9S_MB_2U(SCH_1):GND

74LVC2G17GW-74LVC2G17GW,SMLF,IA  I127  U196
   5 P3V3_AUX    VCC @S9S_MB_2U_LIB.S9S_MB_2U(SCH_1):P3V3_AUX
   4 GPU_FPGA_RST_R1_BUF_N     B1 @S9S_MB_2U_LIB.S9S_MB_2U(SCH_1):GPU_FPGA_RST_R1_BUF_N
   2    GND    GND @S9S_MB_2U_LIB.S9S_MB_2U(SCH_1):GND
   1 FM_GPU_PWR_EN_R     A0 @S9S_MB_2U_LIB.S9S_MB_2U(SCH_1):FM_GPU_PWR_EN_R
   3 GPU_FPGA_RST_R_N     A1 @S9S_MB_2U_LIB.S9S_MB_2U(SCH_1):GPU_FPGA_RST_R_N
   6 FM_GPU_PWR_EN_R1     B0 @S9S_MB_2U_LIB.S9S_MB_2U(SCH_1):FM_GPU_PWR_EN_R1

Q_CAP_0402-0.1UF,25V,10%,X7R,CA  I140  C1770
   1 P3V3_AUX      A @S9S_MB_2U_LIB.S9S_MB_2U(SCH_1):P3V3_AUX
   2    GND      B @S9S_MB_2U_LIB.S9S_MB_2U(SCH_1):GND

Q_RES_0402LF-4.7K,5%,1/16W,EMPA  I147  R2912
   1 P3V3_AUX      A @S9S_MB_2U_LIB.S9S_MB_2U(SCH_1):P3V3_AUX
   2 FM_GPU_PWR_EN_R1      B @S9S_MB_2U_LIB.S9S_MB_2U(SCH_1):FM_GPU_PWR_EN_R1

Q_RES_0402LF-4.7K,5%,1/16W,EMPA  I153  R2911
   1 P3V3_AUX      A @S9S_MB_2U_LIB.S9S_MB_2U(SCH_1):P3V3_AUX
   2 RST_SWB_BIC_BUF_R_N      B @S9S_MB_2U_LIB.S9S_MB_2U(SCH_1):RST_SWB_BIC_BUF_R_N

Q_RES_0402LF-4.7K,5%,1/16W,CHIA  I160  R2937
   1 FM_GPU_PWR_EN_R      A @S9S_MB_2U_LIB.S9S_MB_2U(SCH_1):FM_GPU_PWR_EN_R
   2    GND      B @S9S_MB_2U_LIB.S9S_MB_2U(SCH_1):GND

Q_RES_0402LF-100K,1%,1/16W,EMPA  I162  R2936
   1 P3V3_AUX      A @S9S_MB_2U_LIB.S9S_MB_2U(SCH_1):P3V3_AUX
   2 FM_GPU_PWR_EN_R      B @S9S_MB_2U_LIB.S9S_MB_2U(SCH_1):FM_GPU_PWR_EN_R

Q_CAP_0402-0.1UF,25V,10%,X7R,CA  I166  C1803
   1 P3V3_AUX      A @S9S_MB_2U_LIB.S9S_MB_2U(SCH_1):P3V3_AUX
   2    GND      B @S9S_MB_2U_LIB.S9S_MB_2U(SCH_1):GND

Q_RES_0402LF-0,5%,1/16W,CHIP,CA  I170  R3033
   1 UART_BMC_BIC_RX      A @S9S_MB_2U_LIB.S9S_MB_2U(SCH_1):UART_BMC_BIC_RX
   2 UART_BMC_BIC_R_RX      B @S9S_MB_2U_LIB.S9S_MB_2U(SCH_1):UART_BMC_BIC_R_RX

Q_RES_0402LF-4.7K,5%,1/16W,EMPA  I190  R3317
   1 P3V3_AUX      A @S9S_MB_2U_LIB.S9S_MB_2U(SCH_1):P3V3_AUX
   2 GPU_FPGA_RST_R1_BUF_N      B @S9S_MB_2U_LIB.S9S_MB_2U(SCH_1):GPU_FPGA_RST_R1_BUF_N

Q_RES_0402LF-10K,1%,1/16W,CHIPA  I191  R3509
   1 GPU_FPGA_RST_R1_BUF_N      A @S9S_MB_2U_LIB.S9S_MB_2U(SCH_1):GPU_FPGA_RST_R1_BUF_N
   2    GND      B @S9S_MB_2U_LIB.S9S_MB_2U(SCH_1):GND

Q_RES_0402LF-10K,1%,1/16W,CHIPA  I192  R3507
   1 GPU_FPGA_RST_R_N      A @S9S_MB_2U_LIB.S9S_MB_2U(SCH_1):GPU_FPGA_RST_R_N
   2    GND      B @S9S_MB_2U_LIB.S9S_MB_2U(SCH_1):GND

Q_RES_0402LF-4.7K,5%,1/16W,EMPA  I193  R3506
   1 P3V3_AUX      A @S9S_MB_2U_LIB.S9S_MB_2U(SCH_1):P3V3_AUX
   2 GPU_FPGA_RST_R_N      B @S9S_MB_2U_LIB.S9S_MB_2U(SCH_1):GPU_FPGA_RST_R_N

Q_RES_0402LF-54.9K,1%,1/16W,CHA  I194  R3508
   1 FM_GPU_PWR_EN_R1      A @S9S_MB_2U_LIB.S9S_MB_2U(SCH_1):FM_GPU_PWR_EN_R1
   2    GND      B @S9S_MB_2U_LIB.S9S_MB_2U(SCH_1):GND

74LVC1G126SE7-74LVC1G126SE-7,SA  I195  U204
   2 UART_BMC_BIC_R_RX      A @S9S_MB_2U_LIB.S9S_MB_2U(SCH_1):UART_BMC_BIC_R_RX
   4 UART_BMC_BIC_R_BUF_RX      Y @S9S_MB_2U_LIB.S9S_MB_2U(SCH_1):UART_BMC_BIC_R_BUF_RX
   5 P3V3_AUX    VCC @S9S_MB_2U_LIB.S9S_MB_2U(SCH_1):P3V3_AUX
   3    GND    GND @S9S_MB_2U_LIB.S9S_MB_2U(SCH_1):GND
   1 FM_UART_EN     OE @S9S_MB_2U_LIB.S9S_MB_2U(SCH_1):FM_UART_EN

Q_RES_0402LF-33.2,1%,1/16W,CHIA  I197  R3036
   1 UART_BMC_BIC_R_BUF_RX      A @S9S_MB_2U_LIB.S9S_MB_2U(SCH_1):UART_BMC_BIC_R_BUF_RX
   2 UART_BMC_BIC_BUF_RX      B @S9S_MB_2U_LIB.S9S_MB_2U(SCH_1):UART_BMC_BIC_BUF_RX

Q_RES_0402LF-4.7K,5%,1/16W,CHIA  I198  R2909
   1 P3V3_AUX      A @S9S_MB_2U_LIB.S9S_MB_2U(SCH_1):P3V3_AUX
   2 RST_SWB_BIC_R_N      B @S9S_MB_2U_LIB.S9S_MB_2U(SCH_1):RST_SWB_BIC_R_N

Q_RES_0402LF-100K,1%,1/16W,CHIA  I200  R4515
   1 P3V3_AUX      A @S9S_MB_2U_LIB.S9S_MB_2U(SCH_1):P3V3_AUX
   2 UART_BMC_BIC_RX      B @S9S_MB_2U_LIB.S9S_MB_2U(SCH_1):UART_BMC_BIC_RX

Q_RES_0402LF-100K,1%,1/16W,EMPA  I202  R4173
   1 P3V3_AUX      A @S9S_MB_2U_LIB.S9S_MB_2U(SCH_1):P3V3_AUX
   2 UART_BMC_BIC_R_BUF_RX      B @S9S_MB_2U_LIB.S9S_MB_2U(SCH_1):UART_BMC_BIC_R_BUF_RX

Q_RES_0402LF-100K,1%,1/16W,CHIA  I203  R2927
   1 RST_SWB_BIC_BUF_R_N      A @S9S_MB_2U_LIB.S9S_MB_2U(SCH_1):RST_SWB_BIC_BUF_R_N
   2    GND      B @S9S_MB_2U_LIB.S9S_MB_2U(SCH_1):GND

Q_RES_0402LF-49.9,1%,1/16W,CHIA  I204  R2925
   1 FM_GPU_PWR_EN_R1      A @S9S_MB_2U_LIB.S9S_MB_2U(SCH_1):FM_GPU_PWR_EN_R1
   2 FM_GPU_PWR_EN_R_BUF      B @S9S_MB_2U_LIB.S9S_MB_2U(SCH_1):FM_GPU_PWR_EN_R_BUF

Q_RES_0402LF-49.9,1%,1/16W,CHIA  I205  R3315
   1 GPU_FPGA_RST_R1_BUF_N      A @S9S_MB_2U_LIB.S9S_MB_2U(SCH_1):GPU_FPGA_RST_R1_BUF_N
   2 GPU_FPGA_RST_R_BUF_N      B @S9S_MB_2U_LIB.S9S_MB_2U(SCH_1):GPU_FPGA_RST_R_BUF_N

Q_RES_0402LF-49.9,1%,1/16W,CHIA  I206  R2917
   1 BMC_MONITER_BUF_R      A @S9S_MB_2U_LIB.S9S_MB_2U(SCH_1):BMC_MONITER_BUF_R
   2 BMC_MONITER_BUF      B @S9S_MB_2U_LIB.S9S_MB_2U(SCH_1):BMC_MONITER_BUF

Q_RES_0402LF-49.9,1%,1/16W,CHIA  I207  R2924
   1 RST_SWB_BIC_BUF_R_N      A @S9S_MB_2U_LIB.S9S_MB_2U(SCH_1):RST_SWB_BIC_BUF_R_N
   2 RST_SWB_BIC_BUF_N      B @S9S_MB_2U_LIB.S9S_MB_2U(SCH_1):RST_SWB_BIC_BUF_N

Q_RES_0402LF-33.2,1%,1/16W,CHIA  I208  R3063
   1 FM_PDB_BUF_EN_R      A @S9S_MB_2U_LIB.S9S_MB_2U(SCH_1):FM_PDB_BUF_EN_R
   2 FM_UART_EN      B @S9S_MB_2U_LIB.S9S_MB_2U(SCH_1):FM_UART_EN


DRAWING: @S9S_MB_2U_LIB.S9S_MB_2U(SCH_1):PAGE230 

Q_CAP_0402-0.1UF,25V,10%,X7R,CA  I14  C1775
   1 P3V3_AUX      A @S9S_MB_2U_LIB.S9S_MB_2U(SCH_1):P3V3_AUX
   2    GND      B @S9S_MB_2U_LIB.S9S_MB_2U(SCH_1):GND

Q_RES_0402LF-33.2,1%,1/16W,CHIA  I24  R2944
   1 FM_GPU_HSC_EN_BUF_R      A @S9S_MB_2U_LIB.S9S_MB_2U(SCH_1):FM_GPU_HSC_EN_BUF_R
   2 FM_GPU_HSC_EN_BUF      B @S9S_MB_2U_LIB.S9S_MB_2U(SCH_1):FM_GPU_HSC_EN_BUF

Q_RES_0402LF-4.7K,5%,1/16W,EMPA  I25  R2946
   1 P3V3_AUX      A @S9S_MB_2U_LIB.S9S_MB_2U(SCH_1):P3V3_AUX
   2 FM_GPU_HSC_EN_BUF_R      B @S9S_MB_2U_LIB.S9S_MB_2U(SCH_1):FM_GPU_HSC_EN_BUF_R

Q_RES_0402LF-4.7K,5%,1/16W,EMPA  I28  R2940
   1 P3V3_AUX      A @S9S_MB_2U_LIB.S9S_MB_2U(SCH_1):P3V3_AUX
   2 FM_GPU_HSC_EN      B @S9S_MB_2U_LIB.S9S_MB_2U(SCH_1):FM_GPU_HSC_EN

Q_RES_0402LF-100K,1%,1/16W,CHIA  I29  R2941
   1 FM_GPU_HSC_EN      A @S9S_MB_2U_LIB.S9S_MB_2U(SCH_1):FM_GPU_HSC_EN
   2    GND      B @S9S_MB_2U_LIB.S9S_MB_2U(SCH_1):GND

Q_RES_0402LF-4.7K,5%,1/16W,EMPA  I30  R2948
   1 FM_GPU_HSC_EN_BUF_R      A @S9S_MB_2U_LIB.S9S_MB_2U(SCH_1):FM_GPU_HSC_EN_BUF_R
   2    GND      B @S9S_MB_2U_LIB.S9S_MB_2U(SCH_1):GND

74LVC1G08W57-74LVC1G08W5-7,SMLA  I31  U278
   1 FM_GPU_HSC_EN      A @S9S_MB_2U_LIB.S9S_MB_2U(SCH_1):FM_GPU_HSC_EN
   2 GPU_PRSNT_R      B @S9S_MB_2U_LIB.S9S_MB_2U(SCH_1):GPU_PRSNT_R
   3    GND    GND @S9S_MB_2U_LIB.S9S_MB_2U(SCH_1):GND
   4 FM_GPU_HSC_EN_BUF_R      Y @S9S_MB_2U_LIB.S9S_MB_2U(SCH_1):FM_GPU_HSC_EN_BUF_R
   5 P3V3_AUX    VCC @S9S_MB_2U_LIB.S9S_MB_2U(SCH_1):P3V3_AUX

Q_RES_0402LF-0,5%,1/16W,CHIP,CA  I34  R3770
   1 GPU_PRSNT      A @S9S_MB_2U_LIB.S9S_MB_2U(SCH_1):GPU_PRSNT
   2 GPU_PRSNT_R      B @S9S_MB_2U_LIB.S9S_MB_2U(SCH_1):GPU_PRSNT_R

74LVC2G07DW7-74LVC2G07DW-7,SMLA  I37  U308
   1 PWRGD_P3V3_AUX_PDB_R     1A @S9S_MB_2U_LIB.S9S_MB_2U(SCH_1):PWRGD_P3V3_AUX_PDB_R
   3     NC     2A     NC
   6 PWRGD_P3V3_AUX_PDB_BUF_R     1Y @S9S_MB_2U_LIB.S9S_MB_2U(SCH_1):PWRGD_P3V3_AUX_PDB_BUF_R
   4     NC     2Y     NC
   2    GND    GND @S9S_MB_2U_LIB.S9S_MB_2U(SCH_1):GND
   5 P3V3_AUX    VCC @S9S_MB_2U_LIB.S9S_MB_2U(SCH_1):P3V3_AUX

Q_CAP_0402-0.1UF,25V,10%,X7R,CA  I40  C2283
   1 P3V3_AUX      A @S9S_MB_2U_LIB.S9S_MB_2U(SCH_1):P3V3_AUX
   2    GND      B @S9S_MB_2U_LIB.S9S_MB_2U(SCH_1):GND

Q_RES_0402LF-0,5%,1/16W,CHIP,CA  I41  R4268
   1 PWRGD_P3V3_AUX_PDB      A @S9S_MB_2U_LIB.S9S_MB_2U(SCH_1):PWRGD_P3V3_AUX_PDB
   2 PWRGD_P3V3_AUX_PDB_R      B @S9S_MB_2U_LIB.S9S_MB_2U(SCH_1):PWRGD_P3V3_AUX_PDB_R

Q_RES_0402LF-4.7K,5%,1/16W,EMPA  I43  R4265
   1 PWRGD_P3V3_AUX_PDB_BUF_R      A @S9S_MB_2U_LIB.S9S_MB_2U(SCH_1):PWRGD_P3V3_AUX_PDB_BUF_R
   2    GND      B @S9S_MB_2U_LIB.S9S_MB_2U(SCH_1):GND

Q_RES_0402LF-4.7K,5%,1/16W,CHIA  I47  R4264
   1 P3V3_AUX      A @S9S_MB_2U_LIB.S9S_MB_2U(SCH_1):P3V3_AUX
   2 PWRGD_P3V3_AUX_PDB_BUF_R      B @S9S_MB_2U_LIB.S9S_MB_2U(SCH_1):PWRGD_P3V3_AUX_PDB_BUF_R

Q_RES_0402LF-33.2,1%,1/16W,CHIA  I48  R4266
   1 PWRGD_P3V3_AUX_PDB_BUF_R      A @S9S_MB_2U_LIB.S9S_MB_2U(SCH_1):PWRGD_P3V3_AUX_PDB_BUF_R
   2 PWRGD_P3V3_AUX_PDB_BUF      B @S9S_MB_2U_LIB.S9S_MB_2U(SCH_1):PWRGD_P3V3_AUX_PDB_BUF

Q_RES_0402LF-100K,1%,1/16W,CHIA  I50  R4552
   1 HPDB_HSC_PWRGD      A @S9S_MB_2U_LIB.S9S_MB_2U(SCH_1):HPDB_HSC_PWRGD
   2    GND      B @S9S_MB_2U_LIB.S9S_MB_2U(SCH_1):GND

Q_RES_0402LF-54.9K,1%,1/16W,EMA  I51  R4551
   1 P3V3_AUX      A @S9S_MB_2U_LIB.S9S_MB_2U(SCH_1):P3V3_AUX
   2 HPDB_HSC_PWRGD      B @S9S_MB_2U_LIB.S9S_MB_2U(SCH_1):HPDB_HSC_PWRGD

MOSFET_NCH_DUAL-PJT138K,SMLF,IA  I53  Q145
   1    GND     S1 @S9S_MB_2U_LIB.S9S_MB_2U(SCH_1):GND
   2 HPDB_HSC_PWRGD     G1 @S9S_MB_2U_LIB.S9S_MB_2U(SCH_1):HPDB_HSC_PWRGD
   6 HPDB_HSC_PWRGD_N     D1 @S9S_MB_2U_LIB.S9S_MB_2U(SCH_1):HPDB_HSC_PWRGD_N

Q_RES_0402LF-4.7K,5%,1/16W,CHIA  I55  R4553
   1 P3V3_AUX      A @S9S_MB_2U_LIB.S9S_MB_2U(SCH_1):P3V3_AUX
   2 HPDB_HSC_PWRGD_N      B @S9S_MB_2U_LIB.S9S_MB_2U(SCH_1):HPDB_HSC_PWRGD_N

MOSFET_NCH_DUAL-PJT138K,SMLF,IA  I58  Q145
   3 HPDB_HSC_PWRGD_ISO     D2 @S9S_MB_2U_LIB.S9S_MB_2U(SCH_1):HPDB_HSC_PWRGD_ISO
   5 HPDB_HSC_PWRGD_N     G2 @S9S_MB_2U_LIB.S9S_MB_2U(SCH_1):HPDB_HSC_PWRGD_N
   4    GND     S2 @S9S_MB_2U_LIB.S9S_MB_2U(SCH_1):GND

Q_RES_0402LF-4.7K,5%,1/16W,CHIA  I59  R4554
   1 P3V3_AUX      A @S9S_MB_2U_LIB.S9S_MB_2U(SCH_1):P3V3_AUX
   2 HPDB_HSC_PWRGD_ISO      B @S9S_MB_2U_LIB.S9S_MB_2U(SCH_1):HPDB_HSC_PWRGD_ISO

Q_CAP_0402-1000PF,50V,5%,EMPTYA  I62  C2342
   1 HPDB_HSC_PWRGD_ISO      A @S9S_MB_2U_LIB.S9S_MB_2U(SCH_1):HPDB_HSC_PWRGD_ISO
   2    GND      B @S9S_MB_2U_LIB.S9S_MB_2U(SCH_1):GND


DRAWING: @S9S_MB_2U_LIB.S9S_MB_2U(SCH_1):PAGE155 

Q_RES_0402LF-0,5%,1/16W,CHIP,CA  I78  R2787
   1 USB2_HUB_SWB_DN      A @S9S_MB_2U_LIB.S9S_MB_2U(SCH_1):USB2_HUB_SWB_DN
   2 USB2_HUB_BUF_SWB_R_DN      B @S9S_MB_2U_LIB.S9S_MB_2U(SCH_1):USB2_HUB_BUF_SWB_R_DN

Q_RES_0402LF-0,5%,1/16W,CHIP,CA  I79  R2786
   1 USB2_HUB_SWB_DP      A @S9S_MB_2U_LIB.S9S_MB_2U(SCH_1):USB2_HUB_SWB_DP
   2 USB2_HUB_BUF_SWB_R_DP      B @S9S_MB_2U_LIB.S9S_MB_2U(SCH_1):USB2_HUB_BUF_SWB_R_DP

Q_CAP_0402-0.1UF,25V,10%,EMPTYA  I81  C5232
   1 PD_U5201_RSTN      A @S9S_MB_2U_LIB.S9S_MB_2U(SCH_1):PD_U5201_RSTN
   2    GND      B @S9S_MB_2U_LIB.S9S_MB_2U(SCH_1):GND

Q_RES_0402LF-3.9K,5%,1/16W,EMPA  I83  R5238
   1 PD_U5201_EQ      A @S9S_MB_2U_LIB.S9S_MB_2U(SCH_1):PD_U5201_EQ
   2    GND      B @S9S_MB_2U_LIB.S9S_MB_2U(SCH_1):GND

TUSB211IRWBR-TUSB211IRWBR,SMLFA  I84  U5201
   5 PD_U5201_RSTN   RSTN @S9S_MB_2U_LIB.S9S_MB_2U(SCH_1):PD_U5201_RSTN
   8 USB2_HUB_BUF_SWB_R_DN    D2M @S9S_MB_2U_LIB.S9S_MB_2U(SCH_1):USB2_HUB_BUF_SWB_R_DN
  11 PD_U5201_VREG   VREG @S9S_MB_2U_LIB.S9S_MB_2U(SCH_1):PD_U5201_VREG
   3 TP_USB2_TEST   TEST @S9S_MB_2U_LIB.S9S_MB_2U(SCH_1):TP_USB2_TEST
  12 P3V3_AUX    VCC @S9S_MB_2U_LIB.S9S_MB_2U(SCH_1):P3V3_AUX
   9 TP_USB2_ENA_HS ENA_HS @S9S_MB_2U_LIB.S9S_MB_2U(SCH_1):TP_USB2_ENA_HS
   4 TP_USB2_CD     CD @S9S_MB_2U_LIB.S9S_MB_2U(SCH_1):TP_USB2_CD
   1 USB2_HUB_BUF_SWB_R_DN    D1M @S9S_MB_2U_LIB.S9S_MB_2U(SCH_1):USB2_HUB_BUF_SWB_R_DN
   2 USB2_HUB_BUF_SWB_R_DP    D1P @S9S_MB_2U_LIB.S9S_MB_2U(SCH_1):USB2_HUB_BUF_SWB_R_DP
   7 USB2_HUB_BUF_SWB_R_DP    D2P @S9S_MB_2U_LIB.S9S_MB_2U(SCH_1):USB2_HUB_BUF_SWB_R_DP
   6 PD_U5201_EQ     EQ @S9S_MB_2U_LIB.S9S_MB_2U(SCH_1):PD_U5201_EQ
  10    GND    GND @S9S_MB_2U_LIB.S9S_MB_2U(SCH_1):GND

Q_CAP_0402-0.1UF,25V,10%,EMPTYA  I87  C5236
   1 PD_U5201_VREG      A @S9S_MB_2U_LIB.S9S_MB_2U(SCH_1):PD_U5201_VREG
   2    GND      B @S9S_MB_2U_LIB.S9S_MB_2U(SCH_1):GND

Q_CAP_C0402-1UF,25V,10%,EMPTY,A  I88  C5229
   1 P3V3_AUX      A @S9S_MB_2U_LIB.S9S_MB_2U(SCH_1):P3V3_AUX
   2    GND      B @S9S_MB_2U_LIB.S9S_MB_2U(SCH_1):GND

Q_RES_0402LF-0,5%,1/16W,CHIP,CA  I90  R5236
   1 USB2_HUB_BUF_SWB_R_DN      A @S9S_MB_2U_LIB.S9S_MB_2U(SCH_1):USB2_HUB_BUF_SWB_R_DN
   2 USB2_HUB_BUF_SWB_DN      B @S9S_MB_2U_LIB.S9S_MB_2U(SCH_1):USB2_HUB_BUF_SWB_DN

Q_RES_0402LF-0,5%,1/16W,CHIP,CA  I91  R5234
   1 USB2_HUB_BUF_SWB_R_DP      A @S9S_MB_2U_LIB.S9S_MB_2U(SCH_1):USB2_HUB_BUF_SWB_R_DP
   2 USB2_HUB_BUF_SWB_DP      B @S9S_MB_2U_LIB.S9S_MB_2U(SCH_1):USB2_HUB_BUF_SWB_DP

Q_CAP_0402-0.1UF,25V,10%,EMPTYA  I92  C5234
   1 P3V3_AUX      A @S9S_MB_2U_LIB.S9S_MB_2U(SCH_1):P3V3_AUX
   2    GND      B @S9S_MB_2U_LIB.S9S_MB_2U(SCH_1):GND

Q_RES_0402LF-0,5%,1/16W,EMPTY,A  I96  R2790
   1 USB2_HOST_BMC_B_DP      A @S9S_MB_2U_LIB.S9S_MB_2U(SCH_1):USB2_HOST_BMC_B_DP
   2 USB2_HOST_BMC_B_BUF_DP      B @S9S_MB_2U_LIB.S9S_MB_2U(SCH_1):USB2_HOST_BMC_B_BUF_DP

Q_RES_0402LF-0,5%,1/16W,EMPTY,A  I97  R2791
   1 USB2_HOST_BMC_B_DN      A @S9S_MB_2U_LIB.S9S_MB_2U(SCH_1):USB2_HOST_BMC_B_DN
   2 USB2_HOST_BMC_B_BUF_DN      B @S9S_MB_2U_LIB.S9S_MB_2U(SCH_1):USB2_HOST_BMC_B_BUF_DN

Q_RES_0402LF-0,5%,1/16W,EMPTY,A  I98  R2789
   1 USB2_HOST_BMC_B_BUF_DN      A @S9S_MB_2U_LIB.S9S_MB_2U(SCH_1):USB2_HOST_BMC_B_BUF_DN
   2 USB2_HUB_BUF_SWB_R_DN      B @S9S_MB_2U_LIB.S9S_MB_2U(SCH_1):USB2_HUB_BUF_SWB_R_DN

Q_RES_0402LF-0,5%,1/16W,EMPTY,A  I99  R2788
   1 USB2_HOST_BMC_B_BUF_DP      A @S9S_MB_2U_LIB.S9S_MB_2U(SCH_1):USB2_HOST_BMC_B_BUF_DP
   2 USB2_HUB_BUF_SWB_R_DP      B @S9S_MB_2U_LIB.S9S_MB_2U(SCH_1):USB2_HUB_BUF_SWB_R_DP

GL852GOHY60-GL852G-OHY60,SMLF,A  I100  U268
  10 USB_HUB_XTAL_IN     X1 @S9S_MB_2U_LIB.S9S_MB_2U(SCH_1):USB_HUB_XTAL_IN
  11 USB_HUB_XTAL_OUT     X2 @S9S_MB_2U_LIB.S9S_MB_2U(SCH_1):USB_HUB_XTAL_OUT
  18 USB_HUB_TEST TEST||SCL @S9S_MB_2U_LIB.S9S_MB_2U(SCH_1):USB_HUB_TEST
  26 NC_USB_HUB_SDA    SDA @S9S_MB_2U_LIB.S9S_MB_2U(SCH_1):NC_USB_HUB_SDA
  27 P3V3_AUX_USB_HUB     V5 @S9S_MB_2U_LIB.S9S_MB_2U(SCH_1):P3V3_AUX_USB_HUB
  28 P3V3_AUX_USB_HUB    V33 @S9S_MB_2U_LIB.S9S_MB_2U(SCH_1):P3V3_AUX_USB_HUB
   5 P3V3_AUX_USB_HUB AVDD<0> @S9S_MB_2U_LIB.S9S_MB_2U(SCH_1):P3V3_AUX_USB_HUB
   9 P3V3_AUX_USB_HUB AVDD<1> @S9S_MB_2U_LIB.S9S_MB_2U(SCH_1):P3V3_AUX_USB_HUB
  14 P3V3_AUX_USB_HUB AVDD<2> @S9S_MB_2U_LIB.S9S_MB_2U(SCH_1):P3V3_AUX_USB_HUB
  21 USB_HUB_DVDD   DVDD @S9S_MB_2U_LIB.S9S_MB_2U(SCH_1):USB_HUB_DVDD
  TH    GND     TH @S9S_MB_2U_LIB.S9S_MB_2U(SCH_1):GND
  25 USB_HUB_OVCUR1 OVCUR1#||SMC @S9S_MB_2U_LIB.S9S_MB_2U(SCH_1):USB_HUB_OVCUR1
  24 USB_HUB_OVCUR2 OVCUR2#||SMD @S9S_MB_2U_LIB.S9S_MB_2U(SCH_1):USB_HUB_OVCUR2
  20 USB_HUB_OVCUR3 OVCUR3# @S9S_MB_2U_LIB.S9S_MB_2U(SCH_1):USB_HUB_OVCUR3
  19 USB_HUB_OVCUR4 OVCUR4# @S9S_MB_2U_LIB.S9S_MB_2U(SCH_1):USB_HUB_OVCUR4
  17 RST_USB_HUB_R_N RESET# @S9S_MB_2U_LIB.S9S_MB_2U(SCH_1):RST_USB_HUB_R_N
  23 USB_HUB_PGANG  PGANG @S9S_MB_2U_LIB.S9S_MB_2U(SCH_1):USB_HUB_PGANG
  22 USB_HUB_PSELF  PSELF @S9S_MB_2U_LIB.S9S_MB_2U(SCH_1):USB_HUB_PSELF
   8 USB_HUB_RREF   RREF @S9S_MB_2U_LIB.S9S_MB_2U(SCH_1):USB_HUB_RREF
   2 USB2_P0_R_DP    DP0 @S9S_MB_2U_LIB.S9S_MB_2U(SCH_1):USB2_P0_R_DP
   1 USB2_P0_R_DN    DM0 @S9S_MB_2U_LIB.S9S_MB_2U(SCH_1):USB2_P0_R_DN
   4 USB2_HUB_SWB_DP    DP1 @S9S_MB_2U_LIB.S9S_MB_2U(SCH_1):USB2_HUB_SWB_DP
   3 USB2_HUB_SWB_DN    DM1 @S9S_MB_2U_LIB.S9S_MB_2U(SCH_1):USB2_HUB_SWB_DN
   7 NC_USB_HUB_DP2    DP2 @S9S_MB_2U_LIB.S9S_MB_2U(SCH_1):NC_USB_HUB_DP2
   6 NC_USB_HUB_DM2    DM2 @S9S_MB_2U_LIB.S9S_MB_2U(SCH_1):NC_USB_HUB_DM2
  13 NC_USB_HUB_DP3    DP3 @S9S_MB_2U_LIB.S9S_MB_2U(SCH_1):NC_USB_HUB_DP3
  12 NC_USB_HUB_DM3    DM3 @S9S_MB_2U_LIB.S9S_MB_2U(SCH_1):NC_USB_HUB_DM3
  16 NC_USB_HUB_DP4    DP4 @S9S_MB_2U_LIB.S9S_MB_2U(SCH_1):NC_USB_HUB_DP4
  15 NC_USB_HUB_DM4    DM4 @S9S_MB_2U_LIB.S9S_MB_2U(SCH_1):NC_USB_HUB_DM4

Q_RES_0402LF-0,5%,1/16W,CHIP,CA  I137  R3652
   1 USB2_P0_R_DN      A @S9S_MB_2U_LIB.S9S_MB_2U(SCH_1):USB2_P0_R_DN
   2 USB2_HOST_BMC_B_DN      B @S9S_MB_2U_LIB.S9S_MB_2U(SCH_1):USB2_HOST_BMC_B_DN

Q_RES_0402LF-0,5%,1/16W,CHIP,CA  I138  R3651
   1 USB2_P0_R_DP      A @S9S_MB_2U_LIB.S9S_MB_2U(SCH_1):USB2_P0_R_DP
   2 USB2_HOST_BMC_B_DP      B @S9S_MB_2U_LIB.S9S_MB_2U(SCH_1):USB2_HOST_BMC_B_DP

Q_RES_0402LF-680,1%,1/16W,CHIPA  I139  R3653
   1 USB_HUB_RREF      A @S9S_MB_2U_LIB.S9S_MB_2U(SCH_1):USB_HUB_RREF
   2    GND      B @S9S_MB_2U_LIB.S9S_MB_2U(SCH_1):GND

Q_CAP_0402-0.1UF,25V,10%,X7R,CA  I142  C2034
   1 P3V3_AUX_USB_HUB      A @S9S_MB_2U_LIB.S9S_MB_2U(SCH_1):P3V3_AUX_USB_HUB
   2    GND      B @S9S_MB_2U_LIB.S9S_MB_2U(SCH_1):GND

Q_CAP_0402-0.1UF,25V,10%,X7R,CA  I143  C2033
   1 P3V3_AUX_USB_HUB      A @S9S_MB_2U_LIB.S9S_MB_2U(SCH_1):P3V3_AUX_USB_HUB
   2    GND      B @S9S_MB_2U_LIB.S9S_MB_2U(SCH_1):GND

Q_CAP_0402-0.1UF,25V,10%,X7R,CA  I145  C2032
   1 P3V3_AUX_USB_HUB      A @S9S_MB_2U_LIB.S9S_MB_2U(SCH_1):P3V3_AUX_USB_HUB
   2    GND      B @S9S_MB_2U_LIB.S9S_MB_2U(SCH_1):GND

Q_CAP_C0402-1UF,25V,10%,X6S,CHA  I147  C2035
   1 P3V3_AUX_USB_HUB      A @S9S_MB_2U_LIB.S9S_MB_2U(SCH_1):P3V3_AUX_USB_HUB
   2    GND      B @S9S_MB_2U_LIB.S9S_MB_2U(SCH_1):GND

Q_CAP_C0402-1UF,25V,10%,X6S,CHA  I148  C2031
   1 P3V3_AUX_USB_HUB      A @S9S_MB_2U_LIB.S9S_MB_2U(SCH_1):P3V3_AUX_USB_HUB
   2    GND      B @S9S_MB_2U_LIB.S9S_MB_2U(SCH_1):GND

Q_RES_0402LF-33.2,1%,1/16W,CHIA  I155  R3654
   1 RST_USB_HUB_N      A @S9S_MB_2U_LIB.S9S_MB_2U(SCH_1):RST_USB_HUB_N
   2 RST_USB_HUB_R_N      B @S9S_MB_2U_LIB.S9S_MB_2U(SCH_1):RST_USB_HUB_R_N

Q_CAP_C0402-1UF,25V,10%,X6S,CHA  I158  C2041
   1 RST_USB_HUB_R_N      A @S9S_MB_2U_LIB.S9S_MB_2U(SCH_1):RST_USB_HUB_R_N
   2    GND      B @S9S_MB_2U_LIB.S9S_MB_2U(SCH_1):GND

Q_RES_0402LF-10K,1%,1/16W,CHIPA  I159  R3660
   1 P3V3_AUX      A @S9S_MB_2U_LIB.S9S_MB_2U(SCH_1):P3V3_AUX
   2 RST_USB_HUB_R_N      B @S9S_MB_2U_LIB.S9S_MB_2U(SCH_1):RST_USB_HUB_R_N

Q_RES_0402LF-0,5%,1/16W,CHIP,CA  I161  R3655
   1 P3V3_AUX      A @S9S_MB_2U_LIB.S9S_MB_2U(SCH_1):P3V3_AUX
   2 P3V3_AUX_USB_HUB      B @S9S_MB_2U_LIB.S9S_MB_2U(SCH_1):P3V3_AUX_USB_HUB

Q_CAP_0402-0.1UF,25V,10%,X7R,CA  I162  C2040
   1 P3V3_AUX_USB_HUB      A @S9S_MB_2U_LIB.S9S_MB_2U(SCH_1):P3V3_AUX_USB_HUB
   2    GND      B @S9S_MB_2U_LIB.S9S_MB_2U(SCH_1):GND

Q_CAP_0402-0.1UF,25V,10%,X7R,CA  I163  C2039
   1 P3V3_AUX_USB_HUB      A @S9S_MB_2U_LIB.S9S_MB_2U(SCH_1):P3V3_AUX_USB_HUB
   2    GND      B @S9S_MB_2U_LIB.S9S_MB_2U(SCH_1):GND

Q_CAP_C0402-10UF,6.3V,20%,X6S,A  I164  C2038
   1 P3V3_AUX_USB_HUB      A @S9S_MB_2U_LIB.S9S_MB_2U(SCH_1):P3V3_AUX_USB_HUB
   2    GND      B @S9S_MB_2U_LIB.S9S_MB_2U(SCH_1):GND

Q_RES_0402LF-0,5%,1/16W,CHIP,CA  I167  R3662
   1 P3V3_AUX_USB_HUB      A @S9S_MB_2U_LIB.S9S_MB_2U(SCH_1):P3V3_AUX_USB_HUB
   2 USB_HUB_DVDD      B @S9S_MB_2U_LIB.S9S_MB_2U(SCH_1):USB_HUB_DVDD

Q_RES_0402LF-100K,1%,1/16W,CHIA  I182  R3665
   1 USB_HUB_PGANG      A @S9S_MB_2U_LIB.S9S_MB_2U(SCH_1):USB_HUB_PGANG
   2    GND      B @S9S_MB_2U_LIB.S9S_MB_2U(SCH_1):GND

Q_RES_0402LF-10K,1%,1/16W,CHIPA  I186  R3663
   1 P3V3_AUX      A @S9S_MB_2U_LIB.S9S_MB_2U(SCH_1):P3V3_AUX
   2 USB_HUB_PSELF      B @S9S_MB_2U_LIB.S9S_MB_2U(SCH_1):USB_HUB_PSELF

Q_RES_0402LF-10K,1%,1/16W,EMPTA  I187  R3664
   1 USB_HUB_PSELF      A @S9S_MB_2U_LIB.S9S_MB_2U(SCH_1):USB_HUB_PSELF
   2    GND      B @S9S_MB_2U_LIB.S9S_MB_2U(SCH_1):GND

Q_RES_0402LF-10K,1%,1/16W,EMPTA  I194  R3656
   1 P3V3_AUX      A @S9S_MB_2U_LIB.S9S_MB_2U(SCH_1):P3V3_AUX
   2 USB_HUB_OVCUR1      B @S9S_MB_2U_LIB.S9S_MB_2U(SCH_1):USB_HUB_OVCUR1

Q_RES_0402LF-10K,1%,1/16W,EMPTA  I195  R3657
   1 P3V3_AUX      A @S9S_MB_2U_LIB.S9S_MB_2U(SCH_1):P3V3_AUX
   2 USB_HUB_OVCUR2      B @S9S_MB_2U_LIB.S9S_MB_2U(SCH_1):USB_HUB_OVCUR2

Q_RES_0402LF-10K,1%,1/16W,EMPTA  I196  R3658
   1 P3V3_AUX      A @S9S_MB_2U_LIB.S9S_MB_2U(SCH_1):P3V3_AUX
   2 USB_HUB_OVCUR3      B @S9S_MB_2U_LIB.S9S_MB_2U(SCH_1):USB_HUB_OVCUR3

Q_RES_0402LF-10K,1%,1/16W,EMPTA  I198  R3659
   1 P3V3_AUX      A @S9S_MB_2U_LIB.S9S_MB_2U(SCH_1):P3V3_AUX
   2 USB_HUB_OVCUR4      B @S9S_MB_2U_LIB.S9S_MB_2U(SCH_1):USB_HUB_OVCUR4

Q_RES_0402LF-0,5%,1/16W,CHIP,CA  I199  R3666
   1 USB_HUB_TEST      A @S9S_MB_2U_LIB.S9S_MB_2U(SCH_1):USB_HUB_TEST
   2    GND      B @S9S_MB_2U_LIB.S9S_MB_2U(SCH_1):GND

Q_XTAL_4P_13BI_24GND-12MHZ,SMLA  I200  Y4
   1 USB_HUB_XTAL_IN     X1 @S9S_MB_2U_LIB.S9S_MB_2U(SCH_1):USB_HUB_XTAL_IN
   2    GND     G1 @S9S_MB_2U_LIB.S9S_MB_2U(SCH_1):GND
   4    GND     G2 @S9S_MB_2U_LIB.S9S_MB_2U(SCH_1):GND
   3 USB_HUB_XTAL_OUT     X2 @S9S_MB_2U_LIB.S9S_MB_2U(SCH_1):USB_HUB_XTAL_OUT

Q_RES_0402LF-47K,0.1%,1/16W,EMA  I201  R3661
   1    GND      A @S9S_MB_2U_LIB.S9S_MB_2U(SCH_1):GND
   2 RST_USB_HUB_R_N      B @S9S_MB_2U_LIB.S9S_MB_2U(SCH_1):RST_USB_HUB_R_N

Q_RES_0402LF-49.9,1%,1/16W,EMPA  I202  R4420
   1 USB2_HOST_BMC_B_DN      A @S9S_MB_2U_LIB.S9S_MB_2U(SCH_1):USB2_HOST_BMC_B_DN
   2    GND      B @S9S_MB_2U_LIB.S9S_MB_2U(SCH_1):GND

Q_RES_0402LF-49.9,1%,1/16W,EMPA  I203  R4419
   1 USB2_HOST_BMC_B_DP      A @S9S_MB_2U_LIB.S9S_MB_2U(SCH_1):USB2_HOST_BMC_B_DP
   2    GND      B @S9S_MB_2U_LIB.S9S_MB_2U(SCH_1):GND

Q_RES_0402LF-49.9,1%,1/16W,EMPA  I208  R4482
   1 USB2_HOST_BMC_B_BUF_DP      A @S9S_MB_2U_LIB.S9S_MB_2U(SCH_1):USB2_HOST_BMC_B_BUF_DP
   2    GND      B @S9S_MB_2U_LIB.S9S_MB_2U(SCH_1):GND

Q_RES_0402LF-49.9,1%,1/16W,EMPA  I206  R4483
   1 USB2_HOST_BMC_B_BUF_DN      A @S9S_MB_2U_LIB.S9S_MB_2U(SCH_1):USB2_HOST_BMC_B_BUF_DN
   2    GND      B @S9S_MB_2U_LIB.S9S_MB_2U(SCH_1):GND

Q_CAP_0402-18PF,50V,5%,C0G,CH0A  I210  C2029
   1 USB_HUB_XTAL_IN      A @S9S_MB_2U_LIB.S9S_MB_2U(SCH_1):USB_HUB_XTAL_IN
   2    GND      B @S9S_MB_2U_LIB.S9S_MB_2U(SCH_1):GND

Q_CAP_0402-18PF,50V,5%,C0G,CH0A  I211  C2030
   1 USB_HUB_XTAL_OUT      A @S9S_MB_2U_LIB.S9S_MB_2U(SCH_1):USB_HUB_XTAL_OUT
   2    GND      B @S9S_MB_2U_LIB.S9S_MB_2U(SCH_1):GND


DRAWING: @S9S_MB_2U_LIB.S9S_MB_2U(SCH_1):PAGE301 

Q_CAP_0402-220PF,50V,10%,EMPTYA  I2  PC2183
   1 HSC_ON      A @S9S_MB_2U_LIB.S9S_MB_2U(SCH_1):HSC_ON
   2 AGND_HSC      B @S9S_MB_2U_LIB.S9S_MB_2U(SCH_1):AGND_HSC

Q_RES_0402LF-2K,0.1%,1/16W,CHIA  I12  PR3915
   1 HSC_CS_2      A @S9S_MB_2U_LIB.S9S_MB_2U(SCH_1):HSC_CS_2
   2 AGND_HSC      B @S9S_MB_2U_LIB.S9S_MB_2U(SCH_1):AGND_HSC

Q_RES_0402LF-2K,0.1%,1/16W,CHIA  I13  PR1101
   1 HSC_IMON      A @S9S_MB_2U_LIB.S9S_MB_2U(SCH_1):HSC_IMON
   2 AGND_HSC      B @S9S_MB_2U_LIB.S9S_MB_2U(SCH_1):AGND_HSC

Q_CAP_0402-1NF,50V,10%,EMPTY,CA  I29  PC2347
   1 HSC_OCREF      A @S9S_MB_2U_LIB.S9S_MB_2U(SCH_1):HSC_OCREF
   2 AGND_HSC      B @S9S_MB_2U_LIB.S9S_MB_2U(SCH_1):AGND_HSC

Q_CAP_C0402-1UF,25V,10%,X6S,CHA  I4  PC2181
   1 HSC_VDD_R_2      A @S9S_MB_2U_LIB.S9S_MB_2U(SCH_1):HSC_VDD_R_2
   2 AGND_HSC      B @S9S_MB_2U_LIB.S9S_MB_2U(SCH_1):AGND_HSC

Q_CAP_C0402-1UF,25V,10%,X6S,CHA  I20  PC1525
   1 HSC_VDD_R_1      A @S9S_MB_2U_LIB.S9S_MB_2U(SCH_1):HSC_VDD_R_1
   2 AGND_HSC      B @S9S_MB_2U_LIB.S9S_MB_2U(SCH_1):AGND_HSC

Q_RES_0402LF-0,5%,1/16W,CHIP,CA  I33  PR3916
   1 HSC_SCREF      A @S9S_MB_2U_LIB.S9S_MB_2U(SCH_1):HSC_SCREF
   2 HSC_SCREF_1      B @S9S_MB_2U_LIB.S9S_MB_2U(SCH_1):HSC_SCREF_1

Q_RES_0402LF-0,5%,1/16W,CHIP,CA  I5  PR3911
   1 HSC_VDD_R_2      A @S9S_MB_2U_LIB.S9S_MB_2U(SCH_1):HSC_VDD_R_2
   2 HSC_VDD      B @S9S_MB_2U_LIB.S9S_MB_2U(SCH_1):HSC_VDD

Q_CAP_0402-1NF,50V,10%,EMPTY,CA  I11  PC2348
   1 HSC_OCREF      A @S9S_MB_2U_LIB.S9S_MB_2U(SCH_1):HSC_OCREF
   2 AGND_HSC      B @S9S_MB_2U_LIB.S9S_MB_2U(SCH_1):AGND_HSC

Q_RES_0402LF-2K,0.1%,1/16W,CHIA  I34  PR3918
   1 HSC_IMON      A @S9S_MB_2U_LIB.S9S_MB_2U(SCH_1):HSC_IMON
   2 AGND_HSC      B @S9S_MB_2U_LIB.S9S_MB_2U(SCH_1):AGND_HSC

Q_RES_0402LF-0,5%,1/16W,CHIP,CA  I39  PR3921
   1 HSC_D_OC_2      A @S9S_MB_2U_LIB.S9S_MB_2U(SCH_1):HSC_D_OC_2
   2 HSC_D_OC_R      B @S9S_MB_2U_LIB.S9S_MB_2U(SCH_1):HSC_D_OC_R

Q_RES_0402LF-0,5%,1/16W,CHIP,CA  I49  PR3919
   1 HSC_D_OC_1      A @S9S_MB_2U_LIB.S9S_MB_2U(SCH_1):HSC_D_OC_1
   2 HSC_D_OC_R      B @S9S_MB_2U_LIB.S9S_MB_2U(SCH_1):HSC_D_OC_R

Q_RES_0402LF-120K,1%,1/16W,CHIA  I15  PR3912
   1 AGND_HSC      A @S9S_MB_2U_LIB.S9S_MB_2U(SCH_1):AGND_HSC
   2 HSC_MODE_2      B @S9S_MB_2U_LIB.S9S_MB_2U(SCH_1):HSC_MODE_2

Q_RES_0402LF-0,5%,1/16W,CHIP,CA  I21  PR3910
   1 HSC_VDD_R_1      A @S9S_MB_2U_LIB.S9S_MB_2U(SCH_1):HSC_VDD_R_1
   2 HSC_VDD      B @S9S_MB_2U_LIB.S9S_MB_2U(SCH_1):HSC_VDD

Q_RES_0402LF-0,5%,1/16W,CHIP,CA  I17  PR3917
   1 HSC_SCREF      A @S9S_MB_2U_LIB.S9S_MB_2U(SCH_1):HSC_SCREF
   2 HSC_SCREF_2      B @S9S_MB_2U_LIB.S9S_MB_2U(SCH_1):HSC_SCREF_2

Q_RES_0402LF-2K,0.1%,1/16W,CHIA  I30  PR3914
   1 HSC_CS_1      A @S9S_MB_2U_LIB.S9S_MB_2U(SCH_1):HSC_CS_1
   2 AGND_HSC      B @S9S_MB_2U_LIB.S9S_MB_2U(SCH_1):AGND_HSC

MP5991GLUZ-MP5991GLU-Z,SMLF,ICA  I35  PU287
   9 P12V_PSU   VIN1 @S9S_MB_2U_LIB.S9S_MB_2U(SCH_1):P12V_PSU
  10 P12V_PSU   VIN2 @S9S_MB_2U_LIB.S9S_MB_2U(SCH_1):P12V_PSU
  11 P12V_PSU   VIN3 @S9S_MB_2U_LIB.S9S_MB_2U(SCH_1):P12V_PSU
  12 P12V_PSU   VIN4 @S9S_MB_2U_LIB.S9S_MB_2U(SCH_1):P12V_PSU
  13 P12V_PSU   VIN5 @S9S_MB_2U_LIB.S9S_MB_2U(SCH_1):P12V_PSU
   4 HSC_ON     ON @S9S_MB_2U_LIB.S9S_MB_2U(SCH_1):HSC_ON
  24 HSC_OCREF  OCREF @S9S_MB_2U_LIB.S9S_MB_2U(SCH_1):HSC_OCREF
  23 HSC_CS_1     CS @S9S_MB_2U_LIB.S9S_MB_2U(SCH_1):HSC_CS_1
  22 HSC_IMON   IMON @S9S_MB_2U_LIB.S9S_MB_2U(SCH_1):HSC_IMON
  21 HSC_VDD_R_1  VDD33 @S9S_MB_2U_LIB.S9S_MB_2U(SCH_1):HSC_VDD_R_1
  20 AGND_HSC    GND @S9S_MB_2U_LIB.S9S_MB_2U(SCH_1):AGND_HSC
  19 HSC_SS     SS @S9S_MB_2U_LIB.S9S_MB_2U(SCH_1):HSC_SS
   5 HSC_FAULT    GOK @S9S_MB_2U_LIB.S9S_MB_2U(SCH_1):HSC_FAULT
  18 HSC_VTEMP  VTEMP @S9S_MB_2U_LIB.S9S_MB_2U(SCH_1):HSC_VTEMP
   1 P12V_AUX  VOUT1 @S9S_MB_2U_LIB.S9S_MB_2U(SCH_1):P12V_AUX
   2 P12V_AUX  VOUT2 @S9S_MB_2U_LIB.S9S_MB_2U(SCH_1):P12V_AUX
  25 P12V_AUX  VOUT3 @S9S_MB_2U_LIB.S9S_MB_2U(SCH_1):P12V_AUX
  26 P12V_AUX  VOUT4 @S9S_MB_2U_LIB.S9S_MB_2U(SCH_1):P12V_AUX
   3 HSC_D_OC_1   D_OC @S9S_MB_2U_LIB.S9S_MB_2U(SCH_1):HSC_D_OC_1
  14 P12V_PSU   VIN6 @S9S_MB_2U_LIB.S9S_MB_2U(SCH_1):P12V_PSU
  15 P12V_PSU   VIN7 @S9S_MB_2U_LIB.S9S_MB_2U(SCH_1):P12V_PSU
  16 P12V_PSU   VIN8 @S9S_MB_2U_LIB.S9S_MB_2U(SCH_1):P12V_PSU
  33 P12V_PSU   VIN9 @S9S_MB_2U_LIB.S9S_MB_2U(SCH_1):P12V_PSU
  27 P12V_AUX  VOUT5 @S9S_MB_2U_LIB.S9S_MB_2U(SCH_1):P12V_AUX
  28 P12V_AUX  VOUT6 @S9S_MB_2U_LIB.S9S_MB_2U(SCH_1):P12V_AUX
  29 P12V_AUX  VOUT7 @S9S_MB_2U_LIB.S9S_MB_2U(SCH_1):P12V_AUX
  30 P12V_AUX  VOUT8 @S9S_MB_2U_LIB.S9S_MB_2U(SCH_1):P12V_AUX
  31 P12V_AUX  VOUT9 @S9S_MB_2U_LIB.S9S_MB_2U(SCH_1):P12V_AUX
  32 P12V_AUX VOUT10 @S9S_MB_2U_LIB.S9S_MB_2U(SCH_1):P12V_AUX
   8 HSC_MODE_1   MODE @S9S_MB_2U_LIB.S9S_MB_2U(SCH_1):HSC_MODE_1
  17 HSC_SCREF_1 SCREF_OCWREF @S9S_MB_2U_LIB.S9S_MB_2U(SCH_1):HSC_SCREF_1
   6 HSC_FLT_TYPE_1 FLT_TYPE @S9S_MB_2U_LIB.S9S_MB_2U(SCH_1):HSC_FLT_TYPE_1
   7 HSC_NC1_1    NC1 @S9S_MB_2U_LIB.S9S_MB_2U(SCH_1):HSC_NC1_1

Q_RES_0402LF-0,5%,1/16W,CHIP,CA  I40  PR3922
   1 HSC_FLT_TYPE_2      A @S9S_MB_2U_LIB.S9S_MB_2U(SCH_1):HSC_FLT_TYPE_2
   2 HSC_FLT_TYPE      B @S9S_MB_2U_LIB.S9S_MB_2U(SCH_1):HSC_FLT_TYPE

Q_RES_0402LF-0,5%,1/16W,CHIP,CA  I50  PR3920
   1 HSC_FLT_TYPE_1      A @S9S_MB_2U_LIB.S9S_MB_2U(SCH_1):HSC_FLT_TYPE_1
   2 HSC_FLT_TYPE      B @S9S_MB_2U_LIB.S9S_MB_2U(SCH_1):HSC_FLT_TYPE

MP5991GLUZ-MP5991GLU-Z,SMLF,ICA  I14  PU288
   9 P12V_PSU   VIN1 @S9S_MB_2U_LIB.S9S_MB_2U(SCH_1):P12V_PSU
  10 P12V_PSU   VIN2 @S9S_MB_2U_LIB.S9S_MB_2U(SCH_1):P12V_PSU
  11 P12V_PSU   VIN3 @S9S_MB_2U_LIB.S9S_MB_2U(SCH_1):P12V_PSU
  12 P12V_PSU   VIN4 @S9S_MB_2U_LIB.S9S_MB_2U(SCH_1):P12V_PSU
  13 P12V_PSU   VIN5 @S9S_MB_2U_LIB.S9S_MB_2U(SCH_1):P12V_PSU
   4 HSC_ON     ON @S9S_MB_2U_LIB.S9S_MB_2U(SCH_1):HSC_ON
  24 HSC_OCREF  OCREF @S9S_MB_2U_LIB.S9S_MB_2U(SCH_1):HSC_OCREF
  23 HSC_CS_2     CS @S9S_MB_2U_LIB.S9S_MB_2U(SCH_1):HSC_CS_2
  22 HSC_IMON   IMON @S9S_MB_2U_LIB.S9S_MB_2U(SCH_1):HSC_IMON
  21 HSC_VDD_R_2  VDD33 @S9S_MB_2U_LIB.S9S_MB_2U(SCH_1):HSC_VDD_R_2
  20 AGND_HSC    GND @S9S_MB_2U_LIB.S9S_MB_2U(SCH_1):AGND_HSC
  19 HSC_SS     SS @S9S_MB_2U_LIB.S9S_MB_2U(SCH_1):HSC_SS
   5 HSC_FAULT    GOK @S9S_MB_2U_LIB.S9S_MB_2U(SCH_1):HSC_FAULT
  18 HSC_VTEMP  VTEMP @S9S_MB_2U_LIB.S9S_MB_2U(SCH_1):HSC_VTEMP
   1 P12V_AUX  VOUT1 @S9S_MB_2U_LIB.S9S_MB_2U(SCH_1):P12V_AUX
   2 P12V_AUX  VOUT2 @S9S_MB_2U_LIB.S9S_MB_2U(SCH_1):P12V_AUX
  25 P12V_AUX  VOUT3 @S9S_MB_2U_LIB.S9S_MB_2U(SCH_1):P12V_AUX
  26 P12V_AUX  VOUT4 @S9S_MB_2U_LIB.S9S_MB_2U(SCH_1):P12V_AUX
   3 HSC_D_OC_2   D_OC @S9S_MB_2U_LIB.S9S_MB_2U(SCH_1):HSC_D_OC_2
  14 P12V_PSU   VIN6 @S9S_MB_2U_LIB.S9S_MB_2U(SCH_1):P12V_PSU
  15 P12V_PSU   VIN7 @S9S_MB_2U_LIB.S9S_MB_2U(SCH_1):P12V_PSU
  16 P12V_PSU   VIN8 @S9S_MB_2U_LIB.S9S_MB_2U(SCH_1):P12V_PSU
  33 P12V_PSU   VIN9 @S9S_MB_2U_LIB.S9S_MB_2U(SCH_1):P12V_PSU
  27 P12V_AUX  VOUT5 @S9S_MB_2U_LIB.S9S_MB_2U(SCH_1):P12V_AUX
  28 P12V_AUX  VOUT6 @S9S_MB_2U_LIB.S9S_MB_2U(SCH_1):P12V_AUX
  29 P12V_AUX  VOUT7 @S9S_MB_2U_LIB.S9S_MB_2U(SCH_1):P12V_AUX
  30 P12V_AUX  VOUT8 @S9S_MB_2U_LIB.S9S_MB_2U(SCH_1):P12V_AUX
  31 P12V_AUX  VOUT9 @S9S_MB_2U_LIB.S9S_MB_2U(SCH_1):P12V_AUX
  32 P12V_AUX VOUT10 @S9S_MB_2U_LIB.S9S_MB_2U(SCH_1):P12V_AUX
   8 HSC_MODE_2   MODE @S9S_MB_2U_LIB.S9S_MB_2U(SCH_1):HSC_MODE_2
  17 HSC_SCREF_2 SCREF_OCWREF @S9S_MB_2U_LIB.S9S_MB_2U(SCH_1):HSC_SCREF_2
   6 HSC_FLT_TYPE_2 FLT_TYPE @S9S_MB_2U_LIB.S9S_MB_2U(SCH_1):HSC_FLT_TYPE_2
   7 HSC_NC1_2    NC1 @S9S_MB_2U_LIB.S9S_MB_2U(SCH_1):HSC_NC1_2

Q_RES_0402LF-120K,1%,1/16W,CHIA  I32  PR1134
   1 AGND_HSC      A @S9S_MB_2U_LIB.S9S_MB_2U(SCH_1):AGND_HSC
   2 HSC_MODE_1      B @S9S_MB_2U_LIB.S9S_MB_2U(SCH_1):HSC_MODE_1

Q_CAP_0402-220PF,50V,10%,X7R,TA  I23  PC2182
   1 HSC_ON      A @S9S_MB_2U_LIB.S9S_MB_2U(SCH_1):HSC_ON
   2 AGND_HSC      B @S9S_MB_2U_LIB.S9S_MB_2U(SCH_1):AGND_HSC

Q_CAP_0402-0.068UF,16V,10%,X7RA  I37  PC2185
   1 HSC_SS      A @S9S_MB_2U_LIB.S9S_MB_2U(SCH_1):HSC_SS
   2 AGND_HSC      B @S9S_MB_2U_LIB.S9S_MB_2U(SCH_1):AGND_HSC

Q_CAP_0402-0.068UF,16V,10%,X7RA  I47  PC2184
   1 HSC_SS      A @S9S_MB_2U_LIB.S9S_MB_2U(SCH_1):HSC_SS
   2 AGND_HSC      B @S9S_MB_2U_LIB.S9S_MB_2U(SCH_1):AGND_HSC


DRAWING: @S9S_MB_2U_LIB.S9S_MB_2U(SCH_1):PAGE215 

Q_RES_0402LF-0,5%,1/16W,CHIP,CA  I2  R3051
   1 IRQ_SML1_PMBUS_ALERT_R_N      A @S9S_MB_2U_LIB.S9S_MB_2U(SCH_1):IRQ_SML1_PMBUS_ALERT_R_N
   2 IRQ_SML1_PMBUS_ALERT_N      B @S9S_MB_2U_LIB.S9S_MB_2U(SCH_1):IRQ_SML1_PMBUS_ALERT_N

Q_RES_0402LF-33.2,1%,1/16W,CHIA  I12  R3053
   1 SMB_HOST_3V3AUX_SDA_R5      A @S9S_MB_2U_LIB.S9S_MB_2U(SCH_1):SMB_HOST_3V3AUX_SDA_R5
   2 SMB_HOST_ME_SDA      B @S9S_MB_2U_LIB.S9S_MB_2U(SCH_1):SMB_HOST_ME_SDA

Q_RES_0402LF-33.2,1%,1/16W,CHIA  I13  R3052
   1 SMB_HOST_3V3AUX_SCL_R5      A @S9S_MB_2U_LIB.S9S_MB_2U(SCH_1):SMB_HOST_3V3AUX_SCL_R5
   2 SMB_HOST_ME_SCL      B @S9S_MB_2U_LIB.S9S_MB_2U(SCH_1):SMB_HOST_ME_SCL

Q_RES_0402LF-33.2,1%,1/16W,CHIA  I23  R3054
   1 PWRGD_PS_PWROK_ME_CONN      A @S9S_MB_2U_LIB.S9S_MB_2U(SCH_1):PWRGD_PS_PWROK_ME_CONN
   2 PWRGD_PS_PWROK      B @S9S_MB_2U_LIB.S9S_MB_2U(SCH_1):PWRGD_PS_PWROK

Q_RES_0402LF-0,5%,1/16W,CHIP,CA  I28  R3103
   1 IRQ_SML0_ALERT_R_N      A @S9S_MB_2U_LIB.S9S_MB_2U(SCH_1):IRQ_SML0_ALERT_R_N
   2 IRQ_SML0_ALERT_R1_N      B @S9S_MB_2U_LIB.S9S_MB_2U(SCH_1):IRQ_SML0_ALERT_R1_N

SCONN20_513860200CV01-SCONN20_A  I32  J100
   1 SMB_SML0_ME_SCL      1 @S9S_MB_2U_LIB.S9S_MB_2U(SCH_1):SMB_SML0_ME_SCL
   2    GND      2 @S9S_MB_2U_LIB.S9S_MB_2U(SCH_1):GND
   3 SMB_SML0_ME_SDA      3 @S9S_MB_2U_LIB.S9S_MB_2U(SCH_1):SMB_SML0_ME_SDA
   4 IRQ_SML0_ALERT_R1_N      4 @S9S_MB_2U_LIB.S9S_MB_2U(SCH_1):IRQ_SML0_ALERT_R1_N
   5 SMB_PMBUS_SML1_ME_SCL      5 @S9S_MB_2U_LIB.S9S_MB_2U(SCH_1):SMB_PMBUS_SML1_ME_SCL
   6    GND      6 @S9S_MB_2U_LIB.S9S_MB_2U(SCH_1):GND
   7 SMB_PMBUS_SML1_ME_SDA      7 @S9S_MB_2U_LIB.S9S_MB_2U(SCH_1):SMB_PMBUS_SML1_ME_SDA
   8 IRQ_SML1_PMBUS_ALERT_R_N      8 @S9S_MB_2U_LIB.S9S_MB_2U(SCH_1):IRQ_SML1_PMBUS_ALERT_R_N
   9 RST_RSMRST_NM_HDR_N      9 @S9S_MB_2U_LIB.S9S_MB_2U(SCH_1):RST_RSMRST_NM_HDR_N
  10    GND     10 @S9S_MB_2U_LIB.S9S_MB_2U(SCH_1):GND
  11 SMB_HOST_ME_SCL     11 @S9S_MB_2U_LIB.S9S_MB_2U(SCH_1):SMB_HOST_ME_SCL
  12    GND     12 @S9S_MB_2U_LIB.S9S_MB_2U(SCH_1):GND
  13 SMB_HOST_ME_SDA     13 @S9S_MB_2U_LIB.S9S_MB_2U(SCH_1):SMB_HOST_ME_SDA
  14     NC     14     NC
  15    GND     15 @S9S_MB_2U_LIB.S9S_MB_2U(SCH_1):GND
  16 PECI_BMC_ME     16 @S9S_MB_2U_LIB.S9S_MB_2U(SCH_1):PECI_BMC_ME
  17    GND     17 @S9S_MB_2U_LIB.S9S_MB_2U(SCH_1):GND
  18 PWRGD_PS_PWROK_ME_CONN     18 @S9S_MB_2U_LIB.S9S_MB_2U(SCH_1):PWRGD_PS_PWROK_ME_CONN
  19 FM_BIOS_POST_CMPLT_HDR_N     19 @S9S_MB_2U_LIB.S9S_MB_2U(SCH_1):FM_BIOS_POST_CMPLT_HDR_N
  20     NC     20     NC


DRAWING: @S9S_MB_2U_LIB.S9S_MB_2U(SCH_1):PAGE305 

MOSFET_NCH_DUAL-PJT138K,SMLF,IA  I2  Q80
   3 LED_PWRGD_PVCCFA_EHV_FIVRA_CP_1     D2 @S9S_MB_2U_LIB.S9S_MB_2U(SCH_1):LED_PWRGD_PVCCFA_EHV_FIVRA_CPU0_D
   5 PWRGD_PVCCFA_EHV_FIVRA_CPU0     G2 @S9S_MB_2U_LIB.S9S_MB_2U(SCH_1):PWRGD_PVCCFA_EHV_FIVRA_CPU0
   4    GND     S2 @S9S_MB_2U_LIB.S9S_MB_2U(SCH_1):GND

MOSFET_NCH_DUAL-PJT138K,SMLF,IA  I4  Q80
   1    GND     S1 @S9S_MB_2U_LIB.S9S_MB_2U(SCH_1):GND
   2 PWRGD_PVCCFA_EHV_CPU0     G1 @S9S_MB_2U_LIB.S9S_MB_2U(SCH_1):PWRGD_PVCCFA_EHV_CPU0
   6 LED_PWRGD_PVCCFA_EHV_CPU0_D     D1 @S9S_MB_2U_LIB.S9S_MB_2U(SCH_1):LED_PWRGD_PVCCFA_EHV_CPU0_D

MOSFET_NCH_DUAL-PJT138K,SMLF,IA  I7  Q79
   3 LED_PWRGD_PVPP_HBM_CPU0_D     D2 @S9S_MB_2U_LIB.S9S_MB_2U(SCH_1):LED_PWRGD_PVPP_HBM_CPU0_D
   5 PWRGD_PVPP_HBM_CPU0     G2 @S9S_MB_2U_LIB.S9S_MB_2U(SCH_1):PWRGD_PVPP_HBM_CPU0
   4    GND     S2 @S9S_MB_2U_LIB.S9S_MB_2U(SCH_1):GND

MOSFET_NCH_DUAL-PJT138K,SMLF,IA  I8  Q79
   1    GND     S1 @S9S_MB_2U_LIB.S9S_MB_2U(SCH_1):GND
   2 PWRGD_PVCCD_HV_CPU0     G1 @S9S_MB_2U_LIB.S9S_MB_2U(SCH_1):PWRGD_PVCCD_HV_CPU0
   6 LED_PWRGD_PVCCD_HV_CPU0_D     D1 @S9S_MB_2U_LIB.S9S_MB_2U(SCH_1):LED_PWRGD_PVCCD_HV_CPU0_D

Q_LED_SMLF-LED_BLUE,LTST-C281TA  I10  D76
   A LED_PWRGD_PVCCFA_EHV_FIVRA_CPU0      A @S9S_MB_2U_LIB.S9S_MB_2U(SCH_1):LED_PWRGD_PVCCFA_EHV_FIVRA_CPU0
   C LED_PWRGD_PVCCFA_EHV_FIVRA_CP_1      C @S9S_MB_2U_LIB.S9S_MB_2U(SCH_1):LED_PWRGD_PVCCFA_EHV_FIVRA_CPU0_D

Q_LED_SMLF-LED_BLUE,LTST-C281TA  I13  D75
   A LED_PWRGD_PVCCFA_EHV_CPU0      A @S9S_MB_2U_LIB.S9S_MB_2U(SCH_1):LED_PWRGD_PVCCFA_EHV_CPU0
   C LED_PWRGD_PVCCFA_EHV_CPU0_D      C @S9S_MB_2U_LIB.S9S_MB_2U(SCH_1):LED_PWRGD_PVCCFA_EHV_CPU0_D

Q_LED_SMLF-LED_BLUE,LTST-C281TA  I21  D74
   A LED_PWRGD_PVPP_HBM_CPU0      A @S9S_MB_2U_LIB.S9S_MB_2U(SCH_1):LED_PWRGD_PVPP_HBM_CPU0
   C LED_PWRGD_PVPP_HBM_CPU0_D      C @S9S_MB_2U_LIB.S9S_MB_2U(SCH_1):LED_PWRGD_PVPP_HBM_CPU0_D

Q_LED_SMLF-LED_BLUE,LTST-C281TA  I22  D73
   A LED_PWRGD_PVCCD_HV_CPU0      A @S9S_MB_2U_LIB.S9S_MB_2U(SCH_1):LED_PWRGD_PVCCD_HV_CPU0
   C LED_PWRGD_PVCCD_HV_CPU0_D      C @S9S_MB_2U_LIB.S9S_MB_2U(SCH_1):LED_PWRGD_PVCCD_HV_CPU0_D

MOSFET_NCH_DUAL-PJT138K,SMLF,IA  I32  Q83
   1    GND     S1 @S9S_MB_2U_LIB.S9S_MB_2U(SCH_1):GND
   2 PWRGD_PVCCIN_CPU0     G1 @S9S_MB_2U_LIB.S9S_MB_2U(SCH_1):PWRGD_PVCCIN_CPU0
   6 LED_PWRGD_PVCCIN_CPU0_D     D1 @S9S_MB_2U_LIB.S9S_MB_2U(SCH_1):LED_PWRGD_PVCCIN_CPU0_D

Q_LED_SMLF-LED_BLUE,LTST-C281TA  I35  D79
   A LED_PWRGD_PVCCIN_CPU0      A @S9S_MB_2U_LIB.S9S_MB_2U(SCH_1):LED_PWRGD_PVCCIN_CPU0
   C LED_PWRGD_PVCCIN_CPU0_D      C @S9S_MB_2U_LIB.S9S_MB_2U(SCH_1):LED_PWRGD_PVCCIN_CPU0_D

MOSFET_NCH_DUAL-PJT138K,SMLF,IA  I40  Q81
   3 LED_PWRGD_PVNN_MAIN_CPU0_D     D2 @S9S_MB_2U_LIB.S9S_MB_2U(SCH_1):LED_PWRGD_PVNN_MAIN_CPU0_D
   5 PWRGD_PVNN_MAIN_CPU0     G2 @S9S_MB_2U_LIB.S9S_MB_2U(SCH_1):PWRGD_PVNN_MAIN_CPU0
   4    GND     S2 @S9S_MB_2U_LIB.S9S_MB_2U(SCH_1):GND

MOSFET_NCH_DUAL-PJT138K,SMLF,IA  I41  Q81
   1    GND     S1 @S9S_MB_2U_LIB.S9S_MB_2U(SCH_1):GND
   2 PWRGD_PVCCINFAON_CPU0     G1 @S9S_MB_2U_LIB.S9S_MB_2U(SCH_1):PWRGD_PVCCINFAON_CPU0
   6 LED_PWRGD_PVCCINFAON_CPU0_D     D1 @S9S_MB_2U_LIB.S9S_MB_2U(SCH_1):LED_PWRGD_PVCCINFAON_CPU0_D

Q_LED_SMLF-LED_BLUE,LTST-C281TA  I43  D78
   A LED_PWRGD_PVNN_MAIN_CPU0      A @S9S_MB_2U_LIB.S9S_MB_2U(SCH_1):LED_PWRGD_PVNN_MAIN_CPU0
   C LED_PWRGD_PVNN_MAIN_CPU0_D      C @S9S_MB_2U_LIB.S9S_MB_2U(SCH_1):LED_PWRGD_PVNN_MAIN_CPU0_D

Q_LED_SMLF-LED_BLUE,LTST-C281TA  I44  D77
   A LED_PWRGD_PVCCINFAON_CPU0      A @S9S_MB_2U_LIB.S9S_MB_2U(SCH_1):LED_PWRGD_PVCCINFAON_CPU0
   C LED_PWRGD_PVCCINFAON_CPU0_D      C @S9S_MB_2U_LIB.S9S_MB_2U(SCH_1):LED_PWRGD_PVCCINFAON_CPU0_D

Q_RES_0402LF-130,1%,1/16W,CHIPA  I49  R3086
   1 LED_PWRGD_PVCCD_HV_CPU0      A @S9S_MB_2U_LIB.S9S_MB_2U(SCH_1):LED_PWRGD_PVCCD_HV_CPU0
   2 P3V3_AUX      B @S9S_MB_2U_LIB.S9S_MB_2U(SCH_1):P3V3_AUX

Q_RES_0402LF-130,1%,1/16W,CHIPA  I50  R3087
   1 LED_PWRGD_PVPP_HBM_CPU0      A @S9S_MB_2U_LIB.S9S_MB_2U(SCH_1):LED_PWRGD_PVPP_HBM_CPU0
   2 P3V3_AUX      B @S9S_MB_2U_LIB.S9S_MB_2U(SCH_1):P3V3_AUX

Q_RES_0402LF-130,1%,1/16W,CHIPA  I51  R3089
   1 LED_PWRGD_PVCCFA_EHV_CPU0      A @S9S_MB_2U_LIB.S9S_MB_2U(SCH_1):LED_PWRGD_PVCCFA_EHV_CPU0
   2 P3V3_AUX      B @S9S_MB_2U_LIB.S9S_MB_2U(SCH_1):P3V3_AUX

Q_RES_0402LF-130,1%,1/16W,CHIPA  I52  R3088
   1 LED_PWRGD_PVCCFA_EHV_FIVRA_CPU0      A @S9S_MB_2U_LIB.S9S_MB_2U(SCH_1):LED_PWRGD_PVCCFA_EHV_FIVRA_CPU0
   2 P3V3_AUX      B @S9S_MB_2U_LIB.S9S_MB_2U(SCH_1):P3V3_AUX

Q_RES_0402LF-130,1%,1/16W,CHIPA  I53  R3091
   1 LED_PWRGD_PVCCIN_CPU0      A @S9S_MB_2U_LIB.S9S_MB_2U(SCH_1):LED_PWRGD_PVCCIN_CPU0
   2 P3V3_AUX      B @S9S_MB_2U_LIB.S9S_MB_2U(SCH_1):P3V3_AUX

Q_RES_0402LF-130,1%,1/16W,CHIPA  I54  R3090
   1 LED_PWRGD_PVNN_MAIN_CPU0      A @S9S_MB_2U_LIB.S9S_MB_2U(SCH_1):LED_PWRGD_PVNN_MAIN_CPU0
   2 P3V3_AUX      B @S9S_MB_2U_LIB.S9S_MB_2U(SCH_1):P3V3_AUX

Q_RES_0402LF-130,1%,1/16W,CHIPA  I55  R3092
   1 LED_PWRGD_PVCCINFAON_CPU0      A @S9S_MB_2U_LIB.S9S_MB_2U(SCH_1):LED_PWRGD_PVCCINFAON_CPU0
   2 P3V3_AUX      B @S9S_MB_2U_LIB.S9S_MB_2U(SCH_1):P3V3_AUX


DRAWING: @S9S_MB_2U_LIB.S9S_MB_2U(SCH_1):PAGE241 

MOSFET_NCH_DUAL-PJT138K,SMLF,IA  I8  Q88
   1    GND     S1 @S9S_MB_2U_LIB.S9S_MB_2U(SCH_1):GND
   2 PWRGD_CPUPWRGD_LVC2_R1     G1 @S9S_MB_2U_LIB.S9S_MB_2U(SCH_1):PWRGD_CPUPWRGD_LVC2_R1
   6 LED_PWRGD_CPUPWRGD_GTL_D     D1 @S9S_MB_2U_LIB.S9S_MB_2U(SCH_1):LED_PWRGD_CPUPWRGD_GTL_D

Q_LED_SMLF-LED_BLUE,LTST-C281TA  I11  D89
   A LED_PWRGD_CPUPWRGD_GTL      A @S9S_MB_2U_LIB.S9S_MB_2U(SCH_1):LED_PWRGD_CPUPWRGD_GTL
   C LED_PWRGD_CPUPWRGD_GTL_D      C @S9S_MB_2U_LIB.S9S_MB_2U(SCH_1):LED_PWRGD_CPUPWRGD_GTL_D

MOSFET_NCH_DUAL-PJT138K,SMLF,IA  I16  Q87
   3 LED_PWRGD_SYS_PWROK_R_D     D2 @S9S_MB_2U_LIB.S9S_MB_2U(SCH_1):LED_PWRGD_SYS_PWROK_R_D
   5 PWRGD_SYS_PWROK_R     G2 @S9S_MB_2U_LIB.S9S_MB_2U(SCH_1):PWRGD_SYS_PWROK_R
   4    GND     S2 @S9S_MB_2U_LIB.S9S_MB_2U(SCH_1):GND

MOSFET_NCH_DUAL-PJT138K,SMLF,IA  I17  Q87
   1    GND     S1 @S9S_MB_2U_LIB.S9S_MB_2U(SCH_1):GND
   2 PWRGD_PCH_PWROK_R     G1 @S9S_MB_2U_LIB.S9S_MB_2U(SCH_1):PWRGD_PCH_PWROK_R
   6 LED_PWRGD_PCH_PWROK_R_D     D1 @S9S_MB_2U_LIB.S9S_MB_2U(SCH_1):LED_PWRGD_PCH_PWROK_R_D

Q_LED_SMLF-LED_BLUE,LTST-C281TA  I19  D88
   A LED_PWRGD_SYS_PWROK_R      A @S9S_MB_2U_LIB.S9S_MB_2U(SCH_1):LED_PWRGD_SYS_PWROK_R
   C LED_PWRGD_SYS_PWROK_R_D      C @S9S_MB_2U_LIB.S9S_MB_2U(SCH_1):LED_PWRGD_SYS_PWROK_R_D

Q_LED_SMLF-LED_BLUE,LTST-C281TA  I20  D87
   A LED_PWRGD_PCH_PWROK_R      A @S9S_MB_2U_LIB.S9S_MB_2U(SCH_1):LED_PWRGD_PCH_PWROK_R
   C LED_PWRGD_PCH_PWROK_R_D      C @S9S_MB_2U_LIB.S9S_MB_2U(SCH_1):LED_PWRGD_PCH_PWROK_R_D

Q_LED_SMLF-LED_BLUE,LTST-C281TA  I33  D90
   A LED_RST_PLTRST_N      A @S9S_MB_2U_LIB.S9S_MB_2U(SCH_1):LED_RST_PLTRST_N
   C LED_RST_PLTRST_N_D      C @S9S_MB_2U_LIB.S9S_MB_2U(SCH_1):LED_RST_PLTRST_N_D

Q_RES_0402LF-130,1%,1/16W,CHIPA  I38  R3068
   1 LED_PWRGD_PCH_PWROK_R      A @S9S_MB_2U_LIB.S9S_MB_2U(SCH_1):LED_PWRGD_PCH_PWROK_R
   2 P3V3_AUX      B @S9S_MB_2U_LIB.S9S_MB_2U(SCH_1):P3V3_AUX

Q_RES_0402LF-130,1%,1/16W,CHIPA  I39  R3069
   1 LED_PWRGD_SYS_PWROK_R      A @S9S_MB_2U_LIB.S9S_MB_2U(SCH_1):LED_PWRGD_SYS_PWROK_R
   2 P3V3_AUX      B @S9S_MB_2U_LIB.S9S_MB_2U(SCH_1):P3V3_AUX

Q_RES_0402LF-130,1%,1/16W,CHIPA  I40  R1044
   1 LED_PWRGD_CPUPWRGD_GTL      A @S9S_MB_2U_LIB.S9S_MB_2U(SCH_1):LED_PWRGD_CPUPWRGD_GTL
   2 P3V3_AUX      B @S9S_MB_2U_LIB.S9S_MB_2U(SCH_1):P3V3_AUX

Q_RES_0402LF-130,1%,1/16W,CHIPA  I41  R3070
   1 LED_RST_PLTRST_N      A @S9S_MB_2U_LIB.S9S_MB_2U(SCH_1):LED_RST_PLTRST_N
   2 P3V3_AUX      B @S9S_MB_2U_LIB.S9S_MB_2U(SCH_1):P3V3_AUX

MOSFET_NCH_DUAL-PJT138K,SMLF,IA  I42  Q88
   3 LED_RST_PLTRST_N_D     D2 @S9S_MB_2U_LIB.S9S_MB_2U(SCH_1):LED_RST_PLTRST_N_D
   5 RST_PLTRST_N     G2 @S9S_MB_2U_LIB.S9S_MB_2U(SCH_1):RST_PLTRST_N
   4    GND     S2 @S9S_MB_2U_LIB.S9S_MB_2U(SCH_1):GND

Q_LED_SMLF-LED_BLUE,LTST-C281TA  I49  D143
   A LED_P12V_PSU_R1      A @S9S_MB_2U_LIB.S9S_MB_2U(SCH_1):LED_P12V_PSU_R1
   C    GND      C @S9S_MB_2U_LIB.S9S_MB_2U(SCH_1):GND

Q_LED_SMLF-LED_BLUE,LTST-C281TA  I58  D142
   A LED_P12V_AUX_R1      A @S9S_MB_2U_LIB.S9S_MB_2U(SCH_1):LED_P12V_AUX_R1
   C    GND      C @S9S_MB_2U_LIB.S9S_MB_2U(SCH_1):GND

Q_RES_0402LF-560,1%,1/16W,CHIPA  I61  R4703
   1 LED_P12V_PSU_R1      A @S9S_MB_2U_LIB.S9S_MB_2U(SCH_1):LED_P12V_PSU_R1
   2 LED_P12V_PSU_R2      B @S9S_MB_2U_LIB.S9S_MB_2U(SCH_1):LED_P12V_PSU_R2

Q_RES_0402LF-560,1%,1/16W,CHIPA  I62  R4705
   1 LED_P12V_PSU_R2      A @S9S_MB_2U_LIB.S9S_MB_2U(SCH_1):LED_P12V_PSU_R2
   2 LED_P12V_PSU_R3      B @S9S_MB_2U_LIB.S9S_MB_2U(SCH_1):LED_P12V_PSU_R3

Q_RES_0402LF-560,1%,1/16W,CHIPA  I63  R4707
   1 LED_P12V_PSU_R3      A @S9S_MB_2U_LIB.S9S_MB_2U(SCH_1):LED_P12V_PSU_R3
   2 P12V_PSU      B @S9S_MB_2U_LIB.S9S_MB_2U(SCH_1):P12V_PSU

Q_RES_0402LF-560,1%,1/16W,CHIPA  I64  R4702
   1 LED_P12V_AUX_R1      A @S9S_MB_2U_LIB.S9S_MB_2U(SCH_1):LED_P12V_AUX_R1
   2 LED_P12V_AUX_R2      B @S9S_MB_2U_LIB.S9S_MB_2U(SCH_1):LED_P12V_AUX_R2

Q_RES_0402LF-560,1%,1/16W,CHIPA  I65  R4704
   1 LED_P12V_AUX_R2      A @S9S_MB_2U_LIB.S9S_MB_2U(SCH_1):LED_P12V_AUX_R2
   2 LED_P12V_AUX_R3      B @S9S_MB_2U_LIB.S9S_MB_2U(SCH_1):LED_P12V_AUX_R3

Q_RES_0402LF-560,1%,1/16W,CHIPA  I66  R4706
   1 LED_P12V_AUX_R3      A @S9S_MB_2U_LIB.S9S_MB_2U(SCH_1):LED_P12V_AUX_R3
   2 P12V_AUX      B @S9S_MB_2U_LIB.S9S_MB_2U(SCH_1):P12V_AUX

Q_LED_SMLF-LED_YELLOW,LTST-C19A  I67  D144
   A LED_P12V_SCM_FAULT      A @S9S_MB_2U_LIB.S9S_MB_2U(SCH_1):LED_P12V_SCM_FAULT
   C LED_P12V_SCM_FAULT_D2      C @S9S_MB_2U_LIB.S9S_MB_2U(SCH_1):LED_P12V_SCM_FAULT_D2

Q_RES_0402LF-249,1%,1/16W,CHIPA  I68  R4711
   1 LED_P12V_SCM_FAULT      A @S9S_MB_2U_LIB.S9S_MB_2U(SCH_1):LED_P12V_SCM_FAULT
   2 P3V3_AUX      B @S9S_MB_2U_LIB.S9S_MB_2U(SCH_1):P3V3_AUX

MOSFET_NCH_DUAL-PJT138K,SMLF,IA  I69  Q150
   1    GND     S1 @S9S_MB_2U_LIB.S9S_MB_2U(SCH_1):GND
   2 P12V_SCM_FAULT_R_N     G1 @S9S_MB_2U_LIB.S9S_MB_2U(SCH_1):P12V_SCM_FAULT_R_N
   6 LED_P12V_SCM_FAULT_D1     D1 @S9S_MB_2U_LIB.S9S_MB_2U(SCH_1):LED_P12V_SCM_FAULT_D1

MOSFET_NCH_DUAL-PJT138K,SMLF,IA  I72  Q150
   3 LED_P12V_SCM_FAULT_D2     D2 @S9S_MB_2U_LIB.S9S_MB_2U(SCH_1):LED_P12V_SCM_FAULT_D2
   5 LED_P12V_SCM_FAULT_D1     G2 @S9S_MB_2U_LIB.S9S_MB_2U(SCH_1):LED_P12V_SCM_FAULT_D1
   4    GND     S2 @S9S_MB_2U_LIB.S9S_MB_2U(SCH_1):GND

Q_RES_0402LF-4.7K,5%,1/16W,CHIA  I74  R4710
   1 P3V3_AUX      A @S9S_MB_2U_LIB.S9S_MB_2U(SCH_1):P3V3_AUX
   2 LED_P12V_SCM_FAULT_D1      B @S9S_MB_2U_LIB.S9S_MB_2U(SCH_1):LED_P12V_SCM_FAULT_D1


DRAWING: @S9S_MB_2U_LIB.S9S_MB_2U(SCH_1):PAGE304 

Q_LED_SMLF-LED_BLUE,LTST-C281TA  I9  D68
   A LED_RST_PLD_CPU0_DRAM_GH_N      A @S9S_MB_2U_LIB.S9S_MB_2U(SCH_1):LED_RST_PLD_CPU0_DRAM_GH_N
   C LED_RST_PLD_CPU0_DRAM_GH_N_D      C @S9S_MB_2U_LIB.S9S_MB_2U(SCH_1):LED_RST_PLD_CPU0_DRAM_GH_N_D

Q_LED_SMLF-LED_BLUE,LTST-C281TA  I12  D67
   A LED_RST_PLD_CPU0_DRAM_EF_N      A @S9S_MB_2U_LIB.S9S_MB_2U(SCH_1):LED_RST_PLD_CPU0_DRAM_EF_N
   C LED_RST_PLD_CPU0_DRAM_EF_N_D      C @S9S_MB_2U_LIB.S9S_MB_2U(SCH_1):LED_RST_PLD_CPU0_DRAM_EF_N_D

Q_LED_SMLF-LED_BLUE,LTST-C281TA  I20  D66
   A LED_RST_PLD_CPU0_DRAM_CD_N      A @S9S_MB_2U_LIB.S9S_MB_2U(SCH_1):LED_RST_PLD_CPU0_DRAM_CD_N
   C LED_RST_PLD_CPU0_DRAM_CD_N_D      C @S9S_MB_2U_LIB.S9S_MB_2U(SCH_1):LED_RST_PLD_CPU0_DRAM_CD_N_D

Q_LED_SMLF-LED_BLUE,LTST-C281TA  I21  D65
   A LED_RST_PLD_CPU0_DRAM_AB_N      A @S9S_MB_2U_LIB.S9S_MB_2U(SCH_1):LED_RST_PLD_CPU0_DRAM_AB_N
   C LED_RST_PLD_CPU0_DRAM_AB_N_D      C @S9S_MB_2U_LIB.S9S_MB_2U(SCH_1):LED_RST_PLD_CPU0_DRAM_AB_N_D

Q_LED_SMLF-LED_BLUE,LTST-C281TA  I31  D70
   A LED_RST_PLD_CPU1_DRAM_CD_N      A @S9S_MB_2U_LIB.S9S_MB_2U(SCH_1):LED_RST_PLD_CPU1_DRAM_CD_N
   C LED_RST_PLD_CPU1_DRAM_CD_N_D      C @S9S_MB_2U_LIB.S9S_MB_2U(SCH_1):LED_RST_PLD_CPU1_DRAM_CD_N_D

Q_LED_SMLF-LED_BLUE,LTST-C281TA  I32  D69
   A LED_RST_PLD_CPU1_DRAM_AB_N      A @S9S_MB_2U_LIB.S9S_MB_2U(SCH_1):LED_RST_PLD_CPU1_DRAM_AB_N
   C LED_RST_PLD_CPU1_DRAM_AB_N_D      C @S9S_MB_2U_LIB.S9S_MB_2U(SCH_1):LED_RST_PLD_CPU1_DRAM_AB_N_D

Q_RES_0402LF-130,1%,1/16W,CHIPA  I49  R1371
   1 LED_RST_PLD_CPU0_DRAM_AB_N      A @S9S_MB_2U_LIB.S9S_MB_2U(SCH_1):LED_RST_PLD_CPU0_DRAM_AB_N
   2 P3V3_AUX      B @S9S_MB_2U_LIB.S9S_MB_2U(SCH_1):P3V3_AUX

Q_RES_0402LF-130,1%,1/16W,CHIPA  I50  R3080
   1 LED_RST_PLD_CPU0_DRAM_CD_N      A @S9S_MB_2U_LIB.S9S_MB_2U(SCH_1):LED_RST_PLD_CPU0_DRAM_CD_N
   2 P3V3_AUX      B @S9S_MB_2U_LIB.S9S_MB_2U(SCH_1):P3V3_AUX

Q_RES_0402LF-130,1%,1/16W,CHIPA  I51  R3079
   1 LED_RST_PLD_CPU0_DRAM_EF_N      A @S9S_MB_2U_LIB.S9S_MB_2U(SCH_1):LED_RST_PLD_CPU0_DRAM_EF_N
   2 P3V3_AUX      B @S9S_MB_2U_LIB.S9S_MB_2U(SCH_1):P3V3_AUX

Q_RES_0402LF-130,1%,1/16W,CHIPA  I52  R3081
   1 LED_RST_PLD_CPU0_DRAM_GH_N      A @S9S_MB_2U_LIB.S9S_MB_2U(SCH_1):LED_RST_PLD_CPU0_DRAM_GH_N
   2 P3V3_AUX      B @S9S_MB_2U_LIB.S9S_MB_2U(SCH_1):P3V3_AUX

Q_RES_0402LF-130,1%,1/16W,CHIPA  I53  R3084
   1 LED_RST_PLD_CPU1_DRAM_CD_N      A @S9S_MB_2U_LIB.S9S_MB_2U(SCH_1):LED_RST_PLD_CPU1_DRAM_CD_N
   2 P3V3_AUX      B @S9S_MB_2U_LIB.S9S_MB_2U(SCH_1):P3V3_AUX

Q_RES_0402LF-130,1%,1/16W,CHIPA  I54  R3082
   1 LED_RST_PLD_CPU1_DRAM_AB_N      A @S9S_MB_2U_LIB.S9S_MB_2U(SCH_1):LED_RST_PLD_CPU1_DRAM_AB_N
   2 P3V3_AUX      B @S9S_MB_2U_LIB.S9S_MB_2U(SCH_1):P3V3_AUX

Q_RES_0402LF-130,1%,1/16W,CHIPA  I57  R3083
   1 LED_RST_PLD_CPU1_DRAM_EF_N      A @S9S_MB_2U_LIB.S9S_MB_2U(SCH_1):LED_RST_PLD_CPU1_DRAM_EF_N
   2 P3V3_AUX      B @S9S_MB_2U_LIB.S9S_MB_2U(SCH_1):P3V3_AUX

Q_LED_SMLF-LED_BLUE,LTST-C281TA  I58  D71
   A LED_RST_PLD_CPU1_DRAM_EF_N      A @S9S_MB_2U_LIB.S9S_MB_2U(SCH_1):LED_RST_PLD_CPU1_DRAM_EF_N
   C LED_RST_PLD_CPU1_DRAM_EF_N_D      C @S9S_MB_2U_LIB.S9S_MB_2U(SCH_1):LED_RST_PLD_CPU1_DRAM_EF_N_D

Q_RES_0402LF-130,1%,1/16W,CHIPA  I62  R3085
   1 LED_RST_PLD_CPU1_DRAM_GH_N      A @S9S_MB_2U_LIB.S9S_MB_2U(SCH_1):LED_RST_PLD_CPU1_DRAM_GH_N
   2 P3V3_AUX      B @S9S_MB_2U_LIB.S9S_MB_2U(SCH_1):P3V3_AUX

Q_LED_SMLF-LED_BLUE,LTST-C281TA  I63  D72
   A LED_RST_PLD_CPU1_DRAM_GH_N      A @S9S_MB_2U_LIB.S9S_MB_2U(SCH_1):LED_RST_PLD_CPU1_DRAM_GH_N
   C LED_RST_PLD_CPU1_DRAM_GH_N_D      C @S9S_MB_2U_LIB.S9S_MB_2U(SCH_1):LED_RST_PLD_CPU1_DRAM_GH_N_D

MOSFET_NCH_DUAL-NX6008NBKS,SMLA  I68  Q98
   1    GND     S1 @S9S_MB_2U_LIB.S9S_MB_2U(SCH_1):GND
   2 RST_PLD_CPU0_DRAM_AB_N     G1 @S9S_MB_2U_LIB.S9S_MB_2U(SCH_1):RST_PLD_CPU0_DRAM_AB_N
   6 LED_RST_PLD_CPU0_DRAM_AB_N_D     D1 @S9S_MB_2U_LIB.S9S_MB_2U(SCH_1):LED_RST_PLD_CPU0_DRAM_AB_N_D

MOSFET_NCH_DUAL-NX6008NBKS,SMLA  I69  Q98
   3 LED_RST_PLD_CPU0_DRAM_CD_N_D     D2 @S9S_MB_2U_LIB.S9S_MB_2U(SCH_1):LED_RST_PLD_CPU0_DRAM_CD_N_D
   5 RST_PLD_CPU0_DRAM_CD_N     G2 @S9S_MB_2U_LIB.S9S_MB_2U(SCH_1):RST_PLD_CPU0_DRAM_CD_N
   4    GND     S2 @S9S_MB_2U_LIB.S9S_MB_2U(SCH_1):GND

MOSFET_NCH_DUAL-NX6008NBKS,SMLA  I70  Q97
   3 LED_RST_PLD_CPU0_DRAM_GH_N_D     D2 @S9S_MB_2U_LIB.S9S_MB_2U(SCH_1):LED_RST_PLD_CPU0_DRAM_GH_N_D
   5 RST_PLD_CPU0_DRAM_GH_N     G2 @S9S_MB_2U_LIB.S9S_MB_2U(SCH_1):RST_PLD_CPU0_DRAM_GH_N
   4    GND     S2 @S9S_MB_2U_LIB.S9S_MB_2U(SCH_1):GND

MOSFET_NCH_DUAL-NX6008NBKS,SMLA  I71  Q97
   1    GND     S1 @S9S_MB_2U_LIB.S9S_MB_2U(SCH_1):GND
   2 RST_PLD_CPU0_DRAM_EF_N     G1 @S9S_MB_2U_LIB.S9S_MB_2U(SCH_1):RST_PLD_CPU0_DRAM_EF_N
   6 LED_RST_PLD_CPU0_DRAM_EF_N_D     D1 @S9S_MB_2U_LIB.S9S_MB_2U(SCH_1):LED_RST_PLD_CPU0_DRAM_EF_N_D

MOSFET_NCH_DUAL-NX6008NBKS,SMLA  I72  Q99
   1    GND     S1 @S9S_MB_2U_LIB.S9S_MB_2U(SCH_1):GND
   2 RST_PLD_CPU1_DRAM_CD_N     G1 @S9S_MB_2U_LIB.S9S_MB_2U(SCH_1):RST_PLD_CPU1_DRAM_CD_N
   6 LED_RST_PLD_CPU1_DRAM_CD_N_D     D1 @S9S_MB_2U_LIB.S9S_MB_2U(SCH_1):LED_RST_PLD_CPU1_DRAM_CD_N_D

MOSFET_NCH_DUAL-NX6008NBKS,SMLA  I74  Q100
   1    GND     S1 @S9S_MB_2U_LIB.S9S_MB_2U(SCH_1):GND
   2 RST_PLD_CPU1_DRAM_EF_N     G1 @S9S_MB_2U_LIB.S9S_MB_2U(SCH_1):RST_PLD_CPU1_DRAM_EF_N
   6 LED_RST_PLD_CPU1_DRAM_EF_N_D     D1 @S9S_MB_2U_LIB.S9S_MB_2U(SCH_1):LED_RST_PLD_CPU1_DRAM_EF_N_D

MOSFET_NCH_DUAL-NX6008NBKS,SMLA  I75  Q100
   3 LED_RST_PLD_CPU1_DRAM_GH_N_D     D2 @S9S_MB_2U_LIB.S9S_MB_2U(SCH_1):LED_RST_PLD_CPU1_DRAM_GH_N_D
   5 RST_PLD_CPU1_DRAM_GH_N     G2 @S9S_MB_2U_LIB.S9S_MB_2U(SCH_1):RST_PLD_CPU1_DRAM_GH_N
   4    GND     S2 @S9S_MB_2U_LIB.S9S_MB_2U(SCH_1):GND

MOSFET_NCH_DUAL-NX6008NBKS,SMLA  I76  Q105
   1    GND     S1 @S9S_MB_2U_LIB.S9S_MB_2U(SCH_1):GND
   2 RST_PLD_CPU1_DRAM_AB_N     G1 @S9S_MB_2U_LIB.S9S_MB_2U(SCH_1):RST_PLD_CPU1_DRAM_AB_N
   6 LED_RST_PLD_CPU1_DRAM_AB_N_D     D1 @S9S_MB_2U_LIB.S9S_MB_2U(SCH_1):LED_RST_PLD_CPU1_DRAM_AB_N_D


DRAWING: @S9S_MB_2U_LIB.S9S_MB_2U(SCH_1):PAGE242 

MOSFET_NCH_DUAL-PJT138K,SMLF,IA  I8  Q76
   3 LED_PWRGD_P1V05_PCH_AUX_D     D2 @S9S_MB_2U_LIB.S9S_MB_2U(SCH_1):LED_PWRGD_P1V05_PCH_AUX_D
   5 PWRGD_P1V05_PCH_AUX     G2 @S9S_MB_2U_LIB.S9S_MB_2U(SCH_1):PWRGD_P1V05_PCH_AUX
   4    GND     S2 @S9S_MB_2U_LIB.S9S_MB_2U(SCH_1):GND

MOSFET_NCH_DUAL-PJT138K,SMLF,IA  I3  Q77
   3 LED_FM_PCH_SLP_S4_N_D     D2 @S9S_MB_2U_LIB.S9S_MB_2U(SCH_1):LED_FM_PCH_SLP_S4_N_D
   5 FM_PCH_SLP_S4_N     G2 @S9S_MB_2U_LIB.S9S_MB_2U(SCH_1):FM_PCH_SLP_S4_N
   4    GND     S2 @S9S_MB_2U_LIB.S9S_MB_2U(SCH_1):GND

MOSFET_NCH_DUAL-PJT138K,SMLF,IA  I6  Q77
   1    GND     S1 @S9S_MB_2U_LIB.S9S_MB_2U(SCH_1):GND
   2 RST_RSMRST_PLD_R_N     G1 @S9S_MB_2U_LIB.S9S_MB_2U(SCH_1):RST_RSMRST_PLD_R_N
   6 LED_RST_RSMRST_PLD_R_N_D     D1 @S9S_MB_2U_LIB.S9S_MB_2U(SCH_1):LED_RST_RSMRST_PLD_R_N_D

Q_LED_SMLF-LED_BLUE,LTST-C281TA  I11  D94
   A LED_FM_PCH_SLP_S4_N      A @S9S_MB_2U_LIB.S9S_MB_2U(SCH_1):LED_FM_PCH_SLP_S4_N
   C LED_FM_PCH_SLP_S4_N_D      C @S9S_MB_2U_LIB.S9S_MB_2U(SCH_1):LED_FM_PCH_SLP_S4_N_D

Q_RES_0402LF-130,1%,1/16W,CHIPA  I12  R3073
   1 LED_FM_PCH_SLP_S4_N      A @S9S_MB_2U_LIB.S9S_MB_2U(SCH_1):LED_FM_PCH_SLP_S4_N
   2 P3V3_AUX      B @S9S_MB_2U_LIB.S9S_MB_2U(SCH_1):P3V3_AUX

Q_LED_SMLF-LED_BLUE,LTST-C281TA  I13  D93
   A LED_RST_RSMRST_PLD_R_N      A @S9S_MB_2U_LIB.S9S_MB_2U(SCH_1):LED_RST_RSMRST_PLD_R_N
   C LED_RST_RSMRST_PLD_R_N_D      C @S9S_MB_2U_LIB.S9S_MB_2U(SCH_1):LED_RST_RSMRST_PLD_R_N_D

Q_RES_0402LF-130,1%,1/16W,CHIPA  I14  R3074
   1 LED_RST_RSMRST_PLD_R_N      A @S9S_MB_2U_LIB.S9S_MB_2U(SCH_1):LED_RST_RSMRST_PLD_R_N
   2 P3V3_AUX      B @S9S_MB_2U_LIB.S9S_MB_2U(SCH_1):P3V3_AUX

Q_RES_0402LF-130,1%,1/16W,CHIPA  I15  R3072
   1 LED_PWRGD_P1V05_PCH_AUX      A @S9S_MB_2U_LIB.S9S_MB_2U(SCH_1):LED_PWRGD_P1V05_PCH_AUX
   2 P3V3_AUX      B @S9S_MB_2U_LIB.S9S_MB_2U(SCH_1):P3V3_AUX

MOSFET_NCH_DUAL-PJT138K,SMLF,IA  I17  Q76
   1    GND     S1 @S9S_MB_2U_LIB.S9S_MB_2U(SCH_1):GND
   2 PWRGD_P1V8_PCH_AUX     G1 @S9S_MB_2U_LIB.S9S_MB_2U(SCH_1):PWRGD_P1V8_PCH_AUX
   6 LED_PWRGD_P1V8_PCH_AUX_D     D1 @S9S_MB_2U_LIB.S9S_MB_2U(SCH_1):LED_PWRGD_P1V8_PCH_AUX_D

Q_LED_SMLF-LED_BLUE,LTST-C281TA  I18  D91
   A LED_PWRGD_P1V8_PCH_AUX      A @S9S_MB_2U_LIB.S9S_MB_2U(SCH_1):LED_PWRGD_P1V8_PCH_AUX
   C LED_PWRGD_P1V8_PCH_AUX_D      C @S9S_MB_2U_LIB.S9S_MB_2U(SCH_1):LED_PWRGD_P1V8_PCH_AUX_D

Q_RES_0402LF-130,1%,1/16W,CHIPA  I19  R3071
   1 LED_PWRGD_P1V8_PCH_AUX      A @S9S_MB_2U_LIB.S9S_MB_2U(SCH_1):LED_PWRGD_P1V8_PCH_AUX
   2 P3V3_AUX      B @S9S_MB_2U_LIB.S9S_MB_2U(SCH_1):P3V3_AUX

MOSFET_NCH_DUAL-PJT138K,SMLF,IA  I26  Q78
   3 LED_PWRGD_PS_PWROK_PLD_D     D2 @S9S_MB_2U_LIB.S9S_MB_2U(SCH_1):LED_PWRGD_PS_PWROK_PLD_D
   5 PWRGD_PS_PWROK_PLD     G2 @S9S_MB_2U_LIB.S9S_MB_2U(SCH_1):PWRGD_PS_PWROK_PLD
   4    GND     S2 @S9S_MB_2U_LIB.S9S_MB_2U(SCH_1):GND

Q_LED_SMLF-LED_BLUE,LTST-C281TA  I31  D96
   A LED_PWRGD_PS_PWROK_PLD      A @S9S_MB_2U_LIB.S9S_MB_2U(SCH_1):LED_PWRGD_PS_PWROK_PLD
   C LED_PWRGD_PS_PWROK_PLD_D      C @S9S_MB_2U_LIB.S9S_MB_2U(SCH_1):LED_PWRGD_PS_PWROK_PLD_D

MOSFET_NCH_DUAL-PJT138K,SMLF,IA  I34  Q78
   1    GND     S1 @S9S_MB_2U_LIB.S9S_MB_2U(SCH_1):GND
   2 FM_PCH_SLP_S3_N     G1 @S9S_MB_2U_LIB.S9S_MB_2U(SCH_1):FM_PCH_SLP_S3_N
   6 LED_FM_PCH_SLP_S3_N_D     D1 @S9S_MB_2U_LIB.S9S_MB_2U(SCH_1):LED_FM_PCH_SLP_S3_N_D

Q_LED_SMLF-LED_BLUE,LTST-C281TA  I35  D95
   A LED_FM_PCH_SLP_S3_N      A @S9S_MB_2U_LIB.S9S_MB_2U(SCH_1):LED_FM_PCH_SLP_S3_N
   C LED_FM_PCH_SLP_S3_N_D      C @S9S_MB_2U_LIB.S9S_MB_2U(SCH_1):LED_FM_PCH_SLP_S3_N_D

Q_RES_0402LF-130,1%,1/16W,CHIPA  I37  R3075
   1 LED_PWRGD_PS_PWROK_PLD      A @S9S_MB_2U_LIB.S9S_MB_2U(SCH_1):LED_PWRGD_PS_PWROK_PLD
   2 P3V3_AUX      B @S9S_MB_2U_LIB.S9S_MB_2U(SCH_1):P3V3_AUX

Q_RES_0402LF-130,1%,1/16W,CHIPA  I41  R3078
   1 LED_FM_PCH_SLP_S3_N      A @S9S_MB_2U_LIB.S9S_MB_2U(SCH_1):LED_FM_PCH_SLP_S3_N
   2 P3V3_AUX      B @S9S_MB_2U_LIB.S9S_MB_2U(SCH_1):P3V3_AUX

Q_LED_SMLF-LED_BLUE,LTST-C281TA  I42  D92
   A LED_PWRGD_P1V05_PCH_AUX      A @S9S_MB_2U_LIB.S9S_MB_2U(SCH_1):LED_PWRGD_P1V05_PCH_AUX
   C LED_PWRGD_P1V05_PCH_AUX_D      C @S9S_MB_2U_LIB.S9S_MB_2U(SCH_1):LED_PWRGD_P1V05_PCH_AUX_D

Q_LED_SMLF-LED_BLUE,LTST-C281TA  I52  D97
   A LED_P5V_AUX      A @S9S_MB_2U_LIB.S9S_MB_2U(SCH_1):LED_P5V_AUX
   C    GND      C @S9S_MB_2U_LIB.S9S_MB_2U(SCH_1):GND

Q_LED_SMLF-LED_BLUE,LTST-C281TA  I53  D98
   A LED_P5V      A @S9S_MB_2U_LIB.S9S_MB_2U(SCH_1):LED_P5V
   C    GND      C @S9S_MB_2U_LIB.S9S_MB_2U(SCH_1):GND

Q_LED_SMLF-LED_BLUE,LTST-C281TA  I60  D99
   A LED_P3V3      A @S9S_MB_2U_LIB.S9S_MB_2U(SCH_1):LED_P3V3
   C    GND      C @S9S_MB_2U_LIB.S9S_MB_2U(SCH_1):GND

Q_RES_0402LF-470,1%,1/16W,CHIPA  I61  R3102
   1 LED_P5V      A @S9S_MB_2U_LIB.S9S_MB_2U(SCH_1):LED_P5V
   2    P5V      B @S9S_MB_2U_LIB.S9S_MB_2U(SCH_1):P5V

Q_RES_0402LF-470,1%,1/16W,CHIPA  I62  R3101
   1 LED_P5V_AUX      A @S9S_MB_2U_LIB.S9S_MB_2U(SCH_1):LED_P5V_AUX
   2 P5V_AUX      B @S9S_MB_2U_LIB.S9S_MB_2U(SCH_1):P5V_AUX

Q_RES_0402LF-130,1%,1/16W,CHIPA  I64  R3100
   1 LED_P3V3      A @S9S_MB_2U_LIB.S9S_MB_2U(SCH_1):LED_P3V3
   2   P3V3      B @S9S_MB_2U_LIB.S9S_MB_2U(SCH_1):P3V3


DRAWING: @S9S_MB_2U_LIB.S9S_MB_2U(SCH_1):PAGE306 

MOSFET_NCH_DUAL-PJT138K,SMLF,IA  I3  Q85
   3 LED_PWRGD_PVCCFA_EHV_FIVRA_CP_2     D2 @S9S_MB_2U_LIB.S9S_MB_2U(SCH_1):LED_PWRGD_PVCCFA_EHV_FIVRA_CPU1_D
   5 PWRGD_PVCCFA_EHV_FIVRA_CPU1     G2 @S9S_MB_2U_LIB.S9S_MB_2U(SCH_1):PWRGD_PVCCFA_EHV_FIVRA_CPU1
   4    GND     S2 @S9S_MB_2U_LIB.S9S_MB_2U(SCH_1):GND

MOSFET_NCH_DUAL-PJT138K,SMLF,IA  I6  Q85
   1    GND     S1 @S9S_MB_2U_LIB.S9S_MB_2U(SCH_1):GND
   2 PWRGD_PVCCFA_EHV_CPU1     G1 @S9S_MB_2U_LIB.S9S_MB_2U(SCH_1):PWRGD_PVCCFA_EHV_CPU1
   6 LED_PWRGD_PVCCFA_EHV_CPU1_D     D1 @S9S_MB_2U_LIB.S9S_MB_2U(SCH_1):LED_PWRGD_PVCCFA_EHV_CPU1_D

MOSFET_NCH_DUAL-PJT138K,SMLF,IA  I8  Q84
   3 LED_PWRGD_PVPP_HBM_CPU1_D     D2 @S9S_MB_2U_LIB.S9S_MB_2U(SCH_1):LED_PWRGD_PVPP_HBM_CPU1_D
   5 PWRGD_PVPP_HBM_CPU1     G2 @S9S_MB_2U_LIB.S9S_MB_2U(SCH_1):PWRGD_PVPP_HBM_CPU1
   4    GND     S2 @S9S_MB_2U_LIB.S9S_MB_2U(SCH_1):GND

Q_LED_SMLF-LED_BLUE,LTST-C281TA  I11  D83
   A LED_PWRGD_PVCCFA_EHV_FIVRA_CPU1      A @S9S_MB_2U_LIB.S9S_MB_2U(SCH_1):LED_PWRGD_PVCCFA_EHV_FIVRA_CPU1
   C LED_PWRGD_PVCCFA_EHV_FIVRA_CP_2      C @S9S_MB_2U_LIB.S9S_MB_2U(SCH_1):LED_PWRGD_PVCCFA_EHV_FIVRA_CPU1_D

Q_RES_0402LF-130,1%,1/16W,CHIPA  I12  R3095
   1 LED_PWRGD_PVCCFA_EHV_FIVRA_CPU1      A @S9S_MB_2U_LIB.S9S_MB_2U(SCH_1):LED_PWRGD_PVCCFA_EHV_FIVRA_CPU1
   2 P3V3_AUX      B @S9S_MB_2U_LIB.S9S_MB_2U(SCH_1):P3V3_AUX

Q_LED_SMLF-LED_BLUE,LTST-C281TA  I13  D82
   A LED_PWRGD_PVCCFA_EHV_CPU1      A @S9S_MB_2U_LIB.S9S_MB_2U(SCH_1):LED_PWRGD_PVCCFA_EHV_CPU1
   C LED_PWRGD_PVCCFA_EHV_CPU1_D      C @S9S_MB_2U_LIB.S9S_MB_2U(SCH_1):LED_PWRGD_PVCCFA_EHV_CPU1_D

Q_LED_SMLF-LED_BLUE,LTST-C281TA  I14  D81
   A LED_PWRGD_PVPP_HBM_CPU1      A @S9S_MB_2U_LIB.S9S_MB_2U(SCH_1):LED_PWRGD_PVPP_HBM_CPU1
   C LED_PWRGD_PVPP_HBM_CPU1_D      C @S9S_MB_2U_LIB.S9S_MB_2U(SCH_1):LED_PWRGD_PVPP_HBM_CPU1_D

Q_RES_0402LF-130,1%,1/16W,CHIPA  I15  R3096
   1 LED_PWRGD_PVCCFA_EHV_CPU1      A @S9S_MB_2U_LIB.S9S_MB_2U(SCH_1):LED_PWRGD_PVCCFA_EHV_CPU1
   2 P3V3_AUX      B @S9S_MB_2U_LIB.S9S_MB_2U(SCH_1):P3V3_AUX

Q_RES_0402LF-130,1%,1/16W,CHIPA  I16  R3094
   1 LED_PWRGD_PVPP_HBM_CPU1      A @S9S_MB_2U_LIB.S9S_MB_2U(SCH_1):LED_PWRGD_PVPP_HBM_CPU1
   2 P3V3_AUX      B @S9S_MB_2U_LIB.S9S_MB_2U(SCH_1):P3V3_AUX

MOSFET_NCH_DUAL-PJT138K,SMLF,IA  I18  Q84
   1    GND     S1 @S9S_MB_2U_LIB.S9S_MB_2U(SCH_1):GND
   2 PWRGD_PVCCD_HV_CPU1     G1 @S9S_MB_2U_LIB.S9S_MB_2U(SCH_1):PWRGD_PVCCD_HV_CPU1
   6 LED_PWRGD_PVCCD_HV_CPU1_D     D1 @S9S_MB_2U_LIB.S9S_MB_2U(SCH_1):LED_PWRGD_PVCCD_HV_CPU1_D

Q_LED_SMLF-LED_BLUE,LTST-C281TA  I19  D80
   A LED_PWRGD_PVCCD_HV_CPU1      A @S9S_MB_2U_LIB.S9S_MB_2U(SCH_1):LED_PWRGD_PVCCD_HV_CPU1
   C LED_PWRGD_PVCCD_HV_CPU1_D      C @S9S_MB_2U_LIB.S9S_MB_2U(SCH_1):LED_PWRGD_PVCCD_HV_CPU1_D

Q_RES_0402LF-130,1%,1/16W,CHIPA  I20  R3093
   1 LED_PWRGD_PVCCD_HV_CPU1      A @S9S_MB_2U_LIB.S9S_MB_2U(SCH_1):LED_PWRGD_PVCCD_HV_CPU1
   2 P3V3_AUX      B @S9S_MB_2U_LIB.S9S_MB_2U(SCH_1):P3V3_AUX

MOSFET_NCH_DUAL-PJT138K,SMLF,IA  I27  Q86
   3 LED_PWRGD_PVNN_MAIN_CPU1_D     D2 @S9S_MB_2U_LIB.S9S_MB_2U(SCH_1):LED_PWRGD_PVNN_MAIN_CPU1_D
   5 PWRGD_PVNN_MAIN_CPU1     G2 @S9S_MB_2U_LIB.S9S_MB_2U(SCH_1):PWRGD_PVNN_MAIN_CPU1
   4    GND     S2 @S9S_MB_2U_LIB.S9S_MB_2U(SCH_1):GND

Q_LED_SMLF-LED_BLUE,LTST-C281TA  I30  D86
   A LED_PWRGD_PVCCIN_CPU1      A @S9S_MB_2U_LIB.S9S_MB_2U(SCH_1):LED_PWRGD_PVCCIN_CPU1
   C LED_PWRGD_PVCCIN_CPU1_D      C @S9S_MB_2U_LIB.S9S_MB_2U(SCH_1):LED_PWRGD_PVCCIN_CPU1_D

Q_LED_SMLF-LED_BLUE,LTST-C281TA  I32  D85
   A LED_PWRGD_PVNN_MAIN_CPU1      A @S9S_MB_2U_LIB.S9S_MB_2U(SCH_1):LED_PWRGD_PVNN_MAIN_CPU1
   C LED_PWRGD_PVNN_MAIN_CPU1_D      C @S9S_MB_2U_LIB.S9S_MB_2U(SCH_1):LED_PWRGD_PVNN_MAIN_CPU1_D

MOSFET_NCH_DUAL-PJT138K,SMLF,IA  I35  Q86
   1    GND     S1 @S9S_MB_2U_LIB.S9S_MB_2U(SCH_1):GND
   2 PWRGD_PVCCINFAON_CPU1     G1 @S9S_MB_2U_LIB.S9S_MB_2U(SCH_1):PWRGD_PVCCINFAON_CPU1
   6 LED_PWRGD_PVCCINFAON_CPU1_D     D1 @S9S_MB_2U_LIB.S9S_MB_2U(SCH_1):LED_PWRGD_PVCCINFAON_CPU1_D

Q_LED_SMLF-LED_BLUE,LTST-C281TA  I36  D84
   A LED_PWRGD_PVCCINFAON_CPU1      A @S9S_MB_2U_LIB.S9S_MB_2U(SCH_1):LED_PWRGD_PVCCINFAON_CPU1
   C LED_PWRGD_PVCCINFAON_CPU1_D      C @S9S_MB_2U_LIB.S9S_MB_2U(SCH_1):LED_PWRGD_PVCCINFAON_CPU1_D

Q_RES_0402LF-130,1%,1/16W,CHIPA  I37  R3098
   1 LED_PWRGD_PVCCIN_CPU1      A @S9S_MB_2U_LIB.S9S_MB_2U(SCH_1):LED_PWRGD_PVCCIN_CPU1
   2 P3V3_AUX      B @S9S_MB_2U_LIB.S9S_MB_2U(SCH_1):P3V3_AUX

Q_RES_0402LF-130,1%,1/16W,CHIPA  I38  R3097
   1 LED_PWRGD_PVNN_MAIN_CPU1      A @S9S_MB_2U_LIB.S9S_MB_2U(SCH_1):LED_PWRGD_PVNN_MAIN_CPU1
   2 P3V3_AUX      B @S9S_MB_2U_LIB.S9S_MB_2U(SCH_1):P3V3_AUX

Q_RES_0402LF-130,1%,1/16W,CHIPA  I41  R3099
   1 LED_PWRGD_PVCCINFAON_CPU1      A @S9S_MB_2U_LIB.S9S_MB_2U(SCH_1):LED_PWRGD_PVCCINFAON_CPU1
   2 P3V3_AUX      B @S9S_MB_2U_LIB.S9S_MB_2U(SCH_1):P3V3_AUX

MOSFET_NCH_DUAL-PJT138K,SMLF,IA  I43  Q83
   3 LED_PWRGD_PVCCIN_CPU1_D     D2 @S9S_MB_2U_LIB.S9S_MB_2U(SCH_1):LED_PWRGD_PVCCIN_CPU1_D
   5 PWRGD_PVCCIN_CPU1     G2 @S9S_MB_2U_LIB.S9S_MB_2U(SCH_1):PWRGD_PVCCIN_CPU1
   4    GND     S2 @S9S_MB_2U_LIB.S9S_MB_2U(SCH_1):GND


DRAWING: @S9S_MB_2U_LIB.S9S_MB_2U(SCH_1):PAGE234 

Q_RES_0402LF-0,5%,1/16W,CHIP,CA  I3  R2531
   1 MB0_P12V_STBY_PWRGD      A @S9S_MB_2U_LIB.S9S_MB_2U(SCH_1):MB0_P12V_STBY_PWRGD
   2 FM_P12V_HSC_EN_R      B @S9S_MB_2U_LIB.S9S_MB_2U(SCH_1):FM_P12V_HSC_EN_R

MOSFET_NCH_GDS_ESD_PROTECTED-2A  I6  U158
   D FM_P12V_HSC_EN_N      D @S9S_MB_2U_LIB.S9S_MB_2U(SCH_1):FM_P12V_HSC_EN_N
   G FM_P12V_HSC_EN_R      G @S9S_MB_2U_LIB.S9S_MB_2U(SCH_1):FM_P12V_HSC_EN_R
   S    GND      S @S9S_MB_2U_LIB.S9S_MB_2U(SCH_1):GND

Q_RES_0402LF-0,5%,1/16W,CHIP,CA  I7  R2529
   1 FM_P12V_HSC_EN_N      A @S9S_MB_2U_LIB.S9S_MB_2U(SCH_1):FM_P12V_HSC_EN_N
   2 FM_P12V_HSC_EN_R_N      B @S9S_MB_2U_LIB.S9S_MB_2U(SCH_1):FM_P12V_HSC_EN_R_N

Q_RES_0402LF-100K,1%,1/16W,CHIA  I8  R2528
   1 P12V_AUX      A @S9S_MB_2U_LIB.S9S_MB_2U(SCH_1):P12V_AUX
   2 FM_P12V_HSC_EN_N      B @S9S_MB_2U_LIB.S9S_MB_2U(SCH_1):FM_P12V_HSC_EN_N

Q_RES_0402LF-4.7K,5%,1/16W,CHIA  I10  R2530
   1 P12V_AUX      A @S9S_MB_2U_LIB.S9S_MB_2U(SCH_1):P12V_AUX
   2 P12V_AUX_BLEEDING      B @S9S_MB_2U_LIB.S9S_MB_2U(SCH_1):P12V_AUX_BLEEDING

MOSFET_NCH_GDS_ESD_PROTECTED-2A  I14  Q54
   D P12V_AUX_BLEEDING      D @S9S_MB_2U_LIB.S9S_MB_2U(SCH_1):P12V_AUX_BLEEDING
   G FM_P12V_HSC_EN_R_N      G @S9S_MB_2U_LIB.S9S_MB_2U(SCH_1):FM_P12V_HSC_EN_R_N
   S    GND      S @S9S_MB_2U_LIB.S9S_MB_2U(SCH_1):GND


DRAWING: @S9S_MB_2U_LIB.S9S_MB_2U(SCH_1):PAGE131 

Q_CAP_0402-0.1UF,25V,10%,X7R,CA  I26  C1809
   1 P3V3_AUX      A @S9S_MB_2U_LIB.S9S_MB_2U(SCH_1):P3V3_AUX
   2    GND      B @S9S_MB_2U_LIB.S9S_MB_2U(SCH_1):GND

MOSFET_NCH_DUAL-PJT138K,SMLF,IA  I38  Q119
   1    GND     S1 @S9S_MB_2U_LIB.S9S_MB_2U(SCH_1):GND
   2 P3V3_OCP_EN_2_R     G1 @S9S_MB_2U_LIB.S9S_MB_2U(SCH_1):P3V3_OCP_EN_2_R
   6 P3V3_OCP_2_EN_G     D1 @S9S_MB_2U_LIB.S9S_MB_2U(SCH_1):P3V3_OCP_2_EN_G

Q_CAP_C0402-1UF,25V,10%,X6S,CHA  I87  PC2147
   1    GND      A @S9S_MB_2U_LIB.S9S_MB_2U(SCH_1):GND
   2 P3V3_OCP_REG_2      B @S9S_MB_2U_LIB.S9S_MB_2U(SCH_1):P3V3_OCP_REG_2

Q_RES_0402LF-30.1K,1%,1/16W,EMA  I59  PR3821
   1 P12V_OCP_CB_2      A @S9S_MB_2U_LIB.S9S_MB_2U(SCH_1):P12V_OCP_CB_2
   2    GND      B @S9S_MB_2U_LIB.S9S_MB_2U(SCH_1):GND

Q_RES_0402LF-10K,1%,1/16W,CHIPA  I70  R4761
   1 P3V3_AUX      A @S9S_MB_2U_LIB.S9S_MB_2U(SCH_1):P3V3_AUX
   2 HP_LVC3_OCP_V3_2_PRSNT2_PLD_N      B @S9S_MB_2U_LIB.S9S_MB_2U(SCH_1):HP_LVC3_OCP_V3_2_PRSNT2_PLD_N

Q_RES_0402LF-10,1%,1/16W,EMPTYA  I85  PR3830
   1 P12V_AUX      A @S9S_MB_2U_LIB.S9S_MB_2U(SCH_1):P12V_AUX
   2 P12V_OCP_VCC_2      B @S9S_MB_2U_LIB.S9S_MB_2U(SCH_1):P12V_OCP_VCC_2

Q_RES_0402LF-0,5%,1/16W,CHIP,CA  I97  R3832
   1 P3V3_OCP_PWRGD_2      A @S9S_MB_2U_LIB.S9S_MB_2U(SCH_1):P3V3_OCP_PWRGD_2
   2 OCP_V3_2_P3V3_PWRGD      B @S9S_MB_2U_LIB.S9S_MB_2U(SCH_1):OCP_V3_2_P3V3_PWRGD

Q_RES_0402LF-160K,1%,1/16W,EMPA  I33  PR3805
   1 P12V_AUX      A @S9S_MB_2U_LIB.S9S_MB_2U(SCH_1):P12V_AUX
   2 P12V_OCP_UV_2      B @S9S_MB_2U_LIB.S9S_MB_2U(SCH_1):P12V_OCP_UV_2

Q_RES_0402LF-0,5%,1/16W,CHIP,CA  I35  R4060
   1 HP_LVC3_OCP_V3_2_EN      A @S9S_MB_2U_LIB.S9S_MB_2U(SCH_1):HP_LVC3_OCP_V3_2_EN
   2 P3V3_OCP_EN_2_R      B @S9S_MB_2U_LIB.S9S_MB_2U(SCH_1):P3V3_OCP_EN_2_R

Q_RES_0402LF-10K,1%,1/16W,CHIPA  I40  R4067
   1 P12V_AUX      A @S9S_MB_2U_LIB.S9S_MB_2U(SCH_1):P12V_AUX
   2 P3V3_OCP_2_EN_G      B @S9S_MB_2U_LIB.S9S_MB_2U(SCH_1):P3V3_OCP_2_EN_G

Q_RES_0402LF-15K,1%,1/16W,CHIPA  I48  PR3812
   1 P3V3_OCP_OV_2      A @S9S_MB_2U_LIB.S9S_MB_2U(SCH_1):P3V3_OCP_OV_2
   2    GND      B @S9S_MB_2U_LIB.S9S_MB_2U(SCH_1):GND

Q_RES_0402LF-0,5%,1/16W,CHIP,CA  I57  R3142
   1 HP_LVC3_OCP_V3_2_PRSNT2_N_R      A @S9S_MB_2U_LIB.S9S_MB_2U(SCH_1):HP_LVC3_OCP_V3_2_PRSNT2_N_R
   2 HP_LVC3_OCP_V3_2_PRSNT2_N      B @S9S_MB_2U_LIB.S9S_MB_2U(SCH_1):HP_LVC3_OCP_V3_2_PRSNT2_N

Q_RES_0402LF-0,5%,1/16W,EMPTY,A  I74  R3868
   1 P12V_OCP_SENSE_2      A @S9S_MB_2U_LIB.S9S_MB_2U(SCH_1):P12V_OCP_SENSE_2
   2 P12V_OCP_V3_2_ISENSE_MAM_TIC      B @S9S_MB_2U_LIB.S9S_MB_2U(SCH_1):P12V_OCP_V3_2_ISENSE_MAM_TIC

Q_RES_0402LF-0,5%,1/16W,EMPTY,A  I78  R3831
   1 P12V_OCP_PWRGD_2      A @S9S_MB_2U_LIB.S9S_MB_2U(SCH_1):P12V_OCP_PWRGD_2
   2 HP_LVC3_OCP_V3_2_P12V_PWRGD      B @S9S_MB_2U_LIB.S9S_MB_2U(SCH_1):HP_LVC3_OCP_V3_2_P12V_PWRGD

Q_RES_0402LF-100K,1%,1/16W,EMPA  I80  R3816
   1 P3V3_AUX      A @S9S_MB_2U_LIB.S9S_MB_2U(SCH_1):P3V3_AUX
   2 P12V_OCP_FAULT_2      B @S9S_MB_2U_LIB.S9S_MB_2U(SCH_1):P12V_OCP_FAULT_2

Q_RES_0402LF-1K,1%,1/16W,CHIP,A  I3  R3134
   1 P3V3_AUX      A @S9S_MB_2U_LIB.S9S_MB_2U(SCH_1):P3V3_AUX
   2 OCP_V3_2_PRSNT2_R_N      B @S9S_MB_2U_LIB.S9S_MB_2U(SCH_1):OCP_V3_2_PRSNT2_R_N

Q_RES_0402LF-1K,1%,1/16W,CHIP,A  I5  R3136
   1 P3V3_AUX      A @S9S_MB_2U_LIB.S9S_MB_2U(SCH_1):P3V3_AUX
   2 OCP_V3_2_PRSNT3_R_N      B @S9S_MB_2U_LIB.S9S_MB_2U(SCH_1):OCP_V3_2_PRSNT3_R_N

Q_RES_0402LF-0,5%,1/16W,EMPTY,A  I6  R4059
   1 HP_LVC3_OCP_V3_2_EN      A @S9S_MB_2U_LIB.S9S_MB_2U(SCH_1):HP_LVC3_OCP_V3_2_EN
   2 P12V_OCP_EN_2_R      B @S9S_MB_2U_LIB.S9S_MB_2U(SCH_1):P12V_OCP_EN_2_R

Q_RES_0402LF-1K,1%,1/16W,CHIP,A  I11  R3133
   1 P3V3_AUX      A @S9S_MB_2U_LIB.S9S_MB_2U(SCH_1):P3V3_AUX
   2 OCP_V3_2_PRSNT0_R_N      B @S9S_MB_2U_LIB.S9S_MB_2U(SCH_1):OCP_V3_2_PRSNT0_R_N

Q_RES_0402LF-1K,1%,1/16W,CHIP,A  I13  R3135
   1 P3V3_AUX      A @S9S_MB_2U_LIB.S9S_MB_2U(SCH_1):P3V3_AUX
   2 OCP_V3_2_PRSNT1_R_N      B @S9S_MB_2U_LIB.S9S_MB_2U(SCH_1):OCP_V3_2_PRSNT1_R_N

Q_RES_0402LF-10K,1%,1/16W,EMPTA  I14  R4065
   1 P12V_AUX      A @S9S_MB_2U_LIB.S9S_MB_2U(SCH_1):P12V_AUX
   2 P12V_OCP_2_EN_G      B @S9S_MB_2U_LIB.S9S_MB_2U(SCH_1):P12V_OCP_2_EN_G

MOSFET_NCH_DUAL-PJT138K,SMLF,EA  I16  Q118
   3 P12V_OCP_UV_2_R     D2 @S9S_MB_2U_LIB.S9S_MB_2U(SCH_1):P12V_OCP_UV_2_R
   5 P12V_OCP_2_EN_G     G2 @S9S_MB_2U_LIB.S9S_MB_2U(SCH_1):P12V_OCP_2_EN_G
   4    GND     S2 @S9S_MB_2U_LIB.S9S_MB_2U(SCH_1):GND

74LVC2G07DW7-74LVC2G07DW-7,SMLA  I19  U59
   1 OCP_V3_2_PRSNT2_R_N     1A @S9S_MB_2U_LIB.S9S_MB_2U(SCH_1):OCP_V3_2_PRSNT2_R_N
   3 OCP_V3_2_PRSNT3_R_N     2A @S9S_MB_2U_LIB.S9S_MB_2U(SCH_1):OCP_V3_2_PRSNT3_R_N
   6 HP_LVC3_OCP_V3_2_PRSNT2_N_R     1Y @S9S_MB_2U_LIB.S9S_MB_2U(SCH_1):HP_LVC3_OCP_V3_2_PRSNT2_N_R
   4 HP_LVC3_OCP_V3_2_PRSNT2_N_R     2Y @S9S_MB_2U_LIB.S9S_MB_2U(SCH_1):HP_LVC3_OCP_V3_2_PRSNT2_N_R
   2    GND    GND @S9S_MB_2U_LIB.S9S_MB_2U(SCH_1):GND
   5 P3V3_AUX    VCC @S9S_MB_2U_LIB.S9S_MB_2U(SCH_1):P3V3_AUX

74LVC2G07DW7-74LVC2G07DW-7,SMLA  I25  U58
   1 OCP_V3_2_PRSNT0_R_N     1A @S9S_MB_2U_LIB.S9S_MB_2U(SCH_1):OCP_V3_2_PRSNT0_R_N
   3 OCP_V3_2_PRSNT1_R_N     2A @S9S_MB_2U_LIB.S9S_MB_2U(SCH_1):OCP_V3_2_PRSNT1_R_N
   6 HP_LVC3_OCP_V3_2_PRSNT2_N_R     1Y @S9S_MB_2U_LIB.S9S_MB_2U(SCH_1):HP_LVC3_OCP_V3_2_PRSNT2_N_R
   4 HP_LVC3_OCP_V3_2_PRSNT2_N_R     2Y @S9S_MB_2U_LIB.S9S_MB_2U(SCH_1):HP_LVC3_OCP_V3_2_PRSNT2_N_R
   2    GND    GND @S9S_MB_2U_LIB.S9S_MB_2U(SCH_1):GND
   5 P3V3_AUX    VCC @S9S_MB_2U_LIB.S9S_MB_2U(SCH_1):P3V3_AUX

Q_RES_0402LF-6.8K,1%,1/16W,EMPA  I32  PR3806
   1 P12V_OCP_UV_2      A @S9S_MB_2U_LIB.S9S_MB_2U(SCH_1):P12V_OCP_UV_2
   2 P12V_OCP_OV_2      B @S9S_MB_2U_LIB.S9S_MB_2U(SCH_1):P12V_OCP_OV_2

MOSFET_NCH_DUAL-PJT138K,SMLF,IA  I42  Q119
   3 P3V3_OCP_UV_2_R1     D2 @S9S_MB_2U_LIB.S9S_MB_2U(SCH_1):P3V3_OCP_UV_2_R1
   5 P3V3_OCP_2_EN_G     G2 @S9S_MB_2U_LIB.S9S_MB_2U(SCH_1):P3V3_OCP_2_EN_G
   4    GND     S2 @S9S_MB_2U_LIB.S9S_MB_2U(SCH_1):GND

Q_RES_0402LF-0,5%,1/16W,CHIP,CA  I47  R3807
   1 P3V3_OCP_UV_2_R1      A @S9S_MB_2U_LIB.S9S_MB_2U(SCH_1):P3V3_OCP_UV_2_R1
   2 P3V3_OCP_UV_2      B @S9S_MB_2U_LIB.S9S_MB_2U(SCH_1):P3V3_OCP_UV_2

Q_CAP_C0402-1UF,25V,10%,X6S,CHA  I52  PC2140
   1 P3V3_AUX      A @S9S_MB_2U_LIB.S9S_MB_2U(SCH_1):P3V3_AUX
   2    GND      B @S9S_MB_2U_LIB.S9S_MB_2U(SCH_1):GND

Q_RES_0402LF-0,5%,1/16W,CHIP,CA  I56  R3143
   1 HP_LVC3_OCP_V3_2_PRSNT2_N_R      A @S9S_MB_2U_LIB.S9S_MB_2U(SCH_1):HP_LVC3_OCP_V3_2_PRSNT2_N_R
   2 HP_LVC3_OCP_V3_2_ATTN_OUT_SW_N      B @S9S_MB_2U_LIB.S9S_MB_2U(SCH_1):HP_LVC3_OCP_V3_2_ATTN_OUT_SW_N

MAX15090BEWIT-MAX15090BEWI+T,SA  I63  PU201
  A2 P12V_OCP_VCC_2    VCC @S9S_MB_2U_LIB.S9S_MB_2U(SCH_1):P12V_OCP_VCC_2
  A3 P12V_AUX  IN_A3 @S9S_MB_2U_LIB.S9S_MB_2U(SCH_1):P12V_AUX
  A5 P12V_AUX  IN_A5 @S9S_MB_2U_LIB.S9S_MB_2U(SCH_1):P12V_AUX
  B3 P12V_AUX  IN_B3 @S9S_MB_2U_LIB.S9S_MB_2U(SCH_1):P12V_AUX
  B5 P12V_AUX  IN_B5 @S9S_MB_2U_LIB.S9S_MB_2U(SCH_1):P12V_AUX
  C3 P12V_AUX  IN_C3 @S9S_MB_2U_LIB.S9S_MB_2U(SCH_1):P12V_AUX
  C5 P12V_AUX  IN_C5 @S9S_MB_2U_LIB.S9S_MB_2U(SCH_1):P12V_AUX
  D5 P12V_AUX  IN_D5 @S9S_MB_2U_LIB.S9S_MB_2U(SCH_1):P12V_AUX
  B1 P12V_OCP_CB_2     CB @S9S_MB_2U_LIB.S9S_MB_2U(SCH_1):P12V_OCP_CB_2
  B7    GND    EN# @S9S_MB_2U_LIB.S9S_MB_2U(SCH_1):GND
  D1 P12V_OCP_REG_2    REG @S9S_MB_2U_LIB.S9S_MB_2U(SCH_1):P12V_OCP_REG_2
  D2 P12V_OCP_UV_2     UV @S9S_MB_2U_LIB.S9S_MB_2U(SCH_1):P12V_OCP_UV_2
  D3 P12V_OCP_OV_2     OV @S9S_MB_2U_LIB.S9S_MB_2U(SCH_1):P12V_OCP_OV_2
  A1 P12V_OCP_SENSE_2 ISENSE @S9S_MB_2U_LIB.S9S_MB_2U(SCH_1):P12V_OCP_SENSE_2
  A4 P12V_OCP_V3_2 OUT_A4 @S9S_MB_2U_LIB.S9S_MB_2U(SCH_1):P12V_OCP_V3_2
  B4 P12V_OCP_V3_2 OUT_B4 @S9S_MB_2U_LIB.S9S_MB_2U(SCH_1):P12V_OCP_V3_2
  B6 P12V_OCP_V3_2 OUT_B6 @S9S_MB_2U_LIB.S9S_MB_2U(SCH_1):P12V_OCP_V3_2
  C4 P12V_OCP_V3_2 OUT_C4 @S9S_MB_2U_LIB.S9S_MB_2U(SCH_1):P12V_OCP_V3_2
  C6 P12V_OCP_V3_2 OUT_C6 @S9S_MB_2U_LIB.S9S_MB_2U(SCH_1):P12V_OCP_V3_2
  D4 P12V_OCP_V3_2 OUT_D4 @S9S_MB_2U_LIB.S9S_MB_2U(SCH_1):P12V_OCP_V3_2
  D6 P12V_OCP_V3_2 OUT_D6 @S9S_MB_2U_LIB.S9S_MB_2U(SCH_1):P12V_OCP_V3_2
  A6 P12V_OCP_GATE_2   GATE @S9S_MB_2U_LIB.S9S_MB_2U(SCH_1):P12V_OCP_GATE_2
  A7    GND   CDLY @S9S_MB_2U_LIB.S9S_MB_2U(SCH_1):GND
  B2    GND GND_B2 @S9S_MB_2U_LIB.S9S_MB_2U(SCH_1):GND
  C1    GND GND_C1 @S9S_MB_2U_LIB.S9S_MB_2U(SCH_1):GND
  C2    GND GND_C2 @S9S_MB_2U_LIB.S9S_MB_2U(SCH_1):GND
  C7 P12V_OCP_FAULT_2 FAULT# @S9S_MB_2U_LIB.S9S_MB_2U(SCH_1):P12V_OCP_FAULT_2
  D7 P12V_OCP_PWRGD_2     PG @S9S_MB_2U_LIB.S9S_MB_2U(SCH_1):P12V_OCP_PWRGD_2

Q_RES_0402LF-10K,1%,1/16W,CHIPA  I66  R3147
   1 P3V3_AUX      A @S9S_MB_2U_LIB.S9S_MB_2U(SCH_1):P3V3_AUX
   2 HP_LVC3_OCP_V3_2_PRSNT2_N      B @S9S_MB_2U_LIB.S9S_MB_2U(SCH_1):HP_LVC3_OCP_V3_2_PRSNT2_N

Q_CAP_C0402-0.01UF,50V,10%,EMPA  I73  C2148
   1 P12V_OCP_V3_2      A @S9S_MB_2U_LIB.S9S_MB_2U(SCH_1):P12V_OCP_V3_2
   2 P12V_OCP_GATE_2      B @S9S_MB_2U_LIB.S9S_MB_2U(SCH_1):P12V_OCP_GATE_2

Q_RES_0402LF-100K,1%,1/16W,EMPA  I81  R3825
   1 P3V3_AUX      A @S9S_MB_2U_LIB.S9S_MB_2U(SCH_1):P3V3_AUX
   2 HP_LVC3_OCP_V3_2_P12V_PWRGD      B @S9S_MB_2U_LIB.S9S_MB_2U(SCH_1):HP_LVC3_OCP_V3_2_P12V_PWRGD

Q_RES_0402LF-5.36K,1%,1/16W,CHA  I89  PR3822
   1 P3V3_OCP_CB_2      A @S9S_MB_2U_LIB.S9S_MB_2U(SCH_1):P3V3_OCP_CB_2
   2    GND      B @S9S_MB_2U_LIB.S9S_MB_2U(SCH_1):GND

MAX15090BEWIT-MAX15090BEWI+T,SB  I90  PU200
  A2 P3V3_OCP_VCC_2    VCC @S9S_MB_2U_LIB.S9S_MB_2U(SCH_1):P3V3_OCP_VCC_2
  A3 P3V3_AUX  IN_A3 @S9S_MB_2U_LIB.S9S_MB_2U(SCH_1):P3V3_AUX
  A5 P3V3_AUX  IN_A5 @S9S_MB_2U_LIB.S9S_MB_2U(SCH_1):P3V3_AUX
  B3 P3V3_AUX  IN_B3 @S9S_MB_2U_LIB.S9S_MB_2U(SCH_1):P3V3_AUX
  B5 P3V3_AUX  IN_B5 @S9S_MB_2U_LIB.S9S_MB_2U(SCH_1):P3V3_AUX
  C3 P3V3_AUX  IN_C3 @S9S_MB_2U_LIB.S9S_MB_2U(SCH_1):P3V3_AUX
  C5 P3V3_AUX  IN_C5 @S9S_MB_2U_LIB.S9S_MB_2U(SCH_1):P3V3_AUX
  D5 P3V3_AUX  IN_D5 @S9S_MB_2U_LIB.S9S_MB_2U(SCH_1):P3V3_AUX
  B1 P3V3_OCP_CB_2     CB @S9S_MB_2U_LIB.S9S_MB_2U(SCH_1):P3V3_OCP_CB_2
  B7    GND    EN# @S9S_MB_2U_LIB.S9S_MB_2U(SCH_1):GND
  D1 P3V3_OCP_REG_2    REG @S9S_MB_2U_LIB.S9S_MB_2U(SCH_1):P3V3_OCP_REG_2
  D2 P3V3_OCP_UV_2     UV @S9S_MB_2U_LIB.S9S_MB_2U(SCH_1):P3V3_OCP_UV_2
  D3 P3V3_OCP_OV_2     OV @S9S_MB_2U_LIB.S9S_MB_2U(SCH_1):P3V3_OCP_OV_2
  A1 P3V3_OCP_SENSE_2 ISENSE @S9S_MB_2U_LIB.S9S_MB_2U(SCH_1):P3V3_OCP_SENSE_2
  A4 P3V3_OCP_V3_2_R OUT_A4 @S9S_MB_2U_LIB.S9S_MB_2U(SCH_1):P3V3_OCP_V3_2_R
  B4 P3V3_OCP_V3_2_R OUT_B4 @S9S_MB_2U_LIB.S9S_MB_2U(SCH_1):P3V3_OCP_V3_2_R
  B6 P3V3_OCP_V3_2_R OUT_B6 @S9S_MB_2U_LIB.S9S_MB_2U(SCH_1):P3V3_OCP_V3_2_R
  C4 P3V3_OCP_V3_2_R OUT_C4 @S9S_MB_2U_LIB.S9S_MB_2U(SCH_1):P3V3_OCP_V3_2_R
  C6 P3V3_OCP_V3_2_R OUT_C6 @S9S_MB_2U_LIB.S9S_MB_2U(SCH_1):P3V3_OCP_V3_2_R
  D4 P3V3_OCP_V3_2_R OUT_D4 @S9S_MB_2U_LIB.S9S_MB_2U(SCH_1):P3V3_OCP_V3_2_R
  D6 P3V3_OCP_V3_2_R OUT_D6 @S9S_MB_2U_LIB.S9S_MB_2U(SCH_1):P3V3_OCP_V3_2_R
  A6 P3V3_OCP_GATE_2   GATE @S9S_MB_2U_LIB.S9S_MB_2U(SCH_1):P3V3_OCP_GATE_2
  A7    GND   CDLY @S9S_MB_2U_LIB.S9S_MB_2U(SCH_1):GND
  B2    GND GND_B2 @S9S_MB_2U_LIB.S9S_MB_2U(SCH_1):GND
  C1    GND GND_C1 @S9S_MB_2U_LIB.S9S_MB_2U(SCH_1):GND
  C2    GND GND_C2 @S9S_MB_2U_LIB.S9S_MB_2U(SCH_1):GND
  C7 P3V3_OCP_FAULT_2 FAULT# @S9S_MB_2U_LIB.S9S_MB_2U(SCH_1):P3V3_OCP_FAULT_2
  D7 P3V3_OCP_PWRGD_2     PG @S9S_MB_2U_LIB.S9S_MB_2U(SCH_1):P3V3_OCP_PWRGD_2

Q_RES_0402LF-10,1%,1/16W,CHIP,A  I92  PR3782
   1 P3V3_AUX      A @S9S_MB_2U_LIB.S9S_MB_2U(SCH_1):P3V3_AUX
   2 P3V3_OCP_VCC_2      B @S9S_MB_2U_LIB.S9S_MB_2U(SCH_1):P3V3_OCP_VCC_2

SCHOTTKY_AC-B340A-13-F,SMLF,ICA  I93  PD108
   A    GND      A @S9S_MB_2U_LIB.S9S_MB_2U(SCH_1):GND
   C P12V_OCP_V3_2      C @S9S_MB_2U_LIB.S9S_MB_2U(SCH_1):P12V_OCP_V3_2

Q_CAP_C0402-6800PF,50V,10%,X7RA  I96  PC2151
   1 P3V3_OCP_GATE_2      A @S9S_MB_2U_LIB.S9S_MB_2U(SCH_1):P3V3_OCP_GATE_2
   2    GND      B @S9S_MB_2U_LIB.S9S_MB_2U(SCH_1):GND

Q_CAP_C0805-22UF,16V,20%,X6S,CC  I100  PC2141
   1 P12V_OCP_V3_2      A @S9S_MB_2U_LIB.S9S_MB_2U(SCH_1):P12V_OCP_V3_2
   2    GND      B @S9S_MB_2U_LIB.S9S_MB_2U(SCH_1):GND

Q_CAP_C0805-10UF,16V,10%,X6S,CC  I102  PC2143
   1 P12V_OCP_V3_2      A @S9S_MB_2U_LIB.S9S_MB_2U(SCH_1):P12V_OCP_V3_2
   2    GND      B @S9S_MB_2U_LIB.S9S_MB_2U(SCH_1):GND

Q_CAP_C0402-0.01UF,50V,10%,EMPA  I105  PC2149
   1 P3V3_OCP_V3_2_R      A @S9S_MB_2U_LIB.S9S_MB_2U(SCH_1):P3V3_OCP_V3_2_R
   2 P3V3_OCP_GATE_2      B @S9S_MB_2U_LIB.S9S_MB_2U(SCH_1):P3V3_OCP_GATE_2

SCHOTTKY_AC-B340A-13-F,SMLF,ICA  I107  PD109
   A    GND      A @S9S_MB_2U_LIB.S9S_MB_2U(SCH_1):GND
   C P3V3_OCP_V3_2_R      C @S9S_MB_2U_LIB.S9S_MB_2U(SCH_1):P3V3_OCP_V3_2_R

Q_CAP_0402-0.1UF,25V,10%,X7R,CA  I109  PC2137
   1 P3V3_OCP_V3_2_R      A @S9S_MB_2U_LIB.S9S_MB_2U(SCH_1):P3V3_OCP_V3_2_R
   2    GND      B @S9S_MB_2U_LIB.S9S_MB_2U(SCH_1):GND

Q_CAP_C0805-10UF,16V,10%,X6S,CB  I113  PC2142
   1 P3V3_OCP_V3_2_R      A @S9S_MB_2U_LIB.S9S_MB_2U(SCH_1):P3V3_OCP_V3_2_R
   2    GND      B @S9S_MB_2U_LIB.S9S_MB_2U(SCH_1):GND

MOSFET_NCH_DUAL-PJT138K,SMLF,EA  I7  Q118
   1    GND     S1 @S9S_MB_2U_LIB.S9S_MB_2U(SCH_1):GND
   2 P12V_OCP_EN_2_R     G1 @S9S_MB_2U_LIB.S9S_MB_2U(SCH_1):P12V_OCP_EN_2_R
   6 P12V_OCP_2_EN_G     D1 @S9S_MB_2U_LIB.S9S_MB_2U(SCH_1):P12V_OCP_2_EN_G

Q_CAP_0402-0.1UF,25V,10%,X7R,CA  I21  C1810
   1 P3V3_AUX      A @S9S_MB_2U_LIB.S9S_MB_2U(SCH_1):P3V3_AUX
   2    GND      B @S9S_MB_2U_LIB.S9S_MB_2U(SCH_1):GND

Q_RES_0402LF-15K,1%,1/16W,EMPTA  I29  PR3828
   1 P12V_OCP_OV_2      A @S9S_MB_2U_LIB.S9S_MB_2U(SCH_1):P12V_OCP_OV_2
   2    GND      B @S9S_MB_2U_LIB.S9S_MB_2U(SCH_1):GND

Q_RES_0402LF-0,5%,1/16W,EMPTY,A  I30  R3827
   1 P12V_OCP_UV_2_R      A @S9S_MB_2U_LIB.S9S_MB_2U(SCH_1):P12V_OCP_UV_2_R
   2 P12V_OCP_UV_2      B @S9S_MB_2U_LIB.S9S_MB_2U(SCH_1):P12V_OCP_UV_2

Q_RES_0402LF-4.7K,5%,1/16W,CHIA  I37  R4066
   1 P3V3_OCP_EN_2_R      A @S9S_MB_2U_LIB.S9S_MB_2U(SCH_1):P3V3_OCP_EN_2_R
   2    GND      B @S9S_MB_2U_LIB.S9S_MB_2U(SCH_1):GND

DIODE_TVS-SMF14A,SMLF,IC,BCSMFA  I44  PD107
   A    GND      A @S9S_MB_2U_LIB.S9S_MB_2U(SCH_1):GND
   C P12V_AUX      C @S9S_MB_2U_LIB.S9S_MB_2U(SCH_1):P12V_AUX

Q_CAP_C0402-1UF,25V,10%,X6S,CHA  I46  PC2139
   1 P12V_AUX      A @S9S_MB_2U_LIB.S9S_MB_2U(SCH_1):P12V_AUX
   2    GND      B @S9S_MB_2U_LIB.S9S_MB_2U(SCH_1):GND

Q_RES_0402LF-7.15K,1%,1/16W,CHA  I50  PR3829
   1 P3V3_OCP_UV_2      A @S9S_MB_2U_LIB.S9S_MB_2U(SCH_1):P3V3_OCP_UV_2
   2 P3V3_OCP_OV_2      B @S9S_MB_2U_LIB.S9S_MB_2U(SCH_1):P3V3_OCP_OV_2

Q_RES_0402LF-25.5K,1%,1/16W,CHA  I53  PR3795
   1 P3V3_AUX      A @S9S_MB_2U_LIB.S9S_MB_2U(SCH_1):P3V3_AUX
   2 P3V3_OCP_UV_2      B @S9S_MB_2U_LIB.S9S_MB_2U(SCH_1):P3V3_OCP_UV_2

Q_RES_0402LF-0,5%,1/16W,CHIP,CA  I55  R4753
   1 HP_LVC3_OCP_V3_2_PRSNT2_N_R      A @S9S_MB_2U_LIB.S9S_MB_2U(SCH_1):HP_LVC3_OCP_V3_2_PRSNT2_N_R
   2 HP_LVC3_OCP_V3_2_PRSNT2_PLD_N      B @S9S_MB_2U_LIB.S9S_MB_2U(SCH_1):HP_LVC3_OCP_V3_2_PRSNT2_PLD_N

Q_CAP_C0402-1UF,25V,10%,EMPTY,A  I61  PC2098
   1 P12V_OCP_VCC_2      A @S9S_MB_2U_LIB.S9S_MB_2U(SCH_1):P12V_OCP_VCC_2
   2    GND      B @S9S_MB_2U_LIB.S9S_MB_2U(SCH_1):GND

Q_CAP_C0402-1UF,25V,10%,EMPTY,A  I62  PC2146
   1    GND      A @S9S_MB_2U_LIB.S9S_MB_2U(SCH_1):GND
   2 P12V_OCP_REG_2      B @S9S_MB_2U_LIB.S9S_MB_2U(SCH_1):P12V_OCP_REG_2

Q_RES_0402LF-10K,1%,1/16W,CHIPA  I64  R3145
   1 P3V3_AUX      A @S9S_MB_2U_LIB.S9S_MB_2U(SCH_1):P3V3_AUX
   2 HP_LVC3_OCP_V3_2_ATTN_OUT_SW_N      B @S9S_MB_2U_LIB.S9S_MB_2U(SCH_1):HP_LVC3_OCP_V3_2_ATTN_OUT_SW_N

Q_RES_0402LF-845,1%,1/16W,EMPTA  I72  PR3823
   1 P12V_OCP_SENSE_2      A @S9S_MB_2U_LIB.S9S_MB_2U(SCH_1):P12V_OCP_SENSE_2
   2    GND      B @S9S_MB_2U_LIB.S9S_MB_2U(SCH_1):GND

Q_RES_0402LF-0,5%,1/16W,EMPTY,A  I75  R3867
   1 P12V_OCP_SENSE_2      A @S9S_MB_2U_LIB.S9S_MB_2U(SCH_1):P12V_OCP_SENSE_2
   2 P12V_OCP_V3_2_ISENSE_MAM_MAM      B @S9S_MB_2U_LIB.S9S_MB_2U(SCH_1):P12V_OCP_V3_2_ISENSE_MAM_MAM

Q_CAP_C0402-3900PF,50V,10%,EMPA  I76  PC2150
   1 P12V_OCP_GATE_2      A @S9S_MB_2U_LIB.S9S_MB_2U(SCH_1):P12V_OCP_GATE_2
   2    GND      B @S9S_MB_2U_LIB.S9S_MB_2U(SCH_1):GND

Q_RES_0402LF-10M,1%,1/16W,EMPTA  I77  PR4522
   1 P12V_OCP_V3_2      A @S9S_MB_2U_LIB.S9S_MB_2U(SCH_1):P12V_OCP_V3_2
   2 P12V_OCP_GATE_2      B @S9S_MB_2U_LIB.S9S_MB_2U(SCH_1):P12V_OCP_GATE_2

Q_CAP_C0402-1UF,25V,10%,X6S,CHA  I91  PC190
   1 P3V3_OCP_VCC_2      A @S9S_MB_2U_LIB.S9S_MB_2U(SCH_1):P3V3_OCP_VCC_2
   2    GND      B @S9S_MB_2U_LIB.S9S_MB_2U(SCH_1):GND

Q_RES_0402LF-4.53K,1%,1/16W,CHA  I95  PR3824
   1 P3V3_OCP_SENSE_2      A @S9S_MB_2U_LIB.S9S_MB_2U(SCH_1):P3V3_OCP_SENSE_2
   2    GND      B @S9S_MB_2U_LIB.S9S_MB_2U(SCH_1):GND

Q_CAP_0402-0.1UF,25V,10%,X7R,CA  I98  PC2152
   1 P12V_OCP_V3_2      A @S9S_MB_2U_LIB.S9S_MB_2U(SCH_1):P12V_OCP_V3_2
   2    GND      B @S9S_MB_2U_LIB.S9S_MB_2U(SCH_1):GND

Q_RES_0402LF-10M,1%,1/16W,CHIPA  I106  PR4523
   1 P3V3_OCP_V3_2_R      A @S9S_MB_2U_LIB.S9S_MB_2U(SCH_1):P3V3_OCP_V3_2_R
   2 P3V3_OCP_GATE_2      B @S9S_MB_2U_LIB.S9S_MB_2U(SCH_1):P3V3_OCP_GATE_2

Q_RES_0402LF-100K,1%,1/16W,CHIA  I108  R3833
   1 P3V3_AUX      A @S9S_MB_2U_LIB.S9S_MB_2U(SCH_1):P3V3_AUX
   2 P3V3_OCP_FAULT_2      B @S9S_MB_2U_LIB.S9S_MB_2U(SCH_1):P3V3_OCP_FAULT_2

Q_RES_0402LF-100K,1%,1/16W,CHIA  I110  R3826
   1 P3V3_AUX      A @S9S_MB_2U_LIB.S9S_MB_2U(SCH_1):P3V3_AUX
   2 OCP_V3_2_P3V3_PWRGD      B @S9S_MB_2U_LIB.S9S_MB_2U(SCH_1):OCP_V3_2_P3V3_PWRGD


DRAWING: @S9S_MB_2U_LIB.S9S_MB_2U(SCH_1):PAGE132 

Q_RES_0402LF-1K,1%,1/16W,CHIP,A  I7  R3155
   1 P3V3_AUX      A @S9S_MB_2U_LIB.S9S_MB_2U(SCH_1):P3V3_AUX
   2 HP_LVC3_OCP_V3_2_PRSNT2      B @S9S_MB_2U_LIB.S9S_MB_2U(SCH_1):HP_LVC3_OCP_V3_2_PRSNT2

74LVC1G08W57-74LVC1G08W5-7,SMLA  I9  U50
   1 HP_OCP_V3_2_EN      A @S9S_MB_2U_LIB.S9S_MB_2U(SCH_1):HP_OCP_V3_2_EN
   2 HP_LVC3_OCP_V3_2_PRSNT2      B @S9S_MB_2U_LIB.S9S_MB_2U(SCH_1):HP_LVC3_OCP_V3_2_PRSNT2
   3    GND    GND @S9S_MB_2U_LIB.S9S_MB_2U(SCH_1):GND
   4 HP_LVC3_OCP_V3_2_EN      Y @S9S_MB_2U_LIB.S9S_MB_2U(SCH_1):HP_LVC3_OCP_V3_2_EN
   5 P3V3_AUX    VCC @S9S_MB_2U_LIB.S9S_MB_2U(SCH_1):P3V3_AUX

Q_CAP_0402-0.1UF,25V,10%,X7R,CA  I15  C1818
   1 P3V3_AUX      A @S9S_MB_2U_LIB.S9S_MB_2U(SCH_1):P3V3_AUX
   2    GND      B @S9S_MB_2U_LIB.S9S_MB_2U(SCH_1):GND

Q_RES_0402LF-33.2,1%,1/16W,CHIA  I23  R3158
   1 FM_SMB_CPU1_ALERT      A @S9S_MB_2U_LIB.S9S_MB_2U(SCH_1):FM_SMB_CPU1_ALERT
   2 FM_SMB_PEHPCPU1_PCIE_ALERT_N      B @S9S_MB_2U_LIB.S9S_MB_2U(SCH_1):FM_SMB_PEHPCPU1_PCIE_ALERT_N

Q_RES_0402LF-1K,1%,1/16W,EMPTYA  I29  R3149
   1 P3V3_AUX      A @S9S_MB_2U_LIB.S9S_MB_2U(SCH_1):P3V3_AUX
   2 PD_SMB_OCP2_HP_ADD2      B @S9S_MB_2U_LIB.S9S_MB_2U(SCH_1):PD_SMB_OCP2_HP_ADD2

Q_RES_0402LF-1K,1%,1/16W,EMPTYA  I32  R3153
   1 P3V3_AUX      A @S9S_MB_2U_LIB.S9S_MB_2U(SCH_1):P3V3_AUX
   2 PD_SMB_OCP2_HP_ADD0      B @S9S_MB_2U_LIB.S9S_MB_2U(SCH_1):PD_SMB_OCP2_HP_ADD0

Q_RES_0402LF-33.2,1%,1/16W,CHIA  I34  R3156
   1 SMB_PEHPCPU1_LVC3_SCL      A @S9S_MB_2U_LIB.S9S_MB_2U(SCH_1):SMB_PEHPCPU1_LVC3_SCL
   2 SMB_PEHPCPU1_LVC3_R3_SCL      B @S9S_MB_2U_LIB.S9S_MB_2U(SCH_1):SMB_PEHPCPU1_LVC3_R3_SCL

74LVC1G08W57-74LVC1G08W5-7,SMLA  I56  U53
   1 HP_LVC3_OCP_V3_2_PWRGD_R      A @S9S_MB_2U_LIB.S9S_MB_2U(SCH_1):HP_LVC3_OCP_V3_2_PWRGD_R
   2 RST_OCP_V3_2_N      B @S9S_MB_2U_LIB.S9S_MB_2U(SCH_1):RST_OCP_V3_2_N
   3    GND    GND @S9S_MB_2U_LIB.S9S_MB_2U(SCH_1):GND
   4 RST_HP_OCP_V3_2_N      Y @S9S_MB_2U_LIB.S9S_MB_2U(SCH_1):RST_HP_OCP_V3_2_N
   5 P3V3_AUX    VCC @S9S_MB_2U_LIB.S9S_MB_2U(SCH_1):P3V3_AUX

Q_RES_0402LF-1K,1%,1/16W,CHIP,A  I65  R3154
   1 PD_SMB_OCP2_HP_ADD0      A @S9S_MB_2U_LIB.S9S_MB_2U(SCH_1):PD_SMB_OCP2_HP_ADD0
   2    GND      B @S9S_MB_2U_LIB.S9S_MB_2U(SCH_1):GND

MOSFET_N_SMLF-BSS138K,BSS138K,A  I3  U215
   G HP_LVC3_OCP_V3_2_PRSNT2_N   GATE @S9S_MB_2U_LIB.S9S_MB_2U(SCH_1):HP_LVC3_OCP_V3_2_PRSNT2_N
   D HP_LVC3_OCP_V3_2_PRSNT2  DRAIN @S9S_MB_2U_LIB.S9S_MB_2U(SCH_1):HP_LVC3_OCP_V3_2_PRSNT2
   S    GND SOURCE @S9S_MB_2U_LIB.S9S_MB_2U(SCH_1):GND

Q_RES_0402LF-1K,1%,1/16W,CHIP,A  I25  R3150
   1 PD_SMB_OCP2_HP_ADD2      A @S9S_MB_2U_LIB.S9S_MB_2U(SCH_1):PD_SMB_OCP2_HP_ADD2
   2    GND      B @S9S_MB_2U_LIB.S9S_MB_2U(SCH_1):GND

Q_RES_0402LF-1K,1%,1/16W,CHIP,A  I27  R3152
   1 PD_SMB_OCP2_HP_ADD1      A @S9S_MB_2U_LIB.S9S_MB_2U(SCH_1):PD_SMB_OCP2_HP_ADD1
   2    GND      B @S9S_MB_2U_LIB.S9S_MB_2U(SCH_1):GND

Q_RES_0402LF-1K,1%,1/16W,EMPTYA  I31  R3151
   1 P3V3_AUX      A @S9S_MB_2U_LIB.S9S_MB_2U(SCH_1):P3V3_AUX
   2 PD_SMB_OCP2_HP_ADD1      B @S9S_MB_2U_LIB.S9S_MB_2U(SCH_1):PD_SMB_OCP2_HP_ADD1

Q_RES_0402LF-33.2,1%,1/16W,CHIA  I33  R3157
   1 SMB_PEHPCPU1_LVC3_SDA      A @S9S_MB_2U_LIB.S9S_MB_2U(SCH_1):SMB_PEHPCPU1_LVC3_SDA
   2 SMB_PEHPCPU1_LVC3_R3_SDA      B @S9S_MB_2U_LIB.S9S_MB_2U(SCH_1):SMB_PEHPCPU1_LVC3_R3_SDA

Q_CAP_0402-0.1UF,25V,10%,X7R,CA  I39  C1817
   1 P3V3_AUX      A @S9S_MB_2U_LIB.S9S_MB_2U(SCH_1):P3V3_AUX
   2    GND      B @S9S_MB_2U_LIB.S9S_MB_2U(SCH_1):GND

Q_CAP_0402-0.1UF,25V,10%,X7R,CA  I58  C1820
   1 P3V3_AUX      A @S9S_MB_2U_LIB.S9S_MB_2U(SCH_1):P3V3_AUX
   2    GND      B @S9S_MB_2U_LIB.S9S_MB_2U(SCH_1):GND

PCA9555APW-PCA9555APW,SMLF,IC,A  I66  U51
  24 P3V3_AUX    VDD @S9S_MB_2U_LIB.S9S_MB_2U(SCH_1):P3V3_AUX
  12    GND    VSS @S9S_MB_2U_LIB.S9S_MB_2U(SCH_1):GND
   1 FM_SMB_CPU1_ALERT   INT# @S9S_MB_2U_LIB.S9S_MB_2U(SCH_1):FM_SMB_CPU1_ALERT
  23 SMB_PEHPCPU1_LVC3_R3_SDA    SDA @S9S_MB_2U_LIB.S9S_MB_2U(SCH_1):SMB_PEHPCPU1_LVC3_R3_SDA
  22 SMB_PEHPCPU1_LVC3_R3_SCL    SCL @S9S_MB_2U_LIB.S9S_MB_2U(SCH_1):SMB_PEHPCPU1_LVC3_R3_SCL
   4 TP_PCA9555_U51_P00   P0_0 @S9S_MB_2U_LIB.S9S_MB_2U(SCH_1):TP_PCA9555_U51_P00
   5 TP_PCA9555_U51_P01   P0_1 @S9S_MB_2U_LIB.S9S_MB_2U(SCH_1):TP_PCA9555_U51_P01
   6 HP_OCP_V3_2_EN   P0_2 @S9S_MB_2U_LIB.S9S_MB_2U(SCH_1):HP_OCP_V3_2_EN
   7 HP_LVC3_OCP_V3_2_ATTN_OUT_SW_N   P0_3 @S9S_MB_2U_LIB.S9S_MB_2U(SCH_1):HP_LVC3_OCP_V3_2_ATTN_OUT_SW_N
   8 HP_LVC3_OCP_V3_2_PRSNT2_N   P0_4 @S9S_MB_2U_LIB.S9S_MB_2U(SCH_1):HP_LVC3_OCP_V3_2_PRSNT2_N
   9 TP_PCA9555_U51_P05   P0_5 @S9S_MB_2U_LIB.S9S_MB_2U(SCH_1):TP_PCA9555_U51_P05
  10 TP_PCA9555_U51_P06   P0_6 @S9S_MB_2U_LIB.S9S_MB_2U(SCH_1):TP_PCA9555_U51_P06
  11 TP_PCA9555_U51_P07   P0_7 @S9S_MB_2U_LIB.S9S_MB_2U(SCH_1):TP_PCA9555_U51_P07
  13 TP_PCA9555_U51_P10   P1_0 @S9S_MB_2U_LIB.S9S_MB_2U(SCH_1):TP_PCA9555_U51_P10
  14 TP_PCA9555_U51_P11   P1_1 @S9S_MB_2U_LIB.S9S_MB_2U(SCH_1):TP_PCA9555_U51_P11
  15 TP_PCA9555_U51_P12   P1_2 @S9S_MB_2U_LIB.S9S_MB_2U(SCH_1):TP_PCA9555_U51_P12
  16 TP_PCA9555_U51_P13   P1_3 @S9S_MB_2U_LIB.S9S_MB_2U(SCH_1):TP_PCA9555_U51_P13
  17 TP_PCA9555_U51_P14   P1_4 @S9S_MB_2U_LIB.S9S_MB_2U(SCH_1):TP_PCA9555_U51_P14
  18 TP_PCA9555_U51_P15   P1_5 @S9S_MB_2U_LIB.S9S_MB_2U(SCH_1):TP_PCA9555_U51_P15
  19 TP_PCA9555_U51_P16   P1_6 @S9S_MB_2U_LIB.S9S_MB_2U(SCH_1):TP_PCA9555_U51_P16
  20 TP_PCA9555_U51_P17   P1_7 @S9S_MB_2U_LIB.S9S_MB_2U(SCH_1):TP_PCA9555_U51_P17
  21 PD_SMB_OCP2_HP_ADD0     A0 @S9S_MB_2U_LIB.S9S_MB_2U(SCH_1):PD_SMB_OCP2_HP_ADD0
   2 PD_SMB_OCP2_HP_ADD1     A1 @S9S_MB_2U_LIB.S9S_MB_2U(SCH_1):PD_SMB_OCP2_HP_ADD1
   3 PD_SMB_OCP2_HP_ADD2     A2 @S9S_MB_2U_LIB.S9S_MB_2U(SCH_1):PD_SMB_OCP2_HP_ADD2

APX80929SAG7-APX809-29SAG-7,SMA  I85  U216
   3 P3V3_OCP_V3_2    VCC @S9S_MB_2U_LIB.S9S_MB_2U(SCH_1):P3V3_OCP_V3_2
   2 HP_OCP_V3_2_RST RESET_L @S9S_MB_2U_LIB.S9S_MB_2U(SCH_1):HP_OCP_V3_2_RST
   1    GND    GND @S9S_MB_2U_LIB.S9S_MB_2U(SCH_1):GND

Q_CAP_0402-0.1UF,25V,10%,X7R,CA  I87  C1819
   1 P3V3_OCP_V3_2      A @S9S_MB_2U_LIB.S9S_MB_2U(SCH_1):P3V3_OCP_V3_2
   2    GND      B @S9S_MB_2U_LIB.S9S_MB_2U(SCH_1):GND

Q_CAP_0402-0.1UF,25V,10%,X7R,CA  I90  C2347
   1 P3V3_AUX      A @S9S_MB_2U_LIB.S9S_MB_2U(SCH_1):P3V3_AUX
   2    GND      B @S9S_MB_2U_LIB.S9S_MB_2U(SCH_1):GND

74LVC1G08W57-74LVC1G08W5-7,SMLA  I92  U323
   1 HP_OCP_V3_2_RST_R      A @S9S_MB_2U_LIB.S9S_MB_2U(SCH_1):HP_OCP_V3_2_RST_R
   2 HP_LVC3_OCP_V3_2_P12V_PWRGD      B @S9S_MB_2U_LIB.S9S_MB_2U(SCH_1):HP_LVC3_OCP_V3_2_P12V_PWRGD
   3    GND    GND @S9S_MB_2U_LIB.S9S_MB_2U(SCH_1):GND
   4 HP_LVC3_OCP_V3_2_PWRGD      Y @S9S_MB_2U_LIB.S9S_MB_2U(SCH_1):HP_LVC3_OCP_V3_2_PWRGD
   5 P3V3_AUX    VCC @S9S_MB_2U_LIB.S9S_MB_2U(SCH_1):P3V3_AUX

Q_RES_0402LF-1K,1%,1/16W,EMPTYA  I95  R1132
   1 P3V3_AUX      A @S9S_MB_2U_LIB.S9S_MB_2U(SCH_1):P3V3_AUX
   2 HP_OCP_V3_2_RST_R      B @S9S_MB_2U_LIB.S9S_MB_2U(SCH_1):HP_OCP_V3_2_RST_R

Q_RES_0402LF-0,5%,1/16W,EMPTY,A  I96  R4615
   1 OCP_V3_2_P3V3_PWRGD      A @S9S_MB_2U_LIB.S9S_MB_2U(SCH_1):OCP_V3_2_P3V3_PWRGD
   2 HP_OCP_V3_2_RST_R      B @S9S_MB_2U_LIB.S9S_MB_2U(SCH_1):HP_OCP_V3_2_RST_R

Q_RES_0402LF-33.2,1%,1/16W,CHIA  I99  R4617
   1 HP_LVC3_OCP_V3_2_PWRGD      A @S9S_MB_2U_LIB.S9S_MB_2U(SCH_1):HP_LVC3_OCP_V3_2_PWRGD
   2 HP_LVC3_OCP_V3_2_PWRGD_R      B @S9S_MB_2U_LIB.S9S_MB_2U(SCH_1):HP_LVC3_OCP_V3_2_PWRGD_R

Q_RES_0402LF-33.2,1%,1/16W,CHIA  I100  R4616
   1 HP_OCP_V3_2_RST      A @S9S_MB_2U_LIB.S9S_MB_2U(SCH_1):HP_OCP_V3_2_RST
   2 HP_OCP_V3_2_RST_R      B @S9S_MB_2U_LIB.S9S_MB_2U(SCH_1):HP_OCP_V3_2_RST_R

Q_RES_0402LF-33.2,1%,1/16W,CHIA  I103  R4755
   1 OCP_V3_2_AUX_PWR_PLD_EN      A @S9S_MB_2U_LIB.S9S_MB_2U(SCH_1):OCP_V3_2_AUX_PWR_PLD_EN
   2 OCP_V3_2_AUX_PWR_PLD_EN_R      B @S9S_MB_2U_LIB.S9S_MB_2U(SCH_1):OCP_V3_2_AUX_PWR_PLD_EN_R

Q_RES_0402LF-33.2,1%,1/16W,CHIA  I104  R4754
   1 HP_LVC3_OCP_V3_2_PWRGD_R      A @S9S_MB_2U_LIB.S9S_MB_2U(SCH_1):HP_LVC3_OCP_V3_2_PWRGD_R
   2 HP_LVC3_OCP_V3_2_PWRGD_R2      B @S9S_MB_2U_LIB.S9S_MB_2U(SCH_1):HP_LVC3_OCP_V3_2_PWRGD_R2

Q_RES_0402LF-10K,1%,1/16W,CHIPA  I105  R4756
   1 P3V3_AUX      A @S9S_MB_2U_LIB.S9S_MB_2U(SCH_1):P3V3_AUX
   2 OCP_V3_2_AUX_PWR_PLD_EN_R      B @S9S_MB_2U_LIB.S9S_MB_2U(SCH_1):OCP_V3_2_AUX_PWR_PLD_EN_R

Q_RES_0402LF-0,5%,1/16W,EMPTY,A  I107  R4758
   1 OCP_V3_2_AUX_PWR_PLD_EN_R      A @S9S_MB_2U_LIB.S9S_MB_2U(SCH_1):OCP_V3_2_AUX_PWR_PLD_EN_R
   2 OCP_V3_2_AUX_PWR_EN_R2      B @S9S_MB_2U_LIB.S9S_MB_2U(SCH_1):OCP_V3_2_AUX_PWR_EN_R2

74LVC1G08W57-74LVC1G08W5-7,SMLA  I108  U335
   1 HP_LVC3_OCP_V3_2_PWRGD_R2      A @S9S_MB_2U_LIB.S9S_MB_2U(SCH_1):HP_LVC3_OCP_V3_2_PWRGD_R2
   2 OCP_V3_2_AUX_PWR_PLD_EN_R      B @S9S_MB_2U_LIB.S9S_MB_2U(SCH_1):OCP_V3_2_AUX_PWR_PLD_EN_R
   3    GND    GND @S9S_MB_2U_LIB.S9S_MB_2U(SCH_1):GND
   4 OCP_V3_2_AUX_PWR_EN_R2      Y @S9S_MB_2U_LIB.S9S_MB_2U(SCH_1):OCP_V3_2_AUX_PWR_EN_R2
   5 P3V3_AUX    VCC @S9S_MB_2U_LIB.S9S_MB_2U(SCH_1):P3V3_AUX

Q_CAP_0402-0.1UF,25V,10%,X7R,CA  I110  C2377
   1 P3V3_AUX      A @S9S_MB_2U_LIB.S9S_MB_2U(SCH_1):P3V3_AUX
   2    GND      B @S9S_MB_2U_LIB.S9S_MB_2U(SCH_1):GND

Q_RES_0402LF-49.9,1%,1/16W,CHIA  I111  R4759
   1 OCP_V3_2_AUX_PWR_EN_R2      A @S9S_MB_2U_LIB.S9S_MB_2U(SCH_1):OCP_V3_2_AUX_PWR_EN_R2
   2 OCP_V3_2_AUX_PWR_EN      B @S9S_MB_2U_LIB.S9S_MB_2U(SCH_1):OCP_V3_2_AUX_PWR_EN

Q_RES_0402LF-0,5%,1/16W,EMPTY,A  I112  R4757
   1 HP_LVC3_OCP_V3_2_PWRGD_R2      A @S9S_MB_2U_LIB.S9S_MB_2U(SCH_1):HP_LVC3_OCP_V3_2_PWRGD_R2
   2 OCP_V3_2_AUX_PWR_EN_R2      B @S9S_MB_2U_LIB.S9S_MB_2U(SCH_1):OCP_V3_2_AUX_PWR_EN_R2

Q_RES_0402LF-10K,1%,1/16W,CHIPA  I119  R4763
   1 P3V3_AUX      A @S9S_MB_2U_LIB.S9S_MB_2U(SCH_1):P3V3_AUX
   2 HP_OCP_V3_2_EN      B @S9S_MB_2U_LIB.S9S_MB_2U(SCH_1):HP_OCP_V3_2_EN


DRAWING: @S9S_MB_2U_LIB.S9S_MB_2U(SCH_1):PAGE146 

Q_RES_0402LF-0,5%,1/16W,CHIP,CA  I5  R3168
   1 OCP_V3_2_MAIN_PWR_EN      A @S9S_MB_2U_LIB.S9S_MB_2U(SCH_1):OCP_V3_2_MAIN_PWR_EN
   2 OCP_V3_2_MAIN_PWR_EN_R      B @S9S_MB_2U_LIB.S9S_MB_2U(SCH_1):OCP_V3_2_MAIN_PWR_EN_R

Q_RES_0402LF-4.7K,1%,1/16W,CHIA  I20  R3167
   1 OCP_V3_2_ID1      A @S9S_MB_2U_LIB.S9S_MB_2U(SCH_1):OCP_V3_2_ID1
   2    GND      B @S9S_MB_2U_LIB.S9S_MB_2U(SCH_1):GND

Q_RES_0402LF-4.7K,1%,1/16W,EMPA  I23  R3166
   1 P3V3_OCP_V3_2      A @S9S_MB_2U_LIB.S9S_MB_2U(SCH_1):P3V3_OCP_V3_2
   2 OCP_V3_2_ID1      B @S9S_MB_2U_LIB.S9S_MB_2U(SCH_1):OCP_V3_2_ID1

Q_RES_0402LF-4.7K,1%,1/16W,EMPA  I25  R3163
   1 OCP_V3_2_ID0      A @S9S_MB_2U_LIB.S9S_MB_2U(SCH_1):OCP_V3_2_ID0
   2    GND      B @S9S_MB_2U_LIB.S9S_MB_2U(SCH_1):GND

Q_RES_0402LF-4.7K,1%,1/16W,CHIA  I26  R3162
   1 P3V3_OCP_V3_2      A @S9S_MB_2U_LIB.S9S_MB_2U(SCH_1):P3V3_OCP_V3_2
   2 OCP_V3_2_ID0      B @S9S_MB_2U_LIB.S9S_MB_2U(SCH_1):OCP_V3_2_ID0

Q_RES_0402LF-0,5%,1/16W,CHIP,CA  I31  R3171
   1 OCP_V3_2_ISO_BIF2_EN      A @S9S_MB_2U_LIB.S9S_MB_2U(SCH_1):OCP_V3_2_ISO_BIF2_EN
   2 OCP_V3_2_BIF2_R_N      B @S9S_MB_2U_LIB.S9S_MB_2U(SCH_1):OCP_V3_2_BIF2_R_N

Q_RES_0402LF-0,5%,1/16W,CHIP,CA  I32  R3170
   1 OCP_V3_2_ISO_BIF1_EN      A @S9S_MB_2U_LIB.S9S_MB_2U(SCH_1):OCP_V3_2_ISO_BIF1_EN
   2 OCP_V3_2_BIF1_R_N      B @S9S_MB_2U_LIB.S9S_MB_2U(SCH_1):OCP_V3_2_BIF1_R_N

Q_RES_0402LF-0,5%,1/16W,CHIP,CA  I33  R3169
   1 OCP_V3_2_ISO_BIF0_EN      A @S9S_MB_2U_LIB.S9S_MB_2U(SCH_1):OCP_V3_2_ISO_BIF0_EN
   2 OCP_V3_2_BIF0_R_N      B @S9S_MB_2U_LIB.S9S_MB_2U(SCH_1):OCP_V3_2_BIF0_R_N

Q_RES_0402LF-0,5%,1/16W,CHIP,CA  I36  R3172
   1 OCP_V3_2_AUX_PWR_EN      A @S9S_MB_2U_LIB.S9S_MB_2U(SCH_1):OCP_V3_2_AUX_PWR_EN
   2 OCP_V3_2_AUX_PWR_EN_R      B @S9S_MB_2U_LIB.S9S_MB_2U(SCH_1):OCP_V3_2_AUX_PWR_EN_R

Q_RES_0402LF-10K,1%,1/16W,CHIPA  I37  R3165
   1    GND      A @S9S_MB_2U_LIB.S9S_MB_2U(SCH_1):GND
   2 OCP_V3_2_MAIN_PWR_EN      B @S9S_MB_2U_LIB.S9S_MB_2U(SCH_1):OCP_V3_2_MAIN_PWR_EN

Q_RES_0402LF-10K,1%,1/16W,CHIPA  I38  R3164
   1    GND      A @S9S_MB_2U_LIB.S9S_MB_2U(SCH_1):GND
   2 OCP_V3_2_AUX_PWR_EN      B @S9S_MB_2U_LIB.S9S_MB_2U(SCH_1):OCP_V3_2_AUX_PWR_EN

Q_RES_0402LF-100K,1%,1/16W,CHIA  I43  R413
   1    GND      A @S9S_MB_2U_LIB.S9S_MB_2U(SCH_1):GND
   2 FM_OCP_V3_2_PWR_GOOD      B @S9S_MB_2U_LIB.S9S_MB_2U(SCH_1):FM_OCP_V3_2_PWR_GOOD

Q_RES_0402LF-0,5%,1/16W,CHIP,CA  I147  R3178
   1 USB2_5_R1_DP      A @S9S_MB_2U_LIB.S9S_MB_2U(SCH_1):USB2_5_R1_DP
   2 USB2_5_DP      B @S9S_MB_2U_LIB.S9S_MB_2U(SCH_1):USB2_5_DP

Q_RES_0402LF-0,5%,1/16W,CHIP,CA  I148  R3177
   1 USB2_5_R1_DN      A @S9S_MB_2U_LIB.S9S_MB_2U(SCH_1):USB2_5_R1_DN
   2 USB2_5_DN      B @S9S_MB_2U_LIB.S9S_MB_2U(SCH_1):USB2_5_DN

Q_RES_0402LF-100,1%,1/16W,CHIPA  I152  R3180
   1 OCP_V3_1_PRSNTA_R_N      A @S9S_MB_2U_LIB.S9S_MB_2U(SCH_1):OCP_V3_1_PRSNTA_R_N
   2    GND      B @S9S_MB_2U_LIB.S9S_MB_2U(SCH_1):GND

Q_RES_0402LF-1K,1%,1/16W,CHIP,A  I165  R3173
   1 SGPIO_OCP_V3_2_LD_N      A @S9S_MB_2U_LIB.S9S_MB_2U(SCH_1):SGPIO_OCP_V3_2_LD_N
   2 P3V3_OCP_V3_2      B @S9S_MB_2U_LIB.S9S_MB_2U(SCH_1):P3V3_OCP_V3_2

Q_CAP_C0805-22UF,16V,20%,X6S,CB  I166  C1829
   1 P12V_OCP_V3_2      A @S9S_MB_2U_LIB.S9S_MB_2U(SCH_1):P12V_OCP_V3_2
   2    GND      B @S9S_MB_2U_LIB.S9S_MB_2U(SCH_1):GND

Q_CAP_C0805-22UF,16V,20%,X6S,CB  I167  C1830
   1 P12V_OCP_V3_2      A @S9S_MB_2U_LIB.S9S_MB_2U(SCH_1):P12V_OCP_V3_2
   2    GND      B @S9S_MB_2U_LIB.S9S_MB_2U(SCH_1):GND

Q_CAP_0402-0.1UF,25V,10%,X7R,CA  I168  C1831
   1 P12V_OCP_V3_2      A @S9S_MB_2U_LIB.S9S_MB_2U(SCH_1):P12V_OCP_V3_2
   2    GND      B @S9S_MB_2U_LIB.S9S_MB_2U(SCH_1):GND

Q_CAP_0402-0.1UF,25V,10%,X7R,CA  I169  C1833
   1 P12V_OCP_V3_2      A @S9S_MB_2U_LIB.S9S_MB_2U(SCH_1):P12V_OCP_V3_2
   2    GND      B @S9S_MB_2U_LIB.S9S_MB_2U(SCH_1):GND

Q_CAP_0402-0.1UF,25V,10%,X7R,CA  I171  C1834
   1 P12V_OCP_V3_2      A @S9S_MB_2U_LIB.S9S_MB_2U(SCH_1):P12V_OCP_V3_2
   2    GND      B @S9S_MB_2U_LIB.S9S_MB_2U(SCH_1):GND

Q_CAP_0402-0.1UF,25V,10%,X7R,CA  I173  C1835
   1 P3V3_OCP_V3_2      A @S9S_MB_2U_LIB.S9S_MB_2U(SCH_1):P3V3_OCP_V3_2
   2    GND      B @S9S_MB_2U_LIB.S9S_MB_2U(SCH_1):GND

Q_CAP_0402-0.1UF,25V,10%,X7R,CA  I174  C1836
   1 P3V3_OCP_V3_2      A @S9S_MB_2U_LIB.S9S_MB_2U(SCH_1):P3V3_OCP_V3_2
   2    GND      B @S9S_MB_2U_LIB.S9S_MB_2U(SCH_1):GND

Q_CAP_0402-0.1UF,25V,10%,X7R,CA  I175  C1837
   1 P3V3_OCP_V3_2      A @S9S_MB_2U_LIB.S9S_MB_2U(SCH_1):P3V3_OCP_V3_2
   2    GND      B @S9S_MB_2U_LIB.S9S_MB_2U(SCH_1):GND

Q_CAP_0402-0.1UF,25V,10%,X7R,CA  I177  C1838
   1 P3V3_OCP_V3_2      A @S9S_MB_2U_LIB.S9S_MB_2U(SCH_1):P3V3_OCP_V3_2
   2    GND      B @S9S_MB_2U_LIB.S9S_MB_2U(SCH_1):GND

Q_CAP_0402-0.1UF,25V,10%,X7R,CA  I179  C1832
   1 P12V_OCP_V3_2      A @S9S_MB_2U_LIB.S9S_MB_2U(SCH_1):P12V_OCP_V3_2
   2    GND      B @S9S_MB_2U_LIB.S9S_MB_2U(SCH_1):GND

Q_CAP_0402-0.1UF,25V,10%,X7R,CA  I180  C1839
   1 P12V_OCP_V3_2      A @S9S_MB_2U_LIB.S9S_MB_2U(SCH_1):P12V_OCP_V3_2
   2    GND      B @S9S_MB_2U_LIB.S9S_MB_2U(SCH_1):GND

SCONN168_ME1016810202011-SCONNA  I303  J35
 OB1 FM_OCP_V3_2_PWR_GOOD NIC_PWR_GOOD @S9S_MB_2U_LIB.S9S_MB_2U(SCH_1):FM_OCP_V3_2_PWR_GOOD
 OB2 OCP_V3_2_MAIN_PWR_EN_R MAIN_PWR_EN @S9S_MB_2U_LIB.S9S_MB_2U(SCH_1):OCP_V3_2_MAIN_PWR_EN_R
 OB3 SGPIO_OCP_V3_2_LD_N    LD# @S9S_MB_2U_LIB.S9S_MB_2U(SCH_1):SGPIO_OCP_V3_2_LD_N
 OB4 SGPIO_OCP_V3_2_DATAIN DATA_IN @S9S_MB_2U_LIB.S9S_MB_2U(SCH_1):SGPIO_OCP_V3_2_DATAIN
 OB5 SGPIO_OCP_V3_2_DATAOUT DATA_OUT @S9S_MB_2U_LIB.S9S_MB_2U(SCH_1):SGPIO_OCP_V3_2_DATAOUT
 OB6 SGPIO_OCP_V3_2_CLK    CLK @S9S_MB_2U_LIB.S9S_MB_2U(SCH_1):SGPIO_OCP_V3_2_CLK
 OB7 OCP_V3_2_ID0 SLOT_ID0 @S9S_MB_2U_LIB.S9S_MB_2U(SCH_1):OCP_V3_2_ID0
 OB8 NCSI_OCP_V3_2_RXD1 RBT_RXD1 @S9S_MB_2U_LIB.S9S_MB_2U(SCH_1):NCSI_OCP_V3_2_RXD1
 OB9 NCSI_OCP_V3_2_RXD0 RBT_RXD0 @S9S_MB_2U_LIB.S9S_MB_2U(SCH_1):NCSI_OCP_V3_2_RXD0
OB10    GND GND_OB10 @S9S_MB_2U_LIB.S9S_MB_2U(SCH_1):GND
OB11 CLK_100M_OCP_V3_2_C_DN REFCLKN2 @S9S_MB_2U_LIB.S9S_MB_2U(SCH_1):CLK_100M_OCP_V3_2_C_DN
OB12 CLK_100M_OCP_V3_2_C_DP REFCLKP2 @S9S_MB_2U_LIB.S9S_MB_2U(SCH_1):CLK_100M_OCP_V3_2_C_DP
OB13    GND GND_OB13 @S9S_MB_2U_LIB.S9S_MB_2U(SCH_1):GND
OB14 NCSI_OCP_V3_2_CRS_DV RBT_CRS_DV @S9S_MB_2U_LIB.S9S_MB_2U(SCH_1):NCSI_OCP_V3_2_CRS_DV
  B1 P12V_OCP_V3_2 +12V_EDGE_B1 @S9S_MB_2U_LIB.S9S_MB_2U(SCH_1):P12V_OCP_V3_2
  B2 P12V_OCP_V3_2 +12V_EDGE_B2 @S9S_MB_2U_LIB.S9S_MB_2U(SCH_1):P12V_OCP_V3_2
  B3 P12V_OCP_V3_2 +12V_EDGE_B3 @S9S_MB_2U_LIB.S9S_MB_2U(SCH_1):P12V_OCP_V3_2
  B4 P12V_OCP_V3_2 +12V_EDGE_B4 @S9S_MB_2U_LIB.S9S_MB_2U(SCH_1):P12V_OCP_V3_2
  B5 P12V_OCP_V3_2 +12V_EDGE_B5 @S9S_MB_2U_LIB.S9S_MB_2U(SCH_1):P12V_OCP_V3_2
  B6 P12V_OCP_V3_2 +12V_EDGE_B6 @S9S_MB_2U_LIB.S9S_MB_2U(SCH_1):P12V_OCP_V3_2
  B7 OCP_V3_2_BIF0_R_N  BIF0# @S9S_MB_2U_LIB.S9S_MB_2U(SCH_1):OCP_V3_2_BIF0_R_N
  B8 OCP_V3_2_BIF1_R_N  BIF1# @S9S_MB_2U_LIB.S9S_MB_2U(SCH_1):OCP_V3_2_BIF1_R_N
  B9 OCP_V3_2_BIF2_R_N  BIF2# @S9S_MB_2U_LIB.S9S_MB_2U(SCH_1):OCP_V3_2_BIF2_R_N
 B10 RST_PERST0_OCP_V3_2_N PERST0# @S9S_MB_2U_LIB.S9S_MB_2U(SCH_1):RST_PERST0_OCP_V3_2_N
 B11 P3V3_OCP_V3_2 +3.3V_EDGE @S9S_MB_2U_LIB.S9S_MB_2U(SCH_1):P3V3_OCP_V3_2
 B12 OCP_V3_2_AUX_PWR_EN_R AUX_PWR_EN @S9S_MB_2U_LIB.S9S_MB_2U(SCH_1):OCP_V3_2_AUX_PWR_EN_R
 B13    GND GND_B13 @S9S_MB_2U_LIB.S9S_MB_2U(SCH_1):GND
 B14 CLK_100M_OCP_V3_2_A_DN REFCLKN0 @S9S_MB_2U_LIB.S9S_MB_2U(SCH_1):CLK_100M_OCP_V3_2_A_DN
 B15 CLK_100M_OCP_V3_2_A_DP REFCLKP0 @S9S_MB_2U_LIB.S9S_MB_2U(SCH_1):CLK_100M_OCP_V3_2_A_DP
 B16    GND GND_B16 @S9S_MB_2U_LIB.S9S_MB_2U(SCH_1):GND
 B17 P5E_CPU1_PE1_TX_C_DP<0>  PETN0 @S9S_MB_2U_LIB.S9S_MB_2U(SCH_1):P5E_CPU1_PE1_TX_C_DP(0)
 B18 P5E_CPU1_PE1_TX_C_DN<0>  PETP0 @S9S_MB_2U_LIB.S9S_MB_2U(SCH_1):P5E_CPU1_PE1_TX_C_DN(0)
 B19    GND GND_B19 @S9S_MB_2U_LIB.S9S_MB_2U(SCH_1):GND
 B20 P5E_CPU1_PE1_TX_C_DN<1>  PETN1 @S9S_MB_2U_LIB.S9S_MB_2U(SCH_1):P5E_CPU1_PE1_TX_C_DN(1)
 B21 P5E_CPU1_PE1_TX_C_DP<1>  PETP1 @S9S_MB_2U_LIB.S9S_MB_2U(SCH_1):P5E_CPU1_PE1_TX_C_DP(1)
 B22    GND GND_B22 @S9S_MB_2U_LIB.S9S_MB_2U(SCH_1):GND
 B23 P5E_CPU1_PE1_TX_C_DP<2>  PETN2 @S9S_MB_2U_LIB.S9S_MB_2U(SCH_1):P5E_CPU1_PE1_TX_C_DP(2)
 B24 P5E_CPU1_PE1_TX_C_DN<2>  PETP2 @S9S_MB_2U_LIB.S9S_MB_2U(SCH_1):P5E_CPU1_PE1_TX_C_DN(2)
 B25    GND GND_B25 @S9S_MB_2U_LIB.S9S_MB_2U(SCH_1):GND
 B26 P5E_CPU1_PE1_TX_C_DN<3>  PETN3 @S9S_MB_2U_LIB.S9S_MB_2U(SCH_1):P5E_CPU1_PE1_TX_C_DN(3)
 B27 P5E_CPU1_PE1_TX_C_DP<3>  PETP3 @S9S_MB_2U_LIB.S9S_MB_2U(SCH_1):P5E_CPU1_PE1_TX_C_DP(3)
 B28    GND GND_B28 @S9S_MB_2U_LIB.S9S_MB_2U(SCH_1):GND
 B29    GND GND_B29 @S9S_MB_2U_LIB.S9S_MB_2U(SCH_1):GND
 B30 P5E_CPU1_PE1_TX_C_DP<4>  PETN4 @S9S_MB_2U_LIB.S9S_MB_2U(SCH_1):P5E_CPU1_PE1_TX_C_DP(4)
 B31 P5E_CPU1_PE1_TX_C_DN<4>  PETP4 @S9S_MB_2U_LIB.S9S_MB_2U(SCH_1):P5E_CPU1_PE1_TX_C_DN(4)
 B32    GND GND_B32 @S9S_MB_2U_LIB.S9S_MB_2U(SCH_1):GND
 B33 P5E_CPU1_PE1_TX_C_DN<5>  PETN5 @S9S_MB_2U_LIB.S9S_MB_2U(SCH_1):P5E_CPU1_PE1_TX_C_DN(5)
 B34 P5E_CPU1_PE1_TX_C_DP<5>  PETP5 @S9S_MB_2U_LIB.S9S_MB_2U(SCH_1):P5E_CPU1_PE1_TX_C_DP(5)
 B35    GND GND_B35 @S9S_MB_2U_LIB.S9S_MB_2U(SCH_1):GND
 B36 P5E_CPU1_PE1_TX_C_DP<6>  PETN6 @S9S_MB_2U_LIB.S9S_MB_2U(SCH_1):P5E_CPU1_PE1_TX_C_DP(6)
 B37 P5E_CPU1_PE1_TX_C_DN<6>  PETP6 @S9S_MB_2U_LIB.S9S_MB_2U(SCH_1):P5E_CPU1_PE1_TX_C_DN(6)
 B38    GND GND_B38 @S9S_MB_2U_LIB.S9S_MB_2U(SCH_1):GND
 B39 P5E_CPU1_PE1_TX_C_DN<7>  PETN7 @S9S_MB_2U_LIB.S9S_MB_2U(SCH_1):P5E_CPU1_PE1_TX_C_DN(7)
 B40 P5E_CPU1_PE1_TX_C_DP<7>  PETP7 @S9S_MB_2U_LIB.S9S_MB_2U(SCH_1):P5E_CPU1_PE1_TX_C_DP(7)
 B41    GND GND_B41 @S9S_MB_2U_LIB.S9S_MB_2U(SCH_1):GND
 B42 OCP_V3_2_PRSNT0_R_N PRSNTB0# @S9S_MB_2U_LIB.S9S_MB_2U(SCH_1):OCP_V3_2_PRSNT0_R_N
 B43    GND GND_B43 @S9S_MB_2U_LIB.S9S_MB_2U(SCH_1):GND
 B44 P5E_CPU1_PE1_TX_C_DP<8>  PETN8 @S9S_MB_2U_LIB.S9S_MB_2U(SCH_1):P5E_CPU1_PE1_TX_C_DP(8)
 B45 P5E_CPU1_PE1_TX_C_DN<8>  PETP8 @S9S_MB_2U_LIB.S9S_MB_2U(SCH_1):P5E_CPU1_PE1_TX_C_DN(8)
 B46    GND GND_B46 @S9S_MB_2U_LIB.S9S_MB_2U(SCH_1):GND
 B47 P5E_CPU1_PE1_TX_C_DN<9>  PETN9 @S9S_MB_2U_LIB.S9S_MB_2U(SCH_1):P5E_CPU1_PE1_TX_C_DN(9)
 B48 P5E_CPU1_PE1_TX_C_DP<9>  PETP9 @S9S_MB_2U_LIB.S9S_MB_2U(SCH_1):P5E_CPU1_PE1_TX_C_DP(9)
 B49    GND GND_B49 @S9S_MB_2U_LIB.S9S_MB_2U(SCH_1):GND
 B50 P5E_CPU1_PE1_TX_C_DP<10> PETN10 @S9S_MB_2U_LIB.S9S_MB_2U(SCH_1):P5E_CPU1_PE1_TX_C_DP(10)
 B51 P5E_CPU1_PE1_TX_C_DN<10> PETP10 @S9S_MB_2U_LIB.S9S_MB_2U(SCH_1):P5E_CPU1_PE1_TX_C_DN(10)
 B52    GND GND_B52 @S9S_MB_2U_LIB.S9S_MB_2U(SCH_1):GND
 B53 P5E_CPU1_PE1_TX_C_DN<11> PETN11 @S9S_MB_2U_LIB.S9S_MB_2U(SCH_1):P5E_CPU1_PE1_TX_C_DN(11)
 B54 P5E_CPU1_PE1_TX_C_DP<11> PETP11 @S9S_MB_2U_LIB.S9S_MB_2U(SCH_1):P5E_CPU1_PE1_TX_C_DP(11)
 B55    GND GND_B55 @S9S_MB_2U_LIB.S9S_MB_2U(SCH_1):GND
 B56 P5E_CPU1_PE1_TX_C_DP<12> PETN12 @S9S_MB_2U_LIB.S9S_MB_2U(SCH_1):P5E_CPU1_PE1_TX_C_DP(12)
 OA1 RST_PERST2_OCP_V3_2_N PERST2# @S9S_MB_2U_LIB.S9S_MB_2U(SCH_1):RST_PERST2_OCP_V3_2_N
 OA2 RST_PERST3_OCP_V3_2_N PERST3# @S9S_MB_2U_LIB.S9S_MB_2U(SCH_1):RST_PERST3_OCP_V3_2_N
 OA3 IRQ_LVC3_OCP_V3_2_WAKE_N  WAKE# @S9S_MB_2U_LIB.S9S_MB_2U(SCH_1):IRQ_LVC3_OCP_V3_2_WAKE_N
 OA4 OCP_V3_2_ISO1_RBT_ARB_IN RBT_ARB_IN @S9S_MB_2U_LIB.S9S_MB_2U(SCH_1):OCP_V3_2_ISO1_RBT_ARB_IN
 OA5 OCP_V3_2_ISO2_RBT_ARB_OUT RBT_ARB_OUT @S9S_MB_2U_LIB.S9S_MB_2U(SCH_1):OCP_V3_2_ISO2_RBT_ARB_OUT
 OA6 OCP_V3_2_ID1 SLOT_ID1 @S9S_MB_2U_LIB.S9S_MB_2U(SCH_1):OCP_V3_2_ID1
 OA7 NCSI_OCP_V3_2_TX_EN RBT_TX_EN @S9S_MB_2U_LIB.S9S_MB_2U(SCH_1):NCSI_OCP_V3_2_TX_EN
 OA8 NCSI_OCP_V3_2_TXD1 RBT_TXD1 @S9S_MB_2U_LIB.S9S_MB_2U(SCH_1):NCSI_OCP_V3_2_TXD1
 OA9 NCSI_OCP_V3_2_TXD0 RBT_TXD0 @S9S_MB_2U_LIB.S9S_MB_2U(SCH_1):NCSI_OCP_V3_2_TXD0
OA10    GND GND_OA10 @S9S_MB_2U_LIB.S9S_MB_2U(SCH_1):GND
OA11 CLK_100M_OCP_V3_2_D_DN REFCLKN3 @S9S_MB_2U_LIB.S9S_MB_2U(SCH_1):CLK_100M_OCP_V3_2_D_DN
OA12 CLK_100M_OCP_V3_2_D_DP REFCLKP3 @S9S_MB_2U_LIB.S9S_MB_2U(SCH_1):CLK_100M_OCP_V3_2_D_DP
OA13    GND GND_OA13 @S9S_MB_2U_LIB.S9S_MB_2U(SCH_1):GND
OA14 CLK_50M_NCSI_OCP_V3_2_ISO RBT_CLK_IN @S9S_MB_2U_LIB.S9S_MB_2U(SCH_1):CLK_50M_NCSI_OCP_V3_2_ISO
  A1    GND GND_A1 @S9S_MB_2U_LIB.S9S_MB_2U(SCH_1):GND
  A2    GND GND_A2 @S9S_MB_2U_LIB.S9S_MB_2U(SCH_1):GND
  A3    GND GND_A3 @S9S_MB_2U_LIB.S9S_MB_2U(SCH_1):GND
  A4    GND GND_A4 @S9S_MB_2U_LIB.S9S_MB_2U(SCH_1):GND
  A5    GND GND_A5 @S9S_MB_2U_LIB.S9S_MB_2U(SCH_1):GND
  A6    GND GND_A6 @S9S_MB_2U_LIB.S9S_MB_2U(SCH_1):GND
  A7 SMB_OCP_V3_2_3V3AUX_BUF_R_SCL  SMCLK @S9S_MB_2U_LIB.S9S_MB_2U(SCH_1):SMB_OCP_V3_2_3V3AUX_BUF_R_SCL
  A8 SMB_OCP_V3_2_3V3AUX_BUF_R_SDA  SMDAT @S9S_MB_2U_LIB.S9S_MB_2U(SCH_1):SMB_OCP_V3_2_3V3AUX_BUF_R_SDA
  A9 RST_SMB_OCP_V3_2_N SMRST# @S9S_MB_2U_LIB.S9S_MB_2U(SCH_1):RST_SMB_OCP_V3_2_N
 A10 OCP_V3_1_PRSNTA_R_N PRSNTA# @S9S_MB_2U_LIB.S9S_MB_2U(SCH_1):OCP_V3_1_PRSNTA_R_N
 A11 RST_PERST1_OCP_V3_2_N PERST1# @S9S_MB_2U_LIB.S9S_MB_2U(SCH_1):RST_PERST1_OCP_V3_2_N
 A12 OCP_V3_2_PRSNT2_R_N PRSNTB2# @S9S_MB_2U_LIB.S9S_MB_2U(SCH_1):OCP_V3_2_PRSNT2_R_N
 A13    GND GND_A13 @S9S_MB_2U_LIB.S9S_MB_2U(SCH_1):GND
 A14 CLK_100M_OCP_V3_2_B_DN REFCLKN1 @S9S_MB_2U_LIB.S9S_MB_2U(SCH_1):CLK_100M_OCP_V3_2_B_DN
 A15 CLK_100M_OCP_V3_2_B_DP REFCLKP1 @S9S_MB_2U_LIB.S9S_MB_2U(SCH_1):CLK_100M_OCP_V3_2_B_DP
 A16    GND GND_A16 @S9S_MB_2U_LIB.S9S_MB_2U(SCH_1):GND
 A17 P5E_CPU1_PE1_RX_DN<0>  PERN0 @S9S_MB_2U_LIB.S9S_MB_2U(SCH_1):P5E_CPU1_PE1_RX_DN(0)
 A18 P5E_CPU1_PE1_RX_DP<0>  PERP0 @S9S_MB_2U_LIB.S9S_MB_2U(SCH_1):P5E_CPU1_PE1_RX_DP(0)
 A19    GND GND_A19 @S9S_MB_2U_LIB.S9S_MB_2U(SCH_1):GND
 A20 P5E_CPU1_PE1_RX_DN<1>  PERN1 @S9S_MB_2U_LIB.S9S_MB_2U(SCH_1):P5E_CPU1_PE1_RX_DN(1)
 A21 P5E_CPU1_PE1_RX_DP<1>  PERP1 @S9S_MB_2U_LIB.S9S_MB_2U(SCH_1):P5E_CPU1_PE1_RX_DP(1)
 A22    GND GND_A22 @S9S_MB_2U_LIB.S9S_MB_2U(SCH_1):GND
 A23 P5E_CPU1_PE1_RX_DN<2>  PERN2 @S9S_MB_2U_LIB.S9S_MB_2U(SCH_1):P5E_CPU1_PE1_RX_DN(2)
 A24 P5E_CPU1_PE1_RX_DP<2>  PERP2 @S9S_MB_2U_LIB.S9S_MB_2U(SCH_1):P5E_CPU1_PE1_RX_DP(2)
 A25    GND GND_A25 @S9S_MB_2U_LIB.S9S_MB_2U(SCH_1):GND
 A26 P5E_CPU1_PE1_RX_DN<3>  PERN3 @S9S_MB_2U_LIB.S9S_MB_2U(SCH_1):P5E_CPU1_PE1_RX_DN(3)
 A27 P5E_CPU1_PE1_RX_DP<3>  PERP3 @S9S_MB_2U_LIB.S9S_MB_2U(SCH_1):P5E_CPU1_PE1_RX_DP(3)
 A28    GND GND_A28 @S9S_MB_2U_LIB.S9S_MB_2U(SCH_1):GND
 A29    GND GND_A29 @S9S_MB_2U_LIB.S9S_MB_2U(SCH_1):GND
 A30 P5E_CPU1_PE1_RX_DN<4>  PERN4 @S9S_MB_2U_LIB.S9S_MB_2U(SCH_1):P5E_CPU1_PE1_RX_DN(4)
 A31 P5E_CPU1_PE1_RX_DP<4>  PERP4 @S9S_MB_2U_LIB.S9S_MB_2U(SCH_1):P5E_CPU1_PE1_RX_DP(4)
 A32    GND GND_A32 @S9S_MB_2U_LIB.S9S_MB_2U(SCH_1):GND
 A33 P5E_CPU1_PE1_RX_DN<5>  PERN5 @S9S_MB_2U_LIB.S9S_MB_2U(SCH_1):P5E_CPU1_PE1_RX_DN(5)
 A34 P5E_CPU1_PE1_RX_DP<5>  PERP5 @S9S_MB_2U_LIB.S9S_MB_2U(SCH_1):P5E_CPU1_PE1_RX_DP(5)
 A35    GND GND_A35 @S9S_MB_2U_LIB.S9S_MB_2U(SCH_1):GND
 A36 P5E_CPU1_PE1_RX_DN<6>  PERN6 @S9S_MB_2U_LIB.S9S_MB_2U(SCH_1):P5E_CPU1_PE1_RX_DN(6)
 A37 P5E_CPU1_PE1_RX_DP<6>  PERP6 @S9S_MB_2U_LIB.S9S_MB_2U(SCH_1):P5E_CPU1_PE1_RX_DP(6)
 A38    GND GND_A38 @S9S_MB_2U_LIB.S9S_MB_2U(SCH_1):GND
 A39 P5E_CPU1_PE1_RX_DN<7>  PERN7 @S9S_MB_2U_LIB.S9S_MB_2U(SCH_1):P5E_CPU1_PE1_RX_DN(7)
 A40 P5E_CPU1_PE1_RX_DP<7>  PERP7 @S9S_MB_2U_LIB.S9S_MB_2U(SCH_1):P5E_CPU1_PE1_RX_DP(7)
 A41    GND GND_A41 @S9S_MB_2U_LIB.S9S_MB_2U(SCH_1):GND
 A42 OCP_V3_2_PRSNT1_R_N PRSNTB1# @S9S_MB_2U_LIB.S9S_MB_2U(SCH_1):OCP_V3_2_PRSNT1_R_N
 A43    GND GND_A43 @S9S_MB_2U_LIB.S9S_MB_2U(SCH_1):GND
 A44 P5E_CPU1_PE1_RX_DN<8>  PERN8 @S9S_MB_2U_LIB.S9S_MB_2U(SCH_1):P5E_CPU1_PE1_RX_DN(8)
 A45 P5E_CPU1_PE1_RX_DP<8>  PERP8 @S9S_MB_2U_LIB.S9S_MB_2U(SCH_1):P5E_CPU1_PE1_RX_DP(8)
 A46    GND GND_A46 @S9S_MB_2U_LIB.S9S_MB_2U(SCH_1):GND
 A47 P5E_CPU1_PE1_RX_DN<9>  PERN9 @S9S_MB_2U_LIB.S9S_MB_2U(SCH_1):P5E_CPU1_PE1_RX_DN(9)
 A48 P5E_CPU1_PE1_RX_DP<9>  PERP9 @S9S_MB_2U_LIB.S9S_MB_2U(SCH_1):P5E_CPU1_PE1_RX_DP(9)
 A49    GND GND_A49 @S9S_MB_2U_LIB.S9S_MB_2U(SCH_1):GND
 A50 P5E_CPU1_PE1_RX_DN<10> PERN10 @S9S_MB_2U_LIB.S9S_MB_2U(SCH_1):P5E_CPU1_PE1_RX_DN(10)
 A51 P5E_CPU1_PE1_RX_DP<10> PERP10 @S9S_MB_2U_LIB.S9S_MB_2U(SCH_1):P5E_CPU1_PE1_RX_DP(10)
 A52    GND GND_A52 @S9S_MB_2U_LIB.S9S_MB_2U(SCH_1):GND
 A53 P5E_CPU1_PE1_RX_DN<11> PERN11 @S9S_MB_2U_LIB.S9S_MB_2U(SCH_1):P5E_CPU1_PE1_RX_DN(11)
 A54 P5E_CPU1_PE1_RX_DP<11> PERP11 @S9S_MB_2U_LIB.S9S_MB_2U(SCH_1):P5E_CPU1_PE1_RX_DP(11)
 A55    GND GND_A55 @S9S_MB_2U_LIB.S9S_MB_2U(SCH_1):GND
 A56 P5E_CPU1_PE1_RX_DN<12> PERN12 @S9S_MB_2U_LIB.S9S_MB_2U(SCH_1):P5E_CPU1_PE1_RX_DN(12)
 A57 P5E_CPU1_PE1_RX_DP<12> PERP12 @S9S_MB_2U_LIB.S9S_MB_2U(SCH_1):P5E_CPU1_PE1_RX_DP(12)
 A58    GND GND_A58 @S9S_MB_2U_LIB.S9S_MB_2U(SCH_1):GND
 A59 P5E_CPU1_PE1_RX_DN<13> PERN13 @S9S_MB_2U_LIB.S9S_MB_2U(SCH_1):P5E_CPU1_PE1_RX_DN(13)
 A60 P5E_CPU1_PE1_RX_DP<13> PERP13 @S9S_MB_2U_LIB.S9S_MB_2U(SCH_1):P5E_CPU1_PE1_RX_DP(13)
 A61    GND GND_A61 @S9S_MB_2U_LIB.S9S_MB_2U(SCH_1):GND
 A62 P5E_CPU1_PE1_RX_DN<14> PERN14 @S9S_MB_2U_LIB.S9S_MB_2U(SCH_1):P5E_CPU1_PE1_RX_DN(14)
 A63 P5E_CPU1_PE1_RX_DP<14> PERP14 @S9S_MB_2U_LIB.S9S_MB_2U(SCH_1):P5E_CPU1_PE1_RX_DP(14)
 A64    GND GND_A64 @S9S_MB_2U_LIB.S9S_MB_2U(SCH_1):GND
 A65 P5E_CPU1_PE1_RX_DN<15> PERN15 @S9S_MB_2U_LIB.S9S_MB_2U(SCH_1):P5E_CPU1_PE1_RX_DN(15)
 A66 P5E_CPU1_PE1_RX_DP<15> PERP15 @S9S_MB_2U_LIB.S9S_MB_2U(SCH_1):P5E_CPU1_PE1_RX_DP(15)
 A67    GND GND_A67 @S9S_MB_2U_LIB.S9S_MB_2U(SCH_1):GND
 A68 USB2_5_R1_DN USB_DATN @S9S_MB_2U_LIB.S9S_MB_2U(SCH_1):USB2_5_R1_DN
 A69 USB2_5_R1_DP USB_DATP @S9S_MB_2U_LIB.S9S_MB_2U(SCH_1):USB2_5_R1_DP
 A70 OCP_V3_2_PWRBRK_N PWRBRK0# @S9S_MB_2U_LIB.S9S_MB_2U(SCH_1):OCP_V3_2_PWRBRK_N
 B57 P5E_CPU1_PE1_TX_C_DN<12> PETP12 @S9S_MB_2U_LIB.S9S_MB_2U(SCH_1):P5E_CPU1_PE1_TX_C_DN(12)
 B58    GND GND_B58 @S9S_MB_2U_LIB.S9S_MB_2U(SCH_1):GND
 B59 P5E_CPU1_PE1_TX_C_DN<13> PETN13 @S9S_MB_2U_LIB.S9S_MB_2U(SCH_1):P5E_CPU1_PE1_TX_C_DN(13)
 B60 P5E_CPU1_PE1_TX_C_DP<13> PETP13 @S9S_MB_2U_LIB.S9S_MB_2U(SCH_1):P5E_CPU1_PE1_TX_C_DP(13)
 B61    GND GND_B61 @S9S_MB_2U_LIB.S9S_MB_2U(SCH_1):GND
 B62 P5E_CPU1_PE1_TX_C_DP<14> PETN14 @S9S_MB_2U_LIB.S9S_MB_2U(SCH_1):P5E_CPU1_PE1_TX_C_DP(14)
 B63 P5E_CPU1_PE1_TX_C_DN<14> PETP14 @S9S_MB_2U_LIB.S9S_MB_2U(SCH_1):P5E_CPU1_PE1_TX_C_DN(14)
 B64    GND GND_B64 @S9S_MB_2U_LIB.S9S_MB_2U(SCH_1):GND
 B65 P5E_CPU1_PE1_TX_C_DN<15> PETN15 @S9S_MB_2U_LIB.S9S_MB_2U(SCH_1):P5E_CPU1_PE1_TX_C_DN(15)
 B66 P5E_CPU1_PE1_TX_C_DP<15> PETP15 @S9S_MB_2U_LIB.S9S_MB_2U(SCH_1):P5E_CPU1_PE1_TX_C_DP(15)
 B67    GND GND_B67 @S9S_MB_2U_LIB.S9S_MB_2U(SCH_1):GND
 B68 TP_OCP_V3_2_B68 RFU1_NC_B68 @S9S_MB_2U_LIB.S9S_MB_2U(SCH_1):TP_OCP_V3_2_B68
 B69 TP_OCP_V3_2_B69 RFU1_NC_B69 @S9S_MB_2U_LIB.S9S_MB_2U(SCH_1):TP_OCP_V3_2_B69
 B70 OCP_V3_2_PRSNT3_R_N PRSNTB3# @S9S_MB_2U_LIB.S9S_MB_2U(SCH_1):OCP_V3_2_PRSNT3_R_N
  G1    GND     G1 @S9S_MB_2U_LIB.S9S_MB_2U(SCH_1):GND
  G2    GND     G2 @S9S_MB_2U_LIB.S9S_MB_2U(SCH_1):GND
  G3    GND     G3 @S9S_MB_2U_LIB.S9S_MB_2U(SCH_1):GND
  G4    GND     G4 @S9S_MB_2U_LIB.S9S_MB_2U(SCH_1):GND
  G5    GND     G5 @S9S_MB_2U_LIB.S9S_MB_2U(SCH_1):GND

Q_RES_0402LF-10K,1%,1/16W,CHIPA  I333  R3174
   1 SGPIO_OCP_V3_2_DATAIN      A @S9S_MB_2U_LIB.S9S_MB_2U(SCH_1):SGPIO_OCP_V3_2_DATAIN
   2 P3V3_OCP_V3_2      B @S9S_MB_2U_LIB.S9S_MB_2U(SCH_1):P3V3_OCP_V3_2

Q_RES_0402LF-10K,1%,1/16W,CHIPA  I334  R3175
   1 SGPIO_OCP_V3_2_DATAOUT      A @S9S_MB_2U_LIB.S9S_MB_2U(SCH_1):SGPIO_OCP_V3_2_DATAOUT
   2    GND      B @S9S_MB_2U_LIB.S9S_MB_2U(SCH_1):GND

Q_RES_0402LF-1K,1%,1/16W,CHIP,A  I336  R3176
   1 SGPIO_OCP_V3_2_CLK      A @S9S_MB_2U_LIB.S9S_MB_2U(SCH_1):SGPIO_OCP_V3_2_CLK
   2 P3V3_OCP_V3_2      B @S9S_MB_2U_LIB.S9S_MB_2U(SCH_1):P3V3_OCP_V3_2

Q_RES_0402LF-200,1%,1/16W,CHIPA  I338  R3229
   1 SMB_OCP_V3_2_3V3AUX_BUF_R_SDA      A @S9S_MB_2U_LIB.S9S_MB_2U(SCH_1):SMB_OCP_V3_2_3V3AUX_BUF_R_SDA
   2 SMB_OCP_V3_2_3V3AUX_BUF_SDA      B @S9S_MB_2U_LIB.S9S_MB_2U(SCH_1):SMB_OCP_V3_2_3V3AUX_BUF_SDA

Q_RES_0402LF-200,1%,1/16W,CHIPA  I339  R3228
   1 SMB_OCP_V3_2_3V3AUX_BUF_R_SCL      A @S9S_MB_2U_LIB.S9S_MB_2U(SCH_1):SMB_OCP_V3_2_3V3AUX_BUF_R_SCL
   2 SMB_OCP_V3_2_3V3AUX_BUF_SCL      B @S9S_MB_2U_LIB.S9S_MB_2U(SCH_1):SMB_OCP_V3_2_3V3AUX_BUF_SCL


DRAWING: @S9S_MB_2U_LIB.S9S_MB_2U(SCH_1):PAGE156 

Q_RES_0402LF-10K,1%,1/16W,CHIPA  I6  R3182
   1 P3V3_OCP_V3_2      A @S9S_MB_2U_LIB.S9S_MB_2U(SCH_1):P3V3_OCP_V3_2
   2 IRQ_LVC3_OCP_V3_2_WAKE_N      B @S9S_MB_2U_LIB.S9S_MB_2U(SCH_1):IRQ_LVC3_OCP_V3_2_WAKE_N

Q_RES_0402LF-10K,1%,1/16W,CHIPA  I7  R3183
   1 P3V3_OCP_V3_2      A @S9S_MB_2U_LIB.S9S_MB_2U(SCH_1):P3V3_OCP_V3_2
   2 PU_OCP_V3_2_WAKE_OE      B @S9S_MB_2U_LIB.S9S_MB_2U(SCH_1):PU_OCP_V3_2_WAKE_OE

Q_CAP_0402-0.1UF,25V,10%,X7R,CA  I12  C1821
   1 P3V3_AUX      A @S9S_MB_2U_LIB.S9S_MB_2U(SCH_1):P3V3_AUX
   2    GND      B @S9S_MB_2U_LIB.S9S_MB_2U(SCH_1):GND

Q_RES_0402LF-33.2,1%,1/16W,CHIA  I24  R3185
   1 OCP_V3_2_WAKE_BUFF_N      A @S9S_MB_2U_LIB.S9S_MB_2U(SCH_1):OCP_V3_2_WAKE_BUFF_N
   2 OCP_V3_2_WAKE_BUFF_R_N      B @S9S_MB_2U_LIB.S9S_MB_2U(SCH_1):OCP_V3_2_WAKE_BUFF_R_N

Q_CAP_0402-0.1UF,25V,10%,X7R,CA  I27  C1822
   1 P3V3_AUX      A @S9S_MB_2U_LIB.S9S_MB_2U(SCH_1):P3V3_AUX
   2    GND      B @S9S_MB_2U_LIB.S9S_MB_2U(SCH_1):GND

Q_RES_0402LF-4.7K,1%,1/16W,CHIA  I28  R3184
   1 P3V3_AUX      A @S9S_MB_2U_LIB.S9S_MB_2U(SCH_1):P3V3_AUX
   2 OCP_V3_2_WAKE_BUFF_N      B @S9S_MB_2U_LIB.S9S_MB_2U(SCH_1):OCP_V3_2_WAKE_BUFF_N

74LVC1G07GV-74LVC1G07GV,SMLF,IA  I31  U218
   5 P3V3_AUX    VCC @S9S_MB_2U_LIB.S9S_MB_2U(SCH_1):P3V3_AUX
   2 FM_SYS_THROTTLE_R_N      A @S9S_MB_2U_LIB.S9S_MB_2U(SCH_1):FM_SYS_THROTTLE_R_N
   3    GND    GND @S9S_MB_2U_LIB.S9S_MB_2U(SCH_1):GND
   4 OCP_V3_2_PWRBRK_BUFF_N      Y @S9S_MB_2U_LIB.S9S_MB_2U(SCH_1):OCP_V3_2_PWRBRK_BUFF_N
   1 NC_U218_NC1    NC1 @S9S_MB_2U_LIB.S9S_MB_2U(SCH_1):NC_U218_NC1

Q_CAP_0402-0.1UF,25V,10%,X7R,CA  I33  C1823
   1 P3V3_AUX      A @S9S_MB_2U_LIB.S9S_MB_2U(SCH_1):P3V3_AUX
   2    GND      B @S9S_MB_2U_LIB.S9S_MB_2U(SCH_1):GND

74LVC1G17GW-74LVC1G17GW,SMLF,IA  I35  U207
   5 P3V3_AUX    VCC @S9S_MB_2U_LIB.S9S_MB_2U(SCH_1):P3V3_AUX
   2 RST_HP_OCP_V3_2_N      A @S9S_MB_2U_LIB.S9S_MB_2U(SCH_1):RST_HP_OCP_V3_2_N
   3    GND    GND @S9S_MB_2U_LIB.S9S_MB_2U(SCH_1):GND
   4 RST_OCP_V3_2_BUF_N      Y @S9S_MB_2U_LIB.S9S_MB_2U(SCH_1):RST_OCP_V3_2_BUF_N
   1     NC     NC     NC

Q_RES_0402LF-33.2,1%,1/16W,CHIA  I38  R3189
   1 RST_OCP_V3_2_BUF_N      A @S9S_MB_2U_LIB.S9S_MB_2U(SCH_1):RST_OCP_V3_2_BUF_N
   2 RST_PERST3_OCP_V3_2_N      B @S9S_MB_2U_LIB.S9S_MB_2U(SCH_1):RST_PERST3_OCP_V3_2_N

Q_RES_0402LF-33.2,1%,1/16W,CHIA  I39  R3188
   1 RST_OCP_V3_2_BUF_N      A @S9S_MB_2U_LIB.S9S_MB_2U(SCH_1):RST_OCP_V3_2_BUF_N
   2 RST_PERST2_OCP_V3_2_N      B @S9S_MB_2U_LIB.S9S_MB_2U(SCH_1):RST_PERST2_OCP_V3_2_N

Q_RES_0402LF-33.2,1%,1/16W,CHIA  I40  R3187
   1 RST_OCP_V3_2_BUF_N      A @S9S_MB_2U_LIB.S9S_MB_2U(SCH_1):RST_OCP_V3_2_BUF_N
   2 RST_PERST1_OCP_V3_2_N      B @S9S_MB_2U_LIB.S9S_MB_2U(SCH_1):RST_PERST1_OCP_V3_2_N

Q_RES_0402LF-33.2,1%,1/16W,CHIA  I41  R3186
   1 RST_OCP_V3_2_BUF_N      A @S9S_MB_2U_LIB.S9S_MB_2U(SCH_1):RST_OCP_V3_2_BUF_N
   2 RST_PERST0_OCP_V3_2_N      B @S9S_MB_2U_LIB.S9S_MB_2U(SCH_1):RST_PERST0_OCP_V3_2_N

Q_RES_0402LF-4.7K,1%,1/16W,CHIA  I42  R3190
   1 P3V3_AUX      A @S9S_MB_2U_LIB.S9S_MB_2U(SCH_1):P3V3_AUX
   2 OCP_V3_2_PWRBRK_BUFF_N      B @S9S_MB_2U_LIB.S9S_MB_2U(SCH_1):OCP_V3_2_PWRBRK_BUFF_N

Q_RES_0402LF-33.2,1%,1/16W,CHIA  I44  R3191
   1 OCP_V3_2_PWRBRK_BUFF_N      A @S9S_MB_2U_LIB.S9S_MB_2U(SCH_1):OCP_V3_2_PWRBRK_BUFF_N
   2 OCP_V3_2_PWRBRK_N      B @S9S_MB_2U_LIB.S9S_MB_2U(SCH_1):OCP_V3_2_PWRBRK_N

Q_CAP_0402-0.1UF,25V,10%,X7R,CA  I47  C1824
   1 P3V3_AUX      A @S9S_MB_2U_LIB.S9S_MB_2U(SCH_1):P3V3_AUX
   2    GND      B @S9S_MB_2U_LIB.S9S_MB_2U(SCH_1):GND

Q_RES_0402LF-33.2,1%,1/16W,CHIA  I55  R3193
   1 IRQ_LVC3_V3_2_WAKE_BUF_N      A @S9S_MB_2U_LIB.S9S_MB_2U(SCH_1):IRQ_LVC3_V3_2_WAKE_BUF_N
   2 IRQ_LVC3_WAKE_N      B @S9S_MB_2U_LIB.S9S_MB_2U(SCH_1):IRQ_LVC3_WAKE_N

Q_RES_0402LF-4.7K,1%,1/16W,EMPA  I59  R3192
   1 P3V3_AUX      A @S9S_MB_2U_LIB.S9S_MB_2U(SCH_1):P3V3_AUX
   2 IRQ_LVC3_V3_2_WAKE_BUF_N      B @S9S_MB_2U_LIB.S9S_MB_2U(SCH_1):IRQ_LVC3_V3_2_WAKE_BUF_N

74LVC1G07GV-74LVC1G07GV,SMLF,IA  I61  U219
   5 P3V3_AUX    VCC @S9S_MB_2U_LIB.S9S_MB_2U(SCH_1):P3V3_AUX
   2 OCP_V3_2_WAKE_BUFF_R_N      A @S9S_MB_2U_LIB.S9S_MB_2U(SCH_1):OCP_V3_2_WAKE_BUFF_R_N
   3    GND    GND @S9S_MB_2U_LIB.S9S_MB_2U(SCH_1):GND
   4 IRQ_LVC3_V3_2_WAKE_BUF_N      Y @S9S_MB_2U_LIB.S9S_MB_2U(SCH_1):IRQ_LVC3_V3_2_WAKE_BUF_N
   1 NC_U219_NC1    NC1 @S9S_MB_2U_LIB.S9S_MB_2U(SCH_1):NC_U219_NC1

Q_CAP_0402-0.1UF,25V,10%,X7R,CA  I65  C1841
   1 P3V3_AUX      A @S9S_MB_2U_LIB.S9S_MB_2U(SCH_1):P3V3_AUX
   2    GND      B @S9S_MB_2U_LIB.S9S_MB_2U(SCH_1):GND

Q_RES_0402LF-0,5%,1/16W,CHIP,CA  I70  R3236
   1 RST_HP_OCP_V3_2_R_N      A @S9S_MB_2U_LIB.S9S_MB_2U(SCH_1):RST_HP_OCP_V3_2_R_N
   2 RST_SMB_OCP_V3_2_N      B @S9S_MB_2U_LIB.S9S_MB_2U(SCH_1):RST_SMB_OCP_V3_2_N

Q_RES_0402LF-100K,1%,1/16W,CHIA  I72  R3235
   1 RST_HP_OCP_V3_2_R_N      A @S9S_MB_2U_LIB.S9S_MB_2U(SCH_1):RST_HP_OCP_V3_2_R_N
   2    GND      B @S9S_MB_2U_LIB.S9S_MB_2U(SCH_1):GND

74LVC1G126SE7-74LVC1G126SE-7,SA  I74  U225
   2 RST_SMB_SWITCH_N      A @S9S_MB_2U_LIB.S9S_MB_2U(SCH_1):RST_SMB_SWITCH_N
   4 RST_HP_OCP_V3_2_R_N      Y @S9S_MB_2U_LIB.S9S_MB_2U(SCH_1):RST_HP_OCP_V3_2_R_N
   5 P3V3_AUX    VCC @S9S_MB_2U_LIB.S9S_MB_2U(SCH_1):P3V3_AUX
   3    GND    GND @S9S_MB_2U_LIB.S9S_MB_2U(SCH_1):GND
   1 OCP_V3_2_AUX_PWR_EN_R3     OE @S9S_MB_2U_LIB.S9S_MB_2U(SCH_1):OCP_V3_2_AUX_PWR_EN_R3

Q_RES_0402LF-33.2,1%,1/16W,CHIA  I75  R3234
   1 OCP_V3_2_AUX_PWR_EN      A @S9S_MB_2U_LIB.S9S_MB_2U(SCH_1):OCP_V3_2_AUX_PWR_EN
   2 OCP_V3_2_AUX_PWR_EN_R3      B @S9S_MB_2U_LIB.S9S_MB_2U(SCH_1):OCP_V3_2_AUX_PWR_EN_R3

74LVC1G126SE7-74LVC1G126SE-7,SA  I79  U217
   2 IRQ_LVC3_OCP_V3_2_WAKE_N      A @S9S_MB_2U_LIB.S9S_MB_2U(SCH_1):IRQ_LVC3_OCP_V3_2_WAKE_N
   4 OCP_V3_2_WAKE_BUFF_N      Y @S9S_MB_2U_LIB.S9S_MB_2U(SCH_1):OCP_V3_2_WAKE_BUFF_N
   5 P3V3_AUX    VCC @S9S_MB_2U_LIB.S9S_MB_2U(SCH_1):P3V3_AUX
   3    GND    GND @S9S_MB_2U_LIB.S9S_MB_2U(SCH_1):GND
   1 PU_OCP_V3_2_WAKE_OE     OE @S9S_MB_2U_LIB.S9S_MB_2U(SCH_1):PU_OCP_V3_2_WAKE_OE

Q_CAP_0402-0.1UF,25V,10%,X7R,CA  I81  C2345
   1 P3V3_AUX      A @S9S_MB_2U_LIB.S9S_MB_2U(SCH_1):P3V3_AUX
   2    GND      B @S9S_MB_2U_LIB.S9S_MB_2U(SCH_1):GND

Q_RES_0402LF-0,5%,1/16W,CHIP,CA  I90  R4602
   1 CLK_50M_NCSI_OCP_V3_2_ISO      A @S9S_MB_2U_LIB.S9S_MB_2U(SCH_1):CLK_50M_NCSI_OCP_V3_2_ISO
   2 CLK_50M_NCSI_OCP_V3_2_ISO_R      B @S9S_MB_2U_LIB.S9S_MB_2U(SCH_1):CLK_50M_NCSI_OCP_V3_2_ISO_R

74LVC1G66GV-74LVC1G66GV,SMLF,IA  I92  U321
   1 CLK_50M_NCSI_OCP_V3_2      Y @S9S_MB_2U_LIB.S9S_MB_2U(SCH_1):CLK_50M_NCSI_OCP_V3_2
   2 CLK_50M_NCSI_OCP_V3_2_ISO_R      Z @S9S_MB_2U_LIB.S9S_MB_2U(SCH_1):CLK_50M_NCSI_OCP_V3_2_ISO_R
   3    GND    GND @S9S_MB_2U_LIB.S9S_MB_2U(SCH_1):GND
   4 FB_BMC_ISOLATE1      E @S9S_MB_2U_LIB.S9S_MB_2U(SCH_1):FB_BMC_ISOLATE1
   5 P3V3_AUX    VCC @S9S_MB_2U_LIB.S9S_MB_2U(SCH_1):P3V3_AUX


DRAWING: @S9S_MB_2U_LIB.S9S_MB_2U(SCH_1):PAGE307 

Q_RES_0402LF-0,5%,1/16W,EMPTY,A  I12  R3206
   1 FM_NCSI_OCP_V3_2_R_OE      A @S9S_MB_2U_LIB.S9S_MB_2U(SCH_1):FM_NCSI_OCP_V3_2_R_OE
   2 FB_BMC_ISOLATE1      B @S9S_MB_2U_LIB.S9S_MB_2U(SCH_1):FB_BMC_ISOLATE1

Q_RES_0402LF-100K,1%,1/16W,CHIA  I15  R3207
   1 FB_BMC_ISOLATE1      A @S9S_MB_2U_LIB.S9S_MB_2U(SCH_1):FB_BMC_ISOLATE1
   2    GND      B @S9S_MB_2U_LIB.S9S_MB_2U(SCH_1):GND

Q_CAP_0402-0.1UF,25V,10%,X7R,CA  I17  C1825
   1 P3V3_AUX      A @S9S_MB_2U_LIB.S9S_MB_2U(SCH_1):P3V3_AUX
   2    GND      B @S9S_MB_2U_LIB.S9S_MB_2U(SCH_1):GND

74CBTLV3126PW-74CBTLV3126PW,SMA  I32  U222
   5 NCSI_BMC_RXD0_R1     2A @S9S_MB_2U_LIB.S9S_MB_2U(SCH_1):NCSI_BMC_RXD0_R1
   8 NCSI_OCP_V3_2_CRS_DV     3B @S9S_MB_2U_LIB.S9S_MB_2U(SCH_1):NCSI_OCP_V3_2_CRS_DV
   1 FB_BMC_ISOLATE1    1OE @S9S_MB_2U_LIB.S9S_MB_2U(SCH_1):FB_BMC_ISOLATE1
   4 FB_BMC_ISOLATE1    2OE @S9S_MB_2U_LIB.S9S_MB_2U(SCH_1):FB_BMC_ISOLATE1
   3 NCSI_OCP_V3_2_RXD1     1B @S9S_MB_2U_LIB.S9S_MB_2U(SCH_1):NCSI_OCP_V3_2_RXD1
   6 NCSI_OCP_V3_2_RXD0     2B @S9S_MB_2U_LIB.S9S_MB_2U(SCH_1):NCSI_OCP_V3_2_RXD0
   2 NCSI_BMC_RXD1_R1     1A @S9S_MB_2U_LIB.S9S_MB_2U(SCH_1):NCSI_BMC_RXD1_R1
   7    GND    GND @S9S_MB_2U_LIB.S9S_MB_2U(SCH_1):GND
   9 NCSI_BMC_CRS_DV_R1     3A @S9S_MB_2U_LIB.S9S_MB_2U(SCH_1):NCSI_BMC_CRS_DV_R1
  10 FB_BMC_ISOLATE1    3OE @S9S_MB_2U_LIB.S9S_MB_2U(SCH_1):FB_BMC_ISOLATE1
  11 OCP_V3_2_ISO1_RBT_ARB_IN     4B @S9S_MB_2U_LIB.S9S_MB_2U(SCH_1):OCP_V3_2_ISO1_RBT_ARB_IN
  12 OCP_V3_2_RBT_ARB_IN_R     4A @S9S_MB_2U_LIB.S9S_MB_2U(SCH_1):OCP_V3_2_RBT_ARB_IN_R
  13 FB_BMC_ISOLATE1    4OE @S9S_MB_2U_LIB.S9S_MB_2U(SCH_1):FB_BMC_ISOLATE1
  14 P3V3_AUX    VCC @S9S_MB_2U_LIB.S9S_MB_2U(SCH_1):P3V3_AUX

Q_CAP_0402-0.1UF,25V,10%,X7R,CA  I33  C1826
   1 P3V3_AUX      A @S9S_MB_2U_LIB.S9S_MB_2U(SCH_1):P3V3_AUX
   2    GND      B @S9S_MB_2U_LIB.S9S_MB_2U(SCH_1):GND

Q_RES_0402LF-100,1%,1/16W,CHIPA  I37  R3208
   1 OCP_V3_2_ISO_BIF0_EN      A @S9S_MB_2U_LIB.S9S_MB_2U(SCH_1):OCP_V3_2_ISO_BIF0_EN
   2    GND      B @S9S_MB_2U_LIB.S9S_MB_2U(SCH_1):GND

Q_RES_0402LF-100,1%,1/16W,CHIPA  I38  R3216
   1 OCP_V3_2_ISO_BIF1_EN      A @S9S_MB_2U_LIB.S9S_MB_2U(SCH_1):OCP_V3_2_ISO_BIF1_EN
   2    GND      B @S9S_MB_2U_LIB.S9S_MB_2U(SCH_1):GND

Q_RES_0402LF-100,1%,1/16W,CHIPA  I40  R3217
   1 OCP_V3_2_ISO_BIF2_EN      A @S9S_MB_2U_LIB.S9S_MB_2U(SCH_1):OCP_V3_2_ISO_BIF2_EN
   2    GND      B @S9S_MB_2U_LIB.S9S_MB_2U(SCH_1):GND

Q_RES_0402LF-0,5%,1/16W,EMPTY,A  I56  R3215
   1 NCSI_BMC_TXD1_R1      A @S9S_MB_2U_LIB.S9S_MB_2U(SCH_1):NCSI_BMC_TXD1_R1
   2 RMII_BMC_OCP_TXD_1      B @S9S_MB_2U_LIB.S9S_MB_2U(SCH_1):RMII_BMC_OCP_TXD_1

Q_RES_0402LF-0,5%,1/16W,EMPTY,A  I60  R3214
   1 NCSI_BMC_TXD0_R1      A @S9S_MB_2U_LIB.S9S_MB_2U(SCH_1):NCSI_BMC_TXD0_R1
   2 RMII_BMC_OCP_TXD_0      B @S9S_MB_2U_LIB.S9S_MB_2U(SCH_1):RMII_BMC_OCP_TXD_0

Q_RES_0402LF-0,5%,1/16W,EMPTY,A  I61  R3213
   1 NCSI_BMC_TX_EN_R1      A @S9S_MB_2U_LIB.S9S_MB_2U(SCH_1):NCSI_BMC_TX_EN_R1
   2 RMII_BMC_OCP_TX_EN      B @S9S_MB_2U_LIB.S9S_MB_2U(SCH_1):RMII_BMC_OCP_TX_EN

Q_RES_0402LF-22,1%,1/16W,EMPTYA  I62  R3212
   1 NCSI_BMC_RXD1_R1      A @S9S_MB_2U_LIB.S9S_MB_2U(SCH_1):NCSI_BMC_RXD1_R1
   2 RMII_OCP_BMC_RXD_1      B @S9S_MB_2U_LIB.S9S_MB_2U(SCH_1):RMII_OCP_BMC_RXD_1

Q_RES_0402LF-22,1%,1/16W,EMPTYA  I63  R3211
   1 NCSI_BMC_RXD0_R1      A @S9S_MB_2U_LIB.S9S_MB_2U(SCH_1):NCSI_BMC_RXD0_R1
   2 RMII_OCP_BMC_RXD_0      B @S9S_MB_2U_LIB.S9S_MB_2U(SCH_1):RMII_OCP_BMC_RXD_0

Q_RES_0402LF-22,1%,1/16W,EMPTYA  I64  R3209
   1 OCP_V3_2_RBT_ARB_IN_R      A @S9S_MB_2U_LIB.S9S_MB_2U(SCH_1):OCP_V3_2_RBT_ARB_IN_R
   2 OCP_V3_2_RBT_ARB_IN      B @S9S_MB_2U_LIB.S9S_MB_2U(SCH_1):OCP_V3_2_RBT_ARB_IN

Q_RES_0402LF-22,1%,1/16W,EMPTYA  I65  R3210
   1 NCSI_BMC_CRS_DV_R1      A @S9S_MB_2U_LIB.S9S_MB_2U(SCH_1):NCSI_BMC_CRS_DV_R1
   2 RMII_OCP_BMC_CRSDV      B @S9S_MB_2U_LIB.S9S_MB_2U(SCH_1):RMII_OCP_BMC_CRSDV

Q_CAP_0402-0.1UF,25V,10%,X7R,CA  I77  C1827
   1 P3V3_AUX      A @S9S_MB_2U_LIB.S9S_MB_2U(SCH_1):P3V3_AUX
   2    GND      B @S9S_MB_2U_LIB.S9S_MB_2U(SCH_1):GND

74CBTLV3126PW-74CBTLV3126PW,SMA  I78  U223
   5 NCSI_BMC_TXD0_R1     2A @S9S_MB_2U_LIB.S9S_MB_2U(SCH_1):NCSI_BMC_TXD0_R1
   8 NCSI_OCP_V3_2_TX_EN     3B @S9S_MB_2U_LIB.S9S_MB_2U(SCH_1):NCSI_OCP_V3_2_TX_EN
   1 FB_BMC_ISOLATE1    1OE @S9S_MB_2U_LIB.S9S_MB_2U(SCH_1):FB_BMC_ISOLATE1
   4 FB_BMC_ISOLATE1    2OE @S9S_MB_2U_LIB.S9S_MB_2U(SCH_1):FB_BMC_ISOLATE1
   3 NCSI_OCP_V3_2_TXD1     1B @S9S_MB_2U_LIB.S9S_MB_2U(SCH_1):NCSI_OCP_V3_2_TXD1
   6 NCSI_OCP_V3_2_TXD0     2B @S9S_MB_2U_LIB.S9S_MB_2U(SCH_1):NCSI_OCP_V3_2_TXD0
   2 NCSI_BMC_TXD1_R1     1A @S9S_MB_2U_LIB.S9S_MB_2U(SCH_1):NCSI_BMC_TXD1_R1
   7    GND    GND @S9S_MB_2U_LIB.S9S_MB_2U(SCH_1):GND
   9 NCSI_BMC_TX_EN_R1     3A @S9S_MB_2U_LIB.S9S_MB_2U(SCH_1):NCSI_BMC_TX_EN_R1
  10 FB_BMC_ISOLATE1    3OE @S9S_MB_2U_LIB.S9S_MB_2U(SCH_1):FB_BMC_ISOLATE1
  11 OCP_V3_2_ISO2_RBT_ARB_OUT     4B @S9S_MB_2U_LIB.S9S_MB_2U(SCH_1):OCP_V3_2_ISO2_RBT_ARB_OUT
  12 OCP_V3_2_RBT_ARB_OUT     4A @S9S_MB_2U_LIB.S9S_MB_2U(SCH_1):OCP_V3_2_RBT_ARB_OUT
  13 FB_BMC_ISOLATE1    4OE @S9S_MB_2U_LIB.S9S_MB_2U(SCH_1):FB_BMC_ISOLATE1
  14 P3V3_AUX    VCC @S9S_MB_2U_LIB.S9S_MB_2U(SCH_1):P3V3_AUX

Q_RES_0402LF-0,5%,1/16W,CHIP,CA  I79  R3244
   1 OCP_V3_2_RBT_ARB_OUT      A @S9S_MB_2U_LIB.S9S_MB_2U(SCH_1):OCP_V3_2_RBT_ARB_OUT
   2 OCP_V3_2_RBT_ARB_IN_R      B @S9S_MB_2U_LIB.S9S_MB_2U(SCH_1):OCP_V3_2_RBT_ARB_IN_R

74LVC1G126SE7-74LVC1G126SE-7,SA  I80  U286
   2 FM_OCP_V3_2_PWR_GOOD      A @S9S_MB_2U_LIB.S9S_MB_2U(SCH_1):FM_OCP_V3_2_PWR_GOOD
   4 FB_BMC_ISOLATE_R2      Y @S9S_MB_2U_LIB.S9S_MB_2U(SCH_1):FB_BMC_ISOLATE_R2
   5 P3V3_AUX    VCC @S9S_MB_2U_LIB.S9S_MB_2U(SCH_1):P3V3_AUX
   3    GND    GND @S9S_MB_2U_LIB.S9S_MB_2U(SCH_1):GND
   1 OCP_V3_2_AUX_PWR_EN_R1     OE @S9S_MB_2U_LIB.S9S_MB_2U(SCH_1):OCP_V3_2_AUX_PWR_EN_R1

Q_RES_0402LF-33.2,1%,1/16W,CHIA  I81  R3203
   1 OCP_V3_2_AUX_PWR_EN      A @S9S_MB_2U_LIB.S9S_MB_2U(SCH_1):OCP_V3_2_AUX_PWR_EN
   2 OCP_V3_2_AUX_PWR_EN_R1      B @S9S_MB_2U_LIB.S9S_MB_2U(SCH_1):OCP_V3_2_AUX_PWR_EN_R1

Q_RES_0402LF-49.9,1%,1/16W,CHIA  I85  R3205
   1 FB_BMC_ISOLATE_R2      A @S9S_MB_2U_LIB.S9S_MB_2U(SCH_1):FB_BMC_ISOLATE_R2
   2 FB_BMC_ISOLATE1      B @S9S_MB_2U_LIB.S9S_MB_2U(SCH_1):FB_BMC_ISOLATE1


DRAWING: @S9S_MB_2U_LIB.S9S_MB_2U(SCH_1):PAGE216 

PCA9617ADP-PCA9617ADP,SMLF,IC,A  I5  U235
   5 HP_LVC3_OCP_V3_2_R_EN     EN @S9S_MB_2U_LIB.S9S_MB_2U(SCH_1):HP_LVC3_OCP_V3_2_R_EN
   1 P3V3_AUX   VCCA @S9S_MB_2U_LIB.S9S_MB_2U(SCH_1):P3V3_AUX
   8 P3V3_OCP_V3_2   VCCB @S9S_MB_2U_LIB.S9S_MB_2U(SCH_1):P3V3_OCP_V3_2
   2 SMB_OCP_V3_2_3V3AUX_SCL   SCLA @S9S_MB_2U_LIB.S9S_MB_2U(SCH_1):SMB_OCP_V3_2_3V3AUX_SCL
   3 SMB_OCP_V3_2_3V3AUX_SDA   SDAA @S9S_MB_2U_LIB.S9S_MB_2U(SCH_1):SMB_OCP_V3_2_3V3AUX_SDA
   6 SMB_OCP_V3_2_3V3AUX_BUF_SDA   SDAB @S9S_MB_2U_LIB.S9S_MB_2U(SCH_1):SMB_OCP_V3_2_3V3AUX_BUF_SDA
   7 SMB_OCP_V3_2_3V3AUX_BUF_SCL   SCLB @S9S_MB_2U_LIB.S9S_MB_2U(SCH_1):SMB_OCP_V3_2_3V3AUX_BUF_SCL
   4    GND    GND @S9S_MB_2U_LIB.S9S_MB_2U(SCH_1):GND

Q_RES_0402LF-0,5%,1/16W,CHIP,CA  I7  R3264
   1 HP_LVC3_OCP_V3_2_R_EN      A @S9S_MB_2U_LIB.S9S_MB_2U(SCH_1):HP_LVC3_OCP_V3_2_R_EN
   2 HP_LVC3_OCP_V3_2_EN      B @S9S_MB_2U_LIB.S9S_MB_2U(SCH_1):HP_LVC3_OCP_V3_2_EN

Q_CAP_0402-0.1UF,25V,10%,X7R,CA  I10  C1859
   1 P3V3_AUX      A @S9S_MB_2U_LIB.S9S_MB_2U(SCH_1):P3V3_AUX
   2    GND      B @S9S_MB_2U_LIB.S9S_MB_2U(SCH_1):GND

Q_CAP_0402-0.1UF,25V,10%,X7R,CA  I11  C1861
   1 P3V3_OCP_V3_2      A @S9S_MB_2U_LIB.S9S_MB_2U(SCH_1):P3V3_OCP_V3_2
   2    GND      B @S9S_MB_2U_LIB.S9S_MB_2U(SCH_1):GND

Q_CAP_0402-0.1UF,25V,10%,X7R,CA  I17  C1860
   1 P3V3_AUX      A @S9S_MB_2U_LIB.S9S_MB_2U(SCH_1):P3V3_AUX
   2    GND      B @S9S_MB_2U_LIB.S9S_MB_2U(SCH_1):GND

Q_RES_0402LF-0,5%,1/16W,CHIP,CA  I21  R3263
   1 HP_LVC3_OCP_V3_1_R_EN      A @S9S_MB_2U_LIB.S9S_MB_2U(SCH_1):HP_LVC3_OCP_V3_1_R_EN
   2 HP_LVC3_OCP_V3_1_EN      B @S9S_MB_2U_LIB.S9S_MB_2U(SCH_1):HP_LVC3_OCP_V3_1_EN

Q_CAP_0402-0.1UF,25V,10%,X7R,CA  I23  C1862
   1 P3V3_OCP_SFF      A @S9S_MB_2U_LIB.S9S_MB_2U(SCH_1):P3V3_OCP_SFF
   2    GND      B @S9S_MB_2U_LIB.S9S_MB_2U(SCH_1):GND

PCA9617ADP-PCA9617ADP,SMLF,IC,A  I28  U236
   5 HP_LVC3_OCP_V3_1_R_EN     EN @S9S_MB_2U_LIB.S9S_MB_2U(SCH_1):HP_LVC3_OCP_V3_1_R_EN
   1 P3V3_AUX   VCCA @S9S_MB_2U_LIB.S9S_MB_2U(SCH_1):P3V3_AUX
   8 P3V3_OCP_SFF   VCCB @S9S_MB_2U_LIB.S9S_MB_2U(SCH_1):P3V3_OCP_SFF
   2 SMB_OCP_SFF_3V3AUX_SCL   SCLA @S9S_MB_2U_LIB.S9S_MB_2U(SCH_1):SMB_OCP_SFF_3V3AUX_SCL
   3 SMB_OCP_SFF_3V3AUX_SDA   SDAA @S9S_MB_2U_LIB.S9S_MB_2U(SCH_1):SMB_OCP_SFF_3V3AUX_SDA
   6 SMB_OCP_SFF_3V3AUX_BUF_SDA   SDAB @S9S_MB_2U_LIB.S9S_MB_2U(SCH_1):SMB_OCP_SFF_3V3AUX_BUF_SDA
   7 SMB_OCP_SFF_3V3AUX_BUF_SCL   SCLB @S9S_MB_2U_LIB.S9S_MB_2U(SCH_1):SMB_OCP_SFF_3V3AUX_BUF_SCL
   4    GND    GND @S9S_MB_2U_LIB.S9S_MB_2U(SCH_1):GND

Q_RES_0402LF-4.7K,5%,1/16W,CHIA  I30  R3501
   1 P3V3_OCP_SFF      A @S9S_MB_2U_LIB.S9S_MB_2U(SCH_1):P3V3_OCP_SFF
   2 SMB_OCP_SFF_3V3AUX_BUF_SDA      B @S9S_MB_2U_LIB.S9S_MB_2U(SCH_1):SMB_OCP_SFF_3V3AUX_BUF_SDA

Q_RES_0402LF-4.7K,5%,1/16W,CHIA  I31  R3500
   1 P3V3_OCP_SFF      A @S9S_MB_2U_LIB.S9S_MB_2U(SCH_1):P3V3_OCP_SFF
   2 SMB_OCP_SFF_3V3AUX_BUF_SCL      B @S9S_MB_2U_LIB.S9S_MB_2U(SCH_1):SMB_OCP_SFF_3V3AUX_BUF_SCL

Q_RES_0402LF-4.7K,5%,1/16W,CHIA  I33  R3520
   1 P3V3_OCP_V3_2      A @S9S_MB_2U_LIB.S9S_MB_2U(SCH_1):P3V3_OCP_V3_2
   2 SMB_OCP_V3_2_3V3AUX_BUF_SDA      B @S9S_MB_2U_LIB.S9S_MB_2U(SCH_1):SMB_OCP_V3_2_3V3AUX_BUF_SDA

Q_RES_0402LF-4.7K,5%,1/16W,CHIA  I34  R3519
   1 P3V3_OCP_V3_2      A @S9S_MB_2U_LIB.S9S_MB_2U(SCH_1):P3V3_OCP_V3_2
   2 SMB_OCP_V3_2_3V3AUX_BUF_SCL      B @S9S_MB_2U_LIB.S9S_MB_2U(SCH_1):SMB_OCP_V3_2_3V3AUX_BUF_SCL


DRAWING: @S9S_MB_2U_LIB.S9S_MB_2U(SCH_1):PAGE136 

Q_RES_0402LF-1K,1%,1/16W,EMPTYA  I16  R3277
   1 P3V3_AUX      A @S9S_MB_2U_LIB.S9S_MB_2U(SCH_1):P3V3_AUX
   2 FM_P2E_EQA0      B @S9S_MB_2U_LIB.S9S_MB_2U(SCH_1):FM_P2E_EQA0

Q_RES_0402LF-68K,1%,1/16W,EMPTA  I23  R3279
   1 FM_P2E_EQB1      A @S9S_MB_2U_LIB.S9S_MB_2U(SCH_1):FM_P2E_EQB1
   2    GND      B @S9S_MB_2U_LIB.S9S_MB_2U(SCH_1):GND

Q_RES_0402LF-1K,1%,1/16W,EMPTYA  I25  R3281
   1 FM_P2E_EQB1      A @S9S_MB_2U_LIB.S9S_MB_2U(SCH_1):FM_P2E_EQB1
   2    GND      B @S9S_MB_2U_LIB.S9S_MB_2U(SCH_1):GND

Q_CAP_C0805-10UF,25V,10%,X6S,CA  I48  C1867
   1 P3V3_AUX      A @S9S_MB_2U_LIB.S9S_MB_2U(SCH_1):P3V3_AUX
   2    GND      B @S9S_MB_2U_LIB.S9S_MB_2U(SCH_1):GND

Q_RES_0402LF-1K,1%,1/16W,EMPTYA  I68  R3290
   1 FM_P2E_SWA      A @S9S_MB_2U_LIB.S9S_MB_2U(SCH_1):FM_P2E_SWA
   2    GND      B @S9S_MB_2U_LIB.S9S_MB_2U(SCH_1):GND

Q_RES_0402LF-1K,1%,1/16W,EMPTYA  I69  R3289
   1 P3V3_AUX      A @S9S_MB_2U_LIB.S9S_MB_2U(SCH_1):P3V3_AUX
   2 FM_P2E_SWA      B @S9S_MB_2U_LIB.S9S_MB_2U(SCH_1):FM_P2E_SWA

Q_RES_0402LF-0,5%,1/16W,CHIP,CA  I73  R4537
   1 FM_P2E_EN_N      A @S9S_MB_2U_LIB.S9S_MB_2U(SCH_1):FM_P2E_EN_N
   2 CLK_GEN2_GPU_FPGA_OE_OR_N      B @S9S_MB_2U_LIB.S9S_MB_2U(SCH_1):CLK_GEN2_GPU_FPGA_OE_OR_N

Q_RES_0402LF-4.7K,1%,1/16W,EMPA  I88  R3293
   1 FM_P2E_MODE      A @S9S_MB_2U_LIB.S9S_MB_2U(SCH_1):FM_P2E_MODE
   2    GND      B @S9S_MB_2U_LIB.S9S_MB_2U(SCH_1):GND

Q_RES_0402LF-68K,1%,1/16W,EMPTA  I2  R3268
   1 FM_P2E_EQA1      A @S9S_MB_2U_LIB.S9S_MB_2U(SCH_1):FM_P2E_EQA1
   2    GND      B @S9S_MB_2U_LIB.S9S_MB_2U(SCH_1):GND

Q_RES_0402LF-1K,1%,1/16W,EMPTYA  I4  R3272
   1 FM_P2E_EQA1      A @S9S_MB_2U_LIB.S9S_MB_2U(SCH_1):FM_P2E_EQA1
   2    GND      B @S9S_MB_2U_LIB.S9S_MB_2U(SCH_1):GND

Q_RES_0402LF-68K,1%,1/16W,EMPTA  I6  R3274
   1 FM_P2E_EQA0      A @S9S_MB_2U_LIB.S9S_MB_2U(SCH_1):FM_P2E_EQA0
   2    GND      B @S9S_MB_2U_LIB.S9S_MB_2U(SCH_1):GND

Q_RES_0402LF-1K,1%,1/16W,CHIP,A  I8  R3278
   1 FM_P2E_EQA0      A @S9S_MB_2U_LIB.S9S_MB_2U(SCH_1):FM_P2E_EQA0
   2    GND      B @S9S_MB_2U_LIB.S9S_MB_2U(SCH_1):GND

Q_RES_0402LF-1K,1%,1/16W,EMPTYA  I9  R3271
   1 P3V3_AUX      A @S9S_MB_2U_LIB.S9S_MB_2U(SCH_1):P3V3_AUX
   2 FM_P2E_EQA1      B @S9S_MB_2U_LIB.S9S_MB_2U(SCH_1):FM_P2E_EQA1

Q_RES_0402LF-68K,1%,1/16W,EMPTA  I12  R3267
   1 FM_P2E_FGB      A @S9S_MB_2U_LIB.S9S_MB_2U(SCH_1):FM_P2E_FGB
   2    GND      B @S9S_MB_2U_LIB.S9S_MB_2U(SCH_1):GND

Q_RES_0402LF-1K,1%,1/16W,EMPTYA  I14  R3270
   1 FM_P2E_FGB      A @S9S_MB_2U_LIB.S9S_MB_2U(SCH_1):FM_P2E_FGB
   2    GND      B @S9S_MB_2U_LIB.S9S_MB_2U(SCH_1):GND

Q_RES_0402LF-1K,1%,1/16W,EMPTYA  I15  R3269
   1 P3V3_AUX      A @S9S_MB_2U_LIB.S9S_MB_2U(SCH_1):P3V3_AUX
   2 FM_P2E_FGB      B @S9S_MB_2U_LIB.S9S_MB_2U(SCH_1):FM_P2E_FGB

Q_RES_0402LF-68K,1%,1/16W,EMPTA  I18  R3273
   1 FM_P2E_FGA      A @S9S_MB_2U_LIB.S9S_MB_2U(SCH_1):FM_P2E_FGA
   2    GND      B @S9S_MB_2U_LIB.S9S_MB_2U(SCH_1):GND

Q_RES_0402LF-1K,1%,1/16W,EMPTYA  I20  R3276
   1 FM_P2E_FGA      A @S9S_MB_2U_LIB.S9S_MB_2U(SCH_1):FM_P2E_FGA
   2    GND      B @S9S_MB_2U_LIB.S9S_MB_2U(SCH_1):GND

Q_RES_0402LF-1K,1%,1/16W,EMPTYA  I21  R3275
   1 P3V3_AUX      A @S9S_MB_2U_LIB.S9S_MB_2U(SCH_1):P3V3_AUX
   2 FM_P2E_FGA      B @S9S_MB_2U_LIB.S9S_MB_2U(SCH_1):FM_P2E_FGA

Q_RES_0402LF-68K,1%,1/16W,EMPTA  I27  R3282
   1 FM_P2E_EQB0      A @S9S_MB_2U_LIB.S9S_MB_2U(SCH_1):FM_P2E_EQB0
   2    GND      B @S9S_MB_2U_LIB.S9S_MB_2U(SCH_1):GND

Q_RES_0402LF-1K,1%,1/16W,EMPTYA  I32  R3280
   1 P3V3_AUX      A @S9S_MB_2U_LIB.S9S_MB_2U(SCH_1):P3V3_AUX
   2 FM_P2E_EQB1      B @S9S_MB_2U_LIB.S9S_MB_2U(SCH_1):FM_P2E_EQB1

Q_CAP_0402-0.1UF,25V,10%,X7R,CA  I49  C1863
   1 P3V3_AUX      A @S9S_MB_2U_LIB.S9S_MB_2U(SCH_1):P3V3_AUX
   2    GND      B @S9S_MB_2U_LIB.S9S_MB_2U(SCH_1):GND

PI3EQX12902AZLEX-PI3EQX12902AZA  I50  U237
   1 P3V3_AUX   VDD1 @S9S_MB_2U_LIB.S9S_MB_2U(SCH_1):P3V3_AUX
   2 P2E_MB_BMC_TX_C_R1_DP<0>    AIP @S9S_MB_2U_LIB.S9S_MB_2U(SCH_1):P2E_MB_BMC_TX_C_R1_DP(0)
   3 P2E_MB_BMC_TX_C_R1_DN<0>    AIN @S9S_MB_2U_LIB.S9S_MB_2U(SCH_1):P2E_MB_BMC_TX_C_R1_DN(0)
   4    GND   GND1 @S9S_MB_2U_LIB.S9S_MB_2U(SCH_1):GND
   5 PU_TEST  TEST# @S9S_MB_2U_LIB.S9S_MB_2U(SCH_1):PU_TEST
   6    GND   GND2 @S9S_MB_2U_LIB.S9S_MB_2U(SCH_1):GND
   7    GND   GND3 @S9S_MB_2U_LIB.S9S_MB_2U(SCH_1):GND
   8 P2E_MB_BMC_RX_BUF_C_DN<0>    BON @S9S_MB_2U_LIB.S9S_MB_2U(SCH_1):P2E_MB_BMC_RX_BUF_C_DN(0)
   9 P2E_MB_BMC_RX_BUF_C_DP<0>    BOP @S9S_MB_2U_LIB.S9S_MB_2U(SCH_1):P2E_MB_BMC_RX_BUF_C_DP(0)
  10 P3V3_AUX   VDD2 @S9S_MB_2U_LIB.S9S_MB_2U(SCH_1):P3V3_AUX
  11 FM_P2E_EN_N    EN# @S9S_MB_2U_LIB.S9S_MB_2U(SCH_1):FM_P2E_EN_N
  12 FM_P2E_SWB    SWB @S9S_MB_2U_LIB.S9S_MB_2U(SCH_1):FM_P2E_SWB
  13    GND   GND4 @S9S_MB_2U_LIB.S9S_MB_2U(SCH_1):GND
  14 FM_P2E_FGB    FGB @S9S_MB_2U_LIB.S9S_MB_2U(SCH_1):FM_P2E_FGB
  15 FM_P2E_EQB1   EQB1 @S9S_MB_2U_LIB.S9S_MB_2U(SCH_1):FM_P2E_EQB1
  16 P3V3_AUX   VDD3 @S9S_MB_2U_LIB.S9S_MB_2U(SCH_1):P3V3_AUX
  17 P2E_MB_BMC_RX_R1_DP<0>    BIP @S9S_MB_2U_LIB.S9S_MB_2U(SCH_1):P2E_MB_BMC_RX_R1_DP(0)
  18 P2E_MB_BMC_RX_R1_DN<0>    BIN @S9S_MB_2U_LIB.S9S_MB_2U(SCH_1):P2E_MB_BMC_RX_R1_DN(0)
  19    GND   GND5 @S9S_MB_2U_LIB.S9S_MB_2U(SCH_1):GND
  20 FM_P2E_EQB0   EQB0 @S9S_MB_2U_LIB.S9S_MB_2U(SCH_1):FM_P2E_EQB0
  21 FM_P2E_EQA0   EQA0 @S9S_MB_2U_LIB.S9S_MB_2U(SCH_1):FM_P2E_EQA0
  22    GND   GND6 @S9S_MB_2U_LIB.S9S_MB_2U(SCH_1):GND
  23 P2E_MB_BMC_TX_BUF_DN<0>    AON @S9S_MB_2U_LIB.S9S_MB_2U(SCH_1):P2E_MB_BMC_TX_BUF_DN(0)
  24 P2E_MB_BMC_TX_BUF_DP<0>    AOP @S9S_MB_2U_LIB.S9S_MB_2U(SCH_1):P2E_MB_BMC_TX_BUF_DP(0)
  25 P3V3_AUX   VDD4 @S9S_MB_2U_LIB.S9S_MB_2U(SCH_1):P3V3_AUX
  26 FM_P2E_EQA1   EQA1 @S9S_MB_2U_LIB.S9S_MB_2U(SCH_1):FM_P2E_EQA1
  27 FM_P2E_FGA    FGA @S9S_MB_2U_LIB.S9S_MB_2U(SCH_1):FM_P2E_FGA
  28    GND   GND7 @S9S_MB_2U_LIB.S9S_MB_2U(SCH_1):GND
  29 FM_P2E_SWA    SWA @S9S_MB_2U_LIB.S9S_MB_2U(SCH_1):FM_P2E_SWA
  30 FM_P2E_MODE   MODE @S9S_MB_2U_LIB.S9S_MB_2U(SCH_1):FM_P2E_MODE
  TH    GND GND_TH @S9S_MB_2U_LIB.S9S_MB_2U(SCH_1):GND

Q_CAP_0402-0.1UF,25V,10%,X7R,CA  I51  C1864
   1 P3V3_AUX      A @S9S_MB_2U_LIB.S9S_MB_2U(SCH_1):P3V3_AUX
   2    GND      B @S9S_MB_2U_LIB.S9S_MB_2U(SCH_1):GND

Q_CAP_0402-0.1UF,25V,10%,X7R,CA  I52  C1865
   1 P3V3_AUX      A @S9S_MB_2U_LIB.S9S_MB_2U(SCH_1):P3V3_AUX
   2    GND      B @S9S_MB_2U_LIB.S9S_MB_2U(SCH_1):GND

Q_CAP_0402-0.1UF,25V,10%,X7R,CA  I53  C1866
   1 P3V3_AUX      A @S9S_MB_2U_LIB.S9S_MB_2U(SCH_1):P3V3_AUX
   2    GND      B @S9S_MB_2U_LIB.S9S_MB_2U(SCH_1):GND

Q_RES_0402LF-1K,1%,1/16W,CHIP,A  I56  R3284
   1 FM_P2E_EQB0      A @S9S_MB_2U_LIB.S9S_MB_2U(SCH_1):FM_P2E_EQB0
   2    GND      B @S9S_MB_2U_LIB.S9S_MB_2U(SCH_1):GND

Q_RES_0402LF-1K,1%,1/16W,EMPTYA  I57  R3283
   1 P3V3_AUX      A @S9S_MB_2U_LIB.S9S_MB_2U(SCH_1):P3V3_AUX
   2 FM_P2E_EQB0      B @S9S_MB_2U_LIB.S9S_MB_2U(SCH_1):FM_P2E_EQB0

Q_RES_0402LF-68K,1%,1/16W,EMPTA  I61  R3285
   1 FM_P2E_SWB      A @S9S_MB_2U_LIB.S9S_MB_2U(SCH_1):FM_P2E_SWB
   2    GND      B @S9S_MB_2U_LIB.S9S_MB_2U(SCH_1):GND

Q_RES_0402LF-1K,1%,1/16W,EMPTYA  I63  R3287
   1 FM_P2E_SWB      A @S9S_MB_2U_LIB.S9S_MB_2U(SCH_1):FM_P2E_SWB
   2    GND      B @S9S_MB_2U_LIB.S9S_MB_2U(SCH_1):GND

Q_RES_0402LF-1K,1%,1/16W,EMPTYA  I64  R3286
   1 P3V3_AUX      A @S9S_MB_2U_LIB.S9S_MB_2U(SCH_1):P3V3_AUX
   2 FM_P2E_SWB      B @S9S_MB_2U_LIB.S9S_MB_2U(SCH_1):FM_P2E_SWB

Q_RES_0402LF-68K,1%,1/16W,EMPTA  I66  R3288
   1 FM_P2E_SWA      A @S9S_MB_2U_LIB.S9S_MB_2U(SCH_1):FM_P2E_SWA
   2    GND      B @S9S_MB_2U_LIB.S9S_MB_2U(SCH_1):GND

Q_RES_0402LF-4.7K,1%,1/16W,EMPA  I82  R3291
   1 PU_TEST      A @S9S_MB_2U_LIB.S9S_MB_2U(SCH_1):PU_TEST
   2    GND      B @S9S_MB_2U_LIB.S9S_MB_2U(SCH_1):GND

Q_RES_0402LF-4.7K,1%,1/16W,EMPA  I84  R3265
   1 CLK_GEN2_GPU_FPGA_OE_OR_N      A @S9S_MB_2U_LIB.S9S_MB_2U(SCH_1):CLK_GEN2_GPU_FPGA_OE_OR_N
   2    GND      B @S9S_MB_2U_LIB.S9S_MB_2U(SCH_1):GND

Q_RES_0402LF-4.7K,1%,1/16W,CHIA  I85  R3292
   1 P3V3_AUX      A @S9S_MB_2U_LIB.S9S_MB_2U(SCH_1):P3V3_AUX
   2 CLK_GEN2_GPU_FPGA_OE_OR_N      B @S9S_MB_2U_LIB.S9S_MB_2U(SCH_1):CLK_GEN2_GPU_FPGA_OE_OR_N

Q_RES_0402LF-4.7K,1%,1/16W,CHIA  I89  R3266
   1 P3V3_AUX      A @S9S_MB_2U_LIB.S9S_MB_2U(SCH_1):P3V3_AUX
   2 FM_P2E_MODE      B @S9S_MB_2U_LIB.S9S_MB_2U(SCH_1):FM_P2E_MODE


DRAWING: @S9S_MB_2U_LIB.S9S_MB_2U(SCH_1):PAGE170 

74LVC2G08DP-74LVC2G08DP,SMLF,IA  I1  U241
   8 P3V3_AUX    VCC @S9S_MB_2U_LIB.S9S_MB_2U(SCH_1):P3V3_AUX
   4    GND    GND @S9S_MB_2U_LIB.S9S_MB_2U(SCH_1):GND
   1 OCP_V3_2_PRSNT0_R_N     1A @S9S_MB_2U_LIB.S9S_MB_2U(SCH_1):OCP_V3_2_PRSNT0_R_N
   2 OCP_V3_2_PRSNT1_R_N     1B @S9S_MB_2U_LIB.S9S_MB_2U(SCH_1):OCP_V3_2_PRSNT1_R_N
   7 OCP_V3_2_PRSNT01_R_N     1Y @S9S_MB_2U_LIB.S9S_MB_2U(SCH_1):OCP_V3_2_PRSNT01_R_N

74LVC2G08DP-74LVC2G08DP,SMLF,IA  I2  U241
   5 OCP_V3_2_PRSNT2_R_N     2A @S9S_MB_2U_LIB.S9S_MB_2U(SCH_1):OCP_V3_2_PRSNT2_R_N
   6 OCP_V3_2_PRSNT3_R_N     2B @S9S_MB_2U_LIB.S9S_MB_2U(SCH_1):OCP_V3_2_PRSNT3_R_N
   3 OCP_V3_2_PRSNT23_R_N     2Y @S9S_MB_2U_LIB.S9S_MB_2U(SCH_1):OCP_V3_2_PRSNT23_R_N

74LVC2G08DP-74LVC2G08DP,SMLF,IA  I11  U240
   8 P3V3_AUX    VCC @S9S_MB_2U_LIB.S9S_MB_2U(SCH_1):P3V3_AUX
   4    GND    GND @S9S_MB_2U_LIB.S9S_MB_2U(SCH_1):GND
   1 OCP_SFF_PRSNT0_R_N     1A @S9S_MB_2U_LIB.S9S_MB_2U(SCH_1):OCP_SFF_PRSNT0_R_N
   2 OCP_SFF_PRSNT1_R_N     1B @S9S_MB_2U_LIB.S9S_MB_2U(SCH_1):OCP_SFF_PRSNT1_R_N
   7 OCP_SFF_PRSNT01_R_N     1Y @S9S_MB_2U_LIB.S9S_MB_2U(SCH_1):OCP_SFF_PRSNT01_R_N

74LVC2G08DP-74LVC2G08DP,SMLF,IA  I12  U240
   5 OCP_SFF_PRSNT2_R_N     2A @S9S_MB_2U_LIB.S9S_MB_2U(SCH_1):OCP_SFF_PRSNT2_R_N
   6 OCP_SFF_PRSNT3_R_N     2B @S9S_MB_2U_LIB.S9S_MB_2U(SCH_1):OCP_SFF_PRSNT3_R_N
   3 OCP_SFF_PRSNT23_R_N     2Y @S9S_MB_2U_LIB.S9S_MB_2U(SCH_1):OCP_SFF_PRSNT23_R_N

74LVC2G08DP-74LVC2G08DP,SMLF,IA  I13  U242
   8 P3V3_AUX    VCC @S9S_MB_2U_LIB.S9S_MB_2U(SCH_1):P3V3_AUX
   4    GND    GND @S9S_MB_2U_LIB.S9S_MB_2U(SCH_1):GND
   1 OCP_SFF_PRSNT01_R_N     1A @S9S_MB_2U_LIB.S9S_MB_2U(SCH_1):OCP_SFF_PRSNT01_R_N
   2 OCP_SFF_PRSNT23_R_N     1B @S9S_MB_2U_LIB.S9S_MB_2U(SCH_1):OCP_SFF_PRSNT23_R_N
   7 OCP_SFF_PRSNT_ALL_R_N     1Y @S9S_MB_2U_LIB.S9S_MB_2U(SCH_1):OCP_SFF_PRSNT_ALL_R_N

74LVC2G08DP-74LVC2G08DP,SMLF,IA  I14  U242
   5 OCP_V3_2_PRSNT01_R_N     2A @S9S_MB_2U_LIB.S9S_MB_2U(SCH_1):OCP_V3_2_PRSNT01_R_N
   6 OCP_V3_2_PRSNT23_R_N     2B @S9S_MB_2U_LIB.S9S_MB_2U(SCH_1):OCP_V3_2_PRSNT23_R_N
   3 OCP_V3_2_PRSNT_ALL_R_N     2Y @S9S_MB_2U_LIB.S9S_MB_2U(SCH_1):OCP_V3_2_PRSNT_ALL_R_N

NC7SB3157_SMLF-NC7SB3157P6X,NCB  I15  U243
   1 OCP_SFF_NOT_PRSNT_RBT_ARB_IN     B1 @S9S_MB_2U_LIB.S9S_MB_2U(SCH_1):OCP_SFF_NOT_PRSNT_RBT_ARB_IN
   2    GND    GND @S9S_MB_2U_LIB.S9S_MB_2U(SCH_1):GND
   3 OCP_SFF_RBT_ARB_OUT     B0 @S9S_MB_2U_LIB.S9S_MB_2U(SCH_1):OCP_SFF_RBT_ARB_OUT
   6 OCP_SFF_PRSNT_ALL_R1_N      S @S9S_MB_2U_LIB.S9S_MB_2U(SCH_1):OCP_SFF_PRSNT_ALL_R1_N
   5 P3V3_AUX    VCC @S9S_MB_2U_LIB.S9S_MB_2U(SCH_1):P3V3_AUX
   4 OCP_SFF_RBT_ARB_IN_MUX2      A @S9S_MB_2U_LIB.S9S_MB_2U(SCH_1):OCP_SFF_RBT_ARB_IN_MUX2

NC7SB3157_SMLF-NC7SB3157P6X,NCB  I16  U244
   1 OCP_SFF_NOT_PRSNT_RBT_ARB_IN     B1 @S9S_MB_2U_LIB.S9S_MB_2U(SCH_1):OCP_SFF_NOT_PRSNT_RBT_ARB_IN
   2    GND    GND @S9S_MB_2U_LIB.S9S_MB_2U(SCH_1):GND
   3 OCP_SFF_RBT_ARB_IN     B0 @S9S_MB_2U_LIB.S9S_MB_2U(SCH_1):OCP_SFF_RBT_ARB_IN
   6 OCP_SFF_PRSNT_ALL_R3_N      S @S9S_MB_2U_LIB.S9S_MB_2U(SCH_1):OCP_SFF_PRSNT_ALL_R3_N
   5 P3V3_AUX    VCC @S9S_MB_2U_LIB.S9S_MB_2U(SCH_1):P3V3_AUX
   4 OCP_SFF_RBT_ARB_IN_MUX1_R      A @S9S_MB_2U_LIB.S9S_MB_2U(SCH_1):OCP_SFF_RBT_ARB_IN_MUX1_R

NC7SB3157_SMLF-NC7SB3157P6X,NCB  I17  U246
   1 OCP_V3_2_NOT_PRSNT_RBT_ARB_IN     B1 @S9S_MB_2U_LIB.S9S_MB_2U(SCH_1):OCP_V3_2_NOT_PRSNT_RBT_ARB_IN
   2    GND    GND @S9S_MB_2U_LIB.S9S_MB_2U(SCH_1):GND
   3 OCP_V3_2_RBT_ARB_OUT     B0 @S9S_MB_2U_LIB.S9S_MB_2U(SCH_1):OCP_V3_2_RBT_ARB_OUT
   6 OCP_V3_2_PRSNT_ALL_R1_N      S @S9S_MB_2U_LIB.S9S_MB_2U(SCH_1):OCP_V3_2_PRSNT_ALL_R1_N
   5 P3V3_AUX    VCC @S9S_MB_2U_LIB.S9S_MB_2U(SCH_1):P3V3_AUX
   4 OCP_SFF_RBT_ARB_IN_MUX1      A @S9S_MB_2U_LIB.S9S_MB_2U(SCH_1):OCP_SFF_RBT_ARB_IN_MUX1

NC7SB3157_SMLF-NC7SB3157P6X,NCB  I18  U245
   1 OCP_V3_2_NOT_PRSNT_RBT_ARB_IN     B1 @S9S_MB_2U_LIB.S9S_MB_2U(SCH_1):OCP_V3_2_NOT_PRSNT_RBT_ARB_IN
   2    GND    GND @S9S_MB_2U_LIB.S9S_MB_2U(SCH_1):GND
   3 OCP_V3_2_RBT_ARB_IN     B0 @S9S_MB_2U_LIB.S9S_MB_2U(SCH_1):OCP_V3_2_RBT_ARB_IN
   6 OCP_V3_2_PRSNT_ALL_R3_N      S @S9S_MB_2U_LIB.S9S_MB_2U(SCH_1):OCP_V3_2_PRSNT_ALL_R3_N
   5 P3V3_AUX    VCC @S9S_MB_2U_LIB.S9S_MB_2U(SCH_1):P3V3_AUX
   4 OCP_SFF_RBT_ARB_IN_MUX2_R      A @S9S_MB_2U_LIB.S9S_MB_2U(SCH_1):OCP_SFF_RBT_ARB_IN_MUX2_R

Q_CAP_0402-0.1UF,25V,10%,X7R,CA  I21  C1875
   1 P3V3_AUX      A @S9S_MB_2U_LIB.S9S_MB_2U(SCH_1):P3V3_AUX
   2    GND      B @S9S_MB_2U_LIB.S9S_MB_2U(SCH_1):GND

Q_CAP_0402-0.1UF,25V,10%,X7R,CA  I22  C1874
   1 P3V3_AUX      A @S9S_MB_2U_LIB.S9S_MB_2U(SCH_1):P3V3_AUX
   2    GND      B @S9S_MB_2U_LIB.S9S_MB_2U(SCH_1):GND

Q_CAP_0402-0.1UF,25V,10%,X7R,CA  I27  C1880
   1 P3V3_AUX      A @S9S_MB_2U_LIB.S9S_MB_2U(SCH_1):P3V3_AUX
   2    GND      B @S9S_MB_2U_LIB.S9S_MB_2U(SCH_1):GND

Q_CAP_0402-0.1UF,25V,10%,X7R,CA  I31  C1879
   1 P3V3_AUX      A @S9S_MB_2U_LIB.S9S_MB_2U(SCH_1):P3V3_AUX
   2    GND      B @S9S_MB_2U_LIB.S9S_MB_2U(SCH_1):GND

Q_CAP_0402-0.1UF,25V,10%,X7R,CA  I34  C1877
   1 P3V3_AUX      A @S9S_MB_2U_LIB.S9S_MB_2U(SCH_1):P3V3_AUX
   2    GND      B @S9S_MB_2U_LIB.S9S_MB_2U(SCH_1):GND

Q_CAP_0402-0.1UF,25V,10%,X7R,CA  I37  C1878
   1 P3V3_AUX      A @S9S_MB_2U_LIB.S9S_MB_2U(SCH_1):P3V3_AUX
   2    GND      B @S9S_MB_2U_LIB.S9S_MB_2U(SCH_1):GND

Q_CAP_0402-0.1UF,25V,10%,X7R,CA  I41  C1876
   1 P3V3_AUX      A @S9S_MB_2U_LIB.S9S_MB_2U(SCH_1):P3V3_AUX
   2    GND      B @S9S_MB_2U_LIB.S9S_MB_2U(SCH_1):GND

Q_RES_0402LF-0,5%,1/16W,CHIP,CA  I44  R3303
   1 OCP_SFF_PRSNT_ALL_R_N      A @S9S_MB_2U_LIB.S9S_MB_2U(SCH_1):OCP_SFF_PRSNT_ALL_R_N
   2 OCP_SFF_PRSNT_ALL_R1_N      B @S9S_MB_2U_LIB.S9S_MB_2U(SCH_1):OCP_SFF_PRSNT_ALL_R1_N

Q_RES_0402LF-0,5%,1/16W,CHIP,CA  I45  R3304
   1 OCP_SFF_PRSNT_ALL_R_N      A @S9S_MB_2U_LIB.S9S_MB_2U(SCH_1):OCP_SFF_PRSNT_ALL_R_N
   2 OCP_SFF_PRSNT_ALL_R3_N      B @S9S_MB_2U_LIB.S9S_MB_2U(SCH_1):OCP_SFF_PRSNT_ALL_R3_N

Q_RES_0402LF-0,5%,1/16W,CHIP,CA  I46  R3308
   1 OCP_V3_2_PRSNT_ALL_R_N      A @S9S_MB_2U_LIB.S9S_MB_2U(SCH_1):OCP_V3_2_PRSNT_ALL_R_N
   2 OCP_V3_2_PRSNT_ALL_R1_N      B @S9S_MB_2U_LIB.S9S_MB_2U(SCH_1):OCP_V3_2_PRSNT_ALL_R1_N

Q_RES_0402LF-0,5%,1/16W,CHIP,CA  I47  R3306
   1 OCP_V3_2_PRSNT_ALL_R_N      A @S9S_MB_2U_LIB.S9S_MB_2U(SCH_1):OCP_V3_2_PRSNT_ALL_R_N
   2 OCP_V3_2_PRSNT_ALL_R3_N      B @S9S_MB_2U_LIB.S9S_MB_2U(SCH_1):OCP_V3_2_PRSNT_ALL_R3_N

Q_RES_0402LF-0,5%,1/16W,CHIP,CA  I50  R3305
   1 OCP_SFF_RBT_ARB_IN_MUX1      A @S9S_MB_2U_LIB.S9S_MB_2U(SCH_1):OCP_SFF_RBT_ARB_IN_MUX1
   2 OCP_SFF_RBT_ARB_IN_MUX1_R      B @S9S_MB_2U_LIB.S9S_MB_2U(SCH_1):OCP_SFF_RBT_ARB_IN_MUX1_R

Q_RES_0402LF-0,5%,1/16W,CHIP,CA  I52  R3307
   1 OCP_SFF_RBT_ARB_IN_MUX2      A @S9S_MB_2U_LIB.S9S_MB_2U(SCH_1):OCP_SFF_RBT_ARB_IN_MUX2
   2 OCP_SFF_RBT_ARB_IN_MUX2_R      B @S9S_MB_2U_LIB.S9S_MB_2U(SCH_1):OCP_SFF_RBT_ARB_IN_MUX2_R


DRAWING: @S9S_MB_2U_LIB.S9S_MB_2U(SCH_1):PAGE189 

Q_RES_0402LF-1K,1%,1/16W,CHIP,A  I86  R2133
   1 P3V3_AUX      A @S9S_MB_2U_LIB.S9S_MB_2U(SCH_1):P3V3_AUX
   2 PU_ESPI_ENABLE_STRAP      B @S9S_MB_2U_LIB.S9S_MB_2U(SCH_1):PU_ESPI_ENABLE_STRAP

Q_RES_0402LF-1K,1%,1/16W,CHIP,A  I87  R1324
   1    GND      A @S9S_MB_2U_LIB.S9S_MB_2U(SCH_1):GND
   2 PD_BIOS_IMAGE_SWAP_N      B @S9S_MB_2U_LIB.S9S_MB_2U(SCH_1):PD_BIOS_IMAGE_SWAP_N

Q_RES_0402LF-1K,1%,1/16W,CHIP,A  I88  R1317
   1 P1V05_PCH_AUX      A @S9S_MB_2U_LIB.S9S_MB_2U(SCH_1):P1V05_PCH_AUX
   2 PU_BIOS_RCVR_BOOT      B @S9S_MB_2U_LIB.S9S_MB_2U(SCH_1):PU_BIOS_RCVR_BOOT

Q_RES_0402LF-1K,1%,1/16W,CHIP,A  I89  R1320
   1 P3V3_AUX      A @S9S_MB_2U_LIB.S9S_MB_2U(SCH_1):P3V3_AUX
   2 PU_SWAP_OVERRIDE_N      B @S9S_MB_2U_LIB.S9S_MB_2U(SCH_1):PU_SWAP_OVERRIDE_N

Q_RES_0402LF-1K,1%,1/16W,CHIP,A  I93  R1325
   1 P3V3_AUX      A @S9S_MB_2U_LIB.S9S_MB_2U(SCH_1):P3V3_AUX
   2 PU_FLASH_SECURITY_STRAP      B @S9S_MB_2U_LIB.S9S_MB_2U(SCH_1):PU_FLASH_SECURITY_STRAP

Q_RES_0402LF-10K,1%,1/16W,CHIPA  I100  R1339
   1 P3V3_AUX      A @S9S_MB_2U_LIB.S9S_MB_2U(SCH_1):P3V3_AUX
   2 FM_BIOS_IMAGE_SWAP_N      B @S9S_MB_2U_LIB.S9S_MB_2U(SCH_1):FM_BIOS_IMAGE_SWAP_N

Q_RES_0402LF-10K,1%,1/16W,CHIPA  I106  R1341
   1 FM_ADR_COMPLETE      A @S9S_MB_2U_LIB.S9S_MB_2U(SCH_1):FM_ADR_COMPLETE
   2    GND      B @S9S_MB_2U_LIB.S9S_MB_2U(SCH_1):GND

Q_RES_0402LF-10K,1%,1/16W,CHIPA  I107  R1338
   1 FM_PCH_BIOS_RCVR_MODE      A @S9S_MB_2U_LIB.S9S_MB_2U(SCH_1):FM_PCH_BIOS_RCVR_MODE
   2    GND      B @S9S_MB_2U_LIB.S9S_MB_2U(SCH_1):GND

Q_RES_0402LF-10K,1%,1/16W,CHIPA  I109  R2134
   1 JTAG_TRC_PCH_PTI<6>      A @S9S_MB_2U_LIB.S9S_MB_2U(SCH_1):JTAG_TRC_PCH_PTI(6)
   2    GND      B @S9S_MB_2U_LIB.S9S_MB_2U(SCH_1):GND

Q_RES_0402LF-10K,1%,1/16W,CHIPA  I113  R1343
   1 P1V05_PCH_AUX      A @S9S_MB_2U_LIB.S9S_MB_2U(SCH_1):P1V05_PCH_AUX
   2 FM_PASSWORD_CLEAR_N      B @S9S_MB_2U_LIB.S9S_MB_2U(SCH_1):FM_PASSWORD_CLEAR_N

Q_RES_0402LF-10K,1%,1/16W,CHIPA  I114  R1342
   1 P1V05_PCH_AUX      A @S9S_MB_2U_LIB.S9S_MB_2U(SCH_1):P1V05_PCH_AUX
   2 FM_ME_RCVR_N      B @S9S_MB_2U_LIB.S9S_MB_2U(SCH_1):FM_ME_RCVR_N

SW_PUSHBUTTON4P_24-SW4S_DTSM-6A  I122  SW5
   1 PD_RST_RTCRST_N      1 @S9S_MB_2U_LIB.S9S_MB_2U(SCH_1):PD_RST_RTCRST_N
   2 PD_RST_RTCRST_N      2 @S9S_MB_2U_LIB.S9S_MB_2U(SCH_1):PD_RST_RTCRST_N
   3 RST_RTCRST_N      3 @S9S_MB_2U_LIB.S9S_MB_2U(SCH_1):RST_RTCRST_N
   4 RST_RTCRST_N      4 @S9S_MB_2U_LIB.S9S_MB_2U(SCH_1):RST_RTCRST_N

Q_RES_0402LF-1K,1%,1/16W,CHIP,A  I123  R1333
   1    GND      A @S9S_MB_2U_LIB.S9S_MB_2U(SCH_1):GND
   2 PD_RST_RTCRST_N      B @S9S_MB_2U_LIB.S9S_MB_2U(SCH_1):PD_RST_RTCRST_N

Q_RES_0402LF-20K,1%,1/16W,CHIPA  I127  R1340
   1 P3V3_RTC_AUX      A @S9S_MB_2U_LIB.S9S_MB_2U(SCH_1):P3V3_RTC_AUX
   2 RST_RTCRST_N      B @S9S_MB_2U_LIB.S9S_MB_2U(SCH_1):RST_RTCRST_N

Q_CAP_C0402-1UF,25V,10%,X6S,CHA  I128  C1177
   1 RST_RTCRST_N      A @S9S_MB_2U_LIB.S9S_MB_2U(SCH_1):RST_RTCRST_N
   2    GND      B @S9S_MB_2U_LIB.S9S_MB_2U(SCH_1):GND

Q_RES_0402LF-1K,1%,1/16W,CHIP,A  I132  R3039
   1    GND      A @S9S_MB_2U_LIB.S9S_MB_2U(SCH_1):GND
   2 PD_ME_RCVR_N      B @S9S_MB_2U_LIB.S9S_MB_2U(SCH_1):PD_ME_RCVR_N

Q_RES_0402LF-1K,1%,1/16W,CHIP,A  I133  R1335
   1    GND      A @S9S_MB_2U_LIB.S9S_MB_2U(SCH_1):GND
   2 PD_PASSWORD_CLEAR      B @S9S_MB_2U_LIB.S9S_MB_2U(SCH_1):PD_PASSWORD_CLEAR

CONN14_210HP207GBR1-CONN14_210A  I134  J104
   1 PU_ESPI_ENABLE_STRAP      1 @S9S_MB_2U_LIB.S9S_MB_2U(SCH_1):PU_ESPI_ENABLE_STRAP
   2 JTAG_TRC_PCH_PTI<6>      2 @S9S_MB_2U_LIB.S9S_MB_2U(SCH_1):JTAG_TRC_PCH_PTI(6)
   3 PU_BIOS_RCVR_BOOT      3 @S9S_MB_2U_LIB.S9S_MB_2U(SCH_1):PU_BIOS_RCVR_BOOT
   4 FM_PCH_BIOS_RCVR_MODE      4 @S9S_MB_2U_LIB.S9S_MB_2U(SCH_1):FM_PCH_BIOS_RCVR_MODE
   5 PU_SWAP_OVERRIDE_N      5 @S9S_MB_2U_LIB.S9S_MB_2U(SCH_1):PU_SWAP_OVERRIDE_N
   6 FM_ADR_COMPLETE      6 @S9S_MB_2U_LIB.S9S_MB_2U(SCH_1):FM_ADR_COMPLETE
   7 PD_BIOS_IMAGE_SWAP_N      7 @S9S_MB_2U_LIB.S9S_MB_2U(SCH_1):PD_BIOS_IMAGE_SWAP_N
   8 FM_BIOS_IMAGE_SWAP_N      8 @S9S_MB_2U_LIB.S9S_MB_2U(SCH_1):FM_BIOS_IMAGE_SWAP_N
   9 PU_FLASH_SECURITY_STRAP      9 @S9S_MB_2U_LIB.S9S_MB_2U(SCH_1):PU_FLASH_SECURITY_STRAP
  10 FM_FLASH_SECURITY_STRAP     10 @S9S_MB_2U_LIB.S9S_MB_2U(SCH_1):FM_FLASH_SECURITY_STRAP
  11 PD_ME_RCVR_N     11 @S9S_MB_2U_LIB.S9S_MB_2U(SCH_1):PD_ME_RCVR_N
  12 FM_ME_RCVR_N     12 @S9S_MB_2U_LIB.S9S_MB_2U(SCH_1):FM_ME_RCVR_N
  13 PD_PASSWORD_CLEAR     13 @S9S_MB_2U_LIB.S9S_MB_2U(SCH_1):PD_PASSWORD_CLEAR
  14 FM_PASSWORD_CLEAR_N     14 @S9S_MB_2U_LIB.S9S_MB_2U(SCH_1):FM_PASSWORD_CLEAR_N


DRAWING: @S9S_MB_2U_LIB.S9S_MB_2U(SCH_1):PAGE201 

Q_CAP_C0805-10UF,25V,10%,X6S,CA  I16  C1883
   1 VFG3P3_CLK_GEN      A @S9S_MB_2U_LIB.S9S_MB_2U(SCH_1):VFG3P3_CLK_GEN
   2    GND      B @S9S_MB_2U_LIB.S9S_MB_2U(SCH_1):GND

Q_CAP_0402-0.1UF,25V,10%,X7R,CA  I18  C1886
   1 VFG3P3_CLK_GEN      A @S9S_MB_2U_LIB.S9S_MB_2U(SCH_1):VFG3P3_CLK_GEN
   2    GND      B @S9S_MB_2U_LIB.S9S_MB_2U(SCH_1):GND

Q_CAP_0402-0.1UF,25V,10%,X7R,CA  I19  C1889
   1 VFG3P3_CLK_GEN      A @S9S_MB_2U_LIB.S9S_MB_2U(SCH_1):VFG3P3_CLK_GEN
   2    GND      B @S9S_MB_2U_LIB.S9S_MB_2U(SCH_1):GND

Q_RES_0402LF-0,5%,1/16W,CHIP,CA  I69  R3335
   1 CLK_100M_BMC_RC_DP_R      A @S9S_MB_2U_LIB.S9S_MB_2U(SCH_1):CLK_100M_BMC_RC_DP_R
   2 CLK_100M_BMC_RC_DP      B @S9S_MB_2U_LIB.S9S_MB_2U(SCH_1):CLK_100M_BMC_RC_DP

Q_RES_0402LF-0,5%,1/16W,CHIP,CA  I74  R3336
   1 CLK_100M_BMC_RC_DN_R      A @S9S_MB_2U_LIB.S9S_MB_2U(SCH_1):CLK_100M_BMC_RC_DN_R
   2 CLK_100M_BMC_RC_DN      B @S9S_MB_2U_LIB.S9S_MB_2U(SCH_1):CLK_100M_BMC_RC_DN

Q_RES_0402LF-0,5%,1/16W,CHIP,CA  I75  R3337
   1 CLK_100M_GPU_FPGA_DP_R      A @S9S_MB_2U_LIB.S9S_MB_2U(SCH_1):CLK_100M_GPU_FPGA_DP_R
   2 CLK_100M_GPU_FPGA_DP      B @S9S_MB_2U_LIB.S9S_MB_2U(SCH_1):CLK_100M_GPU_FPGA_DP

Q_RES_0402LF-0,5%,1/16W,CHIP,CA  I76  R3338
   1 CLK_100M_GPU_FPGA_DN_R      A @S9S_MB_2U_LIB.S9S_MB_2U(SCH_1):CLK_100M_GPU_FPGA_DN_R
   2 CLK_100M_GPU_FPGA_DN      B @S9S_MB_2U_LIB.S9S_MB_2U(SCH_1):CLK_100M_GPU_FPGA_DN

Q_CAP_0402-0.1UF,25V,10%,X7R,CA  I80  C1882
   1 P3V3_AUX      A @S9S_MB_2U_LIB.S9S_MB_2U(SCH_1):P3V3_AUX
   2    GND      B @S9S_MB_2U_LIB.S9S_MB_2U(SCH_1):GND

Q_RES_0402LF-0,5%,1/16W,CHIP,CA  I84  R3326
   1 GPU_FPGA_READY_N      A @S9S_MB_2U_LIB.S9S_MB_2U(SCH_1):GPU_FPGA_READY_N
   2 GPU_FPGA_READY_R_N      B @S9S_MB_2U_LIB.S9S_MB_2U(SCH_1):GPU_FPGA_READY_R_N

Q_RES_0402LF-0,5%,1/16W,CHIP,CA  I85  R3327
   1 CLK_GEN2_GPU_FPGA_OE_N      A @S9S_MB_2U_LIB.S9S_MB_2U(SCH_1):CLK_GEN2_GPU_FPGA_OE_N
   2 CLK_GEN2_GPU_FPGA_OE_R2_N      B @S9S_MB_2U_LIB.S9S_MB_2U(SCH_1):CLK_GEN2_GPU_FPGA_OE_R2_N

Q_RES_0402LF-1,1%,1/16W,CHIP,CA  I102  R4077
   1 VFG3P3_CLK_GEN      A @S9S_MB_2U_LIB.S9S_MB_2U(SCH_1):VFG3P3_CLK_GEN
   2 VFG_3P3A_CLK_GEN      B @S9S_MB_2U_LIB.S9S_MB_2U(SCH_1):VFG_3P3A_CLK_GEN

Q_CAP_C0402-1UF,25V,10%,X6S,CHA  I103  C1884
   1 VFG_3P3A_CLK_GEN      A @S9S_MB_2U_LIB.S9S_MB_2U(SCH_1):VFG_3P3A_CLK_GEN
   2    GND      B @S9S_MB_2U_LIB.S9S_MB_2U(SCH_1):GND

Q_CAP_0402-0.1UF,25V,10%,X7R,CA  I104  C2257
   1 VFG3P3_CLK_GEN      A @S9S_MB_2U_LIB.S9S_MB_2U(SCH_1):VFG3P3_CLK_GEN
   2    GND      B @S9S_MB_2U_LIB.S9S_MB_2U(SCH_1):GND

Q_CAP_0402-0.1UF,25V,10%,X7R,CA  I105  C2258
   1 VFG3P3_CLK_GEN      A @S9S_MB_2U_LIB.S9S_MB_2U(SCH_1):VFG3P3_CLK_GEN
   2    GND      B @S9S_MB_2U_LIB.S9S_MB_2U(SCH_1):GND

Q_CAP_0402-0.1UF,25V,10%,X7R,CA  I106  C2259
   1 VFG_3P3A_CLK_GEN      A @S9S_MB_2U_LIB.S9S_MB_2U(SCH_1):VFG_3P3A_CLK_GEN
   2    GND      B @S9S_MB_2U_LIB.S9S_MB_2U(SCH_1):GND

Q_RES_0402LF-10K,1%,1/16W,EMPTA  I127  R4078
   1 P3V3_AUX      A @S9S_MB_2U_LIB.S9S_MB_2U(SCH_1):P3V3_AUX
   2 FG_SS_EN      B @S9S_MB_2U_LIB.S9S_MB_2U(SCH_1):FG_SS_EN

Q_RES_0402LF-10K,1%,1/16W,CHIPA  I128  R4079
   1 FG_SS_EN      A @S9S_MB_2U_LIB.S9S_MB_2U(SCH_1):FG_SS_EN
   2    GND      B @S9S_MB_2U_LIB.S9S_MB_2U(SCH_1):GND

Q_RES_0402LF-10K,1%,1/16W,EMPTA  I134  R4082
   1 CLK_GEN2_SMB_SADR      A @S9S_MB_2U_LIB.S9S_MB_2U(SCH_1):CLK_GEN2_SMB_SADR
   2    GND      B @S9S_MB_2U_LIB.S9S_MB_2U(SCH_1):GND

Q_RES_0402LF-10K,1%,1/16W,CHIPA  I135  R4081
   1 P3V3_AUX      A @S9S_MB_2U_LIB.S9S_MB_2U(SCH_1):P3V3_AUX
   2 CLK_GEN2_SMB_SADR      B @S9S_MB_2U_LIB.S9S_MB_2U(SCH_1):CLK_GEN2_SMB_SADR

Q_RES_0402LF-10K,1%,1/16W,CHIPA  I142  R4080
   1 P3V3_AUX      A @S9S_MB_2U_LIB.S9S_MB_2U(SCH_1):P3V3_AUX
   2 P3V3_PWRGD_CLKGEN      B @S9S_MB_2U_LIB.S9S_MB_2U(SCH_1):P3V3_PWRGD_CLKGEN

Q_RES_0402LF-0,5%,1/16W,CHIP,CA  I146  R4076
   1 CLK_GEN2_GPU_FPGA_OE_OR_N      A @S9S_MB_2U_LIB.S9S_MB_2U(SCH_1):CLK_GEN2_GPU_FPGA_OE_OR_N
   2 CLK_GEN2_GPU_OE_N      B @S9S_MB_2U_LIB.S9S_MB_2U(SCH_1):CLK_GEN2_GPU_OE_N

Q_RES_0402LF-0,5%,1/16W,CHIP,CA  I147  R4075
   1 CLK_GEN2_BMC_RC_OE_N      A @S9S_MB_2U_LIB.S9S_MB_2U(SCH_1):CLK_GEN2_BMC_RC_OE_N
   2 CLK_GEN2_BMC_RC_OE_R3_N      B @S9S_MB_2U_LIB.S9S_MB_2U(SCH_1):CLK_GEN2_BMC_RC_OE_R3_N

Q_INDUCTOR_SMLF-FCM2012KF-601TA  I155  L17
   2 VFG3P3_CLK_GEN      2 @S9S_MB_2U_LIB.S9S_MB_2U(SCH_1):VFG3P3_CLK_GEN
   1 P3V3_AUX      1 @S9S_MB_2U_LIB.S9S_MB_2U(SCH_1):P3V3_AUX

Q_RES_0402LF-4.7K,1%,1/16W,CHIA  I157  R3322
   1 P3V3_AUX      A @S9S_MB_2U_LIB.S9S_MB_2U(SCH_1):P3V3_AUX
   2 CLK_GEN2_GPU_FPGA_OE_R2_N      B @S9S_MB_2U_LIB.S9S_MB_2U(SCH_1):CLK_GEN2_GPU_FPGA_OE_R2_N

74LVC1G32GW_SMLF-74LVC1G32GW,IA  I158  U248
   1 GPU_FPGA_READY_R_N     I0 @S9S_MB_2U_LIB.S9S_MB_2U(SCH_1):GPU_FPGA_READY_R_N
   2 CLK_GEN2_GPU_FPGA_OE_R2_N     I1 @S9S_MB_2U_LIB.S9S_MB_2U(SCH_1):CLK_GEN2_GPU_FPGA_OE_R2_N
   4 CLK_GEN2_GPU_FPGA_OE_OR_N      O @S9S_MB_2U_LIB.S9S_MB_2U(SCH_1):CLK_GEN2_GPU_FPGA_OE_OR_N
   5 P3V3_AUX    VCC @S9S_MB_2U_LIB.S9S_MB_2U(SCH_1):P3V3_AUX
   3    GND    GND @S9S_MB_2U_LIB.S9S_MB_2U(SCH_1):GND

Q_XTAL_4P_13BI_24GND-25MHZ,SMLB  I159  Y3
   1 CLK_GEN2_XTAL_IN_R     X1 @S9S_MB_2U_LIB.S9S_MB_2U(SCH_1):CLK_GEN2_XTAL_IN_R
   2    GND     G1 @S9S_MB_2U_LIB.S9S_MB_2U(SCH_1):GND
   4    GND     G2 @S9S_MB_2U_LIB.S9S_MB_2U(SCH_1):GND
   3 CLK_GEN2_XTAL_OUT     X2 @S9S_MB_2U_LIB.S9S_MB_2U(SCH_1):CLK_GEN2_XTAL_OUT

Q_RES_0402LF-0,5%,1/16W,CHIP,CA  I160  R4501
   1 CLK_GEN2_XTAL_IN_R      A @S9S_MB_2U_LIB.S9S_MB_2U(SCH_1):CLK_GEN2_XTAL_IN_R
   2 CLK_GEN2_XTAL_IN      B @S9S_MB_2U_LIB.S9S_MB_2U(SCH_1):CLK_GEN2_XTAL_IN

Q_RES_0402LF-4.7K,1%,1/16W,EMPA  I161  R4514
   1 CLK_GEN2_GPU_FPGA_OE_R2_N      A @S9S_MB_2U_LIB.S9S_MB_2U(SCH_1):CLK_GEN2_GPU_FPGA_OE_R2_N
   2    GND      B @S9S_MB_2U_LIB.S9S_MB_2U(SCH_1):GND

Q_RES_0402LF-10K,1%,1/16W,CHIPA  I163  R4521
   1 P3V3_AUX      A @S9S_MB_2U_LIB.S9S_MB_2U(SCH_1):P3V3_AUX
   2 CLK_GEN2_BMC_RC_OE_N      B @S9S_MB_2U_LIB.S9S_MB_2U(SCH_1):CLK_GEN2_BMC_RC_OE_N

Q_CAP_C0402-8.2PF,50V,0.1P,NP0A  I165  C2255
   1 CLK_GEN2_XTAL_IN_R      A @S9S_MB_2U_LIB.S9S_MB_2U(SCH_1):CLK_GEN2_XTAL_IN_R
   2    GND      B @S9S_MB_2U_LIB.S9S_MB_2U(SCH_1):GND

Q_CAP_C0402-8.2PF,50V,0.1P,NP0A  I166  C2256
   1 CLK_GEN2_XTAL_OUT      A @S9S_MB_2U_LIB.S9S_MB_2U(SCH_1):CLK_GEN2_XTAL_OUT
   2    GND      B @S9S_MB_2U_LIB.S9S_MB_2U(SCH_1):GND

9FGL0251DKILFT-9FGL0251DKILFT,A  I167  U247
   1 CLK_GEN2_XTAL_IN XIN||CLKIN_25 @S9S_MB_2U_LIB.S9S_MB_2U(SCH_1):CLK_GEN2_XTAL_IN
   2 CLK_GEN2_XTAL_OUT     X2 @S9S_MB_2U_LIB.S9S_MB_2U(SCH_1):CLK_GEN2_XTAL_OUT
   3 VFG3P3_CLK_GEN VDDXTAL3.3 @S9S_MB_2U_LIB.S9S_MB_2U(SCH_1):VFG3P3_CLK_GEN
   4 CLK_GEN2_SMB_SADR VSADR||REF3.3 @S9S_MB_2U_LIB.S9S_MB_2U(SCH_1):CLK_GEN2_SMB_SADR
   5    GND GNDREF @S9S_MB_2U_LIB.S9S_MB_2U(SCH_1):GND
   6    GND GNDDIG @S9S_MB_2U_LIB.S9S_MB_2U(SCH_1):GND
   7 VFG3P3_CLK_GEN VDDDIG3.3 @S9S_MB_2U_LIB.S9S_MB_2U(SCH_1):VFG3P3_CLK_GEN
   8 SMB_HOST_CLK_GEN2_3V3AUX_SCL SCLK_3.3 @S9S_MB_2U_LIB.S9S_MB_2U(SCH_1):SMB_HOST_CLK_GEN2_3V3AUX_SCL
   9 SMB_HOST_CLK_GEN2_3V3AUX_SDA SDATA_3.3 @S9S_MB_2U_LIB.S9S_MB_2U(SCH_1):SMB_HOST_CLK_GEN2_3V3AUX_SDA
  10    GND GND_10 @S9S_MB_2U_LIB.S9S_MB_2U(SCH_1):GND
  11 VFG3P3_CLK_GEN VDD3.3_11 @S9S_MB_2U_LIB.S9S_MB_2U(SCH_1):VFG3P3_CLK_GEN
  12 CLK_GEN2_BMC_RC_OE_R3_N  VOE0# @S9S_MB_2U_LIB.S9S_MB_2U(SCH_1):CLK_GEN2_BMC_RC_OE_R3_N
  13 CLK_100M_BMC_RC_DP_R   DIF0 @S9S_MB_2U_LIB.S9S_MB_2U(SCH_1):CLK_100M_BMC_RC_DP_R
  14 CLK_100M_BMC_RC_DN_R  DIF0# @S9S_MB_2U_LIB.S9S_MB_2U(SCH_1):CLK_100M_BMC_RC_DN_R
  15    GND   GNDA @S9S_MB_2U_LIB.S9S_MB_2U(SCH_1):GND
  16 VFG_3P3A_CLK_GEN VDDA3.3 @S9S_MB_2U_LIB.S9S_MB_2U(SCH_1):VFG_3P3A_CLK_GEN
  17 CLK_100M_GPU_FPGA_DP_R   DIF1 @S9S_MB_2U_LIB.S9S_MB_2U(SCH_1):CLK_100M_GPU_FPGA_DP_R
  18 CLK_100M_GPU_FPGA_DN_R  DIF1# @S9S_MB_2U_LIB.S9S_MB_2U(SCH_1):CLK_100M_GPU_FPGA_DN_R
  19 CLK_GEN2_GPU_OE_N  VOE1# @S9S_MB_2U_LIB.S9S_MB_2U(SCH_1):CLK_GEN2_GPU_OE_N
  20 VFG3P3_CLK_GEN VDD3.3_20 @S9S_MB_2U_LIB.S9S_MB_2U(SCH_1):VFG3P3_CLK_GEN
  21    GND GND_21 @S9S_MB_2U_LIB.S9S_MB_2U(SCH_1):GND
  22 P3V3_PWRGD_CLKGEN ^CKPWRGD_PD# @S9S_MB_2U_LIB.S9S_MB_2U(SCH_1):P3V3_PWRGD_CLKGEN
  23 FG_SS_EN ^VSS_EN_TRI @S9S_MB_2U_LIB.S9S_MB_2U(SCH_1):FG_SS_EN
  24    GND GNDXTAL @S9S_MB_2U_LIB.S9S_MB_2U(SCH_1):GND
  25    GND TH_GND @S9S_MB_2U_LIB.S9S_MB_2U(SCH_1):GND


DRAWING: @S9S_MB_2U_LIB.S9S_MB_2U(SCH_1):PAGE317 

CONN112_10137002101LF-CONN112_A  I38  J107
  A8    GND     A8 @S9S_MB_2U_LIB.S9S_MB_2U(SCH_1):GND
  A7 SWB_HSC_PWRGD     A7 @S9S_MB_2U_LIB.S9S_MB_2U(SCH_1):SWB_HSC_PWRGD
  A6    GND     A6 @S9S_MB_2U_LIB.S9S_MB_2U(SCH_1):GND
  A5 NC_J107_A5     A5 @S9S_MB_2U_LIB.S9S_MB_2U(SCH_1):NC_J107_A5
  B8 P5E_CPU0_PE0_RX_DN<0>     B8 @S9S_MB_2U_LIB.S9S_MB_2U(SCH_1):P5E_CPU0_PE0_RX_DN(0)
  B7    GND     B7 @S9S_MB_2U_LIB.S9S_MB_2U(SCH_1):GND
  B6 P5E_CPU0_PE0_RX_DN<2>     B6 @S9S_MB_2U_LIB.S9S_MB_2U(SCH_1):P5E_CPU0_PE0_RX_DN(2)
  B5    GND     B5 @S9S_MB_2U_LIB.S9S_MB_2U(SCH_1):GND
  C8 P5E_CPU0_PE0_RX_DP<0>     C8 @S9S_MB_2U_LIB.S9S_MB_2U(SCH_1):P5E_CPU0_PE0_RX_DP(0)
  C7 P5E_CPU0_PE0_RX_DP<1>     C7 @S9S_MB_2U_LIB.S9S_MB_2U(SCH_1):P5E_CPU0_PE0_RX_DP(1)
  C6 P5E_CPU0_PE0_RX_DP<2>     C6 @S9S_MB_2U_LIB.S9S_MB_2U(SCH_1):P5E_CPU0_PE0_RX_DP(2)
  C5 P5E_CPU0_PE0_RX_DP<3>     C5 @S9S_MB_2U_LIB.S9S_MB_2U(SCH_1):P5E_CPU0_PE0_RX_DP(3)
  D8    GND     D8 @S9S_MB_2U_LIB.S9S_MB_2U(SCH_1):GND
  D7 P5E_CPU0_PE0_RX_DN<1>     D7 @S9S_MB_2U_LIB.S9S_MB_2U(SCH_1):P5E_CPU0_PE0_RX_DN(1)
  D6    GND     D6 @S9S_MB_2U_LIB.S9S_MB_2U(SCH_1):GND
  D5 P5E_CPU0_PE0_RX_DN<3>     D5 @S9S_MB_2U_LIB.S9S_MB_2U(SCH_1):P5E_CPU0_PE0_RX_DN(3)
  E8 P5E_CPU0_PE4_RX_DP<15>     E8 @S9S_MB_2U_LIB.S9S_MB_2U(SCH_1):P5E_CPU0_PE4_RX_DP(15)
  E7    GND     E7 @S9S_MB_2U_LIB.S9S_MB_2U(SCH_1):GND
  E6 P5E_CPU0_PE4_RX_DP<13>     E6 @S9S_MB_2U_LIB.S9S_MB_2U(SCH_1):P5E_CPU0_PE4_RX_DP(13)
  E5    GND     E5 @S9S_MB_2U_LIB.S9S_MB_2U(SCH_1):GND
  F8 P5E_CPU0_PE4_RX_DN<15>     F8 @S9S_MB_2U_LIB.S9S_MB_2U(SCH_1):P5E_CPU0_PE4_RX_DN(15)
  F7 P5E_CPU0_PE4_RX_DN<14>     F7 @S9S_MB_2U_LIB.S9S_MB_2U(SCH_1):P5E_CPU0_PE4_RX_DN(14)
  F6 P5E_CPU0_PE4_RX_DN<13>     F6 @S9S_MB_2U_LIB.S9S_MB_2U(SCH_1):P5E_CPU0_PE4_RX_DN(13)
  F5 P5E_CPU0_PE4_RX_DN<12>     F5 @S9S_MB_2U_LIB.S9S_MB_2U(SCH_1):P5E_CPU0_PE4_RX_DN(12)
  G8    GND     G8 @S9S_MB_2U_LIB.S9S_MB_2U(SCH_1):GND
  G7 P5E_CPU0_PE4_RX_DP<14>     G7 @S9S_MB_2U_LIB.S9S_MB_2U(SCH_1):P5E_CPU0_PE4_RX_DP(14)
  G6    GND     G6 @S9S_MB_2U_LIB.S9S_MB_2U(SCH_1):GND
  G5 P5E_CPU0_PE4_RX_DP<12>     G5 @S9S_MB_2U_LIB.S9S_MB_2U(SCH_1):P5E_CPU0_PE4_RX_DP(12)
  H8 P5E_CPU0_PE0_TX_C_DN<0>     H8 @S9S_MB_2U_LIB.S9S_MB_2U(SCH_1):P5E_CPU0_PE0_TX_C_DN(0)
  H7    GND     H7 @S9S_MB_2U_LIB.S9S_MB_2U(SCH_1):GND
  H6 P5E_CPU0_PE0_TX_C_DN<2>     H6 @S9S_MB_2U_LIB.S9S_MB_2U(SCH_1):P5E_CPU0_PE0_TX_C_DN(2)
  H5    GND     H5 @S9S_MB_2U_LIB.S9S_MB_2U(SCH_1):GND
  I8 P5E_CPU0_PE0_TX_C_DP<0>     I8 @S9S_MB_2U_LIB.S9S_MB_2U(SCH_1):P5E_CPU0_PE0_TX_C_DP(0)
  I7 P5E_CPU0_PE0_TX_C_DN<1>     I7 @S9S_MB_2U_LIB.S9S_MB_2U(SCH_1):P5E_CPU0_PE0_TX_C_DN(1)
  I6 P5E_CPU0_PE0_TX_C_DP<2>     I6 @S9S_MB_2U_LIB.S9S_MB_2U(SCH_1):P5E_CPU0_PE0_TX_C_DP(2)
  I5 P5E_CPU0_PE0_TX_C_DN<3>     I5 @S9S_MB_2U_LIB.S9S_MB_2U(SCH_1):P5E_CPU0_PE0_TX_C_DN(3)
  J8    GND     J8 @S9S_MB_2U_LIB.S9S_MB_2U(SCH_1):GND
  J7 P5E_CPU0_PE0_TX_C_DP<1>     J7 @S9S_MB_2U_LIB.S9S_MB_2U(SCH_1):P5E_CPU0_PE0_TX_C_DP(1)
  J6    GND     J6 @S9S_MB_2U_LIB.S9S_MB_2U(SCH_1):GND
  J5 P5E_CPU0_PE0_TX_C_DP<3>     J5 @S9S_MB_2U_LIB.S9S_MB_2U(SCH_1):P5E_CPU0_PE0_TX_C_DP(3)
  K8 P5E_CPU0_PE4_TX_C_DN<15>     K8 @S9S_MB_2U_LIB.S9S_MB_2U(SCH_1):P5E_CPU0_PE4_TX_C_DN(15)
  K7    GND     K7 @S9S_MB_2U_LIB.S9S_MB_2U(SCH_1):GND
  K6 P5E_CPU0_PE4_TX_C_DN<13>     K6 @S9S_MB_2U_LIB.S9S_MB_2U(SCH_1):P5E_CPU0_PE4_TX_C_DN(13)
  K5    GND     K5 @S9S_MB_2U_LIB.S9S_MB_2U(SCH_1):GND
  L8 P5E_CPU0_PE4_TX_C_DP<15>     L8 @S9S_MB_2U_LIB.S9S_MB_2U(SCH_1):P5E_CPU0_PE4_TX_C_DP(15)
  L7 P5E_CPU0_PE4_TX_C_DN<14>     L7 @S9S_MB_2U_LIB.S9S_MB_2U(SCH_1):P5E_CPU0_PE4_TX_C_DN(14)
  L6 P5E_CPU0_PE4_TX_C_DP<13>     L6 @S9S_MB_2U_LIB.S9S_MB_2U(SCH_1):P5E_CPU0_PE4_TX_C_DP(13)
  L5 P5E_CPU0_PE4_TX_C_DN<12>     L5 @S9S_MB_2U_LIB.S9S_MB_2U(SCH_1):P5E_CPU0_PE4_TX_C_DN(12)
  M5 P5E_CPU0_PE4_TX_C_DP<12>     M5 @S9S_MB_2U_LIB.S9S_MB_2U(SCH_1):P5E_CPU0_PE4_TX_C_DP(12)
  N5    GND     N5 @S9S_MB_2U_LIB.S9S_MB_2U(SCH_1):GND
  M6    GND     M6 @S9S_MB_2U_LIB.S9S_MB_2U(SCH_1):GND
  N6 NC_J107_N6     N6 @S9S_MB_2U_LIB.S9S_MB_2U(SCH_1):NC_J107_N6
  M7 P5E_CPU0_PE4_TX_C_DP<14>     M7 @S9S_MB_2U_LIB.S9S_MB_2U(SCH_1):P5E_CPU0_PE4_TX_C_DP(14)
  N7    GND     N7 @S9S_MB_2U_LIB.S9S_MB_2U(SCH_1):GND
  M8    GND     M8 @S9S_MB_2U_LIB.S9S_MB_2U(SCH_1):GND
  N8 SWB_HSC_EN_BUF     N8 @S9S_MB_2U_LIB.S9S_MB_2U(SCH_1):SWB_HSC_EN_BUF

CONN112_10137002101LF-CONN112_A  I58  J107
  A4    GND     A4 @S9S_MB_2U_LIB.S9S_MB_2U(SCH_1):GND
  A3 NC_J107_A3     A3 @S9S_MB_2U_LIB.S9S_MB_2U(SCH_1):NC_J107_A3
  A2    GND     A2 @S9S_MB_2U_LIB.S9S_MB_2U(SCH_1):GND
  A1 NC_J107_A1     A1 @S9S_MB_2U_LIB.S9S_MB_2U(SCH_1):NC_J107_A1
  B4 P5E_CPU0_PE0_RX_DN<4>     B4 @S9S_MB_2U_LIB.S9S_MB_2U(SCH_1):P5E_CPU0_PE0_RX_DN(4)
  B3    GND     B3 @S9S_MB_2U_LIB.S9S_MB_2U(SCH_1):GND
  B2 P5E_CPU0_PE0_RX_DN<6>     B2 @S9S_MB_2U_LIB.S9S_MB_2U(SCH_1):P5E_CPU0_PE0_RX_DN(6)
  B1    GND     B1 @S9S_MB_2U_LIB.S9S_MB_2U(SCH_1):GND
  C4 P5E_CPU0_PE0_RX_DP<4>     C4 @S9S_MB_2U_LIB.S9S_MB_2U(SCH_1):P5E_CPU0_PE0_RX_DP(4)
  C3 P5E_CPU0_PE0_RX_DN<5>     C3 @S9S_MB_2U_LIB.S9S_MB_2U(SCH_1):P5E_CPU0_PE0_RX_DN(5)
  C2 P5E_CPU0_PE0_RX_DP<6>     C2 @S9S_MB_2U_LIB.S9S_MB_2U(SCH_1):P5E_CPU0_PE0_RX_DP(6)
  C1 P5E_CPU0_PE0_RX_DN<7>     C1 @S9S_MB_2U_LIB.S9S_MB_2U(SCH_1):P5E_CPU0_PE0_RX_DN(7)
  D4    GND     D4 @S9S_MB_2U_LIB.S9S_MB_2U(SCH_1):GND
  D3 P5E_CPU0_PE0_RX_DP<5>     D3 @S9S_MB_2U_LIB.S9S_MB_2U(SCH_1):P5E_CPU0_PE0_RX_DP(5)
  D2    GND     D2 @S9S_MB_2U_LIB.S9S_MB_2U(SCH_1):GND
  D1 P5E_CPU0_PE0_RX_DP<7>     D1 @S9S_MB_2U_LIB.S9S_MB_2U(SCH_1):P5E_CPU0_PE0_RX_DP(7)
  E4 P5E_CPU0_PE4_RX_DP<11>     E4 @S9S_MB_2U_LIB.S9S_MB_2U(SCH_1):P5E_CPU0_PE4_RX_DP(11)
  E3    GND     E3 @S9S_MB_2U_LIB.S9S_MB_2U(SCH_1):GND
  E2 P5E_CPU0_PE4_RX_DP<9>     E2 @S9S_MB_2U_LIB.S9S_MB_2U(SCH_1):P5E_CPU0_PE4_RX_DP(9)
  E1    GND     E1 @S9S_MB_2U_LIB.S9S_MB_2U(SCH_1):GND
  F4 P5E_CPU0_PE4_RX_DN<11>     F4 @S9S_MB_2U_LIB.S9S_MB_2U(SCH_1):P5E_CPU0_PE4_RX_DN(11)
  F3 P5E_CPU0_PE4_RX_DN<10>     F3 @S9S_MB_2U_LIB.S9S_MB_2U(SCH_1):P5E_CPU0_PE4_RX_DN(10)
  F2 P5E_CPU0_PE4_RX_DN<9>     F2 @S9S_MB_2U_LIB.S9S_MB_2U(SCH_1):P5E_CPU0_PE4_RX_DN(9)
  F1 P5E_CPU0_PE4_RX_DN<8>     F1 @S9S_MB_2U_LIB.S9S_MB_2U(SCH_1):P5E_CPU0_PE4_RX_DN(8)
  G4    GND     G4 @S9S_MB_2U_LIB.S9S_MB_2U(SCH_1):GND
  G3 P5E_CPU0_PE4_RX_DP<10>     G3 @S9S_MB_2U_LIB.S9S_MB_2U(SCH_1):P5E_CPU0_PE4_RX_DP(10)
  G2    GND     G2 @S9S_MB_2U_LIB.S9S_MB_2U(SCH_1):GND
  G1 P5E_CPU0_PE4_RX_DP<8>     G1 @S9S_MB_2U_LIB.S9S_MB_2U(SCH_1):P5E_CPU0_PE4_RX_DP(8)
  H4 P5E_CPU0_PE0_TX_C_DN<4>     H4 @S9S_MB_2U_LIB.S9S_MB_2U(SCH_1):P5E_CPU0_PE0_TX_C_DN(4)
  H3    GND     H3 @S9S_MB_2U_LIB.S9S_MB_2U(SCH_1):GND
  H2 P5E_CPU0_PE0_TX_C_DN<6>     H2 @S9S_MB_2U_LIB.S9S_MB_2U(SCH_1):P5E_CPU0_PE0_TX_C_DN(6)
  H1    GND     H1 @S9S_MB_2U_LIB.S9S_MB_2U(SCH_1):GND
  I4 P5E_CPU0_PE0_TX_C_DP<4>     I4 @S9S_MB_2U_LIB.S9S_MB_2U(SCH_1):P5E_CPU0_PE0_TX_C_DP(4)
  I3 P5E_CPU0_PE0_TX_C_DN<5>     I3 @S9S_MB_2U_LIB.S9S_MB_2U(SCH_1):P5E_CPU0_PE0_TX_C_DN(5)
  I2 P5E_CPU0_PE0_TX_C_DP<6>     I2 @S9S_MB_2U_LIB.S9S_MB_2U(SCH_1):P5E_CPU0_PE0_TX_C_DP(6)
  I1 P5E_CPU0_PE0_TX_C_DN<7>     I1 @S9S_MB_2U_LIB.S9S_MB_2U(SCH_1):P5E_CPU0_PE0_TX_C_DN(7)
  J4    GND     J4 @S9S_MB_2U_LIB.S9S_MB_2U(SCH_1):GND
  J3 P5E_CPU0_PE0_TX_C_DP<5>     J3 @S9S_MB_2U_LIB.S9S_MB_2U(SCH_1):P5E_CPU0_PE0_TX_C_DP(5)
  J2    GND     J2 @S9S_MB_2U_LIB.S9S_MB_2U(SCH_1):GND
  J1 P5E_CPU0_PE0_TX_C_DP<7>     J1 @S9S_MB_2U_LIB.S9S_MB_2U(SCH_1):P5E_CPU0_PE0_TX_C_DP(7)
  K4 P5E_CPU0_PE4_TX_C_DP<11>     K4 @S9S_MB_2U_LIB.S9S_MB_2U(SCH_1):P5E_CPU0_PE4_TX_C_DP(11)
  K3    GND     K3 @S9S_MB_2U_LIB.S9S_MB_2U(SCH_1):GND
  K2 P5E_CPU0_PE4_TX_C_DN<9>     K2 @S9S_MB_2U_LIB.S9S_MB_2U(SCH_1):P5E_CPU0_PE4_TX_C_DN(9)
  K1    GND     K1 @S9S_MB_2U_LIB.S9S_MB_2U(SCH_1):GND
  L4 P5E_CPU0_PE4_TX_C_DN<11>     L4 @S9S_MB_2U_LIB.S9S_MB_2U(SCH_1):P5E_CPU0_PE4_TX_C_DN(11)
  L3 P5E_CPU0_PE4_TX_C_DN<10>     L3 @S9S_MB_2U_LIB.S9S_MB_2U(SCH_1):P5E_CPU0_PE4_TX_C_DN(10)
  L2 P5E_CPU0_PE4_TX_C_DP<9>     L2 @S9S_MB_2U_LIB.S9S_MB_2U(SCH_1):P5E_CPU0_PE4_TX_C_DP(9)
  L1 P5E_CPU0_PE4_TX_C_DN<8>     L1 @S9S_MB_2U_LIB.S9S_MB_2U(SCH_1):P5E_CPU0_PE4_TX_C_DN(8)
  M1 P5E_CPU0_PE4_TX_C_DP<8>     M1 @S9S_MB_2U_LIB.S9S_MB_2U(SCH_1):P5E_CPU0_PE4_TX_C_DP(8)
  N1    GND     N1 @S9S_MB_2U_LIB.S9S_MB_2U(SCH_1):GND
  M2    GND     M2 @S9S_MB_2U_LIB.S9S_MB_2U(SCH_1):GND
  N2 PRSNT_CABLE_SWB_B2_N     N2 @S9S_MB_2U_LIB.S9S_MB_2U(SCH_1):PRSNT_CABLE_SWB_B2_N
  M3 P5E_CPU0_PE4_TX_C_DP<10>     M3 @S9S_MB_2U_LIB.S9S_MB_2U(SCH_1):P5E_CPU0_PE4_TX_C_DP(10)
  N3    GND     N3 @S9S_MB_2U_LIB.S9S_MB_2U(SCH_1):GND
  M4    GND     M4 @S9S_MB_2U_LIB.S9S_MB_2U(SCH_1):GND
  N4 NC_J107_N4     N4 @S9S_MB_2U_LIB.S9S_MB_2U(SCH_1):NC_J107_N4


DRAWING: @S9S_MB_2U_LIB.S9S_MB_2U(SCH_1):PAGE320 

CONN112_10137002101LF-CONN112_A  I57  J108
  A4    GND     A4 @S9S_MB_2U_LIB.S9S_MB_2U(SCH_1):GND
  A3 PRSNT_CABLE_GPU_A2_N     A3 @S9S_MB_2U_LIB.S9S_MB_2U(SCH_1):PRSNT_CABLE_GPU_A2_N
  A2    GND     A2 @S9S_MB_2U_LIB.S9S_MB_2U(SCH_1):GND
  A1 GPU_3V3IO_RSVD3_FFU     A1 @S9S_MB_2U_LIB.S9S_MB_2U(SCH_1):GPU_3V3IO_RSVD3_FFU
  B4 P5E_CPU0_PE0_RX_DN<12>     B4 @S9S_MB_2U_LIB.S9S_MB_2U(SCH_1):P5E_CPU0_PE0_RX_DN(12)
  B3    GND     B3 @S9S_MB_2U_LIB.S9S_MB_2U(SCH_1):GND
  B2 P5E_CPU0_PE0_RX_DN<14>     B2 @S9S_MB_2U_LIB.S9S_MB_2U(SCH_1):P5E_CPU0_PE0_RX_DN(14)
  B1    GND     B1 @S9S_MB_2U_LIB.S9S_MB_2U(SCH_1):GND
  C4 P5E_CPU0_PE0_RX_DP<12>     C4 @S9S_MB_2U_LIB.S9S_MB_2U(SCH_1):P5E_CPU0_PE0_RX_DP(12)
  C3 P5E_CPU0_PE0_RX_DN<13>     C3 @S9S_MB_2U_LIB.S9S_MB_2U(SCH_1):P5E_CPU0_PE0_RX_DN(13)
  C2 P5E_CPU0_PE0_RX_DP<14>     C2 @S9S_MB_2U_LIB.S9S_MB_2U(SCH_1):P5E_CPU0_PE0_RX_DP(14)
  C1 P5E_CPU0_PE0_RX_DN<15>     C1 @S9S_MB_2U_LIB.S9S_MB_2U(SCH_1):P5E_CPU0_PE0_RX_DN(15)
  D4    GND     D4 @S9S_MB_2U_LIB.S9S_MB_2U(SCH_1):GND
  D3 P5E_CPU0_PE0_RX_DP<13>     D3 @S9S_MB_2U_LIB.S9S_MB_2U(SCH_1):P5E_CPU0_PE0_RX_DP(13)
  D2    GND     D2 @S9S_MB_2U_LIB.S9S_MB_2U(SCH_1):GND
  D1 P5E_CPU0_PE0_RX_DP<15>     D1 @S9S_MB_2U_LIB.S9S_MB_2U(SCH_1):P5E_CPU0_PE0_RX_DP(15)
  E4 P5E_CPU0_PE4_RX_DP<3>     E4 @S9S_MB_2U_LIB.S9S_MB_2U(SCH_1):P5E_CPU0_PE4_RX_DP(3)
  E3    GND     E3 @S9S_MB_2U_LIB.S9S_MB_2U(SCH_1):GND
  E2 P5E_CPU0_PE4_RX_DP<1>     E2 @S9S_MB_2U_LIB.S9S_MB_2U(SCH_1):P5E_CPU0_PE4_RX_DP(1)
  E1    GND     E1 @S9S_MB_2U_LIB.S9S_MB_2U(SCH_1):GND
  F4 P5E_CPU0_PE4_RX_DN<3>     F4 @S9S_MB_2U_LIB.S9S_MB_2U(SCH_1):P5E_CPU0_PE4_RX_DN(3)
  F3 P5E_CPU0_PE4_RX_DN<2>     F3 @S9S_MB_2U_LIB.S9S_MB_2U(SCH_1):P5E_CPU0_PE4_RX_DN(2)
  F2 P5E_CPU0_PE4_RX_DN<1>     F2 @S9S_MB_2U_LIB.S9S_MB_2U(SCH_1):P5E_CPU0_PE4_RX_DN(1)
  F1 P5E_CPU0_PE4_RX_DN<0>     F1 @S9S_MB_2U_LIB.S9S_MB_2U(SCH_1):P5E_CPU0_PE4_RX_DN(0)
  G4    GND     G4 @S9S_MB_2U_LIB.S9S_MB_2U(SCH_1):GND
  G3 P5E_CPU0_PE4_RX_DP<2>     G3 @S9S_MB_2U_LIB.S9S_MB_2U(SCH_1):P5E_CPU0_PE4_RX_DP(2)
  G2    GND     G2 @S9S_MB_2U_LIB.S9S_MB_2U(SCH_1):GND
  G1 P5E_CPU0_PE4_RX_DP<0>     G1 @S9S_MB_2U_LIB.S9S_MB_2U(SCH_1):P5E_CPU0_PE4_RX_DP(0)
  H4 P5E_CPU0_PE0_TX_C_DN<12>     H4 @S9S_MB_2U_LIB.S9S_MB_2U(SCH_1):P5E_CPU0_PE0_TX_C_DN(12)
  H3    GND     H3 @S9S_MB_2U_LIB.S9S_MB_2U(SCH_1):GND
  H2 P5E_CPU0_PE0_TX_C_DN<14>     H2 @S9S_MB_2U_LIB.S9S_MB_2U(SCH_1):P5E_CPU0_PE0_TX_C_DN(14)
  H1    GND     H1 @S9S_MB_2U_LIB.S9S_MB_2U(SCH_1):GND
  I4 P5E_CPU0_PE0_TX_C_DP<12>     I4 @S9S_MB_2U_LIB.S9S_MB_2U(SCH_1):P5E_CPU0_PE0_TX_C_DP(12)
  I3 P5E_CPU0_PE0_TX_C_DN<13>     I3 @S9S_MB_2U_LIB.S9S_MB_2U(SCH_1):P5E_CPU0_PE0_TX_C_DN(13)
  I2 P5E_CPU0_PE0_TX_C_DP<14>     I2 @S9S_MB_2U_LIB.S9S_MB_2U(SCH_1):P5E_CPU0_PE0_TX_C_DP(14)
  I1 P5E_CPU0_PE0_TX_C_DN<15>     I1 @S9S_MB_2U_LIB.S9S_MB_2U(SCH_1):P5E_CPU0_PE0_TX_C_DN(15)
  J4    GND     J4 @S9S_MB_2U_LIB.S9S_MB_2U(SCH_1):GND
  J3 P5E_CPU0_PE0_TX_C_DP<13>     J3 @S9S_MB_2U_LIB.S9S_MB_2U(SCH_1):P5E_CPU0_PE0_TX_C_DP(13)
  J2    GND     J2 @S9S_MB_2U_LIB.S9S_MB_2U(SCH_1):GND
  J1 P5E_CPU0_PE0_TX_C_DP<15>     J1 @S9S_MB_2U_LIB.S9S_MB_2U(SCH_1):P5E_CPU0_PE0_TX_C_DP(15)
  K4 P5E_CPU0_PE4_TX_C_DN<3>     K4 @S9S_MB_2U_LIB.S9S_MB_2U(SCH_1):P5E_CPU0_PE4_TX_C_DN(3)
  K3    GND     K3 @S9S_MB_2U_LIB.S9S_MB_2U(SCH_1):GND
  K2 P5E_CPU0_PE4_TX_C_DP<1>     K2 @S9S_MB_2U_LIB.S9S_MB_2U(SCH_1):P5E_CPU0_PE4_TX_C_DP(1)
  K1    GND     K1 @S9S_MB_2U_LIB.S9S_MB_2U(SCH_1):GND
  L4 P5E_CPU0_PE4_TX_C_DP<3>     L4 @S9S_MB_2U_LIB.S9S_MB_2U(SCH_1):P5E_CPU0_PE4_TX_C_DP(3)
  L3 P5E_CPU0_PE4_TX_C_DN<2>     L3 @S9S_MB_2U_LIB.S9S_MB_2U(SCH_1):P5E_CPU0_PE4_TX_C_DN(2)
  L2 P5E_CPU0_PE4_TX_C_DN<1>     L2 @S9S_MB_2U_LIB.S9S_MB_2U(SCH_1):P5E_CPU0_PE4_TX_C_DN(1)
  L1 P5E_CPU0_PE4_TX_C_DN<0>     L1 @S9S_MB_2U_LIB.S9S_MB_2U(SCH_1):P5E_CPU0_PE4_TX_C_DN(0)
  M1 P5E_CPU0_PE4_TX_C_DP<0>     M1 @S9S_MB_2U_LIB.S9S_MB_2U(SCH_1):P5E_CPU0_PE4_TX_C_DP(0)
  N1    GND     N1 @S9S_MB_2U_LIB.S9S_MB_2U(SCH_1):GND
  M2    GND     M2 @S9S_MB_2U_LIB.S9S_MB_2U(SCH_1):GND
  N2 NC_J108_N2     N2 @S9S_MB_2U_LIB.S9S_MB_2U(SCH_1):NC_J108_N2
  M3 P5E_CPU0_PE4_TX_C_DP<2>     M3 @S9S_MB_2U_LIB.S9S_MB_2U(SCH_1):P5E_CPU0_PE4_TX_C_DP(2)
  N3    GND     N3 @S9S_MB_2U_LIB.S9S_MB_2U(SCH_1):GND
  M4    GND     M4 @S9S_MB_2U_LIB.S9S_MB_2U(SCH_1):GND
  N4 NC_J108_N4     N4 @S9S_MB_2U_LIB.S9S_MB_2U(SCH_1):NC_J108_N4

CONN112_10137002101LF-CONN112_A  I76  J108
  A8    GND     A8 @S9S_MB_2U_LIB.S9S_MB_2U(SCH_1):GND
  A7 GPU_FPGA_OVERT_N     A7 @S9S_MB_2U_LIB.S9S_MB_2U(SCH_1):GPU_FPGA_OVERT_N
  A6    GND     A6 @S9S_MB_2U_LIB.S9S_MB_2U(SCH_1):GND
  A5 GPU_3V3IO_RSVD5_FFU     A5 @S9S_MB_2U_LIB.S9S_MB_2U(SCH_1):GPU_3V3IO_RSVD5_FFU
  B8 P5E_CPU0_PE0_RX_DN<8>     B8 @S9S_MB_2U_LIB.S9S_MB_2U(SCH_1):P5E_CPU0_PE0_RX_DN(8)
  B7    GND     B7 @S9S_MB_2U_LIB.S9S_MB_2U(SCH_1):GND
  B6 P5E_CPU0_PE0_RX_DN<10>     B6 @S9S_MB_2U_LIB.S9S_MB_2U(SCH_1):P5E_CPU0_PE0_RX_DN(10)
  B5    GND     B5 @S9S_MB_2U_LIB.S9S_MB_2U(SCH_1):GND
  C8 P5E_CPU0_PE0_RX_DP<8>     C8 @S9S_MB_2U_LIB.S9S_MB_2U(SCH_1):P5E_CPU0_PE0_RX_DP(8)
  C7 P5E_CPU0_PE0_RX_DN<9>     C7 @S9S_MB_2U_LIB.S9S_MB_2U(SCH_1):P5E_CPU0_PE0_RX_DN(9)
  C6 P5E_CPU0_PE0_RX_DP<10>     C6 @S9S_MB_2U_LIB.S9S_MB_2U(SCH_1):P5E_CPU0_PE0_RX_DP(10)
  C5 P5E_CPU0_PE0_RX_DP<11>     C5 @S9S_MB_2U_LIB.S9S_MB_2U(SCH_1):P5E_CPU0_PE0_RX_DP(11)
  D8    GND     D8 @S9S_MB_2U_LIB.S9S_MB_2U(SCH_1):GND
  D7 P5E_CPU0_PE0_RX_DP<9>     D7 @S9S_MB_2U_LIB.S9S_MB_2U(SCH_1):P5E_CPU0_PE0_RX_DP(9)
  D6    GND     D6 @S9S_MB_2U_LIB.S9S_MB_2U(SCH_1):GND
  D5 P5E_CPU0_PE0_RX_DN<11>     D5 @S9S_MB_2U_LIB.S9S_MB_2U(SCH_1):P5E_CPU0_PE0_RX_DN(11)
  E8 P5E_CPU0_PE4_RX_DP<7>     E8 @S9S_MB_2U_LIB.S9S_MB_2U(SCH_1):P5E_CPU0_PE4_RX_DP(7)
  E7    GND     E7 @S9S_MB_2U_LIB.S9S_MB_2U(SCH_1):GND
  E6 P5E_CPU0_PE4_RX_DP<5>     E6 @S9S_MB_2U_LIB.S9S_MB_2U(SCH_1):P5E_CPU0_PE4_RX_DP(5)
  E5    GND     E5 @S9S_MB_2U_LIB.S9S_MB_2U(SCH_1):GND
  F8 P5E_CPU0_PE4_RX_DN<7>     F8 @S9S_MB_2U_LIB.S9S_MB_2U(SCH_1):P5E_CPU0_PE4_RX_DN(7)
  F7 P5E_CPU0_PE4_RX_DN<6>     F7 @S9S_MB_2U_LIB.S9S_MB_2U(SCH_1):P5E_CPU0_PE4_RX_DN(6)
  F6 P5E_CPU0_PE4_RX_DN<5>     F6 @S9S_MB_2U_LIB.S9S_MB_2U(SCH_1):P5E_CPU0_PE4_RX_DN(5)
  F5 P5E_CPU0_PE4_RX_DN<4>     F5 @S9S_MB_2U_LIB.S9S_MB_2U(SCH_1):P5E_CPU0_PE4_RX_DN(4)
  G8    GND     G8 @S9S_MB_2U_LIB.S9S_MB_2U(SCH_1):GND
  G7 P5E_CPU0_PE4_RX_DP<6>     G7 @S9S_MB_2U_LIB.S9S_MB_2U(SCH_1):P5E_CPU0_PE4_RX_DP(6)
  G6    GND     G6 @S9S_MB_2U_LIB.S9S_MB_2U(SCH_1):GND
  G5 P5E_CPU0_PE4_RX_DP<4>     G5 @S9S_MB_2U_LIB.S9S_MB_2U(SCH_1):P5E_CPU0_PE4_RX_DP(4)
  H8 P5E_CPU0_PE0_TX_C_DN<8>     H8 @S9S_MB_2U_LIB.S9S_MB_2U(SCH_1):P5E_CPU0_PE0_TX_C_DN(8)
  H7    GND     H7 @S9S_MB_2U_LIB.S9S_MB_2U(SCH_1):GND
  H6 P5E_CPU0_PE0_TX_C_DN<10>     H6 @S9S_MB_2U_LIB.S9S_MB_2U(SCH_1):P5E_CPU0_PE0_TX_C_DN(10)
  H5    GND     H5 @S9S_MB_2U_LIB.S9S_MB_2U(SCH_1):GND
  I8 P5E_CPU0_PE0_TX_C_DP<8>     I8 @S9S_MB_2U_LIB.S9S_MB_2U(SCH_1):P5E_CPU0_PE0_TX_C_DP(8)
  I7 P5E_CPU0_PE0_TX_C_DN<9>     I7 @S9S_MB_2U_LIB.S9S_MB_2U(SCH_1):P5E_CPU0_PE0_TX_C_DN(9)
  I6 P5E_CPU0_PE0_TX_C_DP<10>     I6 @S9S_MB_2U_LIB.S9S_MB_2U(SCH_1):P5E_CPU0_PE0_TX_C_DP(10)
  I5 P5E_CPU0_PE0_TX_C_DN<11>     I5 @S9S_MB_2U_LIB.S9S_MB_2U(SCH_1):P5E_CPU0_PE0_TX_C_DN(11)
  J8    GND     J8 @S9S_MB_2U_LIB.S9S_MB_2U(SCH_1):GND
  J7 P5E_CPU0_PE0_TX_C_DP<9>     J7 @S9S_MB_2U_LIB.S9S_MB_2U(SCH_1):P5E_CPU0_PE0_TX_C_DP(9)
  J6    GND     J6 @S9S_MB_2U_LIB.S9S_MB_2U(SCH_1):GND
  J5 P5E_CPU0_PE0_TX_C_DP<11>     J5 @S9S_MB_2U_LIB.S9S_MB_2U(SCH_1):P5E_CPU0_PE0_TX_C_DP(11)
  K8 P5E_CPU0_PE4_TX_C_DN<7>     K8 @S9S_MB_2U_LIB.S9S_MB_2U(SCH_1):P5E_CPU0_PE4_TX_C_DN(7)
  K7    GND     K7 @S9S_MB_2U_LIB.S9S_MB_2U(SCH_1):GND
  K6 P5E_CPU0_PE4_TX_C_DN<5>     K6 @S9S_MB_2U_LIB.S9S_MB_2U(SCH_1):P5E_CPU0_PE4_TX_C_DN(5)
  K5    GND     K5 @S9S_MB_2U_LIB.S9S_MB_2U(SCH_1):GND
  L8 P5E_CPU0_PE4_TX_C_DP<7>     L8 @S9S_MB_2U_LIB.S9S_MB_2U(SCH_1):P5E_CPU0_PE4_TX_C_DP(7)
  L7 P5E_CPU0_PE4_TX_C_DN<6>     L7 @S9S_MB_2U_LIB.S9S_MB_2U(SCH_1):P5E_CPU0_PE4_TX_C_DN(6)
  L6 P5E_CPU0_PE4_TX_C_DP<5>     L6 @S9S_MB_2U_LIB.S9S_MB_2U(SCH_1):P5E_CPU0_PE4_TX_C_DP(5)
  L5 P5E_CPU0_PE4_TX_C_DN<4>     L5 @S9S_MB_2U_LIB.S9S_MB_2U(SCH_1):P5E_CPU0_PE4_TX_C_DN(4)
  M5 P5E_CPU0_PE4_TX_C_DP<4>     M5 @S9S_MB_2U_LIB.S9S_MB_2U(SCH_1):P5E_CPU0_PE4_TX_C_DP(4)
  N5    GND     N5 @S9S_MB_2U_LIB.S9S_MB_2U(SCH_1):GND
  M6    GND     M6 @S9S_MB_2U_LIB.S9S_MB_2U(SCH_1):GND
  N6 NC_J108_N6     N6 @S9S_MB_2U_LIB.S9S_MB_2U(SCH_1):NC_J108_N6
  M7 P5E_CPU0_PE4_TX_C_DP<6>     M7 @S9S_MB_2U_LIB.S9S_MB_2U(SCH_1):P5E_CPU0_PE4_TX_C_DP(6)
  N7    GND     N7 @S9S_MB_2U_LIB.S9S_MB_2U(SCH_1):GND
  M8    GND     M8 @S9S_MB_2U_LIB.S9S_MB_2U(SCH_1):GND
  N8 PRSNT_CABLE_GPU_A3_N     N8 @S9S_MB_2U_LIB.S9S_MB_2U(SCH_1):PRSNT_CABLE_GPU_A3_N


DRAWING: @S9S_MB_2U_LIB.S9S_MB_2U(SCH_1):PAGE318 

CONN112_10137002101LF-CONN112_A  I16  J110
  A8    GND     A8 @S9S_MB_2U_LIB.S9S_MB_2U(SCH_1):GND
  A7 GPU_BASE_STBY_EN_BUF     A7 @S9S_MB_2U_LIB.S9S_MB_2U(SCH_1):GPU_BASE_STBY_EN_BUF
  A6    GND     A6 @S9S_MB_2U_LIB.S9S_MB_2U(SCH_1):GND
  A5 GPU_BASE_HMC_READY     A5 @S9S_MB_2U_LIB.S9S_MB_2U(SCH_1):GPU_BASE_HMC_READY
  B8 P5E_CPU1_PE3_RX_DN<8>     B8 @S9S_MB_2U_LIB.S9S_MB_2U(SCH_1):P5E_CPU1_PE3_RX_DN(8)
  B7    GND     B7 @S9S_MB_2U_LIB.S9S_MB_2U(SCH_1):GND
  B6 P5E_CPU1_PE3_RX_DN<10>     B6 @S9S_MB_2U_LIB.S9S_MB_2U(SCH_1):P5E_CPU1_PE3_RX_DN(10)
  B5    GND     B5 @S9S_MB_2U_LIB.S9S_MB_2U(SCH_1):GND
  C8 P5E_CPU1_PE3_RX_DP<8>     C8 @S9S_MB_2U_LIB.S9S_MB_2U(SCH_1):P5E_CPU1_PE3_RX_DP(8)
  C7 P5E_CPU1_PE3_RX_DN<9>     C7 @S9S_MB_2U_LIB.S9S_MB_2U(SCH_1):P5E_CPU1_PE3_RX_DN(9)
  C6 P5E_CPU1_PE3_RX_DP<10>     C6 @S9S_MB_2U_LIB.S9S_MB_2U(SCH_1):P5E_CPU1_PE3_RX_DP(10)
  C5 P5E_CPU1_PE3_RX_DN<11>     C5 @S9S_MB_2U_LIB.S9S_MB_2U(SCH_1):P5E_CPU1_PE3_RX_DN(11)
  D8    GND     D8 @S9S_MB_2U_LIB.S9S_MB_2U(SCH_1):GND
  D7 P5E_CPU1_PE3_RX_DP<9>     D7 @S9S_MB_2U_LIB.S9S_MB_2U(SCH_1):P5E_CPU1_PE3_RX_DP(9)
  D6    GND     D6 @S9S_MB_2U_LIB.S9S_MB_2U(SCH_1):GND
  D5 P5E_CPU1_PE3_RX_DP<11>     D5 @S9S_MB_2U_LIB.S9S_MB_2U(SCH_1):P5E_CPU1_PE3_RX_DP(11)
  E8 P5E_CPU1_PE2_RX_DP<8>     E8 @S9S_MB_2U_LIB.S9S_MB_2U(SCH_1):P5E_CPU1_PE2_RX_DP(8)
  E7    GND     E7 @S9S_MB_2U_LIB.S9S_MB_2U(SCH_1):GND
  E6 P5E_CPU1_PE2_RX_DP<10>     E6 @S9S_MB_2U_LIB.S9S_MB_2U(SCH_1):P5E_CPU1_PE2_RX_DP(10)
  E5    GND     E5 @S9S_MB_2U_LIB.S9S_MB_2U(SCH_1):GND
  F8 P5E_CPU1_PE2_RX_DN<8>     F8 @S9S_MB_2U_LIB.S9S_MB_2U(SCH_1):P5E_CPU1_PE2_RX_DN(8)
  F7 P5E_CPU1_PE2_RX_DP<9>     F7 @S9S_MB_2U_LIB.S9S_MB_2U(SCH_1):P5E_CPU1_PE2_RX_DP(9)
  F6 P5E_CPU1_PE2_RX_DN<10>     F6 @S9S_MB_2U_LIB.S9S_MB_2U(SCH_1):P5E_CPU1_PE2_RX_DN(10)
  F5 P5E_CPU1_PE2_RX_DP<11>     F5 @S9S_MB_2U_LIB.S9S_MB_2U(SCH_1):P5E_CPU1_PE2_RX_DP(11)
  G8    GND     G8 @S9S_MB_2U_LIB.S9S_MB_2U(SCH_1):GND
  G7 P5E_CPU1_PE2_RX_DN<9>     G7 @S9S_MB_2U_LIB.S9S_MB_2U(SCH_1):P5E_CPU1_PE2_RX_DN(9)
  G6    GND     G6 @S9S_MB_2U_LIB.S9S_MB_2U(SCH_1):GND
  G5 P5E_CPU1_PE2_RX_DN<11>     G5 @S9S_MB_2U_LIB.S9S_MB_2U(SCH_1):P5E_CPU1_PE2_RX_DN(11)
  H8 P5E_CPU1_PE3_TX_C_DN<8>     H8 @S9S_MB_2U_LIB.S9S_MB_2U(SCH_1):P5E_CPU1_PE3_TX_C_DN(8)
  H7    GND     H7 @S9S_MB_2U_LIB.S9S_MB_2U(SCH_1):GND
  H6 P5E_CPU1_PE3_TX_C_DN<10>     H6 @S9S_MB_2U_LIB.S9S_MB_2U(SCH_1):P5E_CPU1_PE3_TX_C_DN(10)
  H5    GND     H5 @S9S_MB_2U_LIB.S9S_MB_2U(SCH_1):GND
  I8 P5E_CPU1_PE3_TX_C_DP<8>     I8 @S9S_MB_2U_LIB.S9S_MB_2U(SCH_1):P5E_CPU1_PE3_TX_C_DP(8)
  I7 P5E_CPU1_PE3_TX_C_DN<9>     I7 @S9S_MB_2U_LIB.S9S_MB_2U(SCH_1):P5E_CPU1_PE3_TX_C_DN(9)
  I6 P5E_CPU1_PE3_TX_C_DP<10>     I6 @S9S_MB_2U_LIB.S9S_MB_2U(SCH_1):P5E_CPU1_PE3_TX_C_DP(10)
  I5 P5E_CPU1_PE3_TX_C_DN<11>     I5 @S9S_MB_2U_LIB.S9S_MB_2U(SCH_1):P5E_CPU1_PE3_TX_C_DN(11)
  J8    GND     J8 @S9S_MB_2U_LIB.S9S_MB_2U(SCH_1):GND
  J7 P5E_CPU1_PE3_TX_C_DP<9>     J7 @S9S_MB_2U_LIB.S9S_MB_2U(SCH_1):P5E_CPU1_PE3_TX_C_DP(9)
  J6    GND     J6 @S9S_MB_2U_LIB.S9S_MB_2U(SCH_1):GND
  J5 P5E_CPU1_PE3_TX_C_DP<11>     J5 @S9S_MB_2U_LIB.S9S_MB_2U(SCH_1):P5E_CPU1_PE3_TX_C_DP(11)
  K8 P5E_CPU1_PE2_TX_C_DP<8>     K8 @S9S_MB_2U_LIB.S9S_MB_2U(SCH_1):P5E_CPU1_PE2_TX_C_DP(8)
  K7    GND     K7 @S9S_MB_2U_LIB.S9S_MB_2U(SCH_1):GND
  K6 P5E_CPU1_PE2_TX_C_DP<10>     K6 @S9S_MB_2U_LIB.S9S_MB_2U(SCH_1):P5E_CPU1_PE2_TX_C_DP(10)
  K5    GND     K5 @S9S_MB_2U_LIB.S9S_MB_2U(SCH_1):GND
  L8 P5E_CPU1_PE2_TX_C_DN<8>     L8 @S9S_MB_2U_LIB.S9S_MB_2U(SCH_1):P5E_CPU1_PE2_TX_C_DN(8)
  L7 P5E_CPU1_PE2_TX_C_DP<9>     L7 @S9S_MB_2U_LIB.S9S_MB_2U(SCH_1):P5E_CPU1_PE2_TX_C_DP(9)
  L6 P5E_CPU1_PE2_TX_C_DN<10>     L6 @S9S_MB_2U_LIB.S9S_MB_2U(SCH_1):P5E_CPU1_PE2_TX_C_DN(10)
  L5 P5E_CPU1_PE2_TX_C_DP<11>     L5 @S9S_MB_2U_LIB.S9S_MB_2U(SCH_1):P5E_CPU1_PE2_TX_C_DP(11)
  M5 P5E_CPU1_PE2_TX_C_DN<11>     M5 @S9S_MB_2U_LIB.S9S_MB_2U(SCH_1):P5E_CPU1_PE2_TX_C_DN(11)
  N5    GND     N5 @S9S_MB_2U_LIB.S9S_MB_2U(SCH_1):GND
  M6    GND     M6 @S9S_MB_2U_LIB.S9S_MB_2U(SCH_1):GND
  N6 FM_SMB_2_ALERT_GPU_N     N6 @S9S_MB_2U_LIB.S9S_MB_2U(SCH_1):FM_SMB_2_ALERT_GPU_N
  M7 P5E_CPU1_PE2_TX_C_DN<9>     M7 @S9S_MB_2U_LIB.S9S_MB_2U(SCH_1):P5E_CPU1_PE2_TX_C_DN(9)
  N7    GND     N7 @S9S_MB_2U_LIB.S9S_MB_2U(SCH_1):GND
  M8    GND     M8 @S9S_MB_2U_LIB.S9S_MB_2U(SCH_1):GND
  N8 GPU_FPGA_EROT_RST_BUF_N     N8 @S9S_MB_2U_LIB.S9S_MB_2U(SCH_1):GPU_FPGA_EROT_RST_BUF_N

CONN112_10137002101LF-CONN112_A  I54  J110
  A4    GND     A4 @S9S_MB_2U_LIB.S9S_MB_2U(SCH_1):GND
  A3 GPU_HMC_PRSNT_N     A3 @S9S_MB_2U_LIB.S9S_MB_2U(SCH_1):GPU_HMC_PRSNT_N
  A2    GND     A2 @S9S_MB_2U_LIB.S9S_MB_2U(SCH_1):GND
  A1 GPU_FPGA_EROT_RECOV_BUF_N     A1 @S9S_MB_2U_LIB.S9S_MB_2U(SCH_1):GPU_FPGA_EROT_RECOV_BUF_N
  B4 P5E_CPU1_PE3_RX_DP<12>     B4 @S9S_MB_2U_LIB.S9S_MB_2U(SCH_1):P5E_CPU1_PE3_RX_DP(12)
  B3    GND     B3 @S9S_MB_2U_LIB.S9S_MB_2U(SCH_1):GND
  B2 P5E_CPU1_PE3_RX_DP<14>     B2 @S9S_MB_2U_LIB.S9S_MB_2U(SCH_1):P5E_CPU1_PE3_RX_DP(14)
  B1    GND     B1 @S9S_MB_2U_LIB.S9S_MB_2U(SCH_1):GND
  C4 P5E_CPU1_PE3_RX_DN<12>     C4 @S9S_MB_2U_LIB.S9S_MB_2U(SCH_1):P5E_CPU1_PE3_RX_DN(12)
  C3 P5E_CPU1_PE3_RX_DP<13>     C3 @S9S_MB_2U_LIB.S9S_MB_2U(SCH_1):P5E_CPU1_PE3_RX_DP(13)
  C2 P5E_CPU1_PE3_RX_DN<14>     C2 @S9S_MB_2U_LIB.S9S_MB_2U(SCH_1):P5E_CPU1_PE3_RX_DN(14)
  C1 P5E_CPU1_PE3_RX_DP<15>     C1 @S9S_MB_2U_LIB.S9S_MB_2U(SCH_1):P5E_CPU1_PE3_RX_DP(15)
  D4    GND     D4 @S9S_MB_2U_LIB.S9S_MB_2U(SCH_1):GND
  D3 P5E_CPU1_PE3_RX_DN<13>     D3 @S9S_MB_2U_LIB.S9S_MB_2U(SCH_1):P5E_CPU1_PE3_RX_DN(13)
  D2    GND     D2 @S9S_MB_2U_LIB.S9S_MB_2U(SCH_1):GND
  D1 P5E_CPU1_PE3_RX_DN<15>     D1 @S9S_MB_2U_LIB.S9S_MB_2U(SCH_1):P5E_CPU1_PE3_RX_DN(15)
  E4 P5E_CPU1_PE2_RX_DP<12>     E4 @S9S_MB_2U_LIB.S9S_MB_2U(SCH_1):P5E_CPU1_PE2_RX_DP(12)
  E3    GND     E3 @S9S_MB_2U_LIB.S9S_MB_2U(SCH_1):GND
  E2 P5E_CPU1_PE2_RX_DP<14>     E2 @S9S_MB_2U_LIB.S9S_MB_2U(SCH_1):P5E_CPU1_PE2_RX_DP(14)
  E1    GND     E1 @S9S_MB_2U_LIB.S9S_MB_2U(SCH_1):GND
  F4 P5E_CPU1_PE2_RX_DN<12>     F4 @S9S_MB_2U_LIB.S9S_MB_2U(SCH_1):P5E_CPU1_PE2_RX_DN(12)
  F3 P5E_CPU1_PE2_RX_DP<13>     F3 @S9S_MB_2U_LIB.S9S_MB_2U(SCH_1):P5E_CPU1_PE2_RX_DP(13)
  F2 P5E_CPU1_PE2_RX_DN<14>     F2 @S9S_MB_2U_LIB.S9S_MB_2U(SCH_1):P5E_CPU1_PE2_RX_DN(14)
  F1 P5E_CPU1_PE2_RX_DP<15>     F1 @S9S_MB_2U_LIB.S9S_MB_2U(SCH_1):P5E_CPU1_PE2_RX_DP(15)
  G4    GND     G4 @S9S_MB_2U_LIB.S9S_MB_2U(SCH_1):GND
  G3 P5E_CPU1_PE2_RX_DN<13>     G3 @S9S_MB_2U_LIB.S9S_MB_2U(SCH_1):P5E_CPU1_PE2_RX_DN(13)
  G2    GND     G2 @S9S_MB_2U_LIB.S9S_MB_2U(SCH_1):GND
  G1 P5E_CPU1_PE2_RX_DN<15>     G1 @S9S_MB_2U_LIB.S9S_MB_2U(SCH_1):P5E_CPU1_PE2_RX_DN(15)
  H4 P5E_CPU1_PE3_TX_C_DN<12>     H4 @S9S_MB_2U_LIB.S9S_MB_2U(SCH_1):P5E_CPU1_PE3_TX_C_DN(12)
  H3    GND     H3 @S9S_MB_2U_LIB.S9S_MB_2U(SCH_1):GND
  H2 P5E_CPU1_PE3_TX_C_DN<14>     H2 @S9S_MB_2U_LIB.S9S_MB_2U(SCH_1):P5E_CPU1_PE3_TX_C_DN(14)
  H1    GND     H1 @S9S_MB_2U_LIB.S9S_MB_2U(SCH_1):GND
  I4 P5E_CPU1_PE3_TX_C_DP<12>     I4 @S9S_MB_2U_LIB.S9S_MB_2U(SCH_1):P5E_CPU1_PE3_TX_C_DP(12)
  I3 P5E_CPU1_PE3_TX_C_DN<13>     I3 @S9S_MB_2U_LIB.S9S_MB_2U(SCH_1):P5E_CPU1_PE3_TX_C_DN(13)
  I2 P5E_CPU1_PE3_TX_C_DP<14>     I2 @S9S_MB_2U_LIB.S9S_MB_2U(SCH_1):P5E_CPU1_PE3_TX_C_DP(14)
  I1 P5E_CPU1_PE3_TX_C_DN<15>     I1 @S9S_MB_2U_LIB.S9S_MB_2U(SCH_1):P5E_CPU1_PE3_TX_C_DN(15)
  J4    GND     J4 @S9S_MB_2U_LIB.S9S_MB_2U(SCH_1):GND
  J3 P5E_CPU1_PE3_TX_C_DP<13>     J3 @S9S_MB_2U_LIB.S9S_MB_2U(SCH_1):P5E_CPU1_PE3_TX_C_DP(13)
  J2    GND     J2 @S9S_MB_2U_LIB.S9S_MB_2U(SCH_1):GND
  J1 P5E_CPU1_PE3_TX_C_DP<15>     J1 @S9S_MB_2U_LIB.S9S_MB_2U(SCH_1):P5E_CPU1_PE3_TX_C_DP(15)
  K4 P5E_CPU1_PE2_TX_C_DP<12>     K4 @S9S_MB_2U_LIB.S9S_MB_2U(SCH_1):P5E_CPU1_PE2_TX_C_DP(12)
  K3    GND     K3 @S9S_MB_2U_LIB.S9S_MB_2U(SCH_1):GND
  K2 P5E_CPU1_PE2_TX_C_DP<14>     K2 @S9S_MB_2U_LIB.S9S_MB_2U(SCH_1):P5E_CPU1_PE2_TX_C_DP(14)
  K1    GND     K1 @S9S_MB_2U_LIB.S9S_MB_2U(SCH_1):GND
  L4 P5E_CPU1_PE2_TX_C_DN<12>     L4 @S9S_MB_2U_LIB.S9S_MB_2U(SCH_1):P5E_CPU1_PE2_TX_C_DN(12)
  L3 P5E_CPU1_PE2_TX_C_DP<13>     L3 @S9S_MB_2U_LIB.S9S_MB_2U(SCH_1):P5E_CPU1_PE2_TX_C_DP(13)
  L2 P5E_CPU1_PE2_TX_C_DN<14>     L2 @S9S_MB_2U_LIB.S9S_MB_2U(SCH_1):P5E_CPU1_PE2_TX_C_DN(14)
  L1 P5E_CPU1_PE2_TX_C_DP<15>     L1 @S9S_MB_2U_LIB.S9S_MB_2U(SCH_1):P5E_CPU1_PE2_TX_C_DP(15)
  M1 P5E_CPU1_PE2_TX_C_DN<15>     M1 @S9S_MB_2U_LIB.S9S_MB_2U(SCH_1):P5E_CPU1_PE2_TX_C_DN(15)
  N1    GND     N1 @S9S_MB_2U_LIB.S9S_MB_2U(SCH_1):GND
  M2    GND     M2 @S9S_MB_2U_LIB.S9S_MB_2U(SCH_1):GND
  N2 GPU_FPGA_BOOT_EN_BUF     N2 @S9S_MB_2U_LIB.S9S_MB_2U(SCH_1):GPU_FPGA_BOOT_EN_BUF
  M3 P5E_CPU1_PE2_TX_C_DN<13>     M3 @S9S_MB_2U_LIB.S9S_MB_2U(SCH_1):P5E_CPU1_PE2_TX_C_DN(13)
  N3    GND     N3 @S9S_MB_2U_LIB.S9S_MB_2U(SCH_1):GND
  M4    GND     M4 @S9S_MB_2U_LIB.S9S_MB_2U(SCH_1):GND
  N4 FM_SMB_1_ALERT_GPU_N     N4 @S9S_MB_2U_LIB.S9S_MB_2U(SCH_1):FM_SMB_1_ALERT_GPU_N


DRAWING: @S9S_MB_2U_LIB.S9S_MB_2U(SCH_1):PAGE319 

CONN112_10137002101LF-CONN112_A  I53  J109
  A4    GND     A4 @S9S_MB_2U_LIB.S9S_MB_2U(SCH_1):GND
  A3 BIC_MONITER     A3 @S9S_MB_2U_LIB.S9S_MB_2U(SCH_1):BIC_MONITER
  A2    GND     A2 @S9S_MB_2U_LIB.S9S_MB_2U(SCH_1):GND
  A1 BMC_MONITER_BUF     A1 @S9S_MB_2U_LIB.S9S_MB_2U(SCH_1):BMC_MONITER_BUF
  B4 P5E_CPU1_PE3_RX_DP<4>     B4 @S9S_MB_2U_LIB.S9S_MB_2U(SCH_1):P5E_CPU1_PE3_RX_DP(4)
  B3    GND     B3 @S9S_MB_2U_LIB.S9S_MB_2U(SCH_1):GND
  B2 P5E_CPU1_PE3_RX_DP<6>     B2 @S9S_MB_2U_LIB.S9S_MB_2U(SCH_1):P5E_CPU1_PE3_RX_DP(6)
  B1    GND     B1 @S9S_MB_2U_LIB.S9S_MB_2U(SCH_1):GND
  C4 P5E_CPU1_PE3_RX_DN<4>     C4 @S9S_MB_2U_LIB.S9S_MB_2U(SCH_1):P5E_CPU1_PE3_RX_DN(4)
  C3 P5E_CPU1_PE3_RX_DP<5>     C3 @S9S_MB_2U_LIB.S9S_MB_2U(SCH_1):P5E_CPU1_PE3_RX_DP(5)
  C2 P5E_CPU1_PE3_RX_DN<6>     C2 @S9S_MB_2U_LIB.S9S_MB_2U(SCH_1):P5E_CPU1_PE3_RX_DN(6)
  C1 P5E_CPU1_PE3_RX_DP<7>     C1 @S9S_MB_2U_LIB.S9S_MB_2U(SCH_1):P5E_CPU1_PE3_RX_DP(7)
  D4    GND     D4 @S9S_MB_2U_LIB.S9S_MB_2U(SCH_1):GND
  D3 P5E_CPU1_PE3_RX_DN<5>     D3 @S9S_MB_2U_LIB.S9S_MB_2U(SCH_1):P5E_CPU1_PE3_RX_DN(5)
  D2    GND     D2 @S9S_MB_2U_LIB.S9S_MB_2U(SCH_1):GND
  D1 P5E_CPU1_PE3_RX_DN<7>     D1 @S9S_MB_2U_LIB.S9S_MB_2U(SCH_1):P5E_CPU1_PE3_RX_DN(7)
  E4 P5E_CPU1_PE2_RX_DP<4>     E4 @S9S_MB_2U_LIB.S9S_MB_2U(SCH_1):P5E_CPU1_PE2_RX_DP(4)
  E3    GND     E3 @S9S_MB_2U_LIB.S9S_MB_2U(SCH_1):GND
  E2 P5E_CPU1_PE2_RX_DP<6>     E2 @S9S_MB_2U_LIB.S9S_MB_2U(SCH_1):P5E_CPU1_PE2_RX_DP(6)
  E1    GND     E1 @S9S_MB_2U_LIB.S9S_MB_2U(SCH_1):GND
  F4 P5E_CPU1_PE2_RX_DN<4>     F4 @S9S_MB_2U_LIB.S9S_MB_2U(SCH_1):P5E_CPU1_PE2_RX_DN(4)
  F3 P5E_CPU1_PE2_RX_DP<5>     F3 @S9S_MB_2U_LIB.S9S_MB_2U(SCH_1):P5E_CPU1_PE2_RX_DP(5)
  F2 P5E_CPU1_PE2_RX_DN<6>     F2 @S9S_MB_2U_LIB.S9S_MB_2U(SCH_1):P5E_CPU1_PE2_RX_DN(6)
  F1 P5E_CPU1_PE2_RX_DP<7>     F1 @S9S_MB_2U_LIB.S9S_MB_2U(SCH_1):P5E_CPU1_PE2_RX_DP(7)
  G4    GND     G4 @S9S_MB_2U_LIB.S9S_MB_2U(SCH_1):GND
  G3 P5E_CPU1_PE2_RX_DN<5>     G3 @S9S_MB_2U_LIB.S9S_MB_2U(SCH_1):P5E_CPU1_PE2_RX_DN(5)
  G2    GND     G2 @S9S_MB_2U_LIB.S9S_MB_2U(SCH_1):GND
  G1 P5E_CPU1_PE2_RX_DN<7>     G1 @S9S_MB_2U_LIB.S9S_MB_2U(SCH_1):P5E_CPU1_PE2_RX_DN(7)
  H4 P5E_CPU1_PE3_TX_C_DN<4>     H4 @S9S_MB_2U_LIB.S9S_MB_2U(SCH_1):P5E_CPU1_PE3_TX_C_DN(4)
  H3    GND     H3 @S9S_MB_2U_LIB.S9S_MB_2U(SCH_1):GND
  H2 P5E_CPU1_PE3_TX_C_DN<6>     H2 @S9S_MB_2U_LIB.S9S_MB_2U(SCH_1):P5E_CPU1_PE3_TX_C_DN(6)
  H1    GND     H1 @S9S_MB_2U_LIB.S9S_MB_2U(SCH_1):GND
  I4 P5E_CPU1_PE3_TX_C_DP<4>     I4 @S9S_MB_2U_LIB.S9S_MB_2U(SCH_1):P5E_CPU1_PE3_TX_C_DP(4)
  I3 P5E_CPU1_PE3_TX_C_DN<5>     I3 @S9S_MB_2U_LIB.S9S_MB_2U(SCH_1):P5E_CPU1_PE3_TX_C_DN(5)
  I2 P5E_CPU1_PE3_TX_C_DP<6>     I2 @S9S_MB_2U_LIB.S9S_MB_2U(SCH_1):P5E_CPU1_PE3_TX_C_DP(6)
  I1 P5E_CPU1_PE3_TX_C_DN<7>     I1 @S9S_MB_2U_LIB.S9S_MB_2U(SCH_1):P5E_CPU1_PE3_TX_C_DN(7)
  J4    GND     J4 @S9S_MB_2U_LIB.S9S_MB_2U(SCH_1):GND
  J3 P5E_CPU1_PE3_TX_C_DP<5>     J3 @S9S_MB_2U_LIB.S9S_MB_2U(SCH_1):P5E_CPU1_PE3_TX_C_DP(5)
  J2    GND     J2 @S9S_MB_2U_LIB.S9S_MB_2U(SCH_1):GND
  J1 P5E_CPU1_PE3_TX_C_DP<7>     J1 @S9S_MB_2U_LIB.S9S_MB_2U(SCH_1):P5E_CPU1_PE3_TX_C_DP(7)
  K4 P5E_CPU1_PE2_TX_C_DP<4>     K4 @S9S_MB_2U_LIB.S9S_MB_2U(SCH_1):P5E_CPU1_PE2_TX_C_DP(4)
  K3    GND     K3 @S9S_MB_2U_LIB.S9S_MB_2U(SCH_1):GND
  K2 P5E_CPU1_PE2_TX_C_DP<6>     K2 @S9S_MB_2U_LIB.S9S_MB_2U(SCH_1):P5E_CPU1_PE2_TX_C_DP(6)
  K1    GND     K1 @S9S_MB_2U_LIB.S9S_MB_2U(SCH_1):GND
  L4 P5E_CPU1_PE2_TX_C_DN<4>     L4 @S9S_MB_2U_LIB.S9S_MB_2U(SCH_1):P5E_CPU1_PE2_TX_C_DN(4)
  L3 P5E_CPU1_PE2_TX_C_DP<5>     L3 @S9S_MB_2U_LIB.S9S_MB_2U(SCH_1):P5E_CPU1_PE2_TX_C_DP(5)
  L2 P5E_CPU1_PE2_TX_C_DN<6>     L2 @S9S_MB_2U_LIB.S9S_MB_2U(SCH_1):P5E_CPU1_PE2_TX_C_DN(6)
  L1 P5E_CPU1_PE2_TX_C_DP<7>     L1 @S9S_MB_2U_LIB.S9S_MB_2U(SCH_1):P5E_CPU1_PE2_TX_C_DP(7)
  M1 P5E_CPU1_PE2_TX_C_DN<7>     M1 @S9S_MB_2U_LIB.S9S_MB_2U(SCH_1):P5E_CPU1_PE2_TX_C_DN(7)
  N1    GND     N1 @S9S_MB_2U_LIB.S9S_MB_2U(SCH_1):GND
  M2    GND     M2 @S9S_MB_2U_LIB.S9S_MB_2U(SCH_1):GND
  N2 GPU_FPGA_EROT_FATALERR_N     N2 @S9S_MB_2U_LIB.S9S_MB_2U(SCH_1):GPU_FPGA_EROT_FATALERR_N
  M3 P5E_CPU1_PE2_TX_C_DN<5>     M3 @S9S_MB_2U_LIB.S9S_MB_2U(SCH_1):P5E_CPU1_PE2_TX_C_DN(5)
  N3    GND     N3 @S9S_MB_2U_LIB.S9S_MB_2U(SCH_1):GND
  M4    GND     M4 @S9S_MB_2U_LIB.S9S_MB_2U(SCH_1):GND
  N4 GPU_3V3IO_RSVD0_FFU     N4 @S9S_MB_2U_LIB.S9S_MB_2U(SCH_1):GPU_3V3IO_RSVD0_FFU

CONN112_10137002101LF-CONN112_A  I76  J109
  A8    GND     A8 @S9S_MB_2U_LIB.S9S_MB_2U(SCH_1):GND
  A7 SMB_BMC_SWB_BUF_SDA     A7 @S9S_MB_2U_LIB.S9S_MB_2U(SCH_1):SMB_BMC_SWB_BUF_SDA
  A6    GND     A6 @S9S_MB_2U_LIB.S9S_MB_2U(SCH_1):GND
  A5 SMB_BMC_SWB_BUF_SCL     A5 @S9S_MB_2U_LIB.S9S_MB_2U(SCH_1):SMB_BMC_SWB_BUF_SCL
  B8 P5E_CPU1_PE3_RX_DP<0>     B8 @S9S_MB_2U_LIB.S9S_MB_2U(SCH_1):P5E_CPU1_PE3_RX_DP(0)
  B7    GND     B7 @S9S_MB_2U_LIB.S9S_MB_2U(SCH_1):GND
  B6 P5E_CPU1_PE3_RX_DN<2>     B6 @S9S_MB_2U_LIB.S9S_MB_2U(SCH_1):P5E_CPU1_PE3_RX_DN(2)
  B5    GND     B5 @S9S_MB_2U_LIB.S9S_MB_2U(SCH_1):GND
  C8 P5E_CPU1_PE3_RX_DN<0>     C8 @S9S_MB_2U_LIB.S9S_MB_2U(SCH_1):P5E_CPU1_PE3_RX_DN(0)
  C7 P5E_CPU1_PE3_RX_DN<1>     C7 @S9S_MB_2U_LIB.S9S_MB_2U(SCH_1):P5E_CPU1_PE3_RX_DN(1)
  C6 P5E_CPU1_PE3_RX_DP<2>     C6 @S9S_MB_2U_LIB.S9S_MB_2U(SCH_1):P5E_CPU1_PE3_RX_DP(2)
  C5 P5E_CPU1_PE3_RX_DN<3>     C5 @S9S_MB_2U_LIB.S9S_MB_2U(SCH_1):P5E_CPU1_PE3_RX_DN(3)
  D8    GND     D8 @S9S_MB_2U_LIB.S9S_MB_2U(SCH_1):GND
  D7 P5E_CPU1_PE3_RX_DP<1>     D7 @S9S_MB_2U_LIB.S9S_MB_2U(SCH_1):P5E_CPU1_PE3_RX_DP(1)
  D6    GND     D6 @S9S_MB_2U_LIB.S9S_MB_2U(SCH_1):GND
  D5 P5E_CPU1_PE3_RX_DP<3>     D5 @S9S_MB_2U_LIB.S9S_MB_2U(SCH_1):P5E_CPU1_PE3_RX_DP(3)
  E8 P5E_CPU1_PE2_RX_DP<0>     E8 @S9S_MB_2U_LIB.S9S_MB_2U(SCH_1):P5E_CPU1_PE2_RX_DP(0)
  E7    GND     E7 @S9S_MB_2U_LIB.S9S_MB_2U(SCH_1):GND
  E6 P5E_CPU1_PE2_RX_DP<2>     E6 @S9S_MB_2U_LIB.S9S_MB_2U(SCH_1):P5E_CPU1_PE2_RX_DP(2)
  E5    GND     E5 @S9S_MB_2U_LIB.S9S_MB_2U(SCH_1):GND
  F8 P5E_CPU1_PE2_RX_DN<0>     F8 @S9S_MB_2U_LIB.S9S_MB_2U(SCH_1):P5E_CPU1_PE2_RX_DN(0)
  F7 P5E_CPU1_PE2_RX_DP<1>     F7 @S9S_MB_2U_LIB.S9S_MB_2U(SCH_1):P5E_CPU1_PE2_RX_DP(1)
  F6 P5E_CPU1_PE2_RX_DN<2>     F6 @S9S_MB_2U_LIB.S9S_MB_2U(SCH_1):P5E_CPU1_PE2_RX_DN(2)
  F5 P5E_CPU1_PE2_RX_DP<3>     F5 @S9S_MB_2U_LIB.S9S_MB_2U(SCH_1):P5E_CPU1_PE2_RX_DP(3)
  G8    GND     G8 @S9S_MB_2U_LIB.S9S_MB_2U(SCH_1):GND
  G7 P5E_CPU1_PE2_RX_DN<1>     G7 @S9S_MB_2U_LIB.S9S_MB_2U(SCH_1):P5E_CPU1_PE2_RX_DN(1)
  G6    GND     G6 @S9S_MB_2U_LIB.S9S_MB_2U(SCH_1):GND
  G5 P5E_CPU1_PE2_RX_DN<3>     G5 @S9S_MB_2U_LIB.S9S_MB_2U(SCH_1):P5E_CPU1_PE2_RX_DN(3)
  H8 P5E_CPU1_PE3_TX_C_DP<0>     H8 @S9S_MB_2U_LIB.S9S_MB_2U(SCH_1):P5E_CPU1_PE3_TX_C_DP(0)
  H7    GND     H7 @S9S_MB_2U_LIB.S9S_MB_2U(SCH_1):GND
  H6 P5E_CPU1_PE3_TX_C_DN<2>     H6 @S9S_MB_2U_LIB.S9S_MB_2U(SCH_1):P5E_CPU1_PE3_TX_C_DN(2)
  H5    GND     H5 @S9S_MB_2U_LIB.S9S_MB_2U(SCH_1):GND
  I8 P5E_CPU1_PE3_TX_C_DN<0>     I8 @S9S_MB_2U_LIB.S9S_MB_2U(SCH_1):P5E_CPU1_PE3_TX_C_DN(0)
  I7 P5E_CPU1_PE3_TX_C_DN<1>     I7 @S9S_MB_2U_LIB.S9S_MB_2U(SCH_1):P5E_CPU1_PE3_TX_C_DN(1)
  I6 P5E_CPU1_PE3_TX_C_DP<2>     I6 @S9S_MB_2U_LIB.S9S_MB_2U(SCH_1):P5E_CPU1_PE3_TX_C_DP(2)
  I5 P5E_CPU1_PE3_TX_C_DN<3>     I5 @S9S_MB_2U_LIB.S9S_MB_2U(SCH_1):P5E_CPU1_PE3_TX_C_DN(3)
  J8    GND     J8 @S9S_MB_2U_LIB.S9S_MB_2U(SCH_1):GND
  J7 P5E_CPU1_PE3_TX_C_DP<1>     J7 @S9S_MB_2U_LIB.S9S_MB_2U(SCH_1):P5E_CPU1_PE3_TX_C_DP(1)
  J6    GND     J6 @S9S_MB_2U_LIB.S9S_MB_2U(SCH_1):GND
  J5 P5E_CPU1_PE3_TX_C_DP<3>     J5 @S9S_MB_2U_LIB.S9S_MB_2U(SCH_1):P5E_CPU1_PE3_TX_C_DP(3)
  K8 P5E_CPU1_PE2_TX_C_DP<0>     K8 @S9S_MB_2U_LIB.S9S_MB_2U(SCH_1):P5E_CPU1_PE2_TX_C_DP(0)
  K7    GND     K7 @S9S_MB_2U_LIB.S9S_MB_2U(SCH_1):GND
  K6 P5E_CPU1_PE2_TX_C_DP<2>     K6 @S9S_MB_2U_LIB.S9S_MB_2U(SCH_1):P5E_CPU1_PE2_TX_C_DP(2)
  K5    GND     K5 @S9S_MB_2U_LIB.S9S_MB_2U(SCH_1):GND
  L8 P5E_CPU1_PE2_TX_C_DN<0>     L8 @S9S_MB_2U_LIB.S9S_MB_2U(SCH_1):P5E_CPU1_PE2_TX_C_DN(0)
  L7 P5E_CPU1_PE2_TX_C_DP<1>     L7 @S9S_MB_2U_LIB.S9S_MB_2U(SCH_1):P5E_CPU1_PE2_TX_C_DP(1)
  L6 P5E_CPU1_PE2_TX_C_DN<2>     L6 @S9S_MB_2U_LIB.S9S_MB_2U(SCH_1):P5E_CPU1_PE2_TX_C_DN(2)
  L5 P5E_CPU1_PE2_TX_C_DP<3>     L5 @S9S_MB_2U_LIB.S9S_MB_2U(SCH_1):P5E_CPU1_PE2_TX_C_DP(3)
  M5 P5E_CPU1_PE2_TX_C_DN<3>     M5 @S9S_MB_2U_LIB.S9S_MB_2U(SCH_1):P5E_CPU1_PE2_TX_C_DN(3)
  N5    GND     N5 @S9S_MB_2U_LIB.S9S_MB_2U(SCH_1):GND
  M6    GND     M6 @S9S_MB_2U_LIB.S9S_MB_2U(SCH_1):GND
  N6 GPU_3V3IO_RSVD1_FFU     N6 @S9S_MB_2U_LIB.S9S_MB_2U(SCH_1):GPU_3V3IO_RSVD1_FFU
  M7 P5E_CPU1_PE2_TX_C_DN<1>     M7 @S9S_MB_2U_LIB.S9S_MB_2U(SCH_1):P5E_CPU1_PE2_TX_C_DN(1)
  N7    GND     N7 @S9S_MB_2U_LIB.S9S_MB_2U(SCH_1):GND
  M8    GND     M8 @S9S_MB_2U_LIB.S9S_MB_2U(SCH_1):GND
  N8 PRSNT_CABLE_GPU_B3_N     N8 @S9S_MB_2U_LIB.S9S_MB_2U(SCH_1):PRSNT_CABLE_GPU_B3_N


DRAWING: @S9S_MB_2U_LIB.S9S_MB_2U(SCH_1):PAGE313 

LCMXO3LF9400C5BG484C-LCMXO3LF-A  I1  U249
 W20 FM_PCH_SPKR_R  PR30B @S9S_MB_2U_LIB.S9S_MB_2U(SCH_1):FM_PCH_SPKR_R
 V18 FM_BMC_CPU_FBRK_OUT_R_N  PR30A @S9S_MB_2U_LIB.S9S_MB_2U(SCH_1):FM_BMC_CPU_FBRK_OUT_R_N
 V19 CLK_GEN2_GPU_FPGA_OE_R_N  PR29D @S9S_MB_2U_LIB.S9S_MB_2U(SCH_1):CLK_GEN2_GPU_FPGA_OE_R_N
 Y21 GPU_FPGA_RST_N  PR29B @S9S_MB_2U_LIB.S9S_MB_2U(SCH_1):GPU_FPGA_RST_N
 U17 FM_JTAG_TCK_MUX_SEL_R  PR29C @S9S_MB_2U_LIB.S9S_MB_2U(SCH_1):FM_JTAG_TCK_MUX_SEL_R
AA22 LED_HDD_ACTIVITY_B_PLD_N  PR29A @S9S_MB_2U_LIB.S9S_MB_2U(SCH_1):LED_HDD_ACTIVITY_B_PLD_N
 W22 PWRGD_FAIL_CPU0_AB_R  PR25B @S9S_MB_2U_LIB.S9S_MB_2U(SCH_1):PWRGD_FAIL_CPU0_AB_R
 V22 FM_PS_EN_PLD_R  PR25A @S9S_MB_2U_LIB.S9S_MB_2U(SCH_1):FM_PS_EN_PLD_R
 R21 FM_CPU1_PKGID0  PR20B @S9S_MB_2U_LIB.S9S_MB_2U(SCH_1):FM_CPU1_PKGID0
 R22 FM_CPU0_PKGID2  PR20A @S9S_MB_2U_LIB.S9S_MB_2U(SCH_1):FM_CPU0_PKGID2
 P21 FM_CPU1_PROC_ID1  PR19B @S9S_MB_2U_LIB.S9S_MB_2U(SCH_1):FM_CPU1_PROC_ID1
 N22 FM_CPU1_PROC_ID0  PR19A @S9S_MB_2U_LIB.S9S_MB_2U(SCH_1):FM_CPU1_PROC_ID0
 M21 SMB_2_PLD_3V3AUX_SDA_R1 PR17B||PCLKC1_0 @S9S_MB_2U_LIB.S9S_MB_2U(SCH_1):SMB_2_PLD_3V3AUX_SDA_R1
 M22 SMB_2_PLD_3V3AUX_SCL_R1 PR17A||PCLKT1_0 @S9S_MB_2U_LIB.S9S_MB_2U(SCH_1):SMB_2_PLD_3V3AUX_SCL_R1
 L21 FM_THERMAL_ALERT_R_N  PR16B @S9S_MB_2U_LIB.S9S_MB_2U(SCH_1):FM_THERMAL_ALERT_R_N
 K22 FM_SOL_UART_CH_SEL  PR16A @S9S_MB_2U_LIB.S9S_MB_2U(SCH_1):FM_SOL_UART_CH_SEL
 L16 NC_FPGA_PR14B  PR14B @S9S_MB_2U_LIB.S9S_MB_2U(SCH_1):NC_FPGA_PR14B
 L17 NC_FPGA_PR14A  PR14A @S9S_MB_2U_LIB.S9S_MB_2U(SCH_1):NC_FPGA_PR14A
 H21 PWRGD_PVCCFA_EHV_CPU1   PR7B @S9S_MB_2U_LIB.S9S_MB_2U(SCH_1):PWRGD_PVCCFA_EHV_CPU1
 H22 PWRGD_PVCCFA_EHV_CPU0   PR7A @S9S_MB_2U_LIB.S9S_MB_2U(SCH_1):PWRGD_PVCCFA_EHV_CPU0
 D21 FM_PVCCFA_EHV_FIVRA_CPU1_R_EN PR3B||R_GPLLC_IN @S9S_MB_2U_LIB.S9S_MB_2U(SCH_1):FM_PVCCFA_EHV_FIVRA_CPU1_R_EN
 D22 FM_PVCCFA_EHV_FIVRA_CPU0_R_EN PR3A||R_GPLLT_IN @S9S_MB_2U_LIB.S9S_MB_2U(SCH_1):FM_PVCCFA_EHV_FIVRA_CPU0_R_EN
 C22 FM_PVCCD_HV_CPU1_EN PR2B||R_GPLLC_FB @S9S_MB_2U_LIB.S9S_MB_2U(SCH_1):FM_PVCCD_HV_CPU1_EN
 C21 FM_PVCCD_HV_CPU0_EN PR2A||R_GPLLT_FB @S9S_MB_2U_LIB.S9S_MB_2U(SCH_1):FM_PVCCD_HV_CPU0_EN
 F17 FM_PVCCFA_EHV_CPU0_R_EN   PR2C @S9S_MB_2U_LIB.S9S_MB_2U(SCH_1):FM_PVCCFA_EHV_CPU0_R_EN
 G16 FM_PVCCFA_EHV_CPU1_R_EN   PR2D @S9S_MB_2U_LIB.S9S_MB_2U(SCH_1):FM_PVCCFA_EHV_CPU1_R_EN
 D19 FM_PVCCINFAON_CPU0_R_EN   PR3C @S9S_MB_2U_LIB.S9S_MB_2U(SCH_1):FM_PVCCINFAON_CPU0_R_EN
 D20 FM_PVCCINFAON_CPU1_R_EN   PR3D @S9S_MB_2U_LIB.S9S_MB_2U(SCH_1):FM_PVCCINFAON_CPU1_R_EN
 E19 FM_PVCCIN_CPU0_R_EN   PR4C @S9S_MB_2U_LIB.S9S_MB_2U(SCH_1):FM_PVCCIN_CPU0_R_EN
 E20 FM_PVCCIN_CPU1_R_EN   PR4D @S9S_MB_2U_LIB.S9S_MB_2U(SCH_1):FM_PVCCIN_CPU1_R_EN
 E22 FM_PVNN_MAIN_CPU0_EN   PR4A @S9S_MB_2U_LIB.S9S_MB_2U(SCH_1):FM_PVNN_MAIN_CPU0_EN
 E21 FM_PVNN_MAIN_CPU1_EN   PR4B @S9S_MB_2U_LIB.S9S_MB_2U(SCH_1):FM_PVNN_MAIN_CPU1_EN
 F22 FM_PVPP_HBM_CPU1_EN   PR5A @S9S_MB_2U_LIB.S9S_MB_2U(SCH_1):FM_PVPP_HBM_CPU1_EN
 G22 FM_PVPP_HBM_CPU0_EN   PR5B @S9S_MB_2U_LIB.S9S_MB_2U(SCH_1):FM_PVPP_HBM_CPU0_EN
 F18 FM_AUX_SW_EN   PR5C @S9S_MB_2U_LIB.S9S_MB_2U(SCH_1):FM_AUX_SW_EN
 F19 FM_PCH_P1V8_AUX_EN   PR5D @S9S_MB_2U_LIB.S9S_MB_2U(SCH_1):FM_PCH_P1V8_AUX_EN
 G21 FM_P5V_EN   PR6A @S9S_MB_2U_LIB.S9S_MB_2U(SCH_1):FM_P5V_EN
 G20 FM_P1V05_PCH_AUX_EN   PR6B @S9S_MB_2U_LIB.S9S_MB_2U(SCH_1):FM_P1V05_PCH_AUX_EN
 G19 FM_ESPI_PLD_R_EN   PR6C @S9S_MB_2U_LIB.S9S_MB_2U(SCH_1):FM_ESPI_PLD_R_EN
 G18 PWRGD_PVCCIN_CPU1   PR6D @S9S_MB_2U_LIB.S9S_MB_2U(SCH_1):PWRGD_PVCCIN_CPU1
 G17 PWRGD_PVCCINFAON_CPU0   PR7C @S9S_MB_2U_LIB.S9S_MB_2U(SCH_1):PWRGD_PVCCINFAON_CPU0
 H20 PWRGD_PVCCINFAON_CPU1   PR7D @S9S_MB_2U_LIB.S9S_MB_2U(SCH_1):PWRGD_PVCCINFAON_CPU1
 H19 PWRGD_PVCCFA_EHV_FIVRA_CPU1  PR10A @S9S_MB_2U_LIB.S9S_MB_2U(SCH_1):PWRGD_PVCCFA_EHV_FIVRA_CPU1
 H18 PWRGD_PVCCD_HV_CPU1  PR10B @S9S_MB_2U_LIB.S9S_MB_2U(SCH_1):PWRGD_PVCCD_HV_CPU1
 H17 FM_PFR_DSW_PWROK_N  PR10C @S9S_MB_2U_LIB.S9S_MB_2U(SCH_1):FM_PFR_DSW_PWROK_N
 H16 PWRGD_PS_PWROK_PLD_ISO_R  PR10D @S9S_MB_2U_LIB.S9S_MB_2U(SCH_1):PWRGD_PS_PWROK_PLD_ISO_R
 J16 PWRGD_P1V05_PCH_AUX  PR11A @S9S_MB_2U_LIB.S9S_MB_2U(SCH_1):PWRGD_P1V05_PCH_AUX
 J17 PWRGD_P1V8_PCH_AUX_PLD  PR11B @S9S_MB_2U_LIB.S9S_MB_2U(SCH_1):PWRGD_P1V8_PCH_AUX_PLD
 J18 PWRGD_SYS_PWROK_R  PR11C @S9S_MB_2U_LIB.S9S_MB_2U(SCH_1):PWRGD_SYS_PWROK_R
 J19 PWRGD_PCH_PWROK_R  PR11D @S9S_MB_2U_LIB.S9S_MB_2U(SCH_1):PWRGD_PCH_PWROK_R
 J21 IRQ_PVCCFA_CPU0_VRHOT_R_N  PR12A @S9S_MB_2U_LIB.S9S_MB_2U(SCH_1):IRQ_PVCCFA_CPU0_VRHOT_R_N
 J22 IRQ_PVCCFA_CPU1_VRHOT_R_N  PR12B @S9S_MB_2U_LIB.S9S_MB_2U(SCH_1):IRQ_PVCCFA_CPU1_VRHOT_R_N
 J20 E1S_0_P3V3_ADC_ALERT  PR12C @S9S_MB_2U_LIB.S9S_MB_2U(SCH_1):E1S_0_P3V3_ADC_ALERT
 K20 OCP_SFF_P3V3_ADC_ALERT  PR12D @S9S_MB_2U_LIB.S9S_MB_2U(SCH_1):OCP_SFF_P3V3_ADC_ALERT
 K19 NC_FPGA_PR13A  PR13A @S9S_MB_2U_LIB.S9S_MB_2U(SCH_1):NC_FPGA_PR13A
 K18 OCP_V3_2_P3V3_ADC_ALERT  PR13B @S9S_MB_2U_LIB.S9S_MB_2U(SCH_1):OCP_V3_2_P3V3_ADC_ALERT
 K17 M2_0_P3V3_ADC_ALERT  PR13C @S9S_MB_2U_LIB.S9S_MB_2U(SCH_1):M2_0_P3V3_ADC_ALERT
 K16 P12V_SCM_ADC_ALERT  PR13D @S9S_MB_2U_LIB.S9S_MB_2U(SCH_1):P12V_SCM_ADC_ALERT
 L19 FM_UARTSW_LSB_N  PR14C @S9S_MB_2U_LIB.S9S_MB_2U(SCH_1):FM_UARTSW_LSB_N
 L20 FM_UARTSW_MSB_N  PR14D @S9S_MB_2U_LIB.S9S_MB_2U(SCH_1):FM_UARTSW_MSB_N
 L22 NC_FPGA_PR16C  PR16C @S9S_MB_2U_LIB.S9S_MB_2U(SCH_1):NC_FPGA_PR16C
 M17 NC_FPGA_PR16D  PR16D @S9S_MB_2U_LIB.S9S_MB_2U(SCH_1):NC_FPGA_PR16D
 M20 RST_PCIE_CPU0_DEV_PERST_N  PR17C @S9S_MB_2U_LIB.S9S_MB_2U(SCH_1):RST_PCIE_CPU0_DEV_PERST_N
 M19 RST_PCIE_CPU1_DEV_PERST_N  PR17D @S9S_MB_2U_LIB.S9S_MB_2U(SCH_1):RST_PCIE_CPU1_DEV_PERST_N
 M16 FM_CPU0_SKTOCC_LVT3_PLD_N  PR18A @S9S_MB_2U_LIB.S9S_MB_2U(SCH_1):FM_CPU0_SKTOCC_LVT3_PLD_N
 N16 FM_CPU1_SKTOCC_LVT3_PLD_N  PR18B @S9S_MB_2U_LIB.S9S_MB_2U(SCH_1):FM_CPU1_SKTOCC_LVT3_PLD_N
 N17 FM_CPU0_PROC_ID0  PR18C @S9S_MB_2U_LIB.S9S_MB_2U(SCH_1):FM_CPU0_PROC_ID0
 N18 FM_CPU0_PROC_ID1  PR18D @S9S_MB_2U_LIB.S9S_MB_2U(SCH_1):FM_CPU0_PROC_ID1
 N20 FM_CPU0_PKGID0  PR19C @S9S_MB_2U_LIB.S9S_MB_2U(SCH_1):FM_CPU0_PKGID0
 N19 FM_CPU0_PKGID1  PR19D @S9S_MB_2U_LIB.S9S_MB_2U(SCH_1):FM_CPU0_PKGID1
 P22 FM_CPU1_PKGID1  PR20C @S9S_MB_2U_LIB.S9S_MB_2U(SCH_1):FM_CPU1_PKGID1
 P20 FM_CPU1_PKGID2  PR20D @S9S_MB_2U_LIB.S9S_MB_2U(SCH_1):FM_CPU1_PKGID2
 T22 PWRGD_DSW_PWROK_R3  PR21A @S9S_MB_2U_LIB.S9S_MB_2U(SCH_1):PWRGD_DSW_PWROK_R3
 T21 IRQ_PVCCIN_CPU0_VRHOT_R_N  PR21B @S9S_MB_2U_LIB.S9S_MB_2U(SCH_1):IRQ_PVCCIN_CPU0_VRHOT_R_N
 P19 IRQ_PVCCIN_CPU1_VRHOT_R_N  PR21C @S9S_MB_2U_LIB.S9S_MB_2U(SCH_1):IRQ_PVCCIN_CPU1_VRHOT_R_N
 P18 FM_RST_PERST_BIT0  PR21D @S9S_MB_2U_LIB.S9S_MB_2U(SCH_1):FM_RST_PERST_BIT0
 P17 FM_RST_PERST_BIT1  PR24A @S9S_MB_2U_LIB.S9S_MB_2U(SCH_1):FM_RST_PERST_BIT1
 P16 FM_CPU_RMCA_CATERR_DLY_LVT3_R_N  PR24B @S9S_MB_2U_LIB.S9S_MB_2U(SCH_1):FM_CPU_RMCA_CATERR_DLY_LVT3_R_N
 U22 FM_JTAG_BMC_MUX_SEL_R  PR24C @S9S_MB_2U_LIB.S9S_MB_2U(SCH_1):FM_JTAG_BMC_MUX_SEL_R
 U21 FM_SLPS4_PLD_N  PR24D @S9S_MB_2U_LIB.S9S_MB_2U(SCH_1):FM_SLPS4_PLD_N
 R20 PWRGD_FAIL_CPU0_CD_R  PR25C @S9S_MB_2U_LIB.S9S_MB_2U(SCH_1):PWRGD_FAIL_CPU0_CD_R
 R19 PWRGD_FAIL_CPU0_EF_R  PR25D @S9S_MB_2U_LIB.S9S_MB_2U(SCH_1):PWRGD_FAIL_CPU0_EF_R
 R18 PWRGD_FAIL_CPU0_GH_R  PR26A @S9S_MB_2U_LIB.S9S_MB_2U(SCH_1):PWRGD_FAIL_CPU0_GH_R
 R17 PWRGD_FAIL_CPU1_AB_R  PR26B @S9S_MB_2U_LIB.S9S_MB_2U(SCH_1):PWRGD_FAIL_CPU1_AB_R
 R16 PWRGD_FAIL_CPU1_CD_R  PR26C @S9S_MB_2U_LIB.S9S_MB_2U(SCH_1):PWRGD_FAIL_CPU1_CD_R
 T20 PWRGD_FAIL_CPU1_EF_R  PR26D @S9S_MB_2U_LIB.S9S_MB_2U(SCH_1):PWRGD_FAIL_CPU1_EF_R
 T19 PWRGD_FAIL_CPU1_GH_R  PR27A @S9S_MB_2U_LIB.S9S_MB_2U(SCH_1):PWRGD_FAIL_CPU1_GH_R
 T18 OCP_SFF_MAIN_PWR_EN  PR27B @S9S_MB_2U_LIB.S9S_MB_2U(SCH_1):OCP_SFF_MAIN_PWR_EN
 T17 OCP_V3_2_MAIN_PWR_EN  PR27C @S9S_MB_2U_LIB.S9S_MB_2U(SCH_1):OCP_V3_2_MAIN_PWR_EN
 U20 HP_LVC3_OCP_V3_2_HSC_PWRGD_PLD_  PR27D @S9S_MB_2U_LIB.S9S_MB_2U(SCH_1):HP_LVC3_OCP_V3_2_HSC_PWRGD_PLD_R
 Y22 HP_LVC3_OCP_V3_1_HSC_PWRGD_PLD_  PR28A @S9S_MB_2U_LIB.S9S_MB_2U(SCH_1):HP_LVC3_OCP_V3_1_HSC_PWRGD_PLD_R
 W21 FM_SMB_1_ALERT_GPU_ISO_R_N  PR28B @S9S_MB_2U_LIB.S9S_MB_2U(SCH_1):FM_SMB_1_ALERT_GPU_ISO_R_N
 U19 FM_SMB_2_ALERT_GPU_ISO_R_N  PR28C @S9S_MB_2U_LIB.S9S_MB_2U(SCH_1):FM_SMB_2_ALERT_GPU_ISO_R_N
 U18 E1S_0_LED_ACT_R_N  PR28D @S9S_MB_2U_LIB.S9S_MB_2U(SCH_1):E1S_0_LED_ACT_R_N
 W19 RST_PERST_SWB_N  PR30C @S9S_MB_2U_LIB.S9S_MB_2U(SCH_1):RST_PERST_SWB_N
 Y20 NC_FPGA_PR30D  PR30D @S9S_MB_2U_LIB.S9S_MB_2U(SCH_1):NC_FPGA_PR30D

Q_RES_0402LF-0,5%,1/16W,CHIP,CA  I83  R2412
   1 PWRGD_DSW_PWROK      A @S9S_MB_2U_LIB.S9S_MB_2U(SCH_1):PWRGD_DSW_PWROK
   2 PWRGD_DSW_PWROK_R3      B @S9S_MB_2U_LIB.S9S_MB_2U(SCH_1):PWRGD_DSW_PWROK_R3

Q_RES_0402LF-0,5%,1/16W,CHIP,CA  I84  R2452
   1 FM_ESPI_PLD_R_EN      A @S9S_MB_2U_LIB.S9S_MB_2U(SCH_1):FM_ESPI_PLD_R_EN
   2 FM_ESPI_PLD_R1_EN      B @S9S_MB_2U_LIB.S9S_MB_2U(SCH_1):FM_ESPI_PLD_R1_EN

Q_RES_0402LF-0,5%,1/16W,CHIP,CA  I85  R3047
   1 MB0_P12V_STBY_PWRGD      A @S9S_MB_2U_LIB.S9S_MB_2U(SCH_1):MB0_P12V_STBY_PWRGD
   2 PWRGD_PS_PWROK_PLD      B @S9S_MB_2U_LIB.S9S_MB_2U(SCH_1):PWRGD_PS_PWROK_PLD

Q_RES_0402LF-0,5%,1/16W,CHIP,CA  I86  R3048
   1 MB0_P12V_STBY_PWRGD      A @S9S_MB_2U_LIB.S9S_MB_2U(SCH_1):MB0_P12V_STBY_PWRGD
   2 PWRGD_PS_PWROK      B @S9S_MB_2U_LIB.S9S_MB_2U(SCH_1):PWRGD_PS_PWROK

Q_RES_0402LF-33.2,1%,1/16W,CHIA  I115  R1100
   1 CLK_25M_OSC_FPGA_R      A @S9S_MB_2U_LIB.S9S_MB_2U(SCH_1):CLK_25M_OSC_FPGA_R
   2 CLK_25M_OSC_MAIN_FPGA      B @S9S_MB_2U_LIB.S9S_MB_2U(SCH_1):CLK_25M_OSC_MAIN_FPGA

Q_CAP_0402-0.1UF,25V,10%,X7R,CA  I126  C1320
   1 P3V3_AUX      A @S9S_MB_2U_LIB.S9S_MB_2U(SCH_1):P3V3_AUX
   2    GND      B @S9S_MB_2U_LIB.S9S_MB_2U(SCH_1):GND

Q_OSC4P_SMLF-25MHZ,OSC,BF62500A  I127  OSC2
   1 PU_CLK25M_OSC_FPGA_EN     OE @S9S_MB_2U_LIB.S9S_MB_2U(SCH_1):PU_CLK25M_OSC_FPGA_EN
   3 CLK_25M_OSC_FPGA_R    OUT @S9S_MB_2U_LIB.S9S_MB_2U(SCH_1):CLK_25M_OSC_FPGA_R
   2    GND    GND @S9S_MB_2U_LIB.S9S_MB_2U(SCH_1):GND
   4 P3V3_AUX    VDD @S9S_MB_2U_LIB.S9S_MB_2U(SCH_1):P3V3_AUX

Q_RES_0402LF-10K,1%,1/16W,CHIPA  I129  R1099
   1 P3V3_AUX      A @S9S_MB_2U_LIB.S9S_MB_2U(SCH_1):P3V3_AUX
   2 PU_CLK25M_OSC_FPGA_EN      B @S9S_MB_2U_LIB.S9S_MB_2U(SCH_1):PU_CLK25M_OSC_FPGA_EN

Q_RES_0402LF-33.2,1%,1/16W,CHIA  I147  R4259
   1 FM_THERMAL_ALERT_N      A @S9S_MB_2U_LIB.S9S_MB_2U(SCH_1):FM_THERMAL_ALERT_N
   2 FM_THERMAL_ALERT_R_N      B @S9S_MB_2U_LIB.S9S_MB_2U(SCH_1):FM_THERMAL_ALERT_R_N

Q_RES_0402LF-0,5%,1/16W,CHIP,CA  I159  R4599
   1 HP_LVC3_OCP_V3_2_P12V_PWRGD      A @S9S_MB_2U_LIB.S9S_MB_2U(SCH_1):HP_LVC3_OCP_V3_2_P12V_PWRGD
   2 HP_LVC3_OCP_V3_2_HSC_PWRGD_PLD_      B @S9S_MB_2U_LIB.S9S_MB_2U(SCH_1):HP_LVC3_OCP_V3_2_HSC_PWRGD_PLD_R

Q_RES_0402LF-0,5%,1/16W,CHIP,CA  I160  R4600
   1 HP_LVC3_OCP_V3_1_P12V_PWRGD      A @S9S_MB_2U_LIB.S9S_MB_2U(SCH_1):HP_LVC3_OCP_V3_1_P12V_PWRGD
   2 HP_LVC3_OCP_V3_1_HSC_PWRGD_PLD_      B @S9S_MB_2U_LIB.S9S_MB_2U(SCH_1):HP_LVC3_OCP_V3_1_HSC_PWRGD_PLD_R

Q_RES_0402LF-0,5%,1/16W,CHIP,CA  I166  R4088
   1 FM_JTAG_BMC_MUX_SEL_FROM_BMC_R      A @S9S_MB_2U_LIB.S9S_MB_2U(SCH_1):FM_JTAG_BMC_MUX_SEL_FROM_BMC_R
   2 FM_JTAG_BMC_MUX_SEL      B @S9S_MB_2U_LIB.S9S_MB_2U(SCH_1):FM_JTAG_BMC_MUX_SEL

Q_RES_0402LF-0,5%,1/16W,EMPTY,A  I167  R1833
   1 FM_JTAG_BMC_MUX_SEL_R      A @S9S_MB_2U_LIB.S9S_MB_2U(SCH_1):FM_JTAG_BMC_MUX_SEL_R
   2 FM_JTAG_BMC_MUX_SEL      B @S9S_MB_2U_LIB.S9S_MB_2U(SCH_1):FM_JTAG_BMC_MUX_SEL

Q_RES_0402LF-0,5%,1/16W,CHIP,CA  I175  R3066
   1 FM_SMB_1_ALERT_GPU_ISO_N      A @S9S_MB_2U_LIB.S9S_MB_2U(SCH_1):FM_SMB_1_ALERT_GPU_ISO_N
   2 FM_SMB_1_ALERT_GPU_ISO_R_N      B @S9S_MB_2U_LIB.S9S_MB_2U(SCH_1):FM_SMB_1_ALERT_GPU_ISO_R_N

Q_RES_0402LF-0,5%,1/16W,CHIP,CA  I176  R3067
   1 FM_SMB_2_ALERT_GPU_ISO_N      A @S9S_MB_2U_LIB.S9S_MB_2U(SCH_1):FM_SMB_2_ALERT_GPU_ISO_N
   2 FM_SMB_2_ALERT_GPU_ISO_R_N      B @S9S_MB_2U_LIB.S9S_MB_2U(SCH_1):FM_SMB_2_ALERT_GPU_ISO_R_N

Q_RES_0402LF-0,5%,1/16W,CHIP,CA  I180  R4606
   1 E1S_0_LED_ACT_R_N      A @S9S_MB_2U_LIB.S9S_MB_2U(SCH_1):E1S_0_LED_ACT_R_N
   2 E1S_0_LED_ACT_N      B @S9S_MB_2U_LIB.S9S_MB_2U(SCH_1):E1S_0_LED_ACT_N

Q_RES_0402LF-0,5%,1/16W,CHIP,CA  I183  R4607
   1 LED_HDD_ACTIVITY_B_N      A @S9S_MB_2U_LIB.S9S_MB_2U(SCH_1):LED_HDD_ACTIVITY_B_N
   2 LED_HDD_ACTIVITY_B_PLD_N      B @S9S_MB_2U_LIB.S9S_MB_2U(SCH_1):LED_HDD_ACTIVITY_B_PLD_N

Q_RES_0402LF-33.2,1%,1/16W,CHIA  I190  R4608
   1 GPU_FPGA_RST_N      A @S9S_MB_2U_LIB.S9S_MB_2U(SCH_1):GPU_FPGA_RST_N
   2 GPU_FPGA_RST_R_N      B @S9S_MB_2U_LIB.S9S_MB_2U(SCH_1):GPU_FPGA_RST_R_N

Q_RES_0402LF-33.2,1%,1/16W,CHIA  I194  R4609
   1 FM_JTAG_TCK_MUX_SEL_R      A @S9S_MB_2U_LIB.S9S_MB_2U(SCH_1):FM_JTAG_TCK_MUX_SEL_R
   2 FM_JTAG_TCK_MUX_SEL      B @S9S_MB_2U_LIB.S9S_MB_2U(SCH_1):FM_JTAG_TCK_MUX_SEL

Q_RES_0402LF-33.2,1%,1/16W,CHIA  I200  R4610
   1 CLK_GEN2_GPU_FPGA_OE_R_N      A @S9S_MB_2U_LIB.S9S_MB_2U(SCH_1):CLK_GEN2_GPU_FPGA_OE_R_N
   2 CLK_GEN2_GPU_FPGA_OE_N      B @S9S_MB_2U_LIB.S9S_MB_2U(SCH_1):CLK_GEN2_GPU_FPGA_OE_N

Q_RES_0402LF-33.2,1%,1/16W,CHIA  I206  R4611
   1 FM_BMC_CPU_FBRK_OUT_R_N      A @S9S_MB_2U_LIB.S9S_MB_2U(SCH_1):FM_BMC_CPU_FBRK_OUT_R_N
   2 FM_BMC_CPU_FBRK_OUT_N      B @S9S_MB_2U_LIB.S9S_MB_2U(SCH_1):FM_BMC_CPU_FBRK_OUT_N

Q_RES_0402LF-33.2,1%,1/16W,CHIA  I211  R4612
   1 FM_PCH_SPKR      A @S9S_MB_2U_LIB.S9S_MB_2U(SCH_1):FM_PCH_SPKR
   2 FM_PCH_SPKR_R      B @S9S_MB_2U_LIB.S9S_MB_2U(SCH_1):FM_PCH_SPKR_R


DRAWING: @S9S_MB_2U_LIB.S9S_MB_2U(SCH_1):PAGE314 

MOSFET_NCH_DUAL-PJT138K,SMLF,IA  I49  Q50
   3 PWRGD_P5V_AUX_R2     D2 @S9S_MB_2U_LIB.S9S_MB_2U(SCH_1):PWRGD_P5V_AUX_R2
   5 PWRGD_P5V_AUX_R1     G2 @S9S_MB_2U_LIB.S9S_MB_2U(SCH_1):PWRGD_P5V_AUX_R1
   4    GND     S2 @S9S_MB_2U_LIB.S9S_MB_2U(SCH_1):GND

Q_RES_0402LF-33.2,1%,1/16W,CHIA  I111  R3043
   1 IRQ_HSC_FAULT_N      A @S9S_MB_2U_LIB.S9S_MB_2U(SCH_1):IRQ_HSC_FAULT_N
   2 IRQ_HSC_FAULT_R1_N      B @S9S_MB_2U_LIB.S9S_MB_2U(SCH_1):IRQ_HSC_FAULT_R1_N

Q_RES_0402LF-33.2,1%,1/16W,CHIA  I115  R2662
   1 FM_GPU_PWR_EN      A @S9S_MB_2U_LIB.S9S_MB_2U(SCH_1):FM_GPU_PWR_EN
   2 FM_GPU_PWR_EN_R      B @S9S_MB_2U_LIB.S9S_MB_2U(SCH_1):FM_GPU_PWR_EN_R

Q_RES_0402LF-0,5%,1/16W,CHIP,CA  I14  R4697
   1 RST_SRST_PLD_BMC_R_N      A @S9S_MB_2U_LIB.S9S_MB_2U(SCH_1):RST_SRST_PLD_BMC_R_N
   2 RST_SRST_PLD_BMC_N      B @S9S_MB_2U_LIB.S9S_MB_2U(SCH_1):RST_SRST_PLD_BMC_N

Q_RES_0402LF-33.2,1%,1/16W,CHIA  I15  R3486
   1 GPU_PRSNT_N_ISO      A @S9S_MB_2U_LIB.S9S_MB_2U(SCH_1):GPU_PRSNT_N_ISO
   2 GPU_PRSNT_N_ISO_R      B @S9S_MB_2U_LIB.S9S_MB_2U(SCH_1):GPU_PRSNT_N_ISO_R

Q_RES_0402LF-33.2,1%,1/16W,CHIA  I16  R3505
   1 GPU_FPGA_EROT_FATALERR_ISO_N      A @S9S_MB_2U_LIB.S9S_MB_2U(SCH_1):GPU_FPGA_EROT_FATALERR_ISO_N
   2 GPU_FPGA_EROT_FATALERR_ISO_R_N      B @S9S_MB_2U_LIB.S9S_MB_2U(SCH_1):GPU_FPGA_EROT_FATALERR_ISO_R_N

Q_RES_0402LF-33.2,1%,1/16W,CHIA  I17  R3484
   1 GPU_FPGA_OVERT_ISO_N      A @S9S_MB_2U_LIB.S9S_MB_2U(SCH_1):GPU_FPGA_OVERT_ISO_N
   2 GPU_FPGA_OVERT_ISO_R_N      B @S9S_MB_2U_LIB.S9S_MB_2U(SCH_1):GPU_FPGA_OVERT_ISO_R_N

Q_RES_0402LF-33.2,1%,1/16W,CHIA  I18  R3485
   1 GPU_WP_HW_CTRL_N      A @S9S_MB_2U_LIB.S9S_MB_2U(SCH_1):GPU_WP_HW_CTRL_N
   2 GPU_WP_HW_CTRL_R_N      B @S9S_MB_2U_LIB.S9S_MB_2U(SCH_1):GPU_WP_HW_CTRL_R_N

Q_RES_0402LF-33.2,1%,1/16W,CHIA  I19  R3482
   1 GPU_FPGA_BOOT_EN      A @S9S_MB_2U_LIB.S9S_MB_2U(SCH_1):GPU_FPGA_BOOT_EN
   2 GPU_FPGA_BOOT_EN_R      B @S9S_MB_2U_LIB.S9S_MB_2U(SCH_1):GPU_FPGA_BOOT_EN_R

Q_RES_0402LF-33.2,1%,1/16W,CHIA  I20  R3483
   1 GPU_FPGA_EROT_RECOV_N      A @S9S_MB_2U_LIB.S9S_MB_2U(SCH_1):GPU_FPGA_EROT_RECOV_N
   2 GPU_FPGA_EROT_RECOV_R_N      B @S9S_MB_2U_LIB.S9S_MB_2U(SCH_1):GPU_FPGA_EROT_RECOV_R_N

Q_RES_0402LF-33.2,1%,1/16W,CHIA  I21  R3480
   1 GPU_BASE_HMC_READY_ISO      A @S9S_MB_2U_LIB.S9S_MB_2U(SCH_1):GPU_BASE_HMC_READY_ISO
   2 GPU_BASE_HMC_READY_ISO_R      B @S9S_MB_2U_LIB.S9S_MB_2U(SCH_1):GPU_BASE_HMC_READY_ISO_R

Q_RES_0402LF-33.2,1%,1/16W,CHIA  I22  R3481
   1 GPU_HMC_PRSNT_ISO_N      A @S9S_MB_2U_LIB.S9S_MB_2U(SCH_1):GPU_HMC_PRSNT_ISO_N
   2 GPU_HMC_PRSNT_ISO_R_N      B @S9S_MB_2U_LIB.S9S_MB_2U(SCH_1):GPU_HMC_PRSNT_ISO_R_N

Q_RES_0402LF-33.2,1%,1/16W,CHIA  I23  R3478
   1 GPU_FPGA_EROT_RST_N      A @S9S_MB_2U_LIB.S9S_MB_2U(SCH_1):GPU_FPGA_EROT_RST_N
   2 GPU_FPGA_EROT_RST_R_N      B @S9S_MB_2U_LIB.S9S_MB_2U(SCH_1):GPU_FPGA_EROT_RST_R_N

Q_RES_0402LF-33.2,1%,1/16W,CHIA  I24  R3479
   1 GPU_BASE_STBY_EN      A @S9S_MB_2U_LIB.S9S_MB_2U(SCH_1):GPU_BASE_STBY_EN
   2 GPU_BASE_STBY_EN_R      B @S9S_MB_2U_LIB.S9S_MB_2U(SCH_1):GPU_BASE_STBY_EN_R

Q_RES_0402LF-33.2,1%,1/16W,CHIA  I25  R3476
   1 GPU_FPGA_THERM_OVERT_ISO_N      A @S9S_MB_2U_LIB.S9S_MB_2U(SCH_1):GPU_FPGA_THERM_OVERT_ISO_N
   2 GPU_FPGA_THERM_OVERT_ISO_R_N      B @S9S_MB_2U_LIB.S9S_MB_2U(SCH_1):GPU_FPGA_THERM_OVERT_ISO_R_N

Q_RES_0402LF-33.2,1%,1/16W,CHIA  I26  R3477
   1 GPU_NVS_PWR_BRAKE_N      A @S9S_MB_2U_LIB.S9S_MB_2U(SCH_1):GPU_NVS_PWR_BRAKE_N
   2 GPU_NVS_PWR_BRAKE_R_N      B @S9S_MB_2U_LIB.S9S_MB_2U(SCH_1):GPU_NVS_PWR_BRAKE_R_N

Q_RES_0402LF-10K,1%,1/16W,EMPTA  I41  R2343
   1 P5V_AUX_VCC      A @S9S_MB_2U_LIB.S9S_MB_2U(SCH_1):P5V_AUX_VCC
   2 PWRGD_P5V_AUX      B @S9S_MB_2U_LIB.S9S_MB_2U(SCH_1):PWRGD_P5V_AUX

MOSFET_NCH_DUAL-PJT138K,SMLF,IA  I43  Q50
   1    GND     S1 @S9S_MB_2U_LIB.S9S_MB_2U(SCH_1):GND
   2 PWRGD_P5V_AUX     G1 @S9S_MB_2U_LIB.S9S_MB_2U(SCH_1):PWRGD_P5V_AUX
   6 PWRGD_P5V_AUX_R1     D1 @S9S_MB_2U_LIB.S9S_MB_2U(SCH_1):PWRGD_P5V_AUX_R1

Q_RES_0402LF-4.7K,5%,1/16W,CHIA  I45  R2344
   1 P3V3_AUX      A @S9S_MB_2U_LIB.S9S_MB_2U(SCH_1):P3V3_AUX
   2 PWRGD_P5V_AUX_R1      B @S9S_MB_2U_LIB.S9S_MB_2U(SCH_1):PWRGD_P5V_AUX_R1

Q_RES_0402LF-10K,1%,1/16W,CHIPA  I47  R1681
   1 P3V3_AUX      A @S9S_MB_2U_LIB.S9S_MB_2U(SCH_1):P3V3_AUX
   2 PU_RST_DEDI_BUSY_PLD_N      B @S9S_MB_2U_LIB.S9S_MB_2U(SCH_1):PU_RST_DEDI_BUSY_PLD_N

Q_RES_0402LF-4.7K,5%,1/16W,CHIA  I51  R2346
   1 P3V3_AUX      A @S9S_MB_2U_LIB.S9S_MB_2U(SCH_1):P3V3_AUX
   2 PWRGD_P5V_AUX_R2      B @S9S_MB_2U_LIB.S9S_MB_2U(SCH_1):PWRGD_P5V_AUX_R2

Q_RES_0402LF-33.2,1%,1/16W,CHIA  I107  R2847
   1 RST_BMC_FROM_SWB_ISO_N      A @S9S_MB_2U_LIB.S9S_MB_2U(SCH_1):RST_BMC_FROM_SWB_ISO_N
   2 RST_BMC_FROM_SWB_ISO_R_N      B @S9S_MB_2U_LIB.S9S_MB_2U(SCH_1):RST_BMC_FROM_SWB_ISO_R_N

Q_RES_0402LF-33.2,1%,1/16W,CHIA  I108  R3324
   1 GPU_FPGA_READY_ISO      A @S9S_MB_2U_LIB.S9S_MB_2U(SCH_1):GPU_FPGA_READY_ISO
   2 GPU_FPGA_READY_ISO_R      B @S9S_MB_2U_LIB.S9S_MB_2U(SCH_1):GPU_FPGA_READY_ISO_R

Q_RES_0402LF-33.2,1%,1/16W,CHIA  I109  R1606
   1 FM_OCP_SFF_PWR_GOOD      A @S9S_MB_2U_LIB.S9S_MB_2U(SCH_1):FM_OCP_SFF_PWR_GOOD
   2 FM_OCP_SFF_PWR_GOOD_R      B @S9S_MB_2U_LIB.S9S_MB_2U(SCH_1):FM_OCP_SFF_PWR_GOOD_R

Q_RES_0402LF-33.2,1%,1/16W,CHIA  I110  R3230
   1 FM_OCP_V3_2_PWR_GOOD      A @S9S_MB_2U_LIB.S9S_MB_2U(SCH_1):FM_OCP_V3_2_PWR_GOOD
   2 FM_OCP_V3_2_PWR_GOOD_R      B @S9S_MB_2U_LIB.S9S_MB_2U(SCH_1):FM_OCP_V3_2_PWR_GOOD_R

Q_RES_0402LF-33.2,1%,1/16W,CHIA  I112  R2844
   1 FM_SWB_BIC_READY_ISO_N      A @S9S_MB_2U_LIB.S9S_MB_2U(SCH_1):FM_SWB_BIC_READY_ISO_N
   2 FM_SWB_BIC_READY_ISO_R_N      B @S9S_MB_2U_LIB.S9S_MB_2U(SCH_1):FM_SWB_BIC_READY_ISO_R_N

Q_RES_0402LF-33.2,1%,1/16W,CHIA  I113  R2664
   1 FM_GPU_PWRGD_ISO      A @S9S_MB_2U_LIB.S9S_MB_2U(SCH_1):FM_GPU_PWRGD_ISO
   2 FM_GPU_PWRGD_ISO_R      B @S9S_MB_2U_LIB.S9S_MB_2U(SCH_1):FM_GPU_PWRGD_ISO_R

Q_RES_0402LF-33.2,1%,1/16W,CHIA  I114  R2663
   1 FM_SWB_PWRGD_ISO      A @S9S_MB_2U_LIB.S9S_MB_2U(SCH_1):FM_SWB_PWRGD_ISO
   2 FM_SWB_PWRGD_ISO_R      B @S9S_MB_2U_LIB.S9S_MB_2U(SCH_1):FM_SWB_PWRGD_ISO_R

Q_RES_0402LF-33.2,1%,1/16W,CHIA  I135  R2661
   1 FM_SWB_PWR_EN      A @S9S_MB_2U_LIB.S9S_MB_2U(SCH_1):FM_SWB_PWR_EN
   2 FM_SWB_PWR_EN_R      B @S9S_MB_2U_LIB.S9S_MB_2U(SCH_1):FM_SWB_PWR_EN_R

Q_RES_0402LF-33.2,1%,1/16W,CHIA  I136  R2845
   1 BMC_MONITER      A @S9S_MB_2U_LIB.S9S_MB_2U(SCH_1):BMC_MONITER
   2 BMC_MONITER_R      B @S9S_MB_2U_LIB.S9S_MB_2U(SCH_1):BMC_MONITER_R

Q_RES_0402LF-0,5%,1/16W,EMPTY,A  I137  R2071
   1 FM_BMC_SUSACK_R_N      A @S9S_MB_2U_LIB.S9S_MB_2U(SCH_1):FM_BMC_SUSACK_R_N
   2 FM_SUSACK_N      B @S9S_MB_2U_LIB.S9S_MB_2U(SCH_1):FM_SUSACK_N

Q_RES_0402LF-0,5%,1/16W,CHIP,CA  I138  R1853
   1 VIRTUAL_RESEAT_FPGA_R_N      A @S9S_MB_2U_LIB.S9S_MB_2U(SCH_1):VIRTUAL_RESEAT_FPGA_R_N
   2 VIRTUAL_RESEAT_FPGA_N      B @S9S_MB_2U_LIB.S9S_MB_2U(SCH_1):VIRTUAL_RESEAT_FPGA_N

Q_RES_0402LF-0,5%,1/16W,CHIP,CA  I139  R1547
   1 FM_TPM_PRSNT_R_N      A @S9S_MB_2U_LIB.S9S_MB_2U(SCH_1):FM_TPM_PRSNT_R_N
   2 FM_TPM_PRSNT_N      B @S9S_MB_2U_LIB.S9S_MB_2U(SCH_1):FM_TPM_PRSNT_N

Q_RES_0402LF-100,1%,1/16W,CHIPA  I140  R4625
   1 JTAG_BMC_SW_OE      A @S9S_MB_2U_LIB.S9S_MB_2U(SCH_1):JTAG_BMC_SW_OE
   2 JTAG_BMC_SW_PLD_OE      B @S9S_MB_2U_LIB.S9S_MB_2U(SCH_1):JTAG_BMC_SW_PLD_OE

Q_RES_0402LF-33.2,1%,1/16W,CHIA  I141  R4495
   1 OCP_SFF_CLK_OE_R_N      A @S9S_MB_2U_LIB.S9S_MB_2U(SCH_1):OCP_SFF_CLK_OE_R_N
   2 OCP_SFF_CLK_OE_N      B @S9S_MB_2U_LIB.S9S_MB_2U(SCH_1):OCP_SFF_CLK_OE_N

Q_RES_0402LF-4.7K,1%,1/16W,EMPA  I179  R1551
   1 P3V3_AUX      A @S9S_MB_2U_LIB.S9S_MB_2U(SCH_1):P3V3_AUX
   2 SMB_1_PLD_3V3AUX_SDA_R1      B @S9S_MB_2U_LIB.S9S_MB_2U(SCH_1):SMB_1_PLD_3V3AUX_SDA_R1

Q_RES_0402LF-33.2,1%,1/16W,CHIA  I106  R2939
   1 FM_GPU_HSC_EN_R      A @S9S_MB_2U_LIB.S9S_MB_2U(SCH_1):FM_GPU_HSC_EN_R
   2 FM_GPU_HSC_EN      B @S9S_MB_2U_LIB.S9S_MB_2U(SCH_1):FM_GPU_HSC_EN

Q_RES_0402LF-33.2,1%,1/16W,CHIA  I134  R2846
   1 BIC_MONITER_ISO      A @S9S_MB_2U_LIB.S9S_MB_2U(SCH_1):BIC_MONITER_ISO
   2 BIC_MONITER_ISO_R      B @S9S_MB_2U_LIB.S9S_MB_2U(SCH_1):BIC_MONITER_ISO_R

Q_RES_0402LF-4.7K,1%,1/16W,EMPA  I178  R1467
   1 P3V3_AUX      A @S9S_MB_2U_LIB.S9S_MB_2U(SCH_1):P3V3_AUX
   2 SMB_1_PLD_3V3AUX_SCL_R1      B @S9S_MB_2U_LIB.S9S_MB_2U(SCH_1):SMB_1_PLD_3V3AUX_SCL_R1

LCMXO3LF9400C5BG484C-LCMXO3LF-A  I188  U249
 B21 NC_FPGA_PT43B PT43B||R_GPLLC @S9S_MB_2U_LIB.S9S_MB_2U(SCH_1):NC_FPGA_PT43B
 A20 NC_FPGA_PT43A PT43A||R_GPLLT @S9S_MB_2U_LIB.S9S_MB_2U(SCH_1):NC_FPGA_PT43A
 B19 PU_MAIN_FPGA_CONFIG_DONE  PT41B @S9S_MB_2U_LIB.S9S_MB_2U(SCH_1):PU_MAIN_FPGA_CONFIG_DONE
 A18 GPU_FPGA_READY_ISO_R  PT41A @S9S_MB_2U_LIB.S9S_MB_2U(SCH_1):GPU_FPGA_READY_ISO_R
 F14 SGPIO_BMC_LD_N  PT31B @S9S_MB_2U_LIB.S9S_MB_2U(SCH_1):SGPIO_BMC_LD_N
 G14 SGPIO_BMC_DIN_R  PT31A @S9S_MB_2U_LIB.S9S_MB_2U(SCH_1):SGPIO_BMC_DIN_R
 F12 PWRGD_PVCCD_HV_CPU0  PT28B @S9S_MB_2U_LIB.S9S_MB_2U(SCH_1):PWRGD_PVCCD_HV_CPU0
 G12 PWRGD_P3V3_AUX_PLD  PT28A @S9S_MB_2U_LIB.S9S_MB_2U(SCH_1):PWRGD_P3V3_AUX_PLD
 A12 SMB_1_PLD_3V3AUX_SDA_R1 PT27D||SDA||PCLKC0_0 @S9S_MB_2U_LIB.S9S_MB_2U(SCH_1):SMB_1_PLD_3V3AUX_SDA_R1
 B12 SMB_1_PLD_3V3AUX_SCL_R1 PT27C||SCL||PCLKT0_0 @S9S_MB_2U_LIB.S9S_MB_2U(SCH_1):SMB_1_PLD_3V3AUX_SCL_R1
 B22 NC_FPGA_PT44B PT44B||R_GPLLC @S9S_MB_2U_LIB.S9S_MB_2U(SCH_1):NC_FPGA_PT44B
 A21 NC_FPGA_PT44A PT44A||R_GPLLT @S9S_MB_2U_LIB.S9S_MB_2U(SCH_1):NC_FPGA_PT44A
 A10 SMB_HOST_3V3AUX_PLD_SCL PT23B||PCLKC0_1 @S9S_MB_2U_LIB.S9S_MB_2U(SCH_1):SMB_HOST_3V3AUX_PLD_SCL
 B10 SMB_HOST_3V3AUX_PLD_SDA PT23A||PCLKT0_1 @S9S_MB_2U_LIB.S9S_MB_2U(SCH_1):SMB_HOST_3V3AUX_PLD_SDA
  D8 IRQ_SML1_PMBUS_BMC_ALERT_N  PT15B @S9S_MB_2U_LIB.S9S_MB_2U(SCH_1):IRQ_SML1_PMBUS_BMC_ALERT_N
  F7 FM_GPU_PWRGD_ISO_R   PT9D @S9S_MB_2U_LIB.S9S_MB_2U(SCH_1):FM_GPU_PWRGD_ISO_R
  A2 FM_GPU_PWR_EN PT9B||L_GPLLC @S9S_MB_2U_LIB.S9S_MB_2U(SCH_1):FM_GPU_PWR_EN
  E6 FM_SWB_PWRGD_ISO_R   PT9C @S9S_MB_2U_LIB.S9S_MB_2U(SCH_1):FM_SWB_PWRGD_ISO_R
  B1 FM_SWB_PWR_EN PT9A||L_GPLLT @S9S_MB_2U_LIB.S9S_MB_2U(SCH_1):FM_SWB_PWR_EN
  C8 OCP_SFF_CLK_OE_R_N  PT15A @S9S_MB_2U_LIB.S9S_MB_2U(SCH_1):OCP_SFF_CLK_OE_R_N
  B3 FM_SWB_BIC_READY_ISO_R_N  PT11A @S9S_MB_2U_LIB.S9S_MB_2U(SCH_1):FM_SWB_BIC_READY_ISO_R_N
  A4 SMB_BMC_SWB_EN  PT11B @S9S_MB_2U_LIB.S9S_MB_2U(SCH_1):SMB_BMC_SWB_EN
 F10 GPU_BASE_HMC_READY_ISO_R  PT22A @S9S_MB_2U_LIB.S9S_MB_2U(SCH_1):GPU_BASE_HMC_READY_ISO_R
 E10 GPU_HMC_PRSNT_ISO_R_N  PT22B @S9S_MB_2U_LIB.S9S_MB_2U(SCH_1):GPU_HMC_PRSNT_ISO_R_N
  F8 RST_BMC_FROM_SWB_ISO_R_N  PT11C @S9S_MB_2U_LIB.S9S_MB_2U(SCH_1):RST_BMC_FROM_SWB_ISO_R_N
  G8 SMB_BMC_GPU_EN  PT11D @S9S_MB_2U_LIB.S9S_MB_2U(SCH_1):SMB_BMC_GPU_EN
  B2 FM_FAN_PWR_EN  PT10A @S9S_MB_2U_LIB.S9S_MB_2U(SCH_1):FM_FAN_PWR_EN
  A3 FM_GPU_HSC_EN_R  PT10B @S9S_MB_2U_LIB.S9S_MB_2U(SCH_1):FM_GPU_HSC_EN_R
  C3 BIC_MONITER_ISO_R  PT10C @S9S_MB_2U_LIB.S9S_MB_2U(SCH_1):BIC_MONITER_ISO_R
  C4 BMC_MONITER  PT10D @S9S_MB_2U_LIB.S9S_MB_2U(SCH_1):BMC_MONITER
  B4 FM_PCH_PRSNT_N  PT12A @S9S_MB_2U_LIB.S9S_MB_2U(SCH_1):FM_PCH_PRSNT_N
  A5 FM_TPM_PRSNT_R_N  PT12B @S9S_MB_2U_LIB.S9S_MB_2U(SCH_1):FM_TPM_PRSNT_R_N
  D5 VIRTUAL_RESEAT_FPGA_R_N  PT12C @S9S_MB_2U_LIB.S9S_MB_2U(SCH_1):VIRTUAL_RESEAT_FPGA_R_N
  C5 FM_BMC_SUSACK_R_N  PT12D @S9S_MB_2U_LIB.S9S_MB_2U(SCH_1):FM_BMC_SUSACK_R_N
  B5 IRQ_HSC_FAULT_R1_N  PT13A @S9S_MB_2U_LIB.S9S_MB_2U(SCH_1):IRQ_HSC_FAULT_R1_N
  A6 FM_PECI_MUX_SEL_N  PT13B @S9S_MB_2U_LIB.S9S_MB_2U(SCH_1):FM_PECI_MUX_SEL_N
  D6 OCP_V3_2_AUX_PWR_PLD_EN  PT13C @S9S_MB_2U_LIB.S9S_MB_2U(SCH_1):OCP_V3_2_AUX_PWR_PLD_EN
  E7 OCP_SFF_AUX_PWR_PLD_EN  PT13D @S9S_MB_2U_LIB.S9S_MB_2U(SCH_1):OCP_SFF_AUX_PWR_PLD_EN
  B6 FM_OCP_V3_2_PWR_GOOD_R  PT14A @S9S_MB_2U_LIB.S9S_MB_2U(SCH_1):FM_OCP_V3_2_PWR_GOOD_R
  A7 FM_OCP_SFF_PWR_GOOD_R  PT14B @S9S_MB_2U_LIB.S9S_MB_2U(SCH_1):FM_OCP_SFF_PWR_GOOD_R
  C6 FM_S3M_CPU0_CPLD_CRC_ERROR  PT14C @S9S_MB_2U_LIB.S9S_MB_2U(SCH_1):FM_S3M_CPU0_CPLD_CRC_ERROR
  D7 FM_S3M_CPU1_CPLD_CRC_ERROR  PT14D @S9S_MB_2U_LIB.S9S_MB_2U(SCH_1):FM_S3M_CPU1_CPLD_CRC_ERROR
  B8 IRQ_SML0_ALERT_R_N  PT20A @S9S_MB_2U_LIB.S9S_MB_2U(SCH_1):IRQ_SML0_ALERT_R_N
  A8 IRQ_SML1_PMBUS_PLD_ALERT_N  PT20B @S9S_MB_2U_LIB.S9S_MB_2U(SCH_1):IRQ_SML1_PMBUS_PLD_ALERT_N
  C9 FM_SLP_SUS_RSM_RST_N  PT20C @S9S_MB_2U_LIB.S9S_MB_2U(SCH_1):FM_SLP_SUS_RSM_RST_N
  D9 PU_RST_DEDI_BUSY_PLD_N  PT20D @S9S_MB_2U_LIB.S9S_MB_2U(SCH_1):PU_RST_DEDI_BUSY_PLD_N
  B9 GPU_FPGA_THERM_OVERT_ISO_R_N  PT21A @S9S_MB_2U_LIB.S9S_MB_2U(SCH_1):GPU_FPGA_THERM_OVERT_ISO_R_N
  A9 GPU_NVS_PWR_BRAKE_R_N  PT21B @S9S_MB_2U_LIB.S9S_MB_2U(SCH_1):GPU_NVS_PWR_BRAKE_R_N
  F9 GPU_FPGA_EROT_RST_R_N  PT21C @S9S_MB_2U_LIB.S9S_MB_2U(SCH_1):GPU_FPGA_EROT_RST_R_N
  G9 GPU_BASE_STBY_EN_R  PT21D @S9S_MB_2U_LIB.S9S_MB_2U(SCH_1):GPU_BASE_STBY_EN_R
 G11 GPU_FPGA_BOOT_EN_R  PT23C @S9S_MB_2U_LIB.S9S_MB_2U(SCH_1):GPU_FPGA_BOOT_EN_R
 F11 GPU_FPGA_EROT_RECOV_R_N  PT23D @S9S_MB_2U_LIB.S9S_MB_2U(SCH_1):GPU_FPGA_EROT_RECOV_R_N
 B11 GPU_FPGA_OVERT_ISO_R_N  PT24A @S9S_MB_2U_LIB.S9S_MB_2U(SCH_1):GPU_FPGA_OVERT_ISO_R_N
 A11 GPU_WP_HW_CTRL_R_N  PT24B @S9S_MB_2U_LIB.S9S_MB_2U(SCH_1):GPU_WP_HW_CTRL_R_N
 E11 GPU_PRSNT_N_ISO_R  PT24C @S9S_MB_2U_LIB.S9S_MB_2U(SCH_1):GPU_PRSNT_N_ISO_R
 D11 GPU_FPGA_EROT_FATALERR_ISO_R_N  PT24D @S9S_MB_2U_LIB.S9S_MB_2U(SCH_1):GPU_FPGA_EROT_FATALERR_ISO_R_N
 D12 PWRGD_P5V_AUX_R2  PT27A @S9S_MB_2U_LIB.S9S_MB_2U(SCH_1):PWRGD_P5V_AUX_R2
 E12 PWRGD_P3V3  PT27B @S9S_MB_2U_LIB.S9S_MB_2U(SCH_1):PWRGD_P3V3
 E13 PWRGD_PVCCFA_EHV_FIVRA_CPU0  PT28C @S9S_MB_2U_LIB.S9S_MB_2U(SCH_1):PWRGD_PVCCFA_EHV_FIVRA_CPU0
 F13 PWRGD_PVCCIN_CPU0  PT28D @S9S_MB_2U_LIB.S9S_MB_2U(SCH_1):PWRGD_PVCCIN_CPU0
 A13 PWRGD_PVNN_MAIN_CPU0  PT29A @S9S_MB_2U_LIB.S9S_MB_2U(SCH_1):PWRGD_PVNN_MAIN_CPU0
 B13 PWRGD_PVNN_PCH_AUX  PT29B @S9S_MB_2U_LIB.S9S_MB_2U(SCH_1):PWRGD_PVNN_PCH_AUX
 C13 PWRGD_PVNN_MAIN_CPU1  PT29C @S9S_MB_2U_LIB.S9S_MB_2U(SCH_1):PWRGD_PVNN_MAIN_CPU1
 D13 PWRGD_PVPP_HBM_CPU0  PT29D @S9S_MB_2U_LIB.S9S_MB_2U(SCH_1):PWRGD_PVPP_HBM_CPU0
 A14 PWRGD_PVPP_HBM_CPU1  PT30A @S9S_MB_2U_LIB.S9S_MB_2U(SCH_1):PWRGD_PVPP_HBM_CPU1
 B14 FM_NCSI_OCP_V3_2_R_OE  PT30B @S9S_MB_2U_LIB.S9S_MB_2U(SCH_1):FM_NCSI_OCP_V3_2_R_OE
 C14 SGPIO_BMC_DOUT  PT30C @S9S_MB_2U_LIB.S9S_MB_2U(SCH_1):SGPIO_BMC_DOUT
 D14 SGPIO_BMC_CLK  PT30D @S9S_MB_2U_LIB.S9S_MB_2U(SCH_1):SGPIO_BMC_CLK
 A15 SGPIO_DEBUG_PLD_DOUT  PT38A @S9S_MB_2U_LIB.S9S_MB_2U(SCH_1):SGPIO_DEBUG_PLD_DOUT
 B15 SGPIO_DEBUG_PLD_CLK  PT38B @S9S_MB_2U_LIB.S9S_MB_2U(SCH_1):SGPIO_DEBUG_PLD_CLK
 C15 SGPIO_DEBUG_PLD_DIN  PT38C @S9S_MB_2U_LIB.S9S_MB_2U(SCH_1):SGPIO_DEBUG_PLD_DIN
 D15 SGPIO_DEBUG_PLD_LD_N  PT38D @S9S_MB_2U_LIB.S9S_MB_2U(SCH_1):SGPIO_DEBUG_PLD_LD_N
 A16 SGPIO_OCP_SFF_DATAOUT  PT39A @S9S_MB_2U_LIB.S9S_MB_2U(SCH_1):SGPIO_OCP_SFF_DATAOUT
 B17 SGPIO_OCP_SFF_CLK  PT39B @S9S_MB_2U_LIB.S9S_MB_2U(SCH_1):SGPIO_OCP_SFF_CLK
 C17 SGPIO_OCP_SFF_DATAIN  PT39C @S9S_MB_2U_LIB.S9S_MB_2U(SCH_1):SGPIO_OCP_SFF_DATAIN
 D16 SGPIO_OCP_SFF_LD_N  PT39D @S9S_MB_2U_LIB.S9S_MB_2U(SCH_1):SGPIO_OCP_SFF_LD_N
 A17 SGPIO_OCP_V3_2_DATAOUT  PT40A @S9S_MB_2U_LIB.S9S_MB_2U(SCH_1):SGPIO_OCP_V3_2_DATAOUT
 B18 SGPIO_OCP_V3_2_CLK  PT40B @S9S_MB_2U_LIB.S9S_MB_2U(SCH_1):SGPIO_OCP_V3_2_CLK
 E16 SGPIO_OCP_V3_2_DATAIN  PT40C @S9S_MB_2U_LIB.S9S_MB_2U(SCH_1):SGPIO_OCP_V3_2_DATAIN
 D17 SGPIO_OCP_V3_2_LD_N  PT40D @S9S_MB_2U_LIB.S9S_MB_2U(SCH_1):SGPIO_OCP_V3_2_LD_N
 C18 JTAG_BMC_SW_PLD_OE  PT41C @S9S_MB_2U_LIB.S9S_MB_2U(SCH_1):JTAG_BMC_SW_PLD_OE
 D18 NC_FPGA_PT41D  PT41D @S9S_MB_2U_LIB.S9S_MB_2U(SCH_1):NC_FPGA_PT41D
 A19 P12V_HSC_TEMP_ALERT_R_N  PT42A @S9S_MB_2U_LIB.S9S_MB_2U(SCH_1):P12V_HSC_TEMP_ALERT_R_N
 B20 P12V_HSC_T_CRIT_R_N  PT42B @S9S_MB_2U_LIB.S9S_MB_2U(SCH_1):P12V_HSC_T_CRIT_R_N
 F15 RST_SRST_PLD_BMC_R_N  PT42C @S9S_MB_2U_LIB.S9S_MB_2U(SCH_1):RST_SRST_PLD_BMC_R_N
 G15 NC_FPGA_PT42D  PT42D @S9S_MB_2U_LIB.S9S_MB_2U(SCH_1):NC_FPGA_PT42D
 C19 NC_FPGA_PT43C  PT43C @S9S_MB_2U_LIB.S9S_MB_2U(SCH_1):NC_FPGA_PT43C
 C20 NC_FPGA_PT43D  PT43D @S9S_MB_2U_LIB.S9S_MB_2U(SCH_1):NC_FPGA_PT43D

Q_RES_0402LF-33.2,1%,1/16W,CHIA  I197  R4714
   1 SMB_HOST_3V3AUX_SDA_R4      A @S9S_MB_2U_LIB.S9S_MB_2U(SCH_1):SMB_HOST_3V3AUX_SDA_R4
   2 SMB_HOST_3V3AUX_PLD_SDA      B @S9S_MB_2U_LIB.S9S_MB_2U(SCH_1):SMB_HOST_3V3AUX_PLD_SDA

Q_RES_0402LF-33.2,1%,1/16W,CHIA  I198  R4715
   1 SMB_HOST_3V3AUX_SCL_R4      A @S9S_MB_2U_LIB.S9S_MB_2U(SCH_1):SMB_HOST_3V3AUX_SCL_R4
   2 SMB_HOST_3V3AUX_PLD_SCL      B @S9S_MB_2U_LIB.S9S_MB_2U(SCH_1):SMB_HOST_3V3AUX_PLD_SCL


DRAWING: @S9S_MB_2U_LIB.S9S_MB_2U(SCH_1):PAGE312 

LCMXO3LF9400C5BG484C-LCMXO3LF-A  I1  U249
 AA2 FM_ADR_ACK_R   PB5A @S9S_MB_2U_LIB.S9S_MB_2U(SCH_1):FM_ADR_ACK_R
 AB2 FM_UV_ADR_TRIGGER_R_N   PB5B @S9S_MB_2U_LIB.S9S_MB_2U(SCH_1):FM_UV_ADR_TRIGGER_R_N
  V6 FM_ADR_TRIGGER_N   PB5C @S9S_MB_2U_LIB.S9S_MB_2U(SCH_1):FM_ADR_TRIGGER_N
  U6 FM_ADR_COMPLETE   PB5D @S9S_MB_2U_LIB.S9S_MB_2U(SCH_1):FM_ADR_COMPLETE
 AA3 FM_ADR_MODE0_R PB7A||CSSPIN @S9S_MB_2U_LIB.S9S_MB_2U(SCH_1):FM_ADR_MODE0_R
 AB3 FM_ADR_MODE1_R   PB7B @S9S_MB_2U_LIB.S9S_MB_2U(SCH_1):FM_ADR_MODE1_R
  Y4 IRQ_UV_DETECT_R_N   PB7C @S9S_MB_2U_LIB.S9S_MB_2U(SCH_1):IRQ_UV_DETECT_R_N
  W5 NC_FPGA_PB7D   PB7D @S9S_MB_2U_LIB.S9S_MB_2U(SCH_1):NC_FPGA_PB7D
  U7 FM_PLD_CLKS_DEV_R_EN   PB8C @S9S_MB_2U_LIB.S9S_MB_2U(SCH_1):FM_PLD_CLKS_DEV_R_EN
  T8 FM_PLD_CLK_25M_R_EN   PB8D @S9S_MB_2U_LIB.S9S_MB_2U(SCH_1):FM_PLD_CLK_25M_R_EN
 AA4 IRQ_PVCCD_CPU0_VRHOT_LVC3_N   PB8A @S9S_MB_2U_LIB.S9S_MB_2U(SCH_1):IRQ_PVCCD_CPU0_VRHOT_LVC3_N
 AB4 IRQ_BMC_PCH_NMI_R   PB8B @S9S_MB_2U_LIB.S9S_MB_2U(SCH_1):IRQ_BMC_PCH_NMI_R
 AA5 PWRGD_PLT_AUX_CPU0_LVT3_R  PB10A @S9S_MB_2U_LIB.S9S_MB_2U(SCH_1):PWRGD_PLT_AUX_CPU0_LVT3_R
 AB5 PWRGD_PLT_AUX_CPU1_LVT3_R  PB10B @S9S_MB_2U_LIB.S9S_MB_2U(SCH_1):PWRGD_PLT_AUX_CPU1_LVT3_R
  Y5 PCIE_M2_SSD0_PRSNT_N  PB10C @S9S_MB_2U_LIB.S9S_MB_2U(SCH_1):PCIE_M2_SSD0_PRSNT_N
  Y6 FM_HBM2_HBM3_VPP_SEL  PB10D @S9S_MB_2U_LIB.S9S_MB_2U(SCH_1):FM_HBM2_HBM3_VPP_SEL
  V8 FM_REMOTE_DEBUG_DET  PB13C @S9S_MB_2U_LIB.S9S_MB_2U(SCH_1):FM_REMOTE_DEBUG_DET
  U8 FM_BMC_DBP_PRESENT_R_N  PB13D @S9S_MB_2U_LIB.S9S_MB_2U(SCH_1):FM_BMC_DBP_PRESENT_R_N
  T9 FM_BIOS_POST_CMPLT_BMC_N PB16A||MCLK||CCLK @S9S_MB_2U_LIB.S9S_MB_2U(SCH_1):FM_BIOS_POST_CMPLT_BMC_N
  U9 FM_BMC_RSTBTN_OUT_N PB16B||SO||SPISO @S9S_MB_2U_LIB.S9S_MB_2U(SCH_1):FM_BMC_RSTBTN_OUT_N
 AA8 FM_CPU_RMCA_CATERR_LVT3_R_N  PB18A @S9S_MB_2U_LIB.S9S_MB_2U(SCH_1):FM_CPU_RMCA_CATERR_LVT3_R_N
 AB8 FM_PCH_BMC_THERMTRIP_N  PB18B @S9S_MB_2U_LIB.S9S_MB_2U(SCH_1):FM_PCH_BMC_THERMTRIP_N
 V10 E1S_0_PRSNT_N  PB21A @S9S_MB_2U_LIB.S9S_MB_2U(SCH_1):E1S_0_PRSNT_N
 W10 HSC_D_OC_R1  PB21B @S9S_MB_2U_LIB.S9S_MB_2U(SCH_1):HSC_D_OC_R1
AA10 CLK_25M_OSC_MAIN_FPGA PB22A||PCLKT2_0 @S9S_MB_2U_LIB.S9S_MB_2U(SCH_1):CLK_25M_OSC_MAIN_FPGA
AB10 NC_FPGA_PB22B PB22B||PCLKC2_0 @S9S_MB_2U_LIB.S9S_MB_2U(SCH_1):NC_FPGA_PB22B
AA11 PRSNT_CABLE_GPU_B3_ISO_R_N  PB24A @S9S_MB_2U_LIB.S9S_MB_2U(SCH_1):PRSNT_CABLE_GPU_B3_ISO_R_N
AB11 GPU_3V3IO_RSVD3_FFU_ISO_R  PB24B @S9S_MB_2U_LIB.S9S_MB_2U(SCH_1):GPU_3V3IO_RSVD3_FFU_ISO_R
 V11 PRSNT_CABLE_GPU_A2_ISO_R_N  PB24C @S9S_MB_2U_LIB.S9S_MB_2U(SCH_1):PRSNT_CABLE_GPU_A2_ISO_R_N
 Y11 GPU_3V3IO_RSVD5_FFU_ISO_R  PB24D @S9S_MB_2U_LIB.S9S_MB_2U(SCH_1):GPU_3V3IO_RSVD5_FFU_ISO_R
AB12 IRQ_SGPIO_INTR_N_R PB29A||PCLKT2_1 @S9S_MB_2U_LIB.S9S_MB_2U(SCH_1):IRQ_SGPIO_INTR_N_R
AA12 IRQ_PSYS_CRIT_N PB29B||PCLKC2_1 @S9S_MB_2U_LIB.S9S_MB_2U(SCH_1):IRQ_PSYS_CRIT_N
AB13 IRQ_TPM_SPI_N  PB30A @S9S_MB_2U_LIB.S9S_MB_2U(SCH_1):IRQ_TPM_SPI_N
AA13 IRQ_PVCCD_CPU1_VRHOT_LVC3_N  PB30B @S9S_MB_2U_LIB.S9S_MB_2U(SCH_1):IRQ_PVCCD_CPU1_VRHOT_LVC3_N
AB14 RST_PLTRST_PLD_B_N  PB33A @S9S_MB_2U_LIB.S9S_MB_2U(SCH_1):RST_PLTRST_PLD_B_N
AA14 FM_SYS_THROTTLE_R_N  PB33B @S9S_MB_2U_LIB.S9S_MB_2U(SCH_1):FM_SYS_THROTTLE_R_N
AB19 CLK_GEN2_BMC_RC_OE_N  PB43A @S9S_MB_2U_LIB.S9S_MB_2U(SCH_1):CLK_GEN2_BMC_RC_OE_N
AA19 FM_PLD_REV_N  PB43B @S9S_MB_2U_LIB.S9S_MB_2U(SCH_1):FM_PLD_REV_N
AB20 HGX_DETECT_N_R  PB44A @S9S_MB_2U_LIB.S9S_MB_2U(SCH_1):HGX_DETECT_N_R
AA20 HPDB_HSC_PWRGD_ISO_R  PB44B @S9S_MB_2U_LIB.S9S_MB_2U(SCH_1):HPDB_HSC_PWRGD_ISO_R
AB21 PULL_FPGA_PB46A PB46A||SN @S9S_MB_2U_LIB.S9S_MB_2U(SCH_1):PULL_FPGA_PB46A
AA21 NC_FPGA_PB46B PB46B||SI||SISPI @S9S_MB_2U_LIB.S9S_MB_2U(SCH_1):NC_FPGA_PB46B
AB15 FM_SPD_REMOTE_EN_R  PB35A @S9S_MB_2U_LIB.S9S_MB_2U(SCH_1):FM_SPD_REMOTE_EN_R
AA15 NC_FPGA_PB35B  PB35B @S9S_MB_2U_LIB.S9S_MB_2U(SCH_1):NC_FPGA_PB35B
 AA6 RST_MB_STBY_R_N  PB11A @S9S_MB_2U_LIB.S9S_MB_2U(SCH_1):RST_MB_STBY_R_N
 AB6 RST_SMB_SWITCH_N  PB11B @S9S_MB_2U_LIB.S9S_MB_2U(SCH_1):RST_SMB_SWITCH_N
  W6 RST_PFR_OVR_RTC_R  PB11C @S9S_MB_2U_LIB.S9S_MB_2U(SCH_1):RST_PFR_OVR_RTC_R
  V7 RST_PFR_OVR_SRTC_R  PB11D @S9S_MB_2U_LIB.S9S_MB_2U(SCH_1):RST_PFR_OVR_SRTC_R
 AA7 FM_DIS_PS_PWROK_DLY  PB13A @S9S_MB_2U_LIB.S9S_MB_2U(SCH_1):FM_DIS_PS_PWROK_DLY
 AB7 FM_PCH_CRASHLOG_TRIG_R_N  PB13B @S9S_MB_2U_LIB.S9S_MB_2U(SCH_1):FM_PCH_CRASHLOG_TRIG_R_N
  V9 FM_PS_PWROK_DLY_SEL  PB16C @S9S_MB_2U_LIB.S9S_MB_2U(SCH_1):FM_PS_PWROK_DLY_SEL
  W8 FM_RST_PERST_BIT2  PB16D @S9S_MB_2U_LIB.S9S_MB_2U(SCH_1):FM_RST_PERST_BIT2
  Y8 FM_ME_AUTHN_FAIL  PB18C @S9S_MB_2U_LIB.S9S_MB_2U(SCH_1):FM_ME_AUTHN_FAIL
  W9 USB_OC1_REAR_N  PB18D @S9S_MB_2U_LIB.S9S_MB_2U(SCH_1):USB_OC1_REAR_N
 AA9 JTAG_DBP_BMC_PRDY_R_N  PB19A @S9S_MB_2U_LIB.S9S_MB_2U(SCH_1):JTAG_DBP_BMC_PRDY_R_N
 AB9 FM_DEBUG_PORT_PRSNT_N  PB19B @S9S_MB_2U_LIB.S9S_MB_2U(SCH_1):FM_DEBUG_PORT_PRSNT_N
 T10 FM_PLD_HEARTBEAT_LVC3  PB19C @S9S_MB_2U_LIB.S9S_MB_2U(SCH_1):FM_PLD_HEARTBEAT_LVC3
 U10 FM_FORCE_PWRON_LVC3  PB19D @S9S_MB_2U_LIB.S9S_MB_2U(SCH_1):FM_FORCE_PWRON_LVC3
 T11 GPU_3V3IO_RSVD0_FFU_ISO_R  PB22C @S9S_MB_2U_LIB.S9S_MB_2U(SCH_1):GPU_3V3IO_RSVD0_FFU_ISO_R
 U11 GPU_3V3IO_RSVD1_FFU_ISO_R  PB22D @S9S_MB_2U_LIB.S9S_MB_2U(SCH_1):GPU_3V3IO_RSVD1_FFU_ISO_R
 Y12 PRSNT_CABLE_GPU_A1_ISO_R_N  PB27A @S9S_MB_2U_LIB.S9S_MB_2U(SCH_1):PRSNT_CABLE_GPU_A1_ISO_R_N
 T12 GPU_3V3IO_RSVD1_ISO_R  PB27B @S9S_MB_2U_LIB.S9S_MB_2U(SCH_1):GPU_3V3IO_RSVD1_ISO_R
 U12 GPU_3V3IO_RSVD3_ISO_R  PB27C @S9S_MB_2U_LIB.S9S_MB_2U(SCH_1):GPU_3V3IO_RSVD3_ISO_R
 V12 GPU_3V3IO_RSVD4_ISO_R  PB27D @S9S_MB_2U_LIB.S9S_MB_2U(SCH_1):GPU_3V3IO_RSVD4_ISO_R
 V13 IRQ_PCH_CPU_NMI_EVENT_N  PB29C @S9S_MB_2U_LIB.S9S_MB_2U(SCH_1):IRQ_PCH_CPU_NMI_EVENT_N
 U13 IRQ_BMC_CPU_NMI_R1  PB29D @S9S_MB_2U_LIB.S9S_MB_2U(SCH_1):IRQ_BMC_CPU_NMI_R1
 Y13 IRQ_PSU_ALERT_R_N  PB30C @S9S_MB_2U_LIB.S9S_MB_2U(SCH_1):IRQ_PSU_ALERT_R_N
 W13 IRQ_PCH_SCI_WHEA_R_N  PB30D @S9S_MB_2U_LIB.S9S_MB_2U(SCH_1):IRQ_PCH_SCI_WHEA_R_N
 Y14 FM_NCSI_OCP_V3_1_R_OE  PB33C @S9S_MB_2U_LIB.S9S_MB_2U(SCH_1):FM_NCSI_OCP_V3_1_R_OE
 W14 FM_BIOS_DEBUG_EN_N  PB33D @S9S_MB_2U_LIB.S9S_MB_2U(SCH_1):FM_BIOS_DEBUG_EN_N
 T13 RST_SGPIO_RESET_N_R  PB32A @S9S_MB_2U_LIB.S9S_MB_2U(SCH_1):RST_SGPIO_RESET_N_R
 T14 FM_ME_BT_DONE  PB32B @S9S_MB_2U_LIB.S9S_MB_2U(SCH_1):FM_ME_BT_DONE
 U14 RST_PCIE_PCH_DEV_PERST_N  PB32C @S9S_MB_2U_LIB.S9S_MB_2U(SCH_1):RST_PCIE_PCH_DEV_PERST_N
 V14 NC_FPGA_PB32D  PB32D @S9S_MB_2U_LIB.S9S_MB_2U(SCH_1):NC_FPGA_PB32D
 Y15 FM_THROTTLE_R_N  PB35C @S9S_MB_2U_LIB.S9S_MB_2U(SCH_1):FM_THROTTLE_R_N
 W15 FM_DIMM_12V_CPS_SX_N  PB35D @S9S_MB_2U_LIB.S9S_MB_2U(SCH_1):FM_DIMM_12V_CPS_SX_N
AB16 VIRTUAL_RESEAT  PB38A @S9S_MB_2U_LIB.S9S_MB_2U(SCH_1):VIRTUAL_RESEAT
AA16 FM_PCH_PLD_GLB_RST_WARN_N  PB38B @S9S_MB_2U_LIB.S9S_MB_2U(SCH_1):FM_PCH_PLD_GLB_RST_WARN_N
 V15 ROT_P1_RST_IND_N_R  PB38C @S9S_MB_2U_LIB.S9S_MB_2U(SCH_1):ROT_P1_RST_IND_N_R
 U15 FM_SLPS3_PLD_N  PB38D @S9S_MB_2U_LIB.S9S_MB_2U(SCH_1):FM_SLPS3_PLD_N
AB17 FM_PCHHOT_R_N  PB40A @S9S_MB_2U_LIB.S9S_MB_2U(SCH_1):FM_PCHHOT_R_N
AA17 FM_BMC_READY_R_PLD_N  PB40B @S9S_MB_2U_LIB.S9S_MB_2U(SCH_1):FM_BMC_READY_R_PLD_N
 Y17 RST_PLTRST_PLD_N  PB40C @S9S_MB_2U_LIB.S9S_MB_2U(SCH_1):RST_PLTRST_PLD_N
 V16 RST_RSMRST_PLD_R_N  PB40D @S9S_MB_2U_LIB.S9S_MB_2U(SCH_1):RST_RSMRST_PLD_R_N
AB18 JTAG_DBP_BMC_PREQ_R_N  PB41A @S9S_MB_2U_LIB.S9S_MB_2U(SCH_1):JTAG_DBP_BMC_PREQ_R_N
AA18 CLK_GPU_1_OE_N  PB41B @S9S_MB_2U_LIB.S9S_MB_2U(SCH_1):CLK_GPU_1_OE_N
 Y18 CLK_GPU_2_OE_N  PB41C @S9S_MB_2U_LIB.S9S_MB_2U(SCH_1):CLK_GPU_2_OE_N
 W17 CLK_SWB_OE_N  PB41D @S9S_MB_2U_LIB.S9S_MB_2U(SCH_1):CLK_SWB_OE_N
 T15 CLK_SWB_BUF2_OE_N  PB43C @S9S_MB_2U_LIB.S9S_MB_2U(SCH_1):CLK_SWB_BUF2_OE_N
 U16 NC_FPGA_PB43D  PB43D @S9S_MB_2U_LIB.S9S_MB_2U(SCH_1):NC_FPGA_PB43D
 Y19 SWB_HSC_EN_R  PB44C @S9S_MB_2U_LIB.S9S_MB_2U(SCH_1):SWB_HSC_EN_R
 W18 SWB_HSC_PWRGD_ISO_R  PB44D @S9S_MB_2U_LIB.S9S_MB_2U(SCH_1):SWB_HSC_PWRGD_ISO_R
 V17 FM_PDB_BUF_EN  PB46C @S9S_MB_2U_LIB.S9S_MB_2U(SCH_1):FM_PDB_BUF_EN
 T16 FM_AC_PWR_BTN_PLD_ISO_N  PB46D @S9S_MB_2U_LIB.S9S_MB_2U(SCH_1):FM_AC_PWR_BTN_PLD_ISO_N
  Y9 PRSNT_SWB_ISO_R_N  PB21C @S9S_MB_2U_LIB.S9S_MB_2U(SCH_1):PRSNT_SWB_ISO_R_N
 Y10 FM_PCH_BMC_RST_N  PB21D @S9S_MB_2U_LIB.S9S_MB_2U(SCH_1):FM_PCH_BMC_RST_N

Q_RES_0402LF-10K,1%,1/16W,EMPTA  I3  R1465
   1 P3V3_AUX      A @S9S_MB_2U_LIB.S9S_MB_2U(SCH_1):P3V3_AUX
   2 IRQ_BMC_CPU_NMI_R1      B @S9S_MB_2U_LIB.S9S_MB_2U(SCH_1):IRQ_BMC_CPU_NMI_R1

Q_RES_0402LF-10K,1%,1/16W,CHIPA  I5  R1106
   1 P3V3_AUX      A @S9S_MB_2U_LIB.S9S_MB_2U(SCH_1):P3V3_AUX
   2 FM_PLD_REV_R_N      B @S9S_MB_2U_LIB.S9S_MB_2U(SCH_1):FM_PLD_REV_R_N

Q_RES_0402LF-49.9,1%,1/16W,CHIA  I38  R1710
   1 FM_PLD_REV_N      A @S9S_MB_2U_LIB.S9S_MB_2U(SCH_1):FM_PLD_REV_N
   2 FM_PLD_REV_R_N      B @S9S_MB_2U_LIB.S9S_MB_2U(SCH_1):FM_PLD_REV_R_N

Q_CAP_0402-0.1UF,25V,10%,X7R,CA  I39  C1325
   1 FM_PLD_REV_N      A @S9S_MB_2U_LIB.S9S_MB_2U(SCH_1):FM_PLD_REV_N
   2    GND      B @S9S_MB_2U_LIB.S9S_MB_2U(SCH_1):GND

Q_RES_0402LF-0,5%,1/16W,CHIP,CA  I80  R4056
   1 HSC_D_OC      A @S9S_MB_2U_LIB.S9S_MB_2U(SCH_1):HSC_D_OC
   2 HSC_D_OC_R1      B @S9S_MB_2U_LIB.S9S_MB_2U(SCH_1):HSC_D_OC_R1

Q_RES_0402LF-10K,1%,1/16W,CHIPA  I86  R4086
   1 P3V3_AUX_FPGA_VCCIO2      A @S9S_MB_2U_LIB.S9S_MB_2U(SCH_1):P3V3_AUX_FPGA_VCCIO2
   2 PULL_FPGA_PB46A      B @S9S_MB_2U_LIB.S9S_MB_2U(SCH_1):PULL_FPGA_PB46A

Q_RES_0402LF-33.2,1%,1/16W,CHIA  I89  R4143
   1 GPU_3V3IO_RSVD0_FFU_ISO      A @S9S_MB_2U_LIB.S9S_MB_2U(SCH_1):GPU_3V3IO_RSVD0_FFU_ISO
   2 GPU_3V3IO_RSVD0_FFU_ISO_R      B @S9S_MB_2U_LIB.S9S_MB_2U(SCH_1):GPU_3V3IO_RSVD0_FFU_ISO_R

Q_RES_0402LF-33.2,1%,1/16W,CHIA  I93  R4144
   1 GPU_3V3IO_RSVD1_FFU_ISO      A @S9S_MB_2U_LIB.S9S_MB_2U(SCH_1):GPU_3V3IO_RSVD1_FFU_ISO
   2 GPU_3V3IO_RSVD1_FFU_ISO_R      B @S9S_MB_2U_LIB.S9S_MB_2U(SCH_1):GPU_3V3IO_RSVD1_FFU_ISO_R

Q_RES_0402LF-33.2,1%,1/16W,CHIA  I97  R4145
   1 PRSNT_CABLE_GPU_B3_ISO_N      A @S9S_MB_2U_LIB.S9S_MB_2U(SCH_1):PRSNT_CABLE_GPU_B3_ISO_N
   2 PRSNT_CABLE_GPU_B3_ISO_R_N      B @S9S_MB_2U_LIB.S9S_MB_2U(SCH_1):PRSNT_CABLE_GPU_B3_ISO_R_N

Q_RES_0402LF-33.2,1%,1/16W,CHIA  I98  R4146
   1 GPU_3V3IO_RSVD3_FFU_ISO      A @S9S_MB_2U_LIB.S9S_MB_2U(SCH_1):GPU_3V3IO_RSVD3_FFU_ISO
   2 GPU_3V3IO_RSVD3_FFU_ISO_R      B @S9S_MB_2U_LIB.S9S_MB_2U(SCH_1):GPU_3V3IO_RSVD3_FFU_ISO_R

Q_RES_0402LF-33.2,1%,1/16W,CHIA  I103  R4148
   1 GPU_3V3IO_RSVD5_FFU_ISO      A @S9S_MB_2U_LIB.S9S_MB_2U(SCH_1):GPU_3V3IO_RSVD5_FFU_ISO
   2 GPU_3V3IO_RSVD5_FFU_ISO_R      B @S9S_MB_2U_LIB.S9S_MB_2U(SCH_1):GPU_3V3IO_RSVD5_FFU_ISO_R

Q_RES_0402LF-33.2,1%,1/16W,CHIA  I104  R4147
   1 PRSNT_CABLE_GPU_A2_ISO_N      A @S9S_MB_2U_LIB.S9S_MB_2U(SCH_1):PRSNT_CABLE_GPU_A2_ISO_N
   2 PRSNT_CABLE_GPU_A2_ISO_R_N      B @S9S_MB_2U_LIB.S9S_MB_2U(SCH_1):PRSNT_CABLE_GPU_A2_ISO_R_N

Q_RES_0402LF-33.2,1%,1/16W,CHIA  I114  R4157
   1 PRSNT_CABLE_GPU_A1_ISO_N      A @S9S_MB_2U_LIB.S9S_MB_2U(SCH_1):PRSNT_CABLE_GPU_A1_ISO_N
   2 PRSNT_CABLE_GPU_A1_ISO_R_N      B @S9S_MB_2U_LIB.S9S_MB_2U(SCH_1):PRSNT_CABLE_GPU_A1_ISO_R_N

Q_RES_0402LF-33.2,1%,1/16W,CHIA  I120  R4170
   1 GPU_3V3IO_RSVD1_ISO      A @S9S_MB_2U_LIB.S9S_MB_2U(SCH_1):GPU_3V3IO_RSVD1_ISO
   2 GPU_3V3IO_RSVD1_ISO_R      B @S9S_MB_2U_LIB.S9S_MB_2U(SCH_1):GPU_3V3IO_RSVD1_ISO_R

Q_RES_0402LF-33.2,1%,1/16W,CHIA  I121  R4171
   1 GPU_3V3IO_RSVD3_ISO      A @S9S_MB_2U_LIB.S9S_MB_2U(SCH_1):GPU_3V3IO_RSVD3_ISO
   2 GPU_3V3IO_RSVD3_ISO_R      B @S9S_MB_2U_LIB.S9S_MB_2U(SCH_1):GPU_3V3IO_RSVD3_ISO_R

Q_RES_0402LF-33.2,1%,1/16W,CHIA  I122  R4172
   1 GPU_3V3IO_RSVD4_ISO      A @S9S_MB_2U_LIB.S9S_MB_2U(SCH_1):GPU_3V3IO_RSVD4_ISO
   2 GPU_3V3IO_RSVD4_ISO_R      B @S9S_MB_2U_LIB.S9S_MB_2U(SCH_1):GPU_3V3IO_RSVD4_ISO_R

Q_RES_0402LF-33.2,1%,1/16W,CHIA  I134  R4174
   1 RST_PCIE_PCH_DEV_PERST_N      A @S9S_MB_2U_LIB.S9S_MB_2U(SCH_1):RST_PCIE_PCH_DEV_PERST_N
   2 RST_PCIE_PCH_DEV_PERST_E1S_R_N      B @S9S_MB_2U_LIB.S9S_MB_2U(SCH_1):RST_PCIE_PCH_DEV_PERST_E1S_R_N

Q_RES_0402LF-33.2,1%,1/16W,CHIA  I135  R4175
   1 RST_PCIE_PCH_DEV_PERST_N      A @S9S_MB_2U_LIB.S9S_MB_2U(SCH_1):RST_PCIE_PCH_DEV_PERST_N
   2 RST_PCIE_PCH_DEV_PERST_M2_R_N      B @S9S_MB_2U_LIB.S9S_MB_2U(SCH_1):RST_PCIE_PCH_DEV_PERST_M2_R_N

Q_RES_0402LF-33.2,1%,1/16W,CHIA  I143  R4556
   1 HGX_DETECT_N_R      A @S9S_MB_2U_LIB.S9S_MB_2U(SCH_1):HGX_DETECT_N_R
   2 HGX_DETECT_N      B @S9S_MB_2U_LIB.S9S_MB_2U(SCH_1):HGX_DETECT_N

Q_RES_0402LF-33.2,1%,1/16W,CHIA  I145  R4557
   1 HPDB_HSC_PWRGD_ISO      A @S9S_MB_2U_LIB.S9S_MB_2U(SCH_1):HPDB_HSC_PWRGD_ISO
   2 HPDB_HSC_PWRGD_ISO_R      B @S9S_MB_2U_LIB.S9S_MB_2U(SCH_1):HPDB_HSC_PWRGD_ISO_R

Q_RES_0402LF-33.2,1%,1/16W,CHIA  I150  R4558
   1 SWB_HSC_EN      A @S9S_MB_2U_LIB.S9S_MB_2U(SCH_1):SWB_HSC_EN
   2 SWB_HSC_EN_R      B @S9S_MB_2U_LIB.S9S_MB_2U(SCH_1):SWB_HSC_EN_R

Q_RES_0402LF-33.2,1%,1/16W,CHIA  I158  R4563
   1 SWB_HSC_PWRGD_ISO_R      A @S9S_MB_2U_LIB.S9S_MB_2U(SCH_1):SWB_HSC_PWRGD_ISO_R
   2 SWB_HSC_PWRGD_ISO      B @S9S_MB_2U_LIB.S9S_MB_2U(SCH_1):SWB_HSC_PWRGD_ISO

Q_RES_0402LF-0,5%,1/16W,CHIP,CA  I164  R3045
   1 IRQ_UV_DETECT_N      A @S9S_MB_2U_LIB.S9S_MB_2U(SCH_1):IRQ_UV_DETECT_N
   2 IRQ_UV_DETECT_R_N      B @S9S_MB_2U_LIB.S9S_MB_2U(SCH_1):IRQ_UV_DETECT_R_N

Q_RES_0402LF-0,5%,1/16W,CHIP,CA  I165  R3046
   1 FM_UV_ADR_TRIGGER_N      A @S9S_MB_2U_LIB.S9S_MB_2U(SCH_1):FM_UV_ADR_TRIGGER_N
   2 FM_UV_ADR_TRIGGER_R_N      B @S9S_MB_2U_LIB.S9S_MB_2U(SCH_1):FM_UV_ADR_TRIGGER_R_N

Q_RES_0402LF-0,5%,1/16W,CHIP,CA  I169  R700
   1 FM_ADR_ACK_R      A @S9S_MB_2U_LIB.S9S_MB_2U(SCH_1):FM_ADR_ACK_R
   2 FM_ADR_ACK      B @S9S_MB_2U_LIB.S9S_MB_2U(SCH_1):FM_ADR_ACK

Q_RES_0402LF-0,5%,1/16W,CHIP,CA  I170  R1944
   1 IRQ_PCH_SCI_WHEA_R_N      A @S9S_MB_2U_LIB.S9S_MB_2U(SCH_1):IRQ_PCH_SCI_WHEA_R_N
   2 IRQ_PCH_SCI_WHEA_N      B @S9S_MB_2U_LIB.S9S_MB_2U(SCH_1):IRQ_PCH_SCI_WHEA_N

Q_RES_0402LF-0,5%,1/16W,CHIP,CA  I176  R3049
   1 IRQ_SML1_PMBUS_ALERT_N      A @S9S_MB_2U_LIB.S9S_MB_2U(SCH_1):IRQ_SML1_PMBUS_ALERT_N
   2 IRQ_PSU_ALERT_R_N      B @S9S_MB_2U_LIB.S9S_MB_2U(SCH_1):IRQ_PSU_ALERT_R_N

Q_RES_0402LF-0,5%,1/16W,CHIP,CA  I177  R2155
   1 FM_BMC_READY_R_PLD_N      A @S9S_MB_2U_LIB.S9S_MB_2U(SCH_1):FM_BMC_READY_R_PLD_N
   2 FM_BMC_READY_R_N      B @S9S_MB_2U_LIB.S9S_MB_2U(SCH_1):FM_BMC_READY_R_N

Q_RES_0402LF-0,5%,1/16W,CHIP,CA  I178  R2792
   1 FM_PDB_BUF_EN      A @S9S_MB_2U_LIB.S9S_MB_2U(SCH_1):FM_PDB_BUF_EN
   2 FM_PDB_BUF_EN_R      B @S9S_MB_2U_LIB.S9S_MB_2U(SCH_1):FM_PDB_BUF_EN_R

Q_RES_0402LF-0,5%,1/16W,CHIP,CA  I183  R2347
   1 FM_REMOTE_DEBUG_DET_R      A @S9S_MB_2U_LIB.S9S_MB_2U(SCH_1):FM_REMOTE_DEBUG_DET_R
   2 FM_REMOTE_DEBUG_DET      B @S9S_MB_2U_LIB.S9S_MB_2U(SCH_1):FM_REMOTE_DEBUG_DET

Q_RES_0402LF-0,5%,1/16W,CHIP,CA  I184  R2348
   1 FM_DEBUG_PORT_PRSNT_N      A @S9S_MB_2U_LIB.S9S_MB_2U(SCH_1):FM_DEBUG_PORT_PRSNT_N
   2 FM_DEBUG_PORT_PRSNT_R_N      B @S9S_MB_2U_LIB.S9S_MB_2U(SCH_1):FM_DEBUG_PORT_PRSNT_R_N

CONN3_210HP1030BR1-CONN3_210-HB  I187  JP15
   3 PD_FORCE_PWRON      3 @S9S_MB_2U_LIB.S9S_MB_2U(SCH_1):PD_FORCE_PWRON
   2 FM_FORCE_PWRON_LVC3      2 @S9S_MB_2U_LIB.S9S_MB_2U(SCH_1):FM_FORCE_PWRON_LVC3
   1 PU_FORCE_PWRON      1 @S9S_MB_2U_LIB.S9S_MB_2U(SCH_1):PU_FORCE_PWRON

Q_RES_0402LF-10K,1%,1/16W,CHIPA  I190  R1495
   1 PD_FORCE_PWRON      A @S9S_MB_2U_LIB.S9S_MB_2U(SCH_1):PD_FORCE_PWRON
   2    GND      B @S9S_MB_2U_LIB.S9S_MB_2U(SCH_1):GND

Q_RES_0402LF-1K,1%,1/16W,CHIP,A  I191  R1493
   1 P3V3_AUX      A @S9S_MB_2U_LIB.S9S_MB_2U(SCH_1):P3V3_AUX
   2 PU_FORCE_PWRON      B @S9S_MB_2U_LIB.S9S_MB_2U(SCH_1):PU_FORCE_PWRON

Q_RES_0402LF-33.2,1%,1/16W,CHIA  I213  R4723
   1 FM_PCH_BMC_RST_R_N      A @S9S_MB_2U_LIB.S9S_MB_2U(SCH_1):FM_PCH_BMC_RST_R_N
   2 FM_PCH_BMC_RST_N      B @S9S_MB_2U_LIB.S9S_MB_2U(SCH_1):FM_PCH_BMC_RST_N

Q_RES_0402LF-33.2,1%,1/16W,CHIA  I217  R4057
   1 PRSNT_SWB_ISO_N      A @S9S_MB_2U_LIB.S9S_MB_2U(SCH_1):PRSNT_SWB_ISO_N
   2 PRSNT_SWB_ISO_R_N      B @S9S_MB_2U_LIB.S9S_MB_2U(SCH_1):PRSNT_SWB_ISO_R_N


DRAWING: @S9S_MB_2U_LIB.S9S_MB_2U(SCH_1):PAGE311 

Q_RES_0402LF-1K,1%,1/16W,CHIP,A  I4  R1823
   1 P3V3_AUX      A @S9S_MB_2U_LIB.S9S_MB_2U(SCH_1):P3V3_AUX
   2 RST_MB_STBY_R_N      B @S9S_MB_2U_LIB.S9S_MB_2U(SCH_1):RST_MB_STBY_R_N

Q_RES_0402LF-10K,1%,1/16W,CHIPA  I29  R3249
   1 P3V3_AUX      A @S9S_MB_2U_LIB.S9S_MB_2U(SCH_1):P3V3_AUX
   2 PU_FPGA_D12_PROGRAMN      B @S9S_MB_2U_LIB.S9S_MB_2U(SCH_1):PU_FPGA_D12_PROGRAMN

LCMXO3LF9400C5BG484C-LCMXO3LF-A  I33  U249
  D3 RST_CPU0_DRAM_AB_PLD_LVT3_N   PL2A @S9S_MB_2U_LIB.S9S_MB_2U(SCH_1):RST_CPU0_DRAM_AB_PLD_LVT3_N
  D4 RST_CPU0_DRAM_CD_PLD_LVT3_N   PL2B @S9S_MB_2U_LIB.S9S_MB_2U(SCH_1):RST_CPU0_DRAM_CD_PLD_LVT3_N
  F6 RST_CPU0_DRAM_EF_PLD_LVT3_N   PL2C @S9S_MB_2U_LIB.S9S_MB_2U(SCH_1):RST_CPU0_DRAM_EF_PLD_LVT3_N
  G7 RST_CPU0_DRAM_GH_PLD_LVT3_N   PL2D @S9S_MB_2U_LIB.S9S_MB_2U(SCH_1):RST_CPU0_DRAM_GH_PLD_LVT3_N
  E4 RST_CPU1_DRAM_AB_PLD_LVT3_N PL3A||L_GPLLT_FB @S9S_MB_2U_LIB.S9S_MB_2U(SCH_1):RST_CPU1_DRAM_AB_PLD_LVT3_N
  F5 RST_CPU1_DRAM_CD_PLD_LVT3_N PL3B||L_GPLLC_FB @S9S_MB_2U_LIB.S9S_MB_2U(SCH_1):RST_CPU1_DRAM_CD_PLD_LVT3_N
  G6 RST_CPU1_DRAM_EF_PLD_LVT3_N   PL3C @S9S_MB_2U_LIB.S9S_MB_2U(SCH_1):RST_CPU1_DRAM_EF_PLD_LVT3_N
  H7 RST_CPU1_DRAM_GH_PLD_LVT3_N   PL3D @S9S_MB_2U_LIB.S9S_MB_2U(SCH_1):RST_CPU1_DRAM_GH_PLD_LVT3_N
  C1 RST_PLD_CPU0_DRAM_AB_N PL4A||L_GPLLT_IN @S9S_MB_2U_LIB.S9S_MB_2U(SCH_1):RST_PLD_CPU0_DRAM_AB_N
  D2 RST_PLD_CPU0_DRAM_CD_N PL4B||L_GPLLC_IN @S9S_MB_2U_LIB.S9S_MB_2U(SCH_1):RST_PLD_CPU0_DRAM_CD_N
  G5 RST_PLD_CPU0_DRAM_EF_N   PL4C @S9S_MB_2U_LIB.S9S_MB_2U(SCH_1):RST_PLD_CPU0_DRAM_EF_N
  H6 RST_PLD_CPU0_DRAM_GH_N   PL4D @S9S_MB_2U_LIB.S9S_MB_2U(SCH_1):RST_PLD_CPU0_DRAM_GH_N
  D1 RST_PLD_CPU1_DRAM_AB_N   PL5A @S9S_MB_2U_LIB.S9S_MB_2U(SCH_1):RST_PLD_CPU1_DRAM_AB_N
  E2 RST_PLD_CPU1_DRAM_CD_N   PL5B @S9S_MB_2U_LIB.S9S_MB_2U(SCH_1):RST_PLD_CPU1_DRAM_CD_N
  E3 RST_PLD_CPU1_DRAM_EF_N   PL5C @S9S_MB_2U_LIB.S9S_MB_2U(SCH_1):RST_PLD_CPU1_DRAM_EF_N
  F4 RST_PLD_CPU1_DRAM_GH_N   PL5D @S9S_MB_2U_LIB.S9S_MB_2U(SCH_1):RST_PLD_CPU1_DRAM_GH_N
  L7 HP_LVC3_OCP_V3_1_FUSE_PWRGD  PL13A @S9S_MB_2U_LIB.S9S_MB_2U(SCH_1):HP_LVC3_OCP_V3_1_FUSE_PWRGD
  K5 HP_LVC3_OCP_V3_2_FUSE_PWRGD  PL13B @S9S_MB_2U_LIB.S9S_MB_2U(SCH_1):HP_LVC3_OCP_V3_2_FUSE_PWRGD
  K4 HP_LVC3_OCP_V3_1_PRSNT2_PLD_N  PL13C @S9S_MB_2U_LIB.S9S_MB_2U(SCH_1):HP_LVC3_OCP_V3_1_PRSNT2_PLD_N
  K3 HP_LVC3_OCP_V3_2_PRSNT2_PLD_N  PL13D @S9S_MB_2U_LIB.S9S_MB_2U(SCH_1):HP_LVC3_OCP_V3_2_PRSNT2_PLD_N
  K2 HP_LVC3_E1S_0_HSC_PWRGD_PLD  PL14A @S9S_MB_2U_LIB.S9S_MB_2U(SCH_1):HP_LVC3_E1S_0_HSC_PWRGD_PLD
  K1 HP_E1S_0_P3V3_PWRGD_PLD  PL14B @S9S_MB_2U_LIB.S9S_MB_2U(SCH_1):HP_E1S_0_P3V3_PWRGD_PLD
  L1     NC PL16A||PCLKT4_0     NC
  M2     NC PL16B||PCLKC4_0     NC
  P4     NC  PL20A     NC
  N5     NC  PL20B     NC
  N6     NC  PL20C     NC
  N7     NC  PL20D     NC
  R2     NC  PL21A     NC
  T1     NC  PL21B     NC
  P5 PWRGD_CPUPWRGD_LVC2_R1  PL21C @S9S_MB_2U_LIB.S9S_MB_2U(SCH_1):PWRGD_CPUPWRGD_LVC2_R1
  P6     NC  PL21D     NC
  T5 H_CPU_ERR1_LVC2_N  PL26C @S9S_MB_2U_LIB.S9S_MB_2U(SCH_1):H_CPU_ERR1_LVC2_N
  T6 H_CPU_ERR0_LVC2_N  PL26D @S9S_MB_2U_LIB.S9S_MB_2U(SCH_1):H_CPU_ERR0_LVC2_N
  L6 E1S_0_CLK_OE_N  PL14C @S9S_MB_2U_LIB.S9S_MB_2U(SCH_1):E1S_0_CLK_OE_N
  L5 HP_LVC3_SCM_HSC_PWRGD_PLD  PL14D @S9S_MB_2U_LIB.S9S_MB_2U(SCH_1):HP_LVC3_SCM_HSC_PWRGD_PLD
  L3     NC  PL16C     NC
  L4     NC  PL16D     NC
  G3     NC   PL6C     NC
  G4     NC   PL6D     NC
  E1     NC   PL6A     NC
  F1     NC   PL6B     NC
  T2 H_CPU0_THERMTRIP_LVC1_N  PL25A @S9S_MB_2U_LIB.S9S_MB_2U(SCH_1):H_CPU0_THERMTRIP_LVC1_N
  U1 H_CPU1_MEMTRIP_LVC1_N  PL25B @S9S_MB_2U_LIB.S9S_MB_2U(SCH_1):H_CPU1_MEMTRIP_LVC1_N
  R3     NC  PL24A     NC
  R4     NC  PL24B     NC
  R5     NC  PL24C     NC
  P7 H_CPU1_THERMTRIP_LVC1_N  PL24D @S9S_MB_2U_LIB.S9S_MB_2U(SCH_1):H_CPU1_THERMTRIP_LVC1_N
  R6 H_CPU0_MEMTRIP_LVC1_N  PL25C @S9S_MB_2U_LIB.S9S_MB_2U(SCH_1):H_CPU0_MEMTRIP_LVC1_N
  R7 H_CPU1_MEMHOT_OUT_LVC1_N  PL25D @S9S_MB_2U_LIB.S9S_MB_2U(SCH_1):H_CPU1_MEMHOT_OUT_LVC1_N
  T3 H_CPU0_MEMHOT_OUT_LVC1_N  PL26A @S9S_MB_2U_LIB.S9S_MB_2U(SCH_1):H_CPU0_MEMHOT_OUT_LVC1_N
  T4 H_CPU_ERR2_LVC2_N  PL26B @S9S_MB_2U_LIB.S9S_MB_2U(SCH_1):H_CPU_ERR2_LVC2_N
  M1     NC  PL17A     NC
  N1     NC  PL17B     NC
  M6     NC  PL17C     NC
  M5     NC  PL17D     NC
  N2     NC  PL18A     NC
  P1     NC  PL18B     NC
  N3     NC  PL18C     NC
  N4     NC  PL18D     NC
  P2     NC  PL19A     NC
  R1     NC  PL19B     NC
  P3     NC  PL19C     NC
  M7     NC  PL19D     NC
  U2     NC PL27A||PCLKT3_0     NC
  V1     NC PL27B||PCLKC3_0     NC
  U3     NC  PL27C     NC
  U4     NC  PL27D     NC
  W1 PWRGD_CPU1_LVC1_R  PL28A @S9S_MB_2U_LIB.S9S_MB_2U(SCH_1):PWRGD_CPU1_LVC1_R
  W2 PWRGD_CPU0_LVC1_R  PL28B @S9S_MB_2U_LIB.S9S_MB_2U(SCH_1):PWRGD_CPU0_LVC1_R
  V4 RST_CPU1_LVC1_R_N  PL28C @S9S_MB_2U_LIB.S9S_MB_2U(SCH_1):RST_CPU1_LVC1_R_N
  U5 RST_CPU0_LVC1_R_N  PL28D @S9S_MB_2U_LIB.S9S_MB_2U(SCH_1):RST_CPU0_LVC1_R_N
  Y1 H_CPU_RMCA_LVC2_R2_N  PL29A @S9S_MB_2U_LIB.S9S_MB_2U(SCH_1):H_CPU_RMCA_LVC2_R2_N
 AA1 H_CPU_NMI_LVC1_R_N  PL29B @S9S_MB_2U_LIB.S9S_MB_2U(SCH_1):H_CPU_NMI_LVC1_R_N
  W3 FM_THERMTRIP_DLY_LVC1_R_N  PL29C @S9S_MB_2U_LIB.S9S_MB_2U(SCH_1):FM_THERMTRIP_DLY_LVC1_R_N
  Y2 H_CPU_CATERR_LVC2_R2_N  PL29D @S9S_MB_2U_LIB.S9S_MB_2U(SCH_1):H_CPU_CATERR_LVC2_R2_N
  Y3 H_CPU1_PROCHOT_LVC1_R_N  PL30A @S9S_MB_2U_LIB.S9S_MB_2U(SCH_1):H_CPU1_PROCHOT_LVC1_R_N
  W4 H_CPU0_PROCHOT_LVC1_R_N  PL30B @S9S_MB_2U_LIB.S9S_MB_2U(SCH_1):H_CPU0_PROCHOT_LVC1_R_N
  V5 H_CPU1_MEMHOT_IN_LVC1_R_N  PL30C @S9S_MB_2U_LIB.S9S_MB_2U(SCH_1):H_CPU1_MEMHOT_IN_LVC1_R_N
  T7 H_CPU0_MEMHOT_IN_LVC1_R_N  PL30D @S9S_MB_2U_LIB.S9S_MB_2U(SCH_1):H_CPU0_MEMHOT_IN_LVC1_R_N
  G2 PWRGD_DRAMPWRGD_CPU0_AB_R_LVC1 PL7A||PCLKT5_0 @S9S_MB_2U_LIB.S9S_MB_2U(SCH_1):PWRGD_DRAMPWRGD_CPU0_AB_R_LVC1
  G1 PWRGD_DRAMPWRGD_CPU0_CD_R_LVC1 PL7B||PCLKC5_0 @S9S_MB_2U_LIB.S9S_MB_2U(SCH_1):PWRGD_DRAMPWRGD_CPU0_CD_R_LVC1
  H4 PWRGD_DRAMPWRGD_CPU0_EF_R_LVC1   PL7C @S9S_MB_2U_LIB.S9S_MB_2U(SCH_1):PWRGD_DRAMPWRGD_CPU0_EF_R_LVC1
  H3 PWRGD_DRAMPWRGD_CPU0_GH_R_LVC1   PL7D @S9S_MB_2U_LIB.S9S_MB_2U(SCH_1):PWRGD_DRAMPWRGD_CPU0_GH_R_LVC1
  H2 PWRGD_DRAMPWRGD_CPU1_AB_R_LVC1  PL10A @S9S_MB_2U_LIB.S9S_MB_2U(SCH_1):PWRGD_DRAMPWRGD_CPU1_AB_R_LVC1
  H1 PWRGD_DRAMPWRGD_CPU1_CD_R_LVC1  PL10B @S9S_MB_2U_LIB.S9S_MB_2U(SCH_1):PWRGD_DRAMPWRGD_CPU1_CD_R_LVC1
  J7 PWRGD_DRAMPWRGD_CPU1_EF_R_LVC1  PL10C @S9S_MB_2U_LIB.S9S_MB_2U(SCH_1):PWRGD_DRAMPWRGD_CPU1_EF_R_LVC1
  J6 PWRGD_DRAMPWRGD_CPU1_GH_R_LVC1  PL10D @S9S_MB_2U_LIB.S9S_MB_2U(SCH_1):PWRGD_DRAMPWRGD_CPU1_GH_R_LVC1
  H5 FM_BOARD_BMC_SKU_ID4  PL11A @S9S_MB_2U_LIB.S9S_MB_2U(SCH_1):FM_BOARD_BMC_SKU_ID4
  J5 FM_BOARD_BMC_SKU_ID3  PL11B @S9S_MB_2U_LIB.S9S_MB_2U(SCH_1):FM_BOARD_BMC_SKU_ID3
  J4 FM_BOARD_BMC_SKU_ID2  PL11C @S9S_MB_2U_LIB.S9S_MB_2U(SCH_1):FM_BOARD_BMC_SKU_ID2
  J3 FM_BOARD_BMC_SKU_ID1  PL11D @S9S_MB_2U_LIB.S9S_MB_2U(SCH_1):FM_BOARD_BMC_SKU_ID1
  J2 FM_BOARD_BMC_SKU_ID0  PL12A @S9S_MB_2U_LIB.S9S_MB_2U(SCH_1):FM_BOARD_BMC_SKU_ID0
  J1 FAB_BMC_REV_ID2  PL12B @S9S_MB_2U_LIB.S9S_MB_2U(SCH_1):FAB_BMC_REV_ID2
  K7 FAB_BMC_REV_ID1  PL12C @S9S_MB_2U_LIB.S9S_MB_2U(SCH_1):FAB_BMC_REV_ID1
  K6 FAB_BMC_REV_ID0  PL12D @S9S_MB_2U_LIB.S9S_MB_2U(SCH_1):FAB_BMC_REV_ID0

LCMXO3LF9400C5BG484C-LCMXO3LF-A  I70  U249
  E8 JTAG_PLD_TDO_R PT15C||TDO @S9S_MB_2U_LIB.S9S_MB_2U(SCH_1):JTAG_PLD_TDO_R
  E9 JTAG_PLD_TDI_R PT15D||TDI @S9S_MB_2U_LIB.S9S_MB_2U(SCH_1):JTAG_PLD_TDI_R
 D10 JTAG_PLD_TCK_R PT22C||TCK @S9S_MB_2U_LIB.S9S_MB_2U(SCH_1):JTAG_PLD_TCK_R
 C10 JTAG_PLD_TMS_R PT22D||TMS @S9S_MB_2U_LIB.S9S_MB_2U(SCH_1):JTAG_PLD_TMS_R
 E15 PU_FPGA_D12_PROGRAMN PT31D||PROGRAMN @S9S_MB_2U_LIB.S9S_MB_2U(SCH_1):PU_FPGA_D12_PROGRAMN
 F16 NC_FPGA_PT44C PT44C||INITN @S9S_MB_2U_LIB.S9S_MB_2U(SCH_1):NC_FPGA_PT44C
 E17 NC_FPGA_PT44D PT44D||DONE @S9S_MB_2U_LIB.S9S_MB_2U(SCH_1):NC_FPGA_PT44D
 E14 JTAG_PLD_JTAGEN PT31C||JTAGENB @S9S_MB_2U_LIB.S9S_MB_2U(SCH_1):JTAG_PLD_JTAGEN

Q_RES_0402LF-33.2,1%,1/16W,CHIA  I79  R4751
   1 HP_LVC3_OCP_V3_1_PWRGD_R      A @S9S_MB_2U_LIB.S9S_MB_2U(SCH_1):HP_LVC3_OCP_V3_1_PWRGD_R
   2 HP_LVC3_OCP_V3_1_FUSE_PWRGD      B @S9S_MB_2U_LIB.S9S_MB_2U(SCH_1):HP_LVC3_OCP_V3_1_FUSE_PWRGD

Q_RES_0402LF-33.2,1%,1/16W,CHIA  I86  R4760
   1 HP_LVC3_OCP_V3_2_PWRGD_R      A @S9S_MB_2U_LIB.S9S_MB_2U(SCH_1):HP_LVC3_OCP_V3_2_PWRGD_R
   2 HP_LVC3_OCP_V3_2_FUSE_PWRGD      B @S9S_MB_2U_LIB.S9S_MB_2U(SCH_1):HP_LVC3_OCP_V3_2_FUSE_PWRGD

Q_RES_0402LF-33.2,1%,1/16W,CHIA  I90  R4765
   1 HP_LVC3_E1S_0_HSC_PWRGD      A @S9S_MB_2U_LIB.S9S_MB_2U(SCH_1):HP_LVC3_E1S_0_HSC_PWRGD
   2 HP_LVC3_E1S_0_HSC_PWRGD_PLD      B @S9S_MB_2U_LIB.S9S_MB_2U(SCH_1):HP_LVC3_E1S_0_HSC_PWRGD_PLD

Q_RES_0402LF-33.2,1%,1/16W,CHIA  I95  R4771
   1 HP_LVC3_SCM_HSC_PWRGD      A @S9S_MB_2U_LIB.S9S_MB_2U(SCH_1):HP_LVC3_SCM_HSC_PWRGD
   2 HP_LVC3_SCM_HSC_PWRGD_PLD      B @S9S_MB_2U_LIB.S9S_MB_2U(SCH_1):HP_LVC3_SCM_HSC_PWRGD_PLD


DRAWING: @S9S_MB_2U_LIB.S9S_MB_2U(SCH_1):PAGE202 

LCMXO3LF9400C5BG484C-LCMXO3LF-A  I1  U249
  A1    GND   GND1 @S9S_MB_2U_LIB.S9S_MB_2U(SCH_1):GND
 A22    GND   GND2 @S9S_MB_2U_LIB.S9S_MB_2U(SCH_1):GND
  B7    GND   GND3 @S9S_MB_2U_LIB.S9S_MB_2U(SCH_1):GND
 B16    GND   GND4 @S9S_MB_2U_LIB.S9S_MB_2U(SCH_1):GND
  C2    GND   GND5 @S9S_MB_2U_LIB.S9S_MB_2U(SCH_1):GND
 C11    GND   GND6 @S9S_MB_2U_LIB.S9S_MB_2U(SCH_1):GND
  E5    GND   GND7 @S9S_MB_2U_LIB.S9S_MB_2U(SCH_1):GND
 E18    GND   GND8 @S9S_MB_2U_LIB.S9S_MB_2U(SCH_1):GND
  F2    GND   GND9 @S9S_MB_2U_LIB.S9S_MB_2U(SCH_1):GND
 F21    GND  GND10 @S9S_MB_2U_LIB.S9S_MB_2U(SCH_1):GND
  H8    GND  GND11 @S9S_MB_2U_LIB.S9S_MB_2U(SCH_1):GND
 H10    GND  GND12 @S9S_MB_2U_LIB.S9S_MB_2U(SCH_1):GND
 H13    GND  GND13 @S9S_MB_2U_LIB.S9S_MB_2U(SCH_1):GND
 H15    GND  GND14 @S9S_MB_2U_LIB.S9S_MB_2U(SCH_1):GND
  J9    GND  GND15 @S9S_MB_2U_LIB.S9S_MB_2U(SCH_1):GND
 J10    GND  GND16 @S9S_MB_2U_LIB.S9S_MB_2U(SCH_1):GND
 J11    GND  GND17 @S9S_MB_2U_LIB.S9S_MB_2U(SCH_1):GND
 J12    GND  GND18 @S9S_MB_2U_LIB.S9S_MB_2U(SCH_1):GND
 J13    GND  GND19 @S9S_MB_2U_LIB.S9S_MB_2U(SCH_1):GND
 J14    GND  GND20 @S9S_MB_2U_LIB.S9S_MB_2U(SCH_1):GND
  K9    GND  GND21 @S9S_MB_2U_LIB.S9S_MB_2U(SCH_1):GND
 K14    GND  GND22 @S9S_MB_2U_LIB.S9S_MB_2U(SCH_1):GND
 K21    GND  GND23 @S9S_MB_2U_LIB.S9S_MB_2U(SCH_1):GND
  L2    GND  GND24 @S9S_MB_2U_LIB.S9S_MB_2U(SCH_1):GND
  L9    GND  GND25 @S9S_MB_2U_LIB.S9S_MB_2U(SCH_1):GND
 L10    GND  GND26 @S9S_MB_2U_LIB.S9S_MB_2U(SCH_1):GND
 L13    GND  GND27 @S9S_MB_2U_LIB.S9S_MB_2U(SCH_1):GND
 L14    GND  GND28 @S9S_MB_2U_LIB.S9S_MB_2U(SCH_1):GND
 L18    GND  GND29 @S9S_MB_2U_LIB.S9S_MB_2U(SCH_1):GND
  M4    GND  GND30 @S9S_MB_2U_LIB.S9S_MB_2U(SCH_1):GND
  M9    GND  GND31 @S9S_MB_2U_LIB.S9S_MB_2U(SCH_1):GND
 M10    GND  GND32 @S9S_MB_2U_LIB.S9S_MB_2U(SCH_1):GND
 M13    GND  GND33 @S9S_MB_2U_LIB.S9S_MB_2U(SCH_1):GND
 M14    GND  GND34 @S9S_MB_2U_LIB.S9S_MB_2U(SCH_1):GND
  N9    GND  GND35 @S9S_MB_2U_LIB.S9S_MB_2U(SCH_1):GND
 N14    GND  GND36 @S9S_MB_2U_LIB.S9S_MB_2U(SCH_1):GND
 N21    GND  GND37 @S9S_MB_2U_LIB.S9S_MB_2U(SCH_1):GND
  P9    GND  GND38 @S9S_MB_2U_LIB.S9S_MB_2U(SCH_1):GND
 P10    GND  GND39 @S9S_MB_2U_LIB.S9S_MB_2U(SCH_1):GND
 P11    GND  GND40 @S9S_MB_2U_LIB.S9S_MB_2U(SCH_1):GND
 P12    GND  GND41 @S9S_MB_2U_LIB.S9S_MB_2U(SCH_1):GND
 P13    GND  GND42 @S9S_MB_2U_LIB.S9S_MB_2U(SCH_1):GND
 P14    GND  GND43 @S9S_MB_2U_LIB.S9S_MB_2U(SCH_1):GND
  R8    GND  GND44 @S9S_MB_2U_LIB.S9S_MB_2U(SCH_1):GND
 R15    GND  GND45 @S9S_MB_2U_LIB.S9S_MB_2U(SCH_1):GND
  V2    GND  GND46 @S9S_MB_2U_LIB.S9S_MB_2U(SCH_1):GND
 V21    GND  GND47 @S9S_MB_2U_LIB.S9S_MB_2U(SCH_1):GND
 W12    GND  GND48 @S9S_MB_2U_LIB.S9S_MB_2U(SCH_1):GND
 Y16    GND  GND50 @S9S_MB_2U_LIB.S9S_MB_2U(SCH_1):GND
  Y7    GND  GND49 @S9S_MB_2U_LIB.S9S_MB_2U(SCH_1):GND
 AB1    GND  GND51 @S9S_MB_2U_LIB.S9S_MB_2U(SCH_1):GND
AB22    GND  GND52 @S9S_MB_2U_LIB.S9S_MB_2U(SCH_1):GND

Q_CAP_C0402-0.01UF,50V,10%,X7RA  I3  C1154
   1 VCC_PLD_CORE      A @S9S_MB_2U_LIB.S9S_MB_2U(SCH_1):VCC_PLD_CORE
   2    GND      B @S9S_MB_2U_LIB.S9S_MB_2U(SCH_1):GND

Q_CAP_C0402-0.01UF,50V,10%,X7RA  I5  C1152
   1 VCC_PLD_CORE      A @S9S_MB_2U_LIB.S9S_MB_2U(SCH_1):VCC_PLD_CORE
   2    GND      B @S9S_MB_2U_LIB.S9S_MB_2U(SCH_1):GND

Q_CAP_C0402-0.01UF,50V,10%,X7RA  I9  C1932
   1 P3V3_AUX_FPGA_VCCIO0      A @S9S_MB_2U_LIB.S9S_MB_2U(SCH_1):P3V3_AUX_FPGA_VCCIO0
   2    GND      B @S9S_MB_2U_LIB.S9S_MB_2U(SCH_1):GND

Q_CAP_C0402-0.01UF,50V,10%,X7RA  I12  C1933
   1 P3V3_AUX_FPGA_VCCIO1      A @S9S_MB_2U_LIB.S9S_MB_2U(SCH_1):P3V3_AUX_FPGA_VCCIO1
   2    GND      B @S9S_MB_2U_LIB.S9S_MB_2U(SCH_1):GND

Q_CAP_C0402-0.01UF,50V,10%,X7RA  I15  C1146
   1 P3V3_AUX_FPGA_VCCIO2      A @S9S_MB_2U_LIB.S9S_MB_2U(SCH_1):P3V3_AUX_FPGA_VCCIO2
   2    GND      B @S9S_MB_2U_LIB.S9S_MB_2U(SCH_1):GND

Q_CAP_C0402-0.01UF,50V,10%,X7RA  I18  C1904
   1 P3V3_AUX_FPGA_VCCIO5      A @S9S_MB_2U_LIB.S9S_MB_2U(SCH_1):P3V3_AUX_FPGA_VCCIO5
   2    GND      B @S9S_MB_2U_LIB.S9S_MB_2U(SCH_1):GND

Q_CAP_C0402-0.01UF,50V,10%,X7RA  I20  C1898
   1 P3V3_AUX_FPGA_VCCIO5      A @S9S_MB_2U_LIB.S9S_MB_2U(SCH_1):P3V3_AUX_FPGA_VCCIO5
   2    GND      B @S9S_MB_2U_LIB.S9S_MB_2U(SCH_1):GND

Q_CAP_C0402-0.01UF,50V,10%,X7RA  I21  C1931
   1 VCC_PLD_CORE      A @S9S_MB_2U_LIB.S9S_MB_2U(SCH_1):VCC_PLD_CORE
   2    GND      B @S9S_MB_2U_LIB.S9S_MB_2U(SCH_1):GND

Q_CAP_C0402-0.01UF,50V,10%,X7RA  I22  C1928
   1 VCC_PLD_CORE      A @S9S_MB_2U_LIB.S9S_MB_2U(SCH_1):VCC_PLD_CORE
   2    GND      B @S9S_MB_2U_LIB.S9S_MB_2U(SCH_1):GND

Q_CAP_C0402-0.01UF,50V,10%,X7RA  I23  C1919
   1 VCC_PLD_CORE      A @S9S_MB_2U_LIB.S9S_MB_2U(SCH_1):VCC_PLD_CORE
   2    GND      B @S9S_MB_2U_LIB.S9S_MB_2U(SCH_1):GND

Q_CAP_C0402-0.01UF,50V,10%,X7RA  I24  C1916
   1 VCC_PLD_CORE      A @S9S_MB_2U_LIB.S9S_MB_2U(SCH_1):VCC_PLD_CORE
   2    GND      B @S9S_MB_2U_LIB.S9S_MB_2U(SCH_1):GND

Q_CAP_0402-0.1UF,25V,10%,X7R,CA  I25  C1907
   1 VCC_PLD_CORE      A @S9S_MB_2U_LIB.S9S_MB_2U(SCH_1):VCC_PLD_CORE
   2    GND      B @S9S_MB_2U_LIB.S9S_MB_2U(SCH_1):GND

Q_CAP_C0402-0.01UF,50V,10%,X7RA  I26  C1903
   1 VCC_PLD_CORE      A @S9S_MB_2U_LIB.S9S_MB_2U(SCH_1):VCC_PLD_CORE
   2    GND      B @S9S_MB_2U_LIB.S9S_MB_2U(SCH_1):GND

Q_CAP_C0402-0.01UF,50V,10%,X7RA  I27  C1897
   1 VCC_PLD_CORE      A @S9S_MB_2U_LIB.S9S_MB_2U(SCH_1):VCC_PLD_CORE
   2    GND      B @S9S_MB_2U_LIB.S9S_MB_2U(SCH_1):GND

Q_CAP_C0402-0.01UF,50V,10%,X7RA  I28  C1912
   1 VCC_PLD_CORE      A @S9S_MB_2U_LIB.S9S_MB_2U(SCH_1):VCC_PLD_CORE
   2    GND      B @S9S_MB_2U_LIB.S9S_MB_2U(SCH_1):GND

Q_CAP_0402-0.1UF,25V,10%,X7R,CA  I29  C1943
   1 VCC_PLD_CORE      A @S9S_MB_2U_LIB.S9S_MB_2U(SCH_1):VCC_PLD_CORE
   2    GND      B @S9S_MB_2U_LIB.S9S_MB_2U(SCH_1):GND

Q_CAP_C0402-10UF,6.3V,20%,X6S,A  I30  C1936
   1 VCC_PLD_CORE      A @S9S_MB_2U_LIB.S9S_MB_2U(SCH_1):VCC_PLD_CORE
   2    GND      B @S9S_MB_2U_LIB.S9S_MB_2U(SCH_1):GND

Q_CAP_C0402-0.01UF,50V,10%,X7RA  I33  C1929
   1 P3V3_AUX_FPGA_VCCIO0      A @S9S_MB_2U_LIB.S9S_MB_2U(SCH_1):P3V3_AUX_FPGA_VCCIO0
   2    GND      B @S9S_MB_2U_LIB.S9S_MB_2U(SCH_1):GND

Q_CAP_C0402-0.01UF,50V,10%,X7RA  I34  C1926
   1 P3V3_AUX_FPGA_VCCIO0      A @S9S_MB_2U_LIB.S9S_MB_2U(SCH_1):P3V3_AUX_FPGA_VCCIO0
   2    GND      B @S9S_MB_2U_LIB.S9S_MB_2U(SCH_1):GND

Q_CAP_C0402-0.01UF,50V,10%,X7RA  I35  C1917
   1 P3V3_AUX_FPGA_VCCIO0      A @S9S_MB_2U_LIB.S9S_MB_2U(SCH_1):P3V3_AUX_FPGA_VCCIO0
   2    GND      B @S9S_MB_2U_LIB.S9S_MB_2U(SCH_1):GND

Q_CAP_C0402-0.01UF,50V,10%,X7RA  I36  C1914
   1 P3V3_AUX_FPGA_VCCIO0      A @S9S_MB_2U_LIB.S9S_MB_2U(SCH_1):P3V3_AUX_FPGA_VCCIO0
   2    GND      B @S9S_MB_2U_LIB.S9S_MB_2U(SCH_1):GND

Q_CAP_C0402-0.01UF,50V,10%,X7RA  I37  C1930
   1 P3V3_AUX_FPGA_VCCIO1      A @S9S_MB_2U_LIB.S9S_MB_2U(SCH_1):P3V3_AUX_FPGA_VCCIO1
   2    GND      B @S9S_MB_2U_LIB.S9S_MB_2U(SCH_1):GND

Q_CAP_C0402-0.01UF,50V,10%,X7RA  I38  C1927
   1 P3V3_AUX_FPGA_VCCIO1      A @S9S_MB_2U_LIB.S9S_MB_2U(SCH_1):P3V3_AUX_FPGA_VCCIO1
   2    GND      B @S9S_MB_2U_LIB.S9S_MB_2U(SCH_1):GND

Q_CAP_C0402-0.01UF,50V,10%,X7RA  I39  C1918
   1 P3V3_AUX_FPGA_VCCIO1      A @S9S_MB_2U_LIB.S9S_MB_2U(SCH_1):P3V3_AUX_FPGA_VCCIO1
   2    GND      B @S9S_MB_2U_LIB.S9S_MB_2U(SCH_1):GND

Q_CAP_C0402-0.01UF,50V,10%,X7RA  I40  C1915
   1 P3V3_AUX_FPGA_VCCIO1      A @S9S_MB_2U_LIB.S9S_MB_2U(SCH_1):P3V3_AUX_FPGA_VCCIO1
   2    GND      B @S9S_MB_2U_LIB.S9S_MB_2U(SCH_1):GND

Q_CAP_0402-0.1UF,25V,10%,X7R,CA  I41  C1905
   1 P3V3_AUX_FPGA_VCCIO0      A @S9S_MB_2U_LIB.S9S_MB_2U(SCH_1):P3V3_AUX_FPGA_VCCIO0
   2    GND      B @S9S_MB_2U_LIB.S9S_MB_2U(SCH_1):GND

Q_CAP_C0402-0.01UF,50V,10%,X7RA  I42  C1901
   1 P3V3_AUX_FPGA_VCCIO0      A @S9S_MB_2U_LIB.S9S_MB_2U(SCH_1):P3V3_AUX_FPGA_VCCIO0
   2    GND      B @S9S_MB_2U_LIB.S9S_MB_2U(SCH_1):GND

Q_CAP_C0402-0.01UF,50V,10%,X7RA  I43  C1895
   1 P3V3_AUX_FPGA_VCCIO0      A @S9S_MB_2U_LIB.S9S_MB_2U(SCH_1):P3V3_AUX_FPGA_VCCIO0
   2    GND      B @S9S_MB_2U_LIB.S9S_MB_2U(SCH_1):GND

Q_CAP_C0402-0.01UF,50V,10%,X7RA  I44  C1910
   1 P3V3_AUX_FPGA_VCCIO0      A @S9S_MB_2U_LIB.S9S_MB_2U(SCH_1):P3V3_AUX_FPGA_VCCIO0
   2    GND      B @S9S_MB_2U_LIB.S9S_MB_2U(SCH_1):GND

Q_CAP_0402-0.1UF,25V,10%,X7R,CA  I45  C1906
   1 P3V3_AUX_FPGA_VCCIO1      A @S9S_MB_2U_LIB.S9S_MB_2U(SCH_1):P3V3_AUX_FPGA_VCCIO1
   2    GND      B @S9S_MB_2U_LIB.S9S_MB_2U(SCH_1):GND

Q_CAP_C0402-0.01UF,50V,10%,X7RA  I46  C1902
   1 P3V3_AUX_FPGA_VCCIO1      A @S9S_MB_2U_LIB.S9S_MB_2U(SCH_1):P3V3_AUX_FPGA_VCCIO1
   2    GND      B @S9S_MB_2U_LIB.S9S_MB_2U(SCH_1):GND

Q_CAP_C0402-0.01UF,50V,10%,X7RA  I47  C1896
   1 P3V3_AUX_FPGA_VCCIO1      A @S9S_MB_2U_LIB.S9S_MB_2U(SCH_1):P3V3_AUX_FPGA_VCCIO1
   2    GND      B @S9S_MB_2U_LIB.S9S_MB_2U(SCH_1):GND

Q_CAP_C0402-0.01UF,50V,10%,X7RA  I48  C1911
   1 P3V3_AUX_FPGA_VCCIO1      A @S9S_MB_2U_LIB.S9S_MB_2U(SCH_1):P3V3_AUX_FPGA_VCCIO1
   2    GND      B @S9S_MB_2U_LIB.S9S_MB_2U(SCH_1):GND

Q_CAP_C0402-0.01UF,50V,10%,X7RA  I49  C1142
   1 P3V3_AUX_FPGA_VCCIO2      A @S9S_MB_2U_LIB.S9S_MB_2U(SCH_1):P3V3_AUX_FPGA_VCCIO2
   2    GND      B @S9S_MB_2U_LIB.S9S_MB_2U(SCH_1):GND

Q_CAP_C0402-0.01UF,50V,10%,X7RA  I50  C1138
   1 P3V3_AUX_FPGA_VCCIO2      A @S9S_MB_2U_LIB.S9S_MB_2U(SCH_1):P3V3_AUX_FPGA_VCCIO2
   2    GND      B @S9S_MB_2U_LIB.S9S_MB_2U(SCH_1):GND

Q_CAP_C0402-0.01UF,50V,10%,X7RA  I51  C1133
   1 P3V3_AUX_FPGA_VCCIO2      A @S9S_MB_2U_LIB.S9S_MB_2U(SCH_1):P3V3_AUX_FPGA_VCCIO2
   2    GND      B @S9S_MB_2U_LIB.S9S_MB_2U(SCH_1):GND

Q_CAP_C0402-0.01UF,50V,10%,X7RA  I52  C1127
   1 P3V3_AUX_FPGA_VCCIO2      A @S9S_MB_2U_LIB.S9S_MB_2U(SCH_1):P3V3_AUX_FPGA_VCCIO2
   2    GND      B @S9S_MB_2U_LIB.S9S_MB_2U(SCH_1):GND

Q_CAP_C0402-0.01UF,50V,10%,X7RA  I53  C1913
   1 P3V3_AUX_FPGA_VCCIO5      A @S9S_MB_2U_LIB.S9S_MB_2U(SCH_1):P3V3_AUX_FPGA_VCCIO5
   2    GND      B @S9S_MB_2U_LIB.S9S_MB_2U(SCH_1):GND

Q_CAP_0402-0.1UF,25V,10%,X7R,CA  I54  C1947
   1 P3V3_AUX_FPGA_VCCIO5      A @S9S_MB_2U_LIB.S9S_MB_2U(SCH_1):P3V3_AUX_FPGA_VCCIO5
   2    GND      B @S9S_MB_2U_LIB.S9S_MB_2U(SCH_1):GND

Q_CAP_C0402-10UF,6.3V,20%,X6S,A  I55  C1940
   1 P3V3_AUX_FPGA_VCCIO5      A @S9S_MB_2U_LIB.S9S_MB_2U(SCH_1):P3V3_AUX_FPGA_VCCIO5
   2    GND      B @S9S_MB_2U_LIB.S9S_MB_2U(SCH_1):GND

Q_CAP_0402-0.1UF,25V,10%,X7R,CA  I56  C1122
   1 P3V3_AUX_FPGA_VCCIO2      A @S9S_MB_2U_LIB.S9S_MB_2U(SCH_1):P3V3_AUX_FPGA_VCCIO2
   2    GND      B @S9S_MB_2U_LIB.S9S_MB_2U(SCH_1):GND

Q_CAP_C0402-0.01UF,50V,10%,X7RA  I57  C1900
   1 P3V3_AUX_FPGA_VCCIO2      A @S9S_MB_2U_LIB.S9S_MB_2U(SCH_1):P3V3_AUX_FPGA_VCCIO2
   2    GND      B @S9S_MB_2U_LIB.S9S_MB_2U(SCH_1):GND

Q_CAP_C0402-0.01UF,50V,10%,X7RA  I58  C1894
   1 P3V3_AUX_FPGA_VCCIO2      A @S9S_MB_2U_LIB.S9S_MB_2U(SCH_1):P3V3_AUX_FPGA_VCCIO2
   2    GND      B @S9S_MB_2U_LIB.S9S_MB_2U(SCH_1):GND

Q_CAP_C0402-0.01UF,50V,10%,X7RA  I59  C1909
   1 P3V3_AUX_FPGA_VCCIO2      A @S9S_MB_2U_LIB.S9S_MB_2U(SCH_1):P3V3_AUX_FPGA_VCCIO2
   2    GND      B @S9S_MB_2U_LIB.S9S_MB_2U(SCH_1):GND

Q_RES_0603LF-1,1%,1/10W,CHIP,CA  I60  R3349
   1 P3V3_AUX      A @S9S_MB_2U_LIB.S9S_MB_2U(SCH_1):P3V3_AUX
   2 P3V3_AUX_FPGA_VCCIO5      B @S9S_MB_2U_LIB.S9S_MB_2U(SCH_1):P3V3_AUX_FPGA_VCCIO5

Q_CAP_0402-0.1UF,25V,10%,X7R,CA  I62  C1945
   1 P3V3_AUX_FPGA_VCCIO0      A @S9S_MB_2U_LIB.S9S_MB_2U(SCH_1):P3V3_AUX_FPGA_VCCIO0
   2    GND      B @S9S_MB_2U_LIB.S9S_MB_2U(SCH_1):GND

Q_RES_0603LF-1,1%,1/10W,CHIP,CA  I63  R3346
   1 P3V3_AUX      A @S9S_MB_2U_LIB.S9S_MB_2U(SCH_1):P3V3_AUX
   2 P3V3_AUX_FPGA_VCCIO0      B @S9S_MB_2U_LIB.S9S_MB_2U(SCH_1):P3V3_AUX_FPGA_VCCIO0

Q_CAP_C0402-10UF,6.3V,20%,X6S,A  I64  C1938
   1 P3V3_AUX_FPGA_VCCIO0      A @S9S_MB_2U_LIB.S9S_MB_2U(SCH_1):P3V3_AUX_FPGA_VCCIO0
   2    GND      B @S9S_MB_2U_LIB.S9S_MB_2U(SCH_1):GND

Q_CAP_0402-0.1UF,25V,10%,X7R,CA  I65  C1946
   1 P3V3_AUX_FPGA_VCCIO1      A @S9S_MB_2U_LIB.S9S_MB_2U(SCH_1):P3V3_AUX_FPGA_VCCIO1
   2    GND      B @S9S_MB_2U_LIB.S9S_MB_2U(SCH_1):GND

Q_CAP_C0402-10UF,6.3V,20%,X6S,A  I66  C1939
   1 P3V3_AUX_FPGA_VCCIO1      A @S9S_MB_2U_LIB.S9S_MB_2U(SCH_1):P3V3_AUX_FPGA_VCCIO1
   2    GND      B @S9S_MB_2U_LIB.S9S_MB_2U(SCH_1):GND

Q_RES_0603LF-1,1%,1/10W,CHIP,CA  I67  R3348
   1 P3V3_AUX      A @S9S_MB_2U_LIB.S9S_MB_2U(SCH_1):P3V3_AUX
   2 P3V3_AUX_FPGA_VCCIO1      B @S9S_MB_2U_LIB.S9S_MB_2U(SCH_1):P3V3_AUX_FPGA_VCCIO1

Q_CAP_0402-0.1UF,25V,10%,X7R,CA  I70  C1944
   1 P3V3_AUX_FPGA_VCCIO2      A @S9S_MB_2U_LIB.S9S_MB_2U(SCH_1):P3V3_AUX_FPGA_VCCIO2
   2    GND      B @S9S_MB_2U_LIB.S9S_MB_2U(SCH_1):GND

Q_CAP_C0402-10UF,6.3V,20%,X6S,A  I71  C1937
   1 P3V3_AUX_FPGA_VCCIO2      A @S9S_MB_2U_LIB.S9S_MB_2U(SCH_1):P3V3_AUX_FPGA_VCCIO2
   2    GND      B @S9S_MB_2U_LIB.S9S_MB_2U(SCH_1):GND

Q_RES_0603LF-1,1%,1/10W,CHIP,CA  I72  R3347
   1 P3V3_AUX      A @S9S_MB_2U_LIB.S9S_MB_2U(SCH_1):P3V3_AUX
   2 P3V3_AUX_FPGA_VCCIO2      B @S9S_MB_2U_LIB.S9S_MB_2U(SCH_1):P3V3_AUX_FPGA_VCCIO2

Q_CAP_C0402-0.01UF,50V,10%,X7RA  I74  C1899
   1 P3V3_AUX_FPGA_VCCIO4      A @S9S_MB_2U_LIB.S9S_MB_2U(SCH_1):P3V3_AUX_FPGA_VCCIO4
   2    GND      B @S9S_MB_2U_LIB.S9S_MB_2U(SCH_1):GND

Q_CAP_C0402-0.01UF,50V,10%,X7RA  I76  C1893
   1 P3V3_AUX_FPGA_VCCIO4      A @S9S_MB_2U_LIB.S9S_MB_2U(SCH_1):P3V3_AUX_FPGA_VCCIO4
   2    GND      B @S9S_MB_2U_LIB.S9S_MB_2U(SCH_1):GND

Q_CAP_C0402-0.01UF,50V,10%,X7RA  I77  C1908
   1 P3V3_AUX_FPGA_VCCIO4      A @S9S_MB_2U_LIB.S9S_MB_2U(SCH_1):P3V3_AUX_FPGA_VCCIO4
   2    GND      B @S9S_MB_2U_LIB.S9S_MB_2U(SCH_1):GND

Q_CAP_0402-0.1UF,25V,10%,X7R,CA  I80  C1942
   1 P3V3_AUX_FPGA_VCCIO4      A @S9S_MB_2U_LIB.S9S_MB_2U(SCH_1):P3V3_AUX_FPGA_VCCIO4
   2    GND      B @S9S_MB_2U_LIB.S9S_MB_2U(SCH_1):GND

Q_RES_0603LF-1,1%,1/10W,CHIP,CA  I81  R3345
   1 P3V3_AUX      A @S9S_MB_2U_LIB.S9S_MB_2U(SCH_1):P3V3_AUX
   2 P3V3_AUX_FPGA_VCCIO4      B @S9S_MB_2U_LIB.S9S_MB_2U(SCH_1):P3V3_AUX_FPGA_VCCIO4

Q_CAP_C0402-10UF,6.3V,20%,X6S,A  I82  C1935
   1 P3V3_AUX_FPGA_VCCIO4      A @S9S_MB_2U_LIB.S9S_MB_2U(SCH_1):P3V3_AUX_FPGA_VCCIO4
   2    GND      B @S9S_MB_2U_LIB.S9S_MB_2U(SCH_1):GND

Q_CAP_C0402-0.01UF,50V,10%,X7RA  I97  C1118
   1 P3V3_AUX_FPGA_VCCIO3      A @S9S_MB_2U_LIB.S9S_MB_2U(SCH_1):P3V3_AUX_FPGA_VCCIO3
   2    GND      B @S9S_MB_2U_LIB.S9S_MB_2U(SCH_1):GND

Q_CAP_C0402-0.01UF,50V,10%,X7RA  I99  C1113
   1 P3V3_AUX_FPGA_VCCIO3      A @S9S_MB_2U_LIB.S9S_MB_2U(SCH_1):P3V3_AUX_FPGA_VCCIO3
   2    GND      B @S9S_MB_2U_LIB.S9S_MB_2U(SCH_1):GND

Q_CAP_C0402-0.01UF,50V,10%,X7RA  I100  C1124
   1 P3V3_AUX_FPGA_VCCIO3      A @S9S_MB_2U_LIB.S9S_MB_2U(SCH_1):P3V3_AUX_FPGA_VCCIO3
   2    GND      B @S9S_MB_2U_LIB.S9S_MB_2U(SCH_1):GND

Q_CAP_0402-0.1UF,25V,10%,X7R,CA  I101  C1941
   1 P3V3_AUX_FPGA_VCCIO3      A @S9S_MB_2U_LIB.S9S_MB_2U(SCH_1):P3V3_AUX_FPGA_VCCIO3
   2    GND      B @S9S_MB_2U_LIB.S9S_MB_2U(SCH_1):GND

LCMXO3LF9400C5BG484C-LCMXO3LF-A  I102  U249
 K10 VCC_PLD_CORE   VCC1 @S9S_MB_2U_LIB.S9S_MB_2U(SCH_1):VCC_PLD_CORE
 K11 VCC_PLD_CORE   VCC2 @S9S_MB_2U_LIB.S9S_MB_2U(SCH_1):VCC_PLD_CORE
 K12 VCC_PLD_CORE   VCC3 @S9S_MB_2U_LIB.S9S_MB_2U(SCH_1):VCC_PLD_CORE
 K13 VCC_PLD_CORE   VCC4 @S9S_MB_2U_LIB.S9S_MB_2U(SCH_1):VCC_PLD_CORE
 L11 VCC_PLD_CORE   VCC5 @S9S_MB_2U_LIB.S9S_MB_2U(SCH_1):VCC_PLD_CORE
 L12 VCC_PLD_CORE   VCC6 @S9S_MB_2U_LIB.S9S_MB_2U(SCH_1):VCC_PLD_CORE
 M11 VCC_PLD_CORE   VCC7 @S9S_MB_2U_LIB.S9S_MB_2U(SCH_1):VCC_PLD_CORE
 M12 VCC_PLD_CORE   VCC8 @S9S_MB_2U_LIB.S9S_MB_2U(SCH_1):VCC_PLD_CORE
 N10 VCC_PLD_CORE   VCC9 @S9S_MB_2U_LIB.S9S_MB_2U(SCH_1):VCC_PLD_CORE
 N11 VCC_PLD_CORE  VCC10 @S9S_MB_2U_LIB.S9S_MB_2U(SCH_1):VCC_PLD_CORE
 N12 VCC_PLD_CORE  VCC11 @S9S_MB_2U_LIB.S9S_MB_2U(SCH_1):VCC_PLD_CORE
 N13 VCC_PLD_CORE  VCC12 @S9S_MB_2U_LIB.S9S_MB_2U(SCH_1):VCC_PLD_CORE
  F3 P3V3_AUX_FPGA_VCCIO5 VCCIO5_1 @S9S_MB_2U_LIB.S9S_MB_2U(SCH_1):P3V3_AUX_FPGA_VCCIO5
  J8 P3V3_AUX_FPGA_VCCIO5 VCCIO5_2 @S9S_MB_2U_LIB.S9S_MB_2U(SCH_1):P3V3_AUX_FPGA_VCCIO5
  K8 P3V3_AUX_FPGA_VCCIO5 VCCIO5_3 @S9S_MB_2U_LIB.S9S_MB_2U(SCH_1):P3V3_AUX_FPGA_VCCIO5
  L8 P3V3_AUX_FPGA_VCCIO4 VCCIO4_1 @S9S_MB_2U_LIB.S9S_MB_2U(SCH_1):P3V3_AUX_FPGA_VCCIO4
  M8 P3V3_AUX_FPGA_VCCIO4 VCCIO4_2 @S9S_MB_2U_LIB.S9S_MB_2U(SCH_1):P3V3_AUX_FPGA_VCCIO4
  M3 P3V3_AUX_FPGA_VCCIO4 VCCIO4_3 @S9S_MB_2U_LIB.S9S_MB_2U(SCH_1):P3V3_AUX_FPGA_VCCIO4
  N8 P3V3_AUX_FPGA_VCCIO3 VCCIO3_1 @S9S_MB_2U_LIB.S9S_MB_2U(SCH_1):P3V3_AUX_FPGA_VCCIO3
  P8 P3V3_AUX_FPGA_VCCIO3 VCCIO3_2 @S9S_MB_2U_LIB.S9S_MB_2U(SCH_1):P3V3_AUX_FPGA_VCCIO3
  V3 P3V3_AUX_FPGA_VCCIO3 VCCIO3_3 @S9S_MB_2U_LIB.S9S_MB_2U(SCH_1):P3V3_AUX_FPGA_VCCIO3
  R9 P3V3_AUX_FPGA_VCCIO2 VCCIO2_1 @S9S_MB_2U_LIB.S9S_MB_2U(SCH_1):P3V3_AUX_FPGA_VCCIO2
 R10 P3V3_AUX_FPGA_VCCIO2 VCCIO2_2 @S9S_MB_2U_LIB.S9S_MB_2U(SCH_1):P3V3_AUX_FPGA_VCCIO2
 R11 P3V3_AUX_FPGA_VCCIO2 VCCIO2_3 @S9S_MB_2U_LIB.S9S_MB_2U(SCH_1):P3V3_AUX_FPGA_VCCIO2
 R12 P3V3_AUX_FPGA_VCCIO2 VCCIO2_4 @S9S_MB_2U_LIB.S9S_MB_2U(SCH_1):P3V3_AUX_FPGA_VCCIO2
 R13 P3V3_AUX_FPGA_VCCIO2 VCCIO2_5 @S9S_MB_2U_LIB.S9S_MB_2U(SCH_1):P3V3_AUX_FPGA_VCCIO2
 R14 P3V3_AUX_FPGA_VCCIO2 VCCIO2_6 @S9S_MB_2U_LIB.S9S_MB_2U(SCH_1):P3V3_AUX_FPGA_VCCIO2
  W7 P3V3_AUX_FPGA_VCCIO2 VCCIO2_7 @S9S_MB_2U_LIB.S9S_MB_2U(SCH_1):P3V3_AUX_FPGA_VCCIO2
 W11 P3V3_AUX_FPGA_VCCIO2 VCCIO2_8 @S9S_MB_2U_LIB.S9S_MB_2U(SCH_1):P3V3_AUX_FPGA_VCCIO2
 W16 P3V3_AUX_FPGA_VCCIO2 VCCIO2_9 @S9S_MB_2U_LIB.S9S_MB_2U(SCH_1):P3V3_AUX_FPGA_VCCIO2
 F20 P3V3_AUX_FPGA_VCCIO1 VCCIO1_1 @S9S_MB_2U_LIB.S9S_MB_2U(SCH_1):P3V3_AUX_FPGA_VCCIO1
 J15 P3V3_AUX_FPGA_VCCIO1 VCCIO1_2 @S9S_MB_2U_LIB.S9S_MB_2U(SCH_1):P3V3_AUX_FPGA_VCCIO1
 K15 P3V3_AUX_FPGA_VCCIO1 VCCIO1_3 @S9S_MB_2U_LIB.S9S_MB_2U(SCH_1):P3V3_AUX_FPGA_VCCIO1
 L15 P3V3_AUX_FPGA_VCCIO1 VCCIO1_4 @S9S_MB_2U_LIB.S9S_MB_2U(SCH_1):P3V3_AUX_FPGA_VCCIO1
 M15 P3V3_AUX_FPGA_VCCIO1 VCCIO1_5 @S9S_MB_2U_LIB.S9S_MB_2U(SCH_1):P3V3_AUX_FPGA_VCCIO1
 M18 P3V3_AUX_FPGA_VCCIO1 VCCIO1_6 @S9S_MB_2U_LIB.S9S_MB_2U(SCH_1):P3V3_AUX_FPGA_VCCIO1
 N15 P3V3_AUX_FPGA_VCCIO1 VCCIO1_7 @S9S_MB_2U_LIB.S9S_MB_2U(SCH_1):P3V3_AUX_FPGA_VCCIO1
 P15 P3V3_AUX_FPGA_VCCIO1 VCCIO1_8 @S9S_MB_2U_LIB.S9S_MB_2U(SCH_1):P3V3_AUX_FPGA_VCCIO1
 V20 P3V3_AUX_FPGA_VCCIO1 VCCIO1_9 @S9S_MB_2U_LIB.S9S_MB_2U(SCH_1):P3V3_AUX_FPGA_VCCIO1
  C7 P3V3_AUX_FPGA_VCCIO0 VCCIO0_1 @S9S_MB_2U_LIB.S9S_MB_2U(SCH_1):P3V3_AUX_FPGA_VCCIO0
 C12 P3V3_AUX_FPGA_VCCIO0 VCCIO0_2 @S9S_MB_2U_LIB.S9S_MB_2U(SCH_1):P3V3_AUX_FPGA_VCCIO0
 C16 P3V3_AUX_FPGA_VCCIO0 VCCIO0_3 @S9S_MB_2U_LIB.S9S_MB_2U(SCH_1):P3V3_AUX_FPGA_VCCIO0
 G10 P3V3_AUX_FPGA_VCCIO0 VCCIO0_4 @S9S_MB_2U_LIB.S9S_MB_2U(SCH_1):P3V3_AUX_FPGA_VCCIO0
 H11 P3V3_AUX_FPGA_VCCIO0 VCCIO0_7 @S9S_MB_2U_LIB.S9S_MB_2U(SCH_1):P3V3_AUX_FPGA_VCCIO0
 H12 P3V3_AUX_FPGA_VCCIO0 VCCIO0_8 @S9S_MB_2U_LIB.S9S_MB_2U(SCH_1):P3V3_AUX_FPGA_VCCIO0
 H14 P3V3_AUX_FPGA_VCCIO0 VCCIO0_9 @S9S_MB_2U_LIB.S9S_MB_2U(SCH_1):P3V3_AUX_FPGA_VCCIO0
  H9 P3V3_AUX_FPGA_VCCIO0 VCCIO0_6 @S9S_MB_2U_LIB.S9S_MB_2U(SCH_1):P3V3_AUX_FPGA_VCCIO0
 G13 P3V3_AUX_FPGA_VCCIO0 VCCIO0_5 @S9S_MB_2U_LIB.S9S_MB_2U(SCH_1):P3V3_AUX_FPGA_VCCIO0

Q_CAP_C0402-10UF,6.3V,20%,X6S,A  I107  C1842
   1 P3V3_AUX_FPGA_VCCIO3      A @S9S_MB_2U_LIB.S9S_MB_2U(SCH_1):P3V3_AUX_FPGA_VCCIO3
   2    GND      B @S9S_MB_2U_LIB.S9S_MB_2U(SCH_1):GND

Q_RES_0603LF-1,1%,1/10W,CHIP,CA  I108  R3344
   1 P3V3_AUX      A @S9S_MB_2U_LIB.S9S_MB_2U(SCH_1):P3V3_AUX
   2 P3V3_AUX_FPGA_VCCIO3      B @S9S_MB_2U_LIB.S9S_MB_2U(SCH_1):P3V3_AUX_FPGA_VCCIO3

Q_RES_0603LF-1,1%,1/10W,CHIP,CA  I119  R3458
   1 P3V3_AUX      A @S9S_MB_2U_LIB.S9S_MB_2U(SCH_1):P3V3_AUX
   2 VCC_PLD_CORE      B @S9S_MB_2U_LIB.S9S_MB_2U(SCH_1):VCC_PLD_CORE

Q_CAP_C0402-0.01UF,50V,10%,X7RA  I120  C1934
   1 VCC_PLD_CORE      A @S9S_MB_2U_LIB.S9S_MB_2U(SCH_1):VCC_PLD_CORE
   2    GND      B @S9S_MB_2U_LIB.S9S_MB_2U(SCH_1):GND

Q_CAP_0402-0.1UF,25V,10%,X7R,CA  I121  C1150
   1 VCC_PLD_CORE      A @S9S_MB_2U_LIB.S9S_MB_2U(SCH_1):VCC_PLD_CORE
   2    GND      B @S9S_MB_2U_LIB.S9S_MB_2U(SCH_1):GND


DRAWING: @S9S_MB_2U_LIB.S9S_MB_2U(SCH_1):PAGE270 

Q_RES_0402LF-1K,1%,1/16W,CHIP,A  I17  R2524
   1 P3V3_AUX      A @S9S_MB_2U_LIB.S9S_MB_2U(SCH_1):P3V3_AUX
   2 PVCCIN_CPU1_VR_FAULT      B @S9S_MB_2U_LIB.S9S_MB_2U(SCH_1):PVCCIN_CPU1_VR_FAULT

Q_RES_0402LF-1K,1%,1/16W,CHIP,A  I18  R2525
   1 P3V3_AUX      A @S9S_MB_2U_LIB.S9S_MB_2U(SCH_1):P3V3_AUX
   2 PVCCIN_CPU1_PIN_ALERT      B @S9S_MB_2U_LIB.S9S_MB_2U(SCH_1):PVCCIN_CPU1_PIN_ALERT

Q_RES_0402LF-0,5%,1/16W,CHIP,CA  I19  R2550
   1 FM_PVCCFA_EHV_FIVRA_CPU1_EN      A @S9S_MB_2U_LIB.S9S_MB_2U(SCH_1):FM_PVCCFA_EHV_FIVRA_CPU1_EN
   2 PVCCFA_EHV_FIVRA_CPU1_EN_R      B @S9S_MB_2U_LIB.S9S_MB_2U(SCH_1):PVCCFA_EHV_FIVRA_CPU1_EN_R

Q_RES_0402LF-0,5%,1/16W,CHIP,CA  I63  PR317
   1 SH_PVCCIN_CPU1      A @S9S_MB_2U_LIB.S9S_MB_2U(SCH_1):SH_PVCCIN_CPU1
   2 SH_PVCCIN_CPU1_R      B @S9S_MB_2U_LIB.S9S_MB_2U(SCH_1):SH_PVCCIN_CPU1_R

Q_CAP_0402-1000PF,50V,5%,X7R,TA  I67  C2860
   1 PVCCIN_CPU1_EN_R      A @S9S_MB_2U_LIB.S9S_MB_2U(SCH_1):PVCCIN_CPU1_EN_R
   2    GND      B @S9S_MB_2U_LIB.S9S_MB_2U(SCH_1):GND

Q_RES_0402LF-28K,1%,1/16W,EMPTA  I4  PR306
   1 PVCCIN_CPU1_VREF      A @S9S_MB_2U_LIB.S9S_MB_2U(SCH_1):PVCCIN_CPU1_VREF
   2 PVCCIN_CPU1_ADDR      B @S9S_MB_2U_LIB.S9S_MB_2U(SCH_1):PVCCIN_CPU1_ADDR

Q_RES_0402LF-1K,1%,1/16W,CHIP,A  I25  R2522
   1 P3V3_AUX      A @S9S_MB_2U_LIB.S9S_MB_2U(SCH_1):P3V3_AUX
   2 IRQ_PVCCIN_CPU1_VRHOT_R_N      B @S9S_MB_2U_LIB.S9S_MB_2U(SCH_1):IRQ_PVCCIN_CPU1_VRHOT_R_N

Q_RES_0402LF-0,5%,1/16W,CHIP,CA  I36  R2523
   1 IRQ_PVCCIN_CPU1_VRHOT_R_N      A @S9S_MB_2U_LIB.S9S_MB_2U(SCH_1):IRQ_PVCCIN_CPU1_VRHOT_R_N
   2 IRQ_PVCCIN_CPU1_VRHOT_N      B @S9S_MB_2U_LIB.S9S_MB_2U(SCH_1):IRQ_PVCCIN_CPU1_VRHOT_N

Q_RES_0402LF-0,5%,1/16W,CHIP,CA  I60  R308
   1 PWRGD_PVCCIN_CPU1      A @S9S_MB_2U_LIB.S9S_MB_2U(SCH_1):PWRGD_PVCCIN_CPU1
   2 PWRGD_PVCCIN_CPU1_R      B @S9S_MB_2U_LIB.S9S_MB_2U(SCH_1):PWRGD_PVCCIN_CPU1_R

Q_RES_0402LF-1K,1%,1/16W,CHIP,A  I61  R307
   1 P3V3_AUX      A @S9S_MB_2U_LIB.S9S_MB_2U(SCH_1):P3V3_AUX
   2 PWRGD_PVCCIN_CPU1_R      B @S9S_MB_2U_LIB.S9S_MB_2U(SCH_1):PWRGD_PVCCIN_CPU1_R

Q_RES_0402LF-0,5%,1/16W,CHIP,CA  I66  R2521
   1 SMB_VR_3V3AUX_SDA_R3      A @S9S_MB_2U_LIB.S9S_MB_2U(SCH_1):SMB_VR_3V3AUX_SDA_R3
   2 SMB_DIO_PVCCIN_CPU1      B @S9S_MB_2U_LIB.S9S_MB_2U(SCH_1):SMB_DIO_PVCCIN_CPU1

Q_CAP_0402-1000PF,50V,5%,EMPTYA  I68  C2859
   1 PWRGD_PVCCIN_CPU1_R      A @S9S_MB_2U_LIB.S9S_MB_2U(SCH_1):PWRGD_PVCCIN_CPU1_R
   2    GND      B @S9S_MB_2U_LIB.S9S_MB_2U(SCH_1):GND

Q_RES_0402LF-10K,1%,1/16W,EMPTA  I74  PR637
   1 PVCCIN_CPU1_ATSEN      A @S9S_MB_2U_LIB.S9S_MB_2U(SCH_1):PVCCIN_CPU1_ATSEN
   2    GND      B @S9S_MB_2U_LIB.S9S_MB_2U(SCH_1):GND

Q_CAP_C0402-1UF,16V,10%,X6S,CHA  I121  PC1194
   1 PVCCIN_CPU1_VREF      A @S9S_MB_2U_LIB.S9S_MB_2U(SCH_1):PVCCIN_CPU1_VREF
   2    GND      B @S9S_MB_2U_LIB.S9S_MB_2U(SCH_1):GND

Q_RES_0402LF-100,1%,1/16W,CHIPA  I12  PR560
   1 VSENSE_PVCCFA_EHV_FIVRA_CPU1_DN      A @S9S_MB_2U_LIB.S9S_MB_2U(SCH_1):VSENSE_PVCCFA_EHV_FIVRA_CPU1_DN
   2    GND      B @S9S_MB_2U_LIB.S9S_MB_2U(SCH_1):GND

Q_CAP_0402-0.1UF,25V,10%,EMPTYA  I28  PC547
   1 PVCCIN_CPU1_CSPIN      A @S9S_MB_2U_LIB.S9S_MB_2U(SCH_1):PVCCIN_CPU1_CSPIN
   2    GND      B @S9S_MB_2U_LIB.S9S_MB_2U(SCH_1):GND

Q_RES_0402LF-1K,1%,1/16W,EMPTYA  I29  PR313
   1 PVCCIN_CPU1_VIN_CSNIN      A @S9S_MB_2U_LIB.S9S_MB_2U(SCH_1):PVCCIN_CPU1_VIN_CSNIN
   2    GND      B @S9S_MB_2U_LIB.S9S_MB_2U(SCH_1):GND

Q_CAP_0402-0.1UF,25V,10%,X7R,CA  I31  PC548
   1 PVCCIN_CPU1_VIN_CSNIN      A @S9S_MB_2U_LIB.S9S_MB_2U(SCH_1):PVCCIN_CPU1_VIN_CSNIN
   2    GND      B @S9S_MB_2U_LIB.S9S_MB_2U(SCH_1):GND

Q_CAP_0402-1000PF,50V,5%,X7R,TA  I34  C2446
   1 PVCCFA_EHV_FIVRA_CPU1_EN_R      A @S9S_MB_2U_LIB.S9S_MB_2U(SCH_1):PVCCFA_EHV_FIVRA_CPU1_EN_R
   2    GND      B @S9S_MB_2U_LIB.S9S_MB_2U(SCH_1):GND

Q_CAP_0402-1000PF,50V,5%,EMPTYA  I35  C2447
   1 PWRGD_PVCCFA_EHV_FIVRA_CPU1_R      A @S9S_MB_2U_LIB.S9S_MB_2U(SCH_1):PWRGD_PVCCFA_EHV_FIVRA_CPU1_R
   2    GND      B @S9S_MB_2U_LIB.S9S_MB_2U(SCH_1):GND

Q_RES_0402LF-0,5%,1/16W,CHIP,CA  I59  R309
   1 FM_PVCCIN_CPU1_EN      A @S9S_MB_2U_LIB.S9S_MB_2U(SCH_1):FM_PVCCIN_CPU1_EN
   2 PVCCIN_CPU1_EN_R      B @S9S_MB_2U_LIB.S9S_MB_2U(SCH_1):PVCCIN_CPU1_EN_R

Q_RES_0402LF-0,5%,1/16W,CHIP,CA  I65  R2520
   1 SMB_VR_3V3AUX_SCL_R3      A @S9S_MB_2U_LIB.S9S_MB_2U(SCH_1):SMB_VR_3V3AUX_SCL_R3
   2 SMB_CLK_PVCCIN_CPU1      B @S9S_MB_2U_LIB.S9S_MB_2U(SCH_1):SMB_CLK_PVCCIN_CPU1

Q_RES_0402LF-49.9,1%,1/16W,EMPA  I101  R2555
   1 SVID_ALERT0_CPU1_R_N      A @S9S_MB_2U_LIB.S9S_MB_2U(SCH_1):SVID_ALERT0_CPU1_R_N
   2 PVNN_TERM_CPU1      B @S9S_MB_2U_LIB.S9S_MB_2U(SCH_1):PVNN_TERM_CPU1

Q_CAP_C0402-100NF,50V,10%,EMPTA  I120  PC552
   1 PVCCIN_CPU1_VCC      A @S9S_MB_2U_LIB.S9S_MB_2U(SCH_1):PVCCIN_CPU1_VCC
   2    GND      B @S9S_MB_2U_LIB.S9S_MB_2U(SCH_1):GND

Q_RES_0402LF-0,5%,1/16W,CHIP,CA  I7  PR303
   1 P12V_AUX      A @S9S_MB_2U_LIB.S9S_MB_2U(SCH_1):P12V_AUX
   2 PVCCIN_CPU1_VIN_CSNIN      B @S9S_MB_2U_LIB.S9S_MB_2U(SCH_1):PVCCIN_CPU1_VIN_CSNIN

Q_RES_0402LF-0,5%,1/16W,CHIP,CA  I16  R2552
   1 PWRGD_PVCCFA_EHV_FIVRA_CPU1      A @S9S_MB_2U_LIB.S9S_MB_2U(SCH_1):PWRGD_PVCCFA_EHV_FIVRA_CPU1
   2 PWRGD_PVCCFA_EHV_FIVRA_CPU1_R      B @S9S_MB_2U_LIB.S9S_MB_2U(SCH_1):PWRGD_PVCCFA_EHV_FIVRA_CPU1_R

Q_SHORT_SM-EMPTY,SHORT6  I22  PJ49
   1 VSENSE_PVCCFA_EHV_FIVRA_CPU1_DP      1 @S9S_MB_2U_LIB.S9S_MB_2U(SCH_1):VSENSE_PVCCFA_EHV_FIVRA_CPU1_DP
   2 SH_PVCCFA_EHV_FIVRA_CPU1      2 @S9S_MB_2U_LIB.S9S_MB_2U(SCH_1):SH_PVCCFA_EHV_FIVRA_CPU1

Q_CAP_0402-3300PF,50V,10%,X7R,A  I38  PC422
   1 SH_PVCCFA_EHV_FIVRA_CPU1_R      A @S9S_MB_2U_LIB.S9S_MB_2U(SCH_1):SH_PVCCFA_EHV_FIVRA_CPU1_R
   2 VSENSE_PVCCFA_EHV_FIVRA_CPU1_DN      B @S9S_MB_2U_LIB.S9S_MB_2U(SCH_1):VSENSE_PVCCFA_EHV_FIVRA_CPU1_DN

Q_RES_0402LF-100,1%,1/16W,CHIPA  I49  PR578
   1 VSENSE_PVCCIN_CPU1_DP      A @S9S_MB_2U_LIB.S9S_MB_2U(SCH_1):VSENSE_PVCCIN_CPU1_DP
   2 PVCCIN_CPU1      B @S9S_MB_2U_LIB.S9S_MB_2U(SCH_1):PVCCIN_CPU1

Q_RES_0402LF-150,1%,1/16W,CHIPA  I58  R310
   1 SVID_CLK0_CPU1_R      A @S9S_MB_2U_LIB.S9S_MB_2U(SCH_1):SVID_CLK0_CPU1_R
   2 SVID_CLK_PVCCIN_CPU1_R      B @S9S_MB_2U_LIB.S9S_MB_2U(SCH_1):SVID_CLK_PVCCIN_CPU1_R

Q_CAP_0402-3300PF,50V,10%,X7R,A  I64  PC549
   1 SH_PVCCIN_CPU1_R      A @S9S_MB_2U_LIB.S9S_MB_2U(SCH_1):SH_PVCCIN_CPU1_R
   2 VSENSE_PVCCIN_CPU1_DN      B @S9S_MB_2U_LIB.S9S_MB_2U(SCH_1):VSENSE_PVCCIN_CPU1_DN

Q_RES_0402LF-0,5%,1/16W,EMPTY,A  I81  PR4238
   1 PVCCFA_EHV_FIVRA_CPU1_IMON4      A @S9S_MB_2U_LIB.S9S_MB_2U(SCH_1):PVCCFA_EHV_FIVRA_CPU1_IMON4
   2    GND      B @S9S_MB_2U_LIB.S9S_MB_2U(SCH_1):GND

Q_RES_0402LF-49.9,1%,1/16W,CHIA  I100  R2554
   1 SVID_CLK0_CPU1_R      A @S9S_MB_2U_LIB.S9S_MB_2U(SCH_1):SVID_CLK0_CPU1_R
   2 PVNN_TERM_CPU1      B @S9S_MB_2U_LIB.S9S_MB_2U(SCH_1):PVNN_TERM_CPU1

Q_CAP_C0402-100NF,50V,10%,X7R,A  I104  C2449
   1 PVNN_TERM_CPU1      A @S9S_MB_2U_LIB.S9S_MB_2U(SCH_1):PVNN_TERM_CPU1
   2    GND      B @S9S_MB_2U_LIB.S9S_MB_2U(SCH_1):GND

Q_CAP_C0402-1UF,16V,10%,X6S,CHA  I122  PC555
   1 PVCCIN_CPU1_VCC      A @S9S_MB_2U_LIB.S9S_MB_2U(SCH_1):PVCCIN_CPU1_VCC
   2    GND      B @S9S_MB_2U_LIB.S9S_MB_2U(SCH_1):GND

Q_RES_0402LF-1,1%,1/16W,CHIP,CA  I126  PR323
   1 PVCCIN_CPU1_VCC      A @S9S_MB_2U_LIB.S9S_MB_2U(SCH_1):PVCCIN_CPU1_VCC
   2 P3V3_AUX      B @S9S_MB_2U_LIB.S9S_MB_2U(SCH_1):P3V3_AUX

Q_RES_0402LF-5.23K,1%,1/16W,CHA  I6  PR318
   1 PVCCIN_CPU1_ADDR      A @S9S_MB_2U_LIB.S9S_MB_2U(SCH_1):PVCCIN_CPU1_ADDR
   2    GND      B @S9S_MB_2U_LIB.S9S_MB_2U(SCH_1):GND

Q_RES_0402LF-0,5%,1/16W,EMPTY,A  I9  PR304
   1 P12V_AUX      A @S9S_MB_2U_LIB.S9S_MB_2U(SCH_1):P12V_AUX
   2 PVCCIN_CPU1_CSPIN      B @S9S_MB_2U_LIB.S9S_MB_2U(SCH_1):PVCCIN_CPU1_CSPIN

Q_RES_0402LF-1K,1%,1/16W,CHIP,A  I15  R2551
   1 P3V3_AUX      A @S9S_MB_2U_LIB.S9S_MB_2U(SCH_1):P3V3_AUX
   2 PWRGD_PVCCFA_EHV_FIVRA_CPU1_R      B @S9S_MB_2U_LIB.S9S_MB_2U(SCH_1):PWRGD_PVCCFA_EHV_FIVRA_CPU1_R

Q_RES_0402LF-100,1%,1/16W,CHIPA  I23  PR561
   1 VSENSE_PVCCFA_EHV_FIVRA_CPU1_DP      A @S9S_MB_2U_LIB.S9S_MB_2U(SCH_1):VSENSE_PVCCFA_EHV_FIVRA_CPU1_DP
   2 PVCCFA_EHV_FIVRA_CPU1      B @S9S_MB_2U_LIB.S9S_MB_2U(SCH_1):PVCCFA_EHV_FIVRA_CPU1

Q_RES_0402LF-0,5%,1/16W,CHIP,CA  I27  PR305
   1 PVCCIN_CPU1_CSPIN      A @S9S_MB_2U_LIB.S9S_MB_2U(SCH_1):PVCCIN_CPU1_CSPIN
   2    GND      B @S9S_MB_2U_LIB.S9S_MB_2U(SCH_1):GND

RAA229126GNPHA0-RAA229126GNP#HA  I33  PU29
  27 PVCCIN_CPU1_IMON1   CS11 @S9S_MB_2U_LIB.S9S_MB_2U(SCH_1):PVCCIN_CPU1_IMON1
  47 PVCCIN_CPU1_VCC    VCC @S9S_MB_2U_LIB.S9S_MB_2U(SCH_1):PVCCIN_CPU1_VCC
  24 PVCCFA_EHV_FIVRA_CPU1_EN_R    EN1 @S9S_MB_2U_LIB.S9S_MB_2U(SCH_1):PVCCFA_EHV_FIVRA_CPU1_EN_R
  14 SMB_CLK_PVCCIN_CPU1  PMSCL @S9S_MB_2U_LIB.S9S_MB_2U(SCH_1):SMB_CLK_PVCCIN_CPU1
  22 SVID_DIO_PVCCIN_CPU1_R SVDATA @S9S_MB_2U_LIB.S9S_MB_2U(SCH_1):SVID_DIO_PVCCIN_CPU1_R
  32 PVCCIN_CPU1_IMON6    CS6 @S9S_MB_2U_LIB.S9S_MB_2U(SCH_1):PVCCIN_CPU1_IMON6
  23 SVID_ALERT_PVCCIN_CPU1_R NSVALERT @S9S_MB_2U_LIB.S9S_MB_2U(SCH_1):SVID_ALERT_PVCCIN_CPU1_R
  18 IRQ_PVCCIN_CPU1_VRHOT_N NVRHOT @S9S_MB_2U_LIB.S9S_MB_2U(SCH_1):IRQ_PVCCIN_CPU1_VRHOT_N
  33 PVCCIN_CPU1_IMON7    CS5 @S9S_MB_2U_LIB.S9S_MB_2U(SCH_1):PVCCIN_CPU1_IMON7
  34 PVCCIN_CPU1_IMON8    CS4 @S9S_MB_2U_LIB.S9S_MB_2U(SCH_1):PVCCIN_CPU1_IMON8
  20 PWRGD_PVCCFA_EHV_FIVRA_CPU1_R    PG1 @S9S_MB_2U_LIB.S9S_MB_2U(SCH_1):PWRGD_PVCCFA_EHV_FIVRA_CPU1_R
  21 SVID_CLK_PVCCIN_CPU1_R  SVCLK @S9S_MB_2U_LIB.S9S_MB_2U(SCH_1):SVID_CLK_PVCCIN_CPU1_R
  15 NC_PVCCIN_CPU1_SMB_ALERT NPMALERT @S9S_MB_2U_LIB.S9S_MB_2U(SCH_1):NC_PVCCIN_CPU1_SMB_ALERT
  17 PVCCIN_CPU1_EN_R    EN0 @S9S_MB_2U_LIB.S9S_MB_2U(SCH_1):PVCCIN_CPU1_EN_R
  26 VSENSE_PVCCIN_CPU1_DN  RGND0 @S9S_MB_2U_LIB.S9S_MB_2U(SCH_1):VSENSE_PVCCIN_CPU1_DN
  13 SMB_DIO_PVCCIN_CPU1  PMSDA @S9S_MB_2U_LIB.S9S_MB_2U(SCH_1):SMB_DIO_PVCCIN_CPU1
   5 PVCCIN_CPU1_PWM8   PWM4 @S9S_MB_2U_LIB.S9S_MB_2U(SCH_1):PVCCIN_CPU1_PWM8
   6 PVCCIN_CPU1_PWM7   PWM5 @S9S_MB_2U_LIB.S9S_MB_2U(SCH_1):PVCCIN_CPU1_PWM7
  25 SH_PVCCIN_CPU1_R  VSEN0 @S9S_MB_2U_LIB.S9S_MB_2U(SCH_1):SH_PVCCIN_CPU1_R
   2 PVCCFA_EHV_FIVRA_CPU1_PWM2   PWM1 @S9S_MB_2U_LIB.S9S_MB_2U(SCH_1):PVCCFA_EHV_FIVRA_CPU1_PWM2
  16 PWRGD_PVCCIN_CPU1_R    PG0 @S9S_MB_2U_LIB.S9S_MB_2U(SCH_1):PWRGD_PVCCIN_CPU1_R
   7 PVCCIN_CPU1_PWM6   PWM6 @S9S_MB_2U_LIB.S9S_MB_2U(SCH_1):PVCCIN_CPU1_PWM6
  48 PVCCIN_CPU1_VREF   VCCS @S9S_MB_2U_LIB.S9S_MB_2U(SCH_1):PVCCIN_CPU1_VREF
  45 PVCCIN_CPU1_CSPIN VMON||IINSEN||VSYS||ISYS @S9S_MB_2U_LIB.S9S_MB_2U(SCH_1):PVCCIN_CPU1_CSPIN
  46 PVCCIN_CPU1_VIN_CSNIN VINSEN||VSYS @S9S_MB_2U_LIB.S9S_MB_2U(SCH_1):PVCCIN_CPU1_VIN_CSNIN
  44 PVCCFA_EHV_FIVRA_CPU1_BTSEN TEMP1||ISYS @S9S_MB_2U_LIB.S9S_MB_2U(SCH_1):PVCCFA_EHV_FIVRA_CPU1_BTSEN
  19 PVCCIN_CPU1_PIN_ALERT NPINALERT||NPSYS_CRIT @S9S_MB_2U_LIB.S9S_MB_2U(SCH_1):PVCCIN_CPU1_PIN_ALERT
  40 SH_PVCCFA_EHV_FIVRA_CPU1_R  VSEN1 @S9S_MB_2U_LIB.S9S_MB_2U(SCH_1):SH_PVCCFA_EHV_FIVRA_CPU1_R
  39 VSENSE_PVCCFA_EHV_FIVRA_CPU1_DN  RGND1 @S9S_MB_2U_LIB.S9S_MB_2U(SCH_1):VSENSE_PVCCFA_EHV_FIVRA_CPU1_DN
  37 PVCCFA_EHV_FIVRA_CPU1_IMON2    CS1 @S9S_MB_2U_LIB.S9S_MB_2U(SCH_1):PVCCFA_EHV_FIVRA_CPU1_IMON2
  12 PVCCIN_CPU1_PWM1  PWM11 @S9S_MB_2U_LIB.S9S_MB_2U(SCH_1):PVCCIN_CPU1_PWM1
   4 PVCCFA_EHV_FIVRA_CPU1_PWM4   PWM3 @S9S_MB_2U_LIB.S9S_MB_2U(SCH_1):PVCCFA_EHV_FIVRA_CPU1_PWM4
  35 PVCCFA_EHV_FIVRA_CPU1_IMON4    CS3 @S9S_MB_2U_LIB.S9S_MB_2U(SCH_1):PVCCFA_EHV_FIVRA_CPU1_IMON4
   3 PVCCFA_EHV_FIVRA_CPU1_PWM3   PWM2 @S9S_MB_2U_LIB.S9S_MB_2U(SCH_1):PVCCFA_EHV_FIVRA_CPU1_PWM3
  36 PVCCFA_EHV_FIVRA_CPU1_IMON3    CS2 @S9S_MB_2U_LIB.S9S_MB_2U(SCH_1):PVCCFA_EHV_FIVRA_CPU1_IMON3
  41 PVCCIN_CPU1_VR_FAULT    CFP @S9S_MB_2U_LIB.S9S_MB_2U(SCH_1):PVCCIN_CPU1_VR_FAULT
  TH    GND TH_GND @S9S_MB_2U_LIB.S9S_MB_2U(SCH_1):GND
  42 PVCCIN_CPU1_ADDR ADDR_CFG @S9S_MB_2U_LIB.S9S_MB_2U(SCH_1):PVCCIN_CPU1_ADDR
  43 PVCCIN_CPU1_ATSEN  TEMP0 @S9S_MB_2U_LIB.S9S_MB_2U(SCH_1):PVCCIN_CPU1_ATSEN
   1 PVCCFA_EHV_FIVRA_CPU1_PWM1   PWM0 @S9S_MB_2U_LIB.S9S_MB_2U(SCH_1):PVCCFA_EHV_FIVRA_CPU1_PWM1
  38 PVCCFA_EHV_FIVRA_CPU1_IMON1    CS0 @S9S_MB_2U_LIB.S9S_MB_2U(SCH_1):PVCCFA_EHV_FIVRA_CPU1_IMON1
   8 PVCCIN_CPU1_PWM5   PWM7 @S9S_MB_2U_LIB.S9S_MB_2U(SCH_1):PVCCIN_CPU1_PWM5
  31 PVCCIN_CPU1_IMON5    CS7 @S9S_MB_2U_LIB.S9S_MB_2U(SCH_1):PVCCIN_CPU1_IMON5
   9 PVCCIN_CPU1_PWM4   PWM8 @S9S_MB_2U_LIB.S9S_MB_2U(SCH_1):PVCCIN_CPU1_PWM4
  30 PVCCIN_CPU1_IMON4    CS8 @S9S_MB_2U_LIB.S9S_MB_2U(SCH_1):PVCCIN_CPU1_IMON4
  10 PVCCIN_CPU1_PWM3   PWM9 @S9S_MB_2U_LIB.S9S_MB_2U(SCH_1):PVCCIN_CPU1_PWM3
  29 PVCCIN_CPU1_IMON3    CS9 @S9S_MB_2U_LIB.S9S_MB_2U(SCH_1):PVCCIN_CPU1_IMON3
  11 PVCCIN_CPU1_PWM2  PWM10 @S9S_MB_2U_LIB.S9S_MB_2U(SCH_1):PVCCIN_CPU1_PWM2
  28 PVCCIN_CPU1_IMON2   CS10 @S9S_MB_2U_LIB.S9S_MB_2U(SCH_1):PVCCIN_CPU1_IMON2

Q_RES_0402LF-0,5%,1/16W,CHIP,CA  I37  PR242
   1 SH_PVCCFA_EHV_FIVRA_CPU1      A @S9S_MB_2U_LIB.S9S_MB_2U(SCH_1):SH_PVCCFA_EHV_FIVRA_CPU1
   2 SH_PVCCFA_EHV_FIVRA_CPU1_R      B @S9S_MB_2U_LIB.S9S_MB_2U(SCH_1):SH_PVCCFA_EHV_FIVRA_CPU1_R

Q_RES_0402LF-100,1%,1/16W,CHIPA  I45  PR574
   1 VSENSE_PVCCIN_CPU1_DN      A @S9S_MB_2U_LIB.S9S_MB_2U(SCH_1):VSENSE_PVCCIN_CPU1_DN
   2    GND      B @S9S_MB_2U_LIB.S9S_MB_2U(SCH_1):GND

Q_SHORT_SM-EMPTY,SHORT6  I46  PJ52
   1 VSENSE_PVCCIN_CPU1_DP      1 @S9S_MB_2U_LIB.S9S_MB_2U(SCH_1):VSENSE_PVCCIN_CPU1_DP
   2 SH_PVCCIN_CPU1      2 @S9S_MB_2U_LIB.S9S_MB_2U(SCH_1):SH_PVCCIN_CPU1

Q_RES_0402LF-0,5%,1/16W,CHIP,CA  I56  R311
   1 SVID_DIO0_CPU1_R      A @S9S_MB_2U_LIB.S9S_MB_2U(SCH_1):SVID_DIO0_CPU1_R
   2 SVID_DIO_PVCCIN_CPU1_R      B @S9S_MB_2U_LIB.S9S_MB_2U(SCH_1):SVID_DIO_PVCCIN_CPU1_R

Q_RES_0402LF-0,5%,1/16W,CHIP,CA  I57  R312
   1 SVID_ALERT0_CPU1_R_N      A @S9S_MB_2U_LIB.S9S_MB_2U(SCH_1):SVID_ALERT0_CPU1_R_N
   2 SVID_ALERT_PVCCIN_CPU1_R      B @S9S_MB_2U_LIB.S9S_MB_2U(SCH_1):SVID_ALERT_PVCCIN_CPU1_R

Q_CAP_0402-470PF,50V,10%,X7R,TA  I72  PC554
   1 PVCCIN_CPU1_ATSEN      A @S9S_MB_2U_LIB.S9S_MB_2U(SCH_1):PVCCIN_CPU1_ATSEN
   2    GND      B @S9S_MB_2U_LIB.S9S_MB_2U(SCH_1):GND

Q_RES_0402LF-0,5%,1/16W,EMPTY,A  I80  PR4239
   1 PVCCFA_EHV_FIVRA_CPU1_IMON3      A @S9S_MB_2U_LIB.S9S_MB_2U(SCH_1):PVCCFA_EHV_FIVRA_CPU1_IMON3
   2    GND      B @S9S_MB_2U_LIB.S9S_MB_2U(SCH_1):GND

Q_CAP_0402-470PF,50V,10%,X7R,TA  I92  PC101
   1 PVCCFA_EHV_FIVRA_CPU1_BTSEN      A @S9S_MB_2U_LIB.S9S_MB_2U(SCH_1):PVCCFA_EHV_FIVRA_CPU1_BTSEN
   2    GND      B @S9S_MB_2U_LIB.S9S_MB_2U(SCH_1):GND

Q_RES_0402LF-10K,1%,1/16W,EMPTA  I94  PR453
   1 PVCCFA_EHV_FIVRA_CPU1_BTSEN      A @S9S_MB_2U_LIB.S9S_MB_2U(SCH_1):PVCCFA_EHV_FIVRA_CPU1_BTSEN
   2    GND      B @S9S_MB_2U_LIB.S9S_MB_2U(SCH_1):GND

Q_RES_0402LF-100,1%,1/16W,CHIPA  I99  R2553
   1 SVID_DIO0_CPU1_R      A @S9S_MB_2U_LIB.S9S_MB_2U(SCH_1):SVID_DIO0_CPU1_R
   2 PVNN_TERM_CPU1      B @S9S_MB_2U_LIB.S9S_MB_2U(SCH_1):PVNN_TERM_CPU1

Q_CAP_C0603-10UF,4V,20%,EMPTY,A  I103  C2448
   1 PVNN_TERM_CPU1      A @S9S_MB_2U_LIB.S9S_MB_2U(SCH_1):PVNN_TERM_CPU1
   2    GND      B @S9S_MB_2U_LIB.S9S_MB_2U(SCH_1):GND

Q_CAP_C0402-10UF,6.3V,20%,X6S,B  I119  PC553
   1 PVCCIN_CPU1_VREF      A @S9S_MB_2U_LIB.S9S_MB_2U(SCH_1):PVCCIN_CPU1_VREF
   2    GND      B @S9S_MB_2U_LIB.S9S_MB_2U(SCH_1):GND

Q_CAP_0402-0.1UF,25V,10%,EMPTYA  I128  PC2366
   1 PVCCIN_CPU1_VCC      A @S9S_MB_2U_LIB.S9S_MB_2U(SCH_1):PVCCIN_CPU1_VCC
   2    GND      B @S9S_MB_2U_LIB.S9S_MB_2U(SCH_1):GND


DRAWING: @S9S_MB_2U_LIB.S9S_MB_2U(SCH_1):PAGE275 

Q_RES_0402LF-8.87K,1%,1/16W,EMA  I2  PR224
   1 PVCCFA_EHV_FIVRA_CPU1_LSET2      A @S9S_MB_2U_LIB.S9S_MB_2U(SCH_1):PVCCFA_EHV_FIVRA_CPU1_LSET2
   2    GND      B @S9S_MB_2U_LIB.S9S_MB_2U(SCH_1):GND

ISL99390FRZTR5935-ISL99390FRZ-A  I9  PU76_P1_2
  34 PVCCFA_EHV_FIVRA_CPU1_PWM2    PWM @S9S_MB_2U_LIB.S9S_MB_2U(SCH_1):PVCCFA_EHV_FIVRA_CPU1_PWM2
  39 PVCCIN_CPU1_VREF  REFIN @S9S_MB_2U_LIB.S9S_MB_2U(SCH_1):PVCCIN_CPU1_VREF
   3 PVCCFA_EHV_FIVRA_CPU1_VDD2    VCC @S9S_MB_2U_LIB.S9S_MB_2U(SCH_1):PVCCFA_EHV_FIVRA_CPU1_VDD2
   2    GND   AGND @S9S_MB_2U_LIB.S9S_MB_2U(SCH_1):GND
  33 SW_PVCCFA_EHV_FIVRA_CPU1_BOOT2   BOOT @S9S_MB_2U_LIB.S9S_MB_2U(SCH_1):SW_PVCCFA_EHV_FIVRA_CPU1_BOOT2
25_29 SW_P12V_PVCCFA_EHV_FIVRA_CPU1_L   VIN1 @S9S_MB_2U_LIB.S9S_MB_2U(SCH_1):SW_P12V_PVCCFA_EHV_FIVRA_CPU1_L
  32 SW_PVCCFA_EHV_FIVRA_CPU1_BOOTR2  PHASE @S9S_MB_2U_LIB.S9S_MB_2U(SCH_1):SW_PVCCFA_EHV_FIVRA_CPU1_BOOTR2
   4 PVCCFA_EHV_FIVRA_CPU1_PVCC2   PVCC @S9S_MB_2U_LIB.S9S_MB_2U(SCH_1):PVCCFA_EHV_FIVRA_CPU1_PVCC2
  36 PVCCFA_EHV_FIVRA_CPU1_BTSEN TOUT_FLT @S9S_MB_2U_LIB.S9S_MB_2U(SCH_1):PVCCFA_EHV_FIVRA_CPU1_BTSEN
  38 PVCCFA_EHV_FIVRA_CPU1_IMON2   IOUT @S9S_MB_2U_LIB.S9S_MB_2U(SCH_1):PVCCFA_EHV_FIVRA_CPU1_IMON2
  37 PVCCFA_EHV_FIVRA_CPU1_LSET2   LSET @S9S_MB_2U_LIB.S9S_MB_2U(SCH_1):PVCCFA_EHV_FIVRA_CPU1_LSET2
10_19 SW_PVCCFA_EHV_FIVRA_CPU1_SW2     SW @S9S_MB_2U_LIB.S9S_MB_2U(SCH_1):SW_PVCCFA_EHV_FIVRA_CPU1_SW2
   5    GND  PGND1 @S9S_MB_2U_LIB.S9S_MB_2U(SCH_1):GND
  30 SW_P12V_PVCCFA_EHV_FIVRA_CPU1_L   VIN2 @S9S_MB_2U_LIB.S9S_MB_2U(SCH_1):SW_P12V_PVCCFA_EHV_FIVRA_CPU1_L
   1 PVCCFA_EHV_FIVRA_CPU1_VOS2    VOS @S9S_MB_2U_LIB.S9S_MB_2U(SCH_1):PVCCFA_EHV_FIVRA_CPU1_VOS2
  40    GND  PGND3 @S9S_MB_2U_LIB.S9S_MB_2U(SCH_1):GND
  35 PVCCFA_EHV_FIVRA_CPU1_VDD2     EN @S9S_MB_2U_LIB.S9S_MB_2U(SCH_1):PVCCFA_EHV_FIVRA_CPU1_VDD2
  31     NC    DNC     NC
   6     NC    GL1     NC
  41     NC    GL2     NC
7_9-20_24    GND  PGND2 @S9S_MB_2U_LIB.S9S_MB_2U(SCH_1):GND

Q_CAP_C0402-2.2UF,10V,10%,X6S,A  I27  PC395
   1 PVCCFA_EHV_FIVRA_CPU1_VDD1      A @S9S_MB_2U_LIB.S9S_MB_2U(SCH_1):PVCCFA_EHV_FIVRA_CPU1_VDD1
   2    GND      B @S9S_MB_2U_LIB.S9S_MB_2U(SCH_1):GND

Q_CAP_0402-3300PF,50V,10%,X7R,A  I37  PC398_P1_2
   1 SW_P12V_PVCCFA_EHV_FIVRA_CPU1_L      A @S9S_MB_2U_LIB.S9S_MB_2U(SCH_1):SW_P12V_PVCCFA_EHV_FIVRA_CPU1_L
   2    GND      B @S9S_MB_2U_LIB.S9S_MB_2U(SCH_1):GND

Q_CAP_C0402-1UF,16V,10%,X6S,CHA  I39  PC400_P1_2
   1 SW_P12V_PVCCFA_EHV_FIVRA_CPU1_L      A @S9S_MB_2U_LIB.S9S_MB_2U(SCH_1):SW_P12V_PVCCFA_EHV_FIVRA_CPU1_L
   2    GND      B @S9S_MB_2U_LIB.S9S_MB_2U(SCH_1):GND

Q_INDUCTOR_SMLF-130NH/106A,INDA  I44  PL19
   2 PVCCFA_EHV_FIVRA_CPU1      2 @S9S_MB_2U_LIB.S9S_MB_2U(SCH_1):PVCCFA_EHV_FIVRA_CPU1
   1 SW_PVCCFA_EHV_FIVRA_CPU1_SW2      1 @S9S_MB_2U_LIB.S9S_MB_2U(SCH_1):SW_PVCCFA_EHV_FIVRA_CPU1_SW2

Q_CAP_C0805-22UF,16V,20%,X6S,CA  I46  PC725_P1_2
   1 SW_P12V_PVCCFA_EHV_FIVRA_CPU1_L      A @S9S_MB_2U_LIB.S9S_MB_2U(SCH_1):SW_P12V_PVCCFA_EHV_FIVRA_CPU1_L
   2    GND      B @S9S_MB_2U_LIB.S9S_MB_2U(SCH_1):GND

Q_CAP_0402-3300PF,50V,10%,X7R,A  I49  PC397_P1_1
   1 SW_P12V_PVCCFA_EHV_FIVRA_CPU1_R      A @S9S_MB_2U_LIB.S9S_MB_2U(SCH_1):SW_P12V_PVCCFA_EHV_FIVRA_CPU1_R
   2    GND      B @S9S_MB_2U_LIB.S9S_MB_2U(SCH_1):GND

Q_RES_0402LF-3.3,1%,1/16W,CHIPA  I50  PR1800
   1 SW_PVCCFA_EHV_FIVRA_CPU1_BOOT1      A @S9S_MB_2U_LIB.S9S_MB_2U(SCH_1):SW_PVCCFA_EHV_FIVRA_CPU1_BOOT1
   2 SW_PVCCFA_EHV_FIVRA_CPU1_BOOT1_      B @S9S_MB_2U_LIB.S9S_MB_2U(SCH_1):SW_PVCCFA_EHV_FIVRA_CPU1_BOOT1_R

Q_RES_0402LF-0,5%,1/16W,CHIP,CA  I53  PR1331
   1 PVCCFA_EHV_FIVRA_CPU1_VOS1      A @S9S_MB_2U_LIB.S9S_MB_2U(SCH_1):PVCCFA_EHV_FIVRA_CPU1_VOS1
   2 PVCCFA_EHV_FIVRA_CPU1      B @S9S_MB_2U_LIB.S9S_MB_2U(SCH_1):PVCCFA_EHV_FIVRA_CPU1

Q_INDUCTOR_SMLF-130NH/106A,INDA  I55  PL18
   2 PVCCFA_EHV_FIVRA_CPU1      2 @S9S_MB_2U_LIB.S9S_MB_2U(SCH_1):PVCCFA_EHV_FIVRA_CPU1
   1 SW_PVCCFA_EHV_FIVRA_CPU1_SW1      1 @S9S_MB_2U_LIB.S9S_MB_2U(SCH_1):SW_PVCCFA_EHV_FIVRA_CPU1_SW1

Q_CAP_C0402-100NF,50V,10%,X7R,A  I60  PC621_P1_1
   1 PVCCFA_EHV_FIVRA_CPU1      A @S9S_MB_2U_LIB.S9S_MB_2U(SCH_1):PVCCFA_EHV_FIVRA_CPU1
   2    GND      B @S9S_MB_2U_LIB.S9S_MB_2U(SCH_1):GND

Q_CAP_C0805-22UF,4V,20%,X6S,CHA  I63  PC413_P1_2
   1 PVCCFA_EHV_FIVRA_CPU1      A @S9S_MB_2U_LIB.S9S_MB_2U(SCH_1):PVCCFA_EHV_FIVRA_CPU1
   2    GND      B @S9S_MB_2U_LIB.S9S_MB_2U(SCH_1):GND

Q_CAPP_THLF-560UF,2.5V,20%,OSCA  I68  PC416
   1 PVCCFA_EHV_FIVRA_CPU1      A @S9S_MB_2U_LIB.S9S_MB_2U(SCH_1):PVCCFA_EHV_FIVRA_CPU1
   2    GND      B @S9S_MB_2U_LIB.S9S_MB_2U(SCH_1):GND

Q_CAP_C0805-22UF,16V,20%,X6S,CA  I84  PC1679
   1 SW_P12V_PVCCFA_EHV_FIVRA_CPU1_L      A @S9S_MB_2U_LIB.S9S_MB_2U(SCH_1):SW_P12V_PVCCFA_EHV_FIVRA_CPU1_L
   2    GND      B @S9S_MB_2U_LIB.S9S_MB_2U(SCH_1):GND

Q_CAP_0402-0.1UF,25V,10%,X7R,CA  I29  PC1367
   1    GND      A @S9S_MB_2U_LIB.S9S_MB_2U(SCH_1):GND
   2 PVCCIN_CPU1_VREF      B @S9S_MB_2U_LIB.S9S_MB_2U(SCH_1):PVCCIN_CPU1_VREF

Q_CAP_C0805-22UF,16V,20%,X6S,CA  I40  PC404_P1_2
   1 SW_P12V_PVCCFA_EHV_FIVRA_CPU1_L      A @S9S_MB_2U_LIB.S9S_MB_2U(SCH_1):SW_P12V_PVCCFA_EHV_FIVRA_CPU1_L
   2    GND      B @S9S_MB_2U_LIB.S9S_MB_2U(SCH_1):GND

Q_RES_0402LF-0,5%,1/16W,CHIP,CA  I41  PR1332
   1 PVCCFA_EHV_FIVRA_CPU1_VOS2      A @S9S_MB_2U_LIB.S9S_MB_2U(SCH_1):PVCCFA_EHV_FIVRA_CPU1_VOS2
   2 PVCCFA_EHV_FIVRA_CPU1      B @S9S_MB_2U_LIB.S9S_MB_2U(SCH_1):PVCCFA_EHV_FIVRA_CPU1

Q_CAP_C0402-1UF,16V,10%,X6S,CHA  I51  PC399_P1_1
   1 SW_P12V_PVCCFA_EHV_FIVRA_CPU1_R      A @S9S_MB_2U_LIB.S9S_MB_2U(SCH_1):SW_P12V_PVCCFA_EHV_FIVRA_CPU1_R
   2    GND      B @S9S_MB_2U_LIB.S9S_MB_2U(SCH_1):GND

Q_CAP_C0805-22UF,16V,20%,X6S,CA  I52  PC403_P1_1
   1 SW_P12V_PVCCFA_EHV_FIVRA_CPU1_R      A @S9S_MB_2U_LIB.S9S_MB_2U(SCH_1):SW_P12V_PVCCFA_EHV_FIVRA_CPU1_R
   2    GND      B @S9S_MB_2U_LIB.S9S_MB_2U(SCH_1):GND

Q_CAP_C0805-22UF,4V,20%,X6S,CHA  I62  PC411_P1_2
   1 PVCCFA_EHV_FIVRA_CPU1      A @S9S_MB_2U_LIB.S9S_MB_2U(SCH_1):PVCCFA_EHV_FIVRA_CPU1
   2    GND      B @S9S_MB_2U_LIB.S9S_MB_2U(SCH_1):GND

Q_CAP_C0805-22UF,16V,20%,X6S,CA  I83  PC1678
   1 SW_P12V_PVCCFA_EHV_FIVRA_CPU1_L      A @S9S_MB_2U_LIB.S9S_MB_2U(SCH_1):SW_P12V_PVCCFA_EHV_FIVRA_CPU1_L
   2    GND      B @S9S_MB_2U_LIB.S9S_MB_2U(SCH_1):GND

Q_CAP_C0402-2.2UF,10V,10%,X6S,A  I11  PC396
   1 PVCCFA_EHV_FIVRA_CPU1_VDD2      A @S9S_MB_2U_LIB.S9S_MB_2U(SCH_1):PVCCFA_EHV_FIVRA_CPU1_VDD2
   2    GND      B @S9S_MB_2U_LIB.S9S_MB_2U(SCH_1):GND

Q_RES_0402LF-2.2,1%,1/16W,CHIPA  I12  PR227
   1 PVCCFA_EHV_FIVRA_CPU1_PVCC2      A @S9S_MB_2U_LIB.S9S_MB_2U(SCH_1):PVCCFA_EHV_FIVRA_CPU1_PVCC2
   2 PVCCFA_EHV_FIVRA_CPU1_VDD2      B @S9S_MB_2U_LIB.S9S_MB_2U(SCH_1):PVCCFA_EHV_FIVRA_CPU1_VDD2

Q_RES_0402LF-0,5%,1/16W,CHIP,CA  I32  PR701
   1    P5V      A @S9S_MB_2U_LIB.S9S_MB_2U(SCH_1):P5V
   2 PVCCFA_EHV_FIVRA_CPU1_PVCC1      B @S9S_MB_2U_LIB.S9S_MB_2U(SCH_1):PVCCFA_EHV_FIVRA_CPU1_PVCC1

Q_RES_0402LF-0,5%,1/16W,EMPTY,A  I34  PR703
   1   P3V3      A @S9S_MB_2U_LIB.S9S_MB_2U(SCH_1):P3V3
   2 PVCCFA_EHV_FIVRA_CPU1_PVCC1      B @S9S_MB_2U_LIB.S9S_MB_2U(SCH_1):PVCCFA_EHV_FIVRA_CPU1_PVCC1

Q_RES_0402LF-3.3,1%,1/16W,CHIPA  I38  PR1801
   1 SW_PVCCFA_EHV_FIVRA_CPU1_BOOT2      A @S9S_MB_2U_LIB.S9S_MB_2U(SCH_1):SW_PVCCFA_EHV_FIVRA_CPU1_BOOT2
   2 SW_PVCCFA_EHV_FIVRA_CPU1_BOOT2_      B @S9S_MB_2U_LIB.S9S_MB_2U(SCH_1):SW_PVCCFA_EHV_FIVRA_CPU1_BOOT2_R

Q_CAP_C0402-100NF,50V,10%,X7R,A  I54  PC401
   1 SW_PVCCFA_EHV_FIVRA_CPU1_BOOT1_      A @S9S_MB_2U_LIB.S9S_MB_2U(SCH_1):SW_PVCCFA_EHV_FIVRA_CPU1_BOOT1_R
   2 SW_PVCCFA_EHV_FIVRA_CPU1_BOOTR1      B @S9S_MB_2U_LIB.S9S_MB_2U(SCH_1):SW_PVCCFA_EHV_FIVRA_CPU1_BOOTR1

Q_CAP_C0805-22UF,16V,20%,X6S,CA  I56  PC405_P1_1
   1 SW_P12V_PVCCFA_EHV_FIVRA_CPU1_R      A @S9S_MB_2U_LIB.S9S_MB_2U(SCH_1):SW_P12V_PVCCFA_EHV_FIVRA_CPU1_R
   2    GND      B @S9S_MB_2U_LIB.S9S_MB_2U(SCH_1):GND

Q_CAP_C0402-1UF,16V,10%,X6S,CHA  I61  PC408_P1_2
   1 PVCCFA_EHV_FIVRA_CPU1      A @S9S_MB_2U_LIB.S9S_MB_2U(SCH_1):PVCCFA_EHV_FIVRA_CPU1
   2    GND      B @S9S_MB_2U_LIB.S9S_MB_2U(SCH_1):GND

Q_RES_0402LF-499,1%,1/16W,CHIPA  I64  PR4241
   1 PVCCFA_EHV_FIVRA_CPU1      A @S9S_MB_2U_LIB.S9S_MB_2U(SCH_1):PVCCFA_EHV_FIVRA_CPU1
   2    GND      B @S9S_MB_2U_LIB.S9S_MB_2U(SCH_1):GND

Q_CAPP_SMLF-330UF,2.5V,+10/-35B  I70  PC418
   1 PVCCFA_EHV_FIVRA_CPU1      A @S9S_MB_2U_LIB.S9S_MB_2U(SCH_1):PVCCFA_EHV_FIVRA_CPU1
   2    GND      B @S9S_MB_2U_LIB.S9S_MB_2U(SCH_1):GND

Q_CAPP_SMLF-330UF,2.5V,+10/-35B  I72  PC2172
   1 PVCCFA_EHV_FIVRA_CPU1      A @S9S_MB_2U_LIB.S9S_MB_2U(SCH_1):PVCCFA_EHV_FIVRA_CPU1
   2    GND      B @S9S_MB_2U_LIB.S9S_MB_2U(SCH_1):GND

Q_CAP_C0805-22UF,16V,20%,X6S,CA  I80  PC1677
   1 SW_P12V_PVCCFA_EHV_FIVRA_CPU1_L      A @S9S_MB_2U_LIB.S9S_MB_2U(SCH_1):SW_P12V_PVCCFA_EHV_FIVRA_CPU1_L
   2    GND      B @S9S_MB_2U_LIB.S9S_MB_2U(SCH_1):GND

Q_CAP_0402-0.1UF,25V,10%,X7R,CA  I8  PC1368
   1    GND      A @S9S_MB_2U_LIB.S9S_MB_2U(SCH_1):GND
   2 PVCCIN_CPU1_VREF      B @S9S_MB_2U_LIB.S9S_MB_2U(SCH_1):PVCCIN_CPU1_VREF

Q_RES_0402LF-0,5%,1/16W,CHIP,CA  I13  PR702
   1    P5V      A @S9S_MB_2U_LIB.S9S_MB_2U(SCH_1):P5V
   2 PVCCFA_EHV_FIVRA_CPU1_PVCC2      B @S9S_MB_2U_LIB.S9S_MB_2U(SCH_1):PVCCFA_EHV_FIVRA_CPU1_PVCC2

Q_CAP_C0402-2.2UF,10V,10%,X6S,A  I16  PC1243_P1_2
   1 PVCCFA_EHV_FIVRA_CPU1_PVCC2      A @S9S_MB_2U_LIB.S9S_MB_2U(SCH_1):PVCCFA_EHV_FIVRA_CPU1_PVCC2
   2    GND      B @S9S_MB_2U_LIB.S9S_MB_2U(SCH_1):GND

Q_RES_0402LF-0,5%,1/16W,EMPTY,A  I17  PR704
   1   P3V3      A @S9S_MB_2U_LIB.S9S_MB_2U(SCH_1):P3V3
   2 PVCCFA_EHV_FIVRA_CPU1_PVCC2      B @S9S_MB_2U_LIB.S9S_MB_2U(SCH_1):PVCCFA_EHV_FIVRA_CPU1_PVCC2

Q_RES_0402LF-8.87K,1%,1/16W,EMA  I20  PR225
   1 PVCCFA_EHV_FIVRA_CPU1_LSET1      A @S9S_MB_2U_LIB.S9S_MB_2U(SCH_1):PVCCFA_EHV_FIVRA_CPU1_LSET1
   2    GND      B @S9S_MB_2U_LIB.S9S_MB_2U(SCH_1):GND

Q_RES_0402LF-2.2,1%,1/16W,CHIPA  I28  PR226
   1 PVCCFA_EHV_FIVRA_CPU1_PVCC1      A @S9S_MB_2U_LIB.S9S_MB_2U(SCH_1):PVCCFA_EHV_FIVRA_CPU1_PVCC1
   2 PVCCFA_EHV_FIVRA_CPU1_VDD1      B @S9S_MB_2U_LIB.S9S_MB_2U(SCH_1):PVCCFA_EHV_FIVRA_CPU1_VDD1

Q_CAP_C0402-2.2UF,10V,10%,X6S,A  I31  PC1242_P1_1
   1 PVCCFA_EHV_FIVRA_CPU1_PVCC1      A @S9S_MB_2U_LIB.S9S_MB_2U(SCH_1):PVCCFA_EHV_FIVRA_CPU1_PVCC1
   2    GND      B @S9S_MB_2U_LIB.S9S_MB_2U(SCH_1):GND

Q_CAP_C0805-22UF,16V,20%,X6S,CA  I42  PC406_P1_2
   1 SW_P12V_PVCCFA_EHV_FIVRA_CPU1_L      A @S9S_MB_2U_LIB.S9S_MB_2U(SCH_1):SW_P12V_PVCCFA_EHV_FIVRA_CPU1_L
   2    GND      B @S9S_MB_2U_LIB.S9S_MB_2U(SCH_1):GND

Q_CAP_C0402-100NF,50V,10%,X7R,A  I43  PC402
   1 SW_PVCCFA_EHV_FIVRA_CPU1_BOOT2_      A @S9S_MB_2U_LIB.S9S_MB_2U(SCH_1):SW_PVCCFA_EHV_FIVRA_CPU1_BOOT2_R
   2 SW_PVCCFA_EHV_FIVRA_CPU1_BOOTR2      B @S9S_MB_2U_LIB.S9S_MB_2U(SCH_1):SW_PVCCFA_EHV_FIVRA_CPU1_BOOTR2

Q_CAP_C0805-22UF,16V,20%,X6S,CA  I58  PC724_P1_1
   1 SW_P12V_PVCCFA_EHV_FIVRA_CPU1_R      A @S9S_MB_2U_LIB.S9S_MB_2U(SCH_1):SW_P12V_PVCCFA_EHV_FIVRA_CPU1_R
   2    GND      B @S9S_MB_2U_LIB.S9S_MB_2U(SCH_1):GND

Q_CAPP_THLF-560UF,2.5V,20%,OSCA  I66  PC414
   1 PVCCFA_EHV_FIVRA_CPU1      A @S9S_MB_2U_LIB.S9S_MB_2U(SCH_1):PVCCFA_EHV_FIVRA_CPU1
   2    GND      B @S9S_MB_2U_LIB.S9S_MB_2U(SCH_1):GND

Q_CAPP_THLF-560UF,2.5V,20%,OSCA  I67  PC415
   1 PVCCFA_EHV_FIVRA_CPU1      A @S9S_MB_2U_LIB.S9S_MB_2U(SCH_1):PVCCFA_EHV_FIVRA_CPU1
   2    GND      B @S9S_MB_2U_LIB.S9S_MB_2U(SCH_1):GND

Q_CAP_C0805-22UF,4V,20%,X6S,CHA  I74  PC410_P1_1
   1 PVCCFA_EHV_FIVRA_CPU1      A @S9S_MB_2U_LIB.S9S_MB_2U(SCH_1):PVCCFA_EHV_FIVRA_CPU1
   2    GND      B @S9S_MB_2U_LIB.S9S_MB_2U(SCH_1):GND

Q_CAP_C0805-22UF,4V,20%,X6S,CHA  I75  PC412_P1_1
   1 PVCCFA_EHV_FIVRA_CPU1      A @S9S_MB_2U_LIB.S9S_MB_2U(SCH_1):PVCCFA_EHV_FIVRA_CPU1
   2    GND      B @S9S_MB_2U_LIB.S9S_MB_2U(SCH_1):GND

Q_CAP_C0402-100NF,50V,10%,X7R,A  I77  PC1657
   1 P12V_AUX      A @S9S_MB_2U_LIB.S9S_MB_2U(SCH_1):P12V_AUX
   2    GND      B @S9S_MB_2U_LIB.S9S_MB_2U(SCH_1):GND

Q_INDUCTOR_SMLF-100NH/16A,IND,A  I79  PL43
   2 SW_P12V_PVCCFA_EHV_FIVRA_CPU1_L      2 @S9S_MB_2U_LIB.S9S_MB_2U(SCH_1):SW_P12V_PVCCFA_EHV_FIVRA_CPU1_L
   1 P12V_AUX      1 @S9S_MB_2U_LIB.S9S_MB_2U(SCH_1):P12V_AUX

Q_CAP_C0805-22UF,16V,20%,X6S,CA  I85  PC1680
   1 SW_P12V_PVCCFA_EHV_FIVRA_CPU1_L      A @S9S_MB_2U_LIB.S9S_MB_2U(SCH_1):SW_P12V_PVCCFA_EHV_FIVRA_CPU1_L
   2    GND      B @S9S_MB_2U_LIB.S9S_MB_2U(SCH_1):GND

Q_CAPP_THLF-270UF,16V,20%,OSCOA  I87  PC417
   1 SW_P12V_PVCCFA_EHV_FIVRA_CPU1_L      A @S9S_MB_2U_LIB.S9S_MB_2U(SCH_1):SW_P12V_PVCCFA_EHV_FIVRA_CPU1_L
   2    GND      B @S9S_MB_2U_LIB.S9S_MB_2U(SCH_1):GND

ISL99390FRZTR5935-ISL99390FRZ-A  I89  PU75_P1_1
  34 PVCCFA_EHV_FIVRA_CPU1_PWM1    PWM @S9S_MB_2U_LIB.S9S_MB_2U(SCH_1):PVCCFA_EHV_FIVRA_CPU1_PWM1
  39 PVCCIN_CPU1_VREF  REFIN @S9S_MB_2U_LIB.S9S_MB_2U(SCH_1):PVCCIN_CPU1_VREF
   3 PVCCFA_EHV_FIVRA_CPU1_VDD1    VCC @S9S_MB_2U_LIB.S9S_MB_2U(SCH_1):PVCCFA_EHV_FIVRA_CPU1_VDD1
   2    GND   AGND @S9S_MB_2U_LIB.S9S_MB_2U(SCH_1):GND
  33 SW_PVCCFA_EHV_FIVRA_CPU1_BOOT1   BOOT @S9S_MB_2U_LIB.S9S_MB_2U(SCH_1):SW_PVCCFA_EHV_FIVRA_CPU1_BOOT1
25_29 SW_P12V_PVCCFA_EHV_FIVRA_CPU1_R   VIN1 @S9S_MB_2U_LIB.S9S_MB_2U(SCH_1):SW_P12V_PVCCFA_EHV_FIVRA_CPU1_R
  32 SW_PVCCFA_EHV_FIVRA_CPU1_BOOTR1  PHASE @S9S_MB_2U_LIB.S9S_MB_2U(SCH_1):SW_PVCCFA_EHV_FIVRA_CPU1_BOOTR1
   4 PVCCFA_EHV_FIVRA_CPU1_PVCC1   PVCC @S9S_MB_2U_LIB.S9S_MB_2U(SCH_1):PVCCFA_EHV_FIVRA_CPU1_PVCC1
  36 PVCCFA_EHV_FIVRA_CPU1_BTSEN TOUT_FLT @S9S_MB_2U_LIB.S9S_MB_2U(SCH_1):PVCCFA_EHV_FIVRA_CPU1_BTSEN
  38 PVCCFA_EHV_FIVRA_CPU1_IMON1   IOUT @S9S_MB_2U_LIB.S9S_MB_2U(SCH_1):PVCCFA_EHV_FIVRA_CPU1_IMON1
  37 PVCCFA_EHV_FIVRA_CPU1_LSET1   LSET @S9S_MB_2U_LIB.S9S_MB_2U(SCH_1):PVCCFA_EHV_FIVRA_CPU1_LSET1
10_19 SW_PVCCFA_EHV_FIVRA_CPU1_SW1     SW @S9S_MB_2U_LIB.S9S_MB_2U(SCH_1):SW_PVCCFA_EHV_FIVRA_CPU1_SW1
   5    GND  PGND1 @S9S_MB_2U_LIB.S9S_MB_2U(SCH_1):GND
  30 SW_P12V_PVCCFA_EHV_FIVRA_CPU1_R   VIN2 @S9S_MB_2U_LIB.S9S_MB_2U(SCH_1):SW_P12V_PVCCFA_EHV_FIVRA_CPU1_R
   1 PVCCFA_EHV_FIVRA_CPU1_VOS1    VOS @S9S_MB_2U_LIB.S9S_MB_2U(SCH_1):PVCCFA_EHV_FIVRA_CPU1_VOS1
  40    GND  PGND3 @S9S_MB_2U_LIB.S9S_MB_2U(SCH_1):GND
  35 PVCCFA_EHV_FIVRA_CPU1_VDD1     EN @S9S_MB_2U_LIB.S9S_MB_2U(SCH_1):PVCCFA_EHV_FIVRA_CPU1_VDD1
  31     NC    DNC     NC
   6     NC    GL1     NC
  41     NC    GL2     NC
7_9-20_24    GND  PGND2 @S9S_MB_2U_LIB.S9S_MB_2U(SCH_1):GND


DRAWING: @S9S_MB_2U_LIB.S9S_MB_2U(SCH_1):PAGE159 

Q_RES_0402LF-1K,1%,1/16W,CHIP,A  I2  R4653
   1 FM_P2E_BUF2_VODB_DB      A @S9S_MB_2U_LIB.S9S_MB_2U(SCH_1):FM_P2E_BUF2_VODB_DB
   2    GND      B @S9S_MB_2U_LIB.S9S_MB_2U(SCH_1):GND

Q_RES_0402LF-1K,1%,1/16W,CHIP,A  I4  R4647
   1 FM_P2E_BUF2_VODA_DB      A @S9S_MB_2U_LIB.S9S_MB_2U(SCH_1):FM_P2E_BUF2_VODA_DB
   2    GND      B @S9S_MB_2U_LIB.S9S_MB_2U(SCH_1):GND

Q_RES_0402LF-1K,1%,1/16W,EMPTYA  I15  R4646
   1 FM_P2E_BUF2_EQB0      A @S9S_MB_2U_LIB.S9S_MB_2U(SCH_1):FM_P2E_BUF2_EQB0
   2    GND      B @S9S_MB_2U_LIB.S9S_MB_2U(SCH_1):GND

Q_RES_0402LF-1K,1%,1/16W,EMPTYA  I16  R4645
   1 P3V3_AUX      A @S9S_MB_2U_LIB.S9S_MB_2U(SCH_1):P3V3_AUX
   2 FM_P2E_BUF2_EQB0      B @S9S_MB_2U_LIB.S9S_MB_2U(SCH_1):FM_P2E_BUF2_EQB0

Q_CAP_0402-0.1UF,25V,10%,EMPTYA  I27  C2353
   1 P2E_MB_BMC_RX_BUF2_C_DP<0>      A @S9S_MB_2U_LIB.S9S_MB_2U(SCH_1):P2E_MB_BMC_RX_BUF2_C_DP(0)
   2 P2E_MB_BMC_RX_BUF_DP<0>      B @S9S_MB_2U_LIB.S9S_MB_2U(SCH_1):P2E_MB_BMC_RX_BUF_DP(0)

Q_CAP_0402-0.1UF,25V,10%,EMPTYA  I32  C2352
   1 P2E_MB_BMC_TX_BUF2_DN<0>      A @S9S_MB_2U_LIB.S9S_MB_2U(SCH_1):P2E_MB_BMC_TX_BUF2_DN(0)
   2 P2E_MB_BMC_TX_BUF_C_DN<0>      B @S9S_MB_2U_LIB.S9S_MB_2U(SCH_1):P2E_MB_BMC_TX_BUF_C_DN(0)

Q_RES_0402LF-1K,1%,1/16W,EMPTYA  I62  R4655
   1 P3V3_AUX      A @S9S_MB_2U_LIB.S9S_MB_2U(SCH_1):P3V3_AUX
   2 FM_P2E_BUF2_RXDET      B @S9S_MB_2U_LIB.S9S_MB_2U(SCH_1):FM_P2E_BUF2_RXDET

Q_RES_0402LF-1K,1%,1/16W,CHIP,A  I66  R4656
   1 P3V3_AUX      A @S9S_MB_2U_LIB.S9S_MB_2U(SCH_1):P3V3_AUX
   2 FM_P2E_BUF2_SD_TH      B @S9S_MB_2U_LIB.S9S_MB_2U(SCH_1):FM_P2E_BUF2_SD_TH

Q_RES_0402LF-1K,1%,1/16W,CHIP,A  I67  R4654
   1 FM_P2E_BUF2_EQA1      A @S9S_MB_2U_LIB.S9S_MB_2U(SCH_1):FM_P2E_BUF2_EQA1
   2    GND      B @S9S_MB_2U_LIB.S9S_MB_2U(SCH_1):GND

Q_RES_0402LF-1K,1%,1/16W,CHIP,A  I81  R3386
   1 P3V3_AUX      A @S9S_MB_2U_LIB.S9S_MB_2U(SCH_1):P3V3_AUX
   2 FM_P2E_BUF2_VOD_SEL      B @S9S_MB_2U_LIB.S9S_MB_2U(SCH_1):FM_P2E_BUF2_VOD_SEL

DS125BR111RTWR-DS125BR111RTWR,A  I95  U328
   1 FM_P2E_BUF2_EQB0 EQB0||AD3 @S9S_MB_2U_LIB.S9S_MB_2U(SCH_1):FM_P2E_BUF2_EQB0
   2 FM_P2E_BUF2_EQB1 EQB1||AD2 @S9S_MB_2U_LIB.S9S_MB_2U(SCH_1):FM_P2E_BUF2_EQB1
   3 PD_P2E_BUF2_ENSMB  ENSMB @S9S_MB_2U_LIB.S9S_MB_2U(SCH_1):PD_P2E_BUF2_ENSMB
   4 FM_P2E_BUF2_VODA_DB SDA||VODA_DB @S9S_MB_2U_LIB.S9S_MB_2U(SCH_1):FM_P2E_BUF2_VODA_DB
   5 FM_P2E_BUF2_VODB_DB SCL||VODB_DB @S9S_MB_2U_LIB.S9S_MB_2U(SCH_1):FM_P2E_BUF2_VODB_DB
   6 FM_P2E_EN2_N   PWDN @S9S_MB_2U_LIB.S9S_MB_2U(SCH_1):FM_P2E_EN2_N
   7 P2E_MB_BMC_TX_BUF2_DP<0>  OUTA+ @S9S_MB_2U_LIB.S9S_MB_2U(SCH_1):P2E_MB_BMC_TX_BUF2_DP(0)
   8 P2E_MB_BMC_TX_BUF2_DN<0>  OUTA- @S9S_MB_2U_LIB.S9S_MB_2U(SCH_1):P2E_MB_BMC_TX_BUF2_DN(0)
   9 FM_P2E_BUF2_EQA1 EQA1||AD1 @S9S_MB_2U_LIB.S9S_MB_2U(SCH_1):FM_P2E_BUF2_EQA1
  10 FM_P2E_BUF2_EQA0 EQA0||AD0 @S9S_MB_2U_LIB.S9S_MB_2U(SCH_1):FM_P2E_BUF2_EQA0
  11 P2E_MB_BMC_RX_R2_DP<0>   INB+ @S9S_MB_2U_LIB.S9S_MB_2U(SCH_1):P2E_MB_BMC_RX_R2_DP(0)
  12 P2E_MB_BMC_RX_R2_DN<0>   INB- @S9S_MB_2U_LIB.S9S_MB_2U(SCH_1):P2E_MB_BMC_RX_R2_DN(0)
  13 NC_RES    RES @S9S_MB_2U_LIB.S9S_MB_2U(SCH_1):NC_RES
  14 FM_P2E_BUF2_SD_TH  SD_TH @S9S_MB_2U_LIB.S9S_MB_2U(SCH_1):FM_P2E_BUF2_SD_TH
  15 P3V3_AUX    VIN @S9S_MB_2U_LIB.S9S_MB_2U(SCH_1):P3V3_AUX
  16    GND VDD_SEL @S9S_MB_2U_LIB.S9S_MB_2U(SCH_1):GND
  17 FM_P2E_BUF2_VOD_SEL VOD_SEL||READEN# @S9S_MB_2U_LIB.S9S_MB_2U(SCH_1):FM_P2E_BUF2_VOD_SEL
  18 FM_P2E_BUF2_RXDET RXDET||DONE# @S9S_MB_2U_LIB.S9S_MB_2U(SCH_1):FM_P2E_BUF2_RXDET
  19 P2E_MB_BMC_RX_BUF2_C_DN<0>  OUTB- @S9S_MB_2U_LIB.S9S_MB_2U(SCH_1):P2E_MB_BMC_RX_BUF2_C_DN(0)
  20 P2E_MB_BMC_RX_BUF2_C_DP<0>  OUTB+ @S9S_MB_2U_LIB.S9S_MB_2U(SCH_1):P2E_MB_BMC_RX_BUF2_C_DP(0)
  21 P2E_BUF2_VDD VDD_21 @S9S_MB_2U_LIB.S9S_MB_2U(SCH_1):P2E_BUF2_VDD
  22 P2E_BUF2_VDD VDD_22 @S9S_MB_2U_LIB.S9S_MB_2U(SCH_1):P2E_BUF2_VDD
  23 P2E_MB_BMC_TX_C_R2_DN<0>   INA- @S9S_MB_2U_LIB.S9S_MB_2U(SCH_1):P2E_MB_BMC_TX_C_R2_DN(0)
  24 P2E_MB_BMC_TX_C_R2_DP<0>   INA+ @S9S_MB_2U_LIB.S9S_MB_2U(SCH_1):P2E_MB_BMC_TX_C_R2_DP(0)
  25    GND TH_GND @S9S_MB_2U_LIB.S9S_MB_2U(SCH_1):GND

Q_CAP_0402-0.1UF,25V,10%,X7R,CA  I100  C2358
   1 P2E_BUF2_VDD      A @S9S_MB_2U_LIB.S9S_MB_2U(SCH_1):P2E_BUF2_VDD
   2    GND      B @S9S_MB_2U_LIB.S9S_MB_2U(SCH_1):GND

Q_RES_0402LF-0,5%,1/16W,CHIP,CA  I102  R4651
   1 FM_P2E_EN2_N      A @S9S_MB_2U_LIB.S9S_MB_2U(SCH_1):FM_P2E_EN2_N
   2 CLK_GEN2_GPU_FPGA_OE_OR_N      B @S9S_MB_2U_LIB.S9S_MB_2U(SCH_1):CLK_GEN2_GPU_FPGA_OE_OR_N

Q_RES_0402LF-1K,1%,1/16W,EMPTYA  I7  R4642
   1 P3V3_AUX      A @S9S_MB_2U_LIB.S9S_MB_2U(SCH_1):P3V3_AUX
   2 FM_P2E_BUF2_VODB_DB      B @S9S_MB_2U_LIB.S9S_MB_2U(SCH_1):FM_P2E_BUF2_VODB_DB

Q_RES_0402LF-1K,1%,1/16W,CHIP,A  I10  R4694
   1 FM_P2E_BUF2_EQB1      A @S9S_MB_2U_LIB.S9S_MB_2U(SCH_1):FM_P2E_BUF2_EQB1
   2    GND      B @S9S_MB_2U_LIB.S9S_MB_2U(SCH_1):GND

Q_RES_0402LF-1K,1%,1/16W,EMPTYA  I11  R4644
   1 P3V3_AUX      A @S9S_MB_2U_LIB.S9S_MB_2U(SCH_1):P3V3_AUX
   2 FM_P2E_BUF2_EQB1      B @S9S_MB_2U_LIB.S9S_MB_2U(SCH_1):FM_P2E_BUF2_EQB1

Q_RES_0402LF-1K,1%,1/16W,EMPTYA  I13  R4643
   1 P3V3_AUX      A @S9S_MB_2U_LIB.S9S_MB_2U(SCH_1):P3V3_AUX
   2 FM_P2E_BUF2_VODA_DB      B @S9S_MB_2U_LIB.S9S_MB_2U(SCH_1):FM_P2E_BUF2_VODA_DB

Q_CAP_0402-0.1UF,25V,10%,EMPTYA  I28  C2354
   1 P2E_MB_BMC_RX_BUF2_C_DN<0>      A @S9S_MB_2U_LIB.S9S_MB_2U(SCH_1):P2E_MB_BMC_RX_BUF2_C_DN(0)
   2 P2E_MB_BMC_RX_BUF_DN<0>      B @S9S_MB_2U_LIB.S9S_MB_2U(SCH_1):P2E_MB_BMC_RX_BUF_DN(0)

Q_CAP_0402-0.1UF,25V,10%,X7R,CA  I29  C1868
   1 P2E_MB_BMC_RX_BUF_C_DP<0>      A @S9S_MB_2U_LIB.S9S_MB_2U(SCH_1):P2E_MB_BMC_RX_BUF_C_DP(0)
   2 P2E_MB_BMC_RX_BUF_DP<0>      B @S9S_MB_2U_LIB.S9S_MB_2U(SCH_1):P2E_MB_BMC_RX_BUF_DP(0)

Q_CAP_0402-0.1UF,25V,10%,X7R,CA  I30  C1869
   1 P2E_MB_BMC_RX_BUF_C_DN<0>      A @S9S_MB_2U_LIB.S9S_MB_2U(SCH_1):P2E_MB_BMC_RX_BUF_C_DN(0)
   2 P2E_MB_BMC_RX_BUF_DN<0>      B @S9S_MB_2U_LIB.S9S_MB_2U(SCH_1):P2E_MB_BMC_RX_BUF_DN(0)

Q_CAP_0402-0.1UF,25V,10%,EMPTYA  I31  C2351
   1 P2E_MB_BMC_TX_BUF2_DP<0>      A @S9S_MB_2U_LIB.S9S_MB_2U(SCH_1):P2E_MB_BMC_TX_BUF2_DP(0)
   2 P2E_MB_BMC_TX_BUF_C_DP<0>      B @S9S_MB_2U_LIB.S9S_MB_2U(SCH_1):P2E_MB_BMC_TX_BUF_C_DP(0)

Q_CAP_0402-0.1UF,25V,10%,X7R,CA  I33  C1870
   1 P2E_MB_BMC_TX_BUF_DP<0>      A @S9S_MB_2U_LIB.S9S_MB_2U(SCH_1):P2E_MB_BMC_TX_BUF_DP(0)
   2 P2E_MB_BMC_TX_BUF_C_DP<0>      B @S9S_MB_2U_LIB.S9S_MB_2U(SCH_1):P2E_MB_BMC_TX_BUF_C_DP(0)

Q_CAP_0402-0.1UF,25V,10%,X7R,CA  I34  C1871
   1 P2E_MB_BMC_TX_BUF_DN<0>      A @S9S_MB_2U_LIB.S9S_MB_2U(SCH_1):P2E_MB_BMC_TX_BUF_DN(0)
   2 P2E_MB_BMC_TX_BUF_C_DN<0>      B @S9S_MB_2U_LIB.S9S_MB_2U(SCH_1):P2E_MB_BMC_TX_BUF_C_DN(0)

Q_RES_0402LF-0,5%,1/16W,EMPTY,A  I35  R4666
   1 P2E_MB_BMC_RX_DN<0>      A @S9S_MB_2U_LIB.S9S_MB_2U(SCH_1):P2E_MB_BMC_RX_DN(0)
   2 P2E_MB_BMC_RX_R2_DN<0>      B @S9S_MB_2U_LIB.S9S_MB_2U(SCH_1):P2E_MB_BMC_RX_R2_DN(0)

Q_RES_0402LF-0,5%,1/16W,EMPTY,A  I36  R4665
   1 P2E_MB_BMC_RX_DP<0>      A @S9S_MB_2U_LIB.S9S_MB_2U(SCH_1):P2E_MB_BMC_RX_DP(0)
   2 P2E_MB_BMC_RX_R2_DP<0>      B @S9S_MB_2U_LIB.S9S_MB_2U(SCH_1):P2E_MB_BMC_RX_R2_DP(0)

Q_RES_0402LF-0,5%,1/16W,CHIP,CA  I41  R4663
   1 P2E_MB_BMC_RX_DP<0>      A @S9S_MB_2U_LIB.S9S_MB_2U(SCH_1):P2E_MB_BMC_RX_DP(0)
   2 P2E_MB_BMC_RX_R1_DP<0>      B @S9S_MB_2U_LIB.S9S_MB_2U(SCH_1):P2E_MB_BMC_RX_R1_DP(0)

Q_RES_0402LF-0,5%,1/16W,CHIP,CA  I42  R4664
   1 P2E_MB_BMC_RX_DN<0>      A @S9S_MB_2U_LIB.S9S_MB_2U(SCH_1):P2E_MB_BMC_RX_DN(0)
   2 P2E_MB_BMC_RX_R1_DN<0>      B @S9S_MB_2U_LIB.S9S_MB_2U(SCH_1):P2E_MB_BMC_RX_R1_DN(0)

Q_RES_0402LF-0,5%,1/16W,EMPTY,A  I43  R4662
   1 P2E_MB_BMC_TX_C_DN<0>      A @S9S_MB_2U_LIB.S9S_MB_2U(SCH_1):P2E_MB_BMC_TX_C_DN(0)
   2 P2E_MB_BMC_TX_C_R2_DN<0>      B @S9S_MB_2U_LIB.S9S_MB_2U(SCH_1):P2E_MB_BMC_TX_C_R2_DN(0)

Q_RES_0402LF-0,5%,1/16W,EMPTY,A  I44  R4661
   1 P2E_MB_BMC_TX_C_DP<0>      A @S9S_MB_2U_LIB.S9S_MB_2U(SCH_1):P2E_MB_BMC_TX_C_DP(0)
   2 P2E_MB_BMC_TX_C_R2_DP<0>      B @S9S_MB_2U_LIB.S9S_MB_2U(SCH_1):P2E_MB_BMC_TX_C_R2_DP(0)

Q_RES_0402LF-0,5%,1/16W,CHIP,CA  I45  R4660
   1 P2E_MB_BMC_TX_C_DN<0>      A @S9S_MB_2U_LIB.S9S_MB_2U(SCH_1):P2E_MB_BMC_TX_C_DN(0)
   2 P2E_MB_BMC_TX_C_R1_DN<0>      B @S9S_MB_2U_LIB.S9S_MB_2U(SCH_1):P2E_MB_BMC_TX_C_R1_DN(0)

Q_RES_0402LF-0,5%,1/16W,CHIP,CA  I46  R4659
   1 P2E_MB_BMC_TX_C_DP<0>      A @S9S_MB_2U_LIB.S9S_MB_2U(SCH_1):P2E_MB_BMC_TX_C_DP(0)
   2 P2E_MB_BMC_TX_C_R1_DP<0>      B @S9S_MB_2U_LIB.S9S_MB_2U(SCH_1):P2E_MB_BMC_TX_C_R1_DP(0)

Q_RES_0402LF-1K,1%,1/16W,CHIP,A  I53  R3362
   1 PD_P2E_BUF2_ENSMB      A @S9S_MB_2U_LIB.S9S_MB_2U(SCH_1):PD_P2E_BUF2_ENSMB
   2    GND      B @S9S_MB_2U_LIB.S9S_MB_2U(SCH_1):GND

Q_RES_0402LF-1K,1%,1/16W,EMPTYA  I61  R3381
   1 FM_P2E_BUF2_RXDET      A @S9S_MB_2U_LIB.S9S_MB_2U(SCH_1):FM_P2E_BUF2_RXDET
   2    GND      B @S9S_MB_2U_LIB.S9S_MB_2U(SCH_1):GND

Q_RES_0402LF-1K,1%,1/16W,EMPTYA  I65  R4657
   1 FM_P2E_BUF2_SD_TH      A @S9S_MB_2U_LIB.S9S_MB_2U(SCH_1):FM_P2E_BUF2_SD_TH
   2    GND      B @S9S_MB_2U_LIB.S9S_MB_2U(SCH_1):GND

Q_RES_0402LF-1K,1%,1/16W,EMPTYA  I71  R4650
   1 FM_P2E_BUF2_EQA0      A @S9S_MB_2U_LIB.S9S_MB_2U(SCH_1):FM_P2E_BUF2_EQA0
   2    GND      B @S9S_MB_2U_LIB.S9S_MB_2U(SCH_1):GND

Q_RES_0402LF-1K,1%,1/16W,EMPTYA  I72  R4648
   1 P3V3_AUX      A @S9S_MB_2U_LIB.S9S_MB_2U(SCH_1):P3V3_AUX
   2 FM_P2E_BUF2_EQA1      B @S9S_MB_2U_LIB.S9S_MB_2U(SCH_1):FM_P2E_BUF2_EQA1

Q_RES_0402LF-1K,1%,1/16W,EMPTYA  I74  R4649
   1 P3V3_AUX      A @S9S_MB_2U_LIB.S9S_MB_2U(SCH_1):P3V3_AUX
   2 FM_P2E_BUF2_EQA0      B @S9S_MB_2U_LIB.S9S_MB_2U(SCH_1):FM_P2E_BUF2_EQA0

Q_RES_0402LF-1K,1%,1/16W,EMPTYA  I80  R4658
   1 FM_P2E_BUF2_VOD_SEL      A @S9S_MB_2U_LIB.S9S_MB_2U(SCH_1):FM_P2E_BUF2_VOD_SEL
   2    GND      B @S9S_MB_2U_LIB.S9S_MB_2U(SCH_1):GND

Q_CAP_C0402-1UF,25V,10%,X6S,CHA  I96  C2355
   1 P3V3_AUX      A @S9S_MB_2U_LIB.S9S_MB_2U(SCH_1):P3V3_AUX
   2    GND      B @S9S_MB_2U_LIB.S9S_MB_2U(SCH_1):GND

Q_CAP_C0805-10UF,16V,10%,X6S,CA  I98  C2356
   1 P3V3_AUX      A @S9S_MB_2U_LIB.S9S_MB_2U(SCH_1):P3V3_AUX
   2    GND      B @S9S_MB_2U_LIB.S9S_MB_2U(SCH_1):GND

Q_CAP_0402-0.1UF,25V,10%,X7R,CA  I99  C2357
   1 P2E_BUF2_VDD      A @S9S_MB_2U_LIB.S9S_MB_2U(SCH_1):P2E_BUF2_VDD
   2    GND      B @S9S_MB_2U_LIB.S9S_MB_2U(SCH_1):GND


DRAWING: @S9S_MB_2U_LIB.S9S_MB_2U(SCH_1):PAGE299 

Q_RES_0402LF-100K,1%,1/16W,EMPA  I3  R3430
   1 GPU_FPGA_OVERT_N      A @S9S_MB_2U_LIB.S9S_MB_2U(SCH_1):GPU_FPGA_OVERT_N
   2    GND      B @S9S_MB_2U_LIB.S9S_MB_2U(SCH_1):GND

Q_RES_0402LF-100K,1%,1/16W,EMPA  I17  R3428
   1 GPU_FPGA_THERM_OVERT_N      A @S9S_MB_2U_LIB.S9S_MB_2U(SCH_1):GPU_FPGA_THERM_OVERT_N
   2    GND      B @S9S_MB_2U_LIB.S9S_MB_2U(SCH_1):GND

MOSFET_NCH_DUAL-PJT138K,SMLF,IA  I21  Q104
   1    GND     S1 @S9S_MB_2U_LIB.S9S_MB_2U(SCH_1):GND
   2 GPU_FPGA_OVERT_N     G1 @S9S_MB_2U_LIB.S9S_MB_2U(SCH_1):GPU_FPGA_OVERT_N
   6 GPU_FPGA_OVERT     D1 @S9S_MB_2U_LIB.S9S_MB_2U(SCH_1):GPU_FPGA_OVERT

Q_RES_0402LF-4.7K,5%,1/16W,CHIA  I23  R3435
   1 P3V3_AUX      A @S9S_MB_2U_LIB.S9S_MB_2U(SCH_1):P3V3_AUX
   2 GPU_FPGA_OVERT      B @S9S_MB_2U_LIB.S9S_MB_2U(SCH_1):GPU_FPGA_OVERT

MOSFET_NCH_DUAL-PJT138K,SMLF,IA  I26  Q104
   3 GPU_FPGA_OVERT_ISO_N     D2 @S9S_MB_2U_LIB.S9S_MB_2U(SCH_1):GPU_FPGA_OVERT_ISO_N
   5 GPU_FPGA_OVERT     G2 @S9S_MB_2U_LIB.S9S_MB_2U(SCH_1):GPU_FPGA_OVERT
   4    GND     S2 @S9S_MB_2U_LIB.S9S_MB_2U(SCH_1):GND

Q_RES_0402LF-4.7K,5%,1/16W,CHIA  I27  R3437
   1 P3V3_AUX      A @S9S_MB_2U_LIB.S9S_MB_2U(SCH_1):P3V3_AUX
   2 GPU_FPGA_OVERT_ISO_N      B @S9S_MB_2U_LIB.S9S_MB_2U(SCH_1):GPU_FPGA_OVERT_ISO_N

Q_CAP_0402-1000PF,50V,5%,EMPTYA  I30  C1976
   1 GPU_FPGA_OVERT_ISO_N      A @S9S_MB_2U_LIB.S9S_MB_2U(SCH_1):GPU_FPGA_OVERT_ISO_N
   2    GND      B @S9S_MB_2U_LIB.S9S_MB_2U(SCH_1):GND

MOSFET_NCH_DUAL-PJT138K,SMLF,IA  I37  Q103
   1    GND     S1 @S9S_MB_2U_LIB.S9S_MB_2U(SCH_1):GND
   2 GPU_HMC_PRSNT_N     G1 @S9S_MB_2U_LIB.S9S_MB_2U(SCH_1):GPU_HMC_PRSNT_N
   6 GPU_HMC_PRSNT     D1 @S9S_MB_2U_LIB.S9S_MB_2U(SCH_1):GPU_HMC_PRSNT

Q_RES_0402LF-4.7K,5%,1/16W,CHIA  I39  R3434
   1 P3V3_AUX      A @S9S_MB_2U_LIB.S9S_MB_2U(SCH_1):P3V3_AUX
   2 GPU_HMC_PRSNT      B @S9S_MB_2U_LIB.S9S_MB_2U(SCH_1):GPU_HMC_PRSNT

MOSFET_NCH_DUAL-PJT138K,SMLF,IA  I40  Q102
   1    GND     S1 @S9S_MB_2U_LIB.S9S_MB_2U(SCH_1):GND
   2 GPU_BASE_HMC_READY     G1 @S9S_MB_2U_LIB.S9S_MB_2U(SCH_1):GPU_BASE_HMC_READY
   6 GPU_BASE_HMC_READY_N     D1 @S9S_MB_2U_LIB.S9S_MB_2U(SCH_1):GPU_BASE_HMC_READY_N

MOSFET_NCH_DUAL-PJT138K,SMLF,IA  I43  Q103
   3 GPU_HMC_PRSNT_ISO_N     D2 @S9S_MB_2U_LIB.S9S_MB_2U(SCH_1):GPU_HMC_PRSNT_ISO_N
   5 GPU_HMC_PRSNT     G2 @S9S_MB_2U_LIB.S9S_MB_2U(SCH_1):GPU_HMC_PRSNT
   4    GND     S2 @S9S_MB_2U_LIB.S9S_MB_2U(SCH_1):GND

Q_RES_0402LF-4.7K,5%,1/16W,CHIA  I45  R3436
   1 P3V3_AUX      A @S9S_MB_2U_LIB.S9S_MB_2U(SCH_1):P3V3_AUX
   2 GPU_HMC_PRSNT_ISO_N      B @S9S_MB_2U_LIB.S9S_MB_2U(SCH_1):GPU_HMC_PRSNT_ISO_N

MOSFET_NCH_DUAL-PJT138K,SMLF,IA  I48  Q102
   3 GPU_BASE_HMC_READY_ISO     D2 @S9S_MB_2U_LIB.S9S_MB_2U(SCH_1):GPU_BASE_HMC_READY_ISO
   5 GPU_BASE_HMC_READY_N     G2 @S9S_MB_2U_LIB.S9S_MB_2U(SCH_1):GPU_BASE_HMC_READY_N
   4    GND     S2 @S9S_MB_2U_LIB.S9S_MB_2U(SCH_1):GND

Q_RES_0402LF-4.7K,5%,1/16W,CHIA  I49  R3433
   1 P3V3_AUX      A @S9S_MB_2U_LIB.S9S_MB_2U(SCH_1):P3V3_AUX
   2 GPU_BASE_HMC_READY_N      B @S9S_MB_2U_LIB.S9S_MB_2U(SCH_1):GPU_BASE_HMC_READY_N

MOSFET_NCH_DUAL-PJT138K,SMLF,IA  I52  Q101
   1    GND     S1 @S9S_MB_2U_LIB.S9S_MB_2U(SCH_1):GND
   2 GPU_FPGA_THERM_OVERT_N     G1 @S9S_MB_2U_LIB.S9S_MB_2U(SCH_1):GPU_FPGA_THERM_OVERT_N
   6 GPU_FPGA_THERM_OVERT     D1 @S9S_MB_2U_LIB.S9S_MB_2U(SCH_1):GPU_FPGA_THERM_OVERT

Q_RES_0402LF-4.7K,5%,1/16W,CHIA  I53  R3432
   1 P3V3_AUX      A @S9S_MB_2U_LIB.S9S_MB_2U(SCH_1):P3V3_AUX
   2 GPU_FPGA_THERM_OVERT      B @S9S_MB_2U_LIB.S9S_MB_2U(SCH_1):GPU_FPGA_THERM_OVERT

Q_RES_0402LF-4.7K,5%,1/16W,CHIA  I55  R3438
   1 P3V3_AUX      A @S9S_MB_2U_LIB.S9S_MB_2U(SCH_1):P3V3_AUX
   2 GPU_BASE_HMC_READY_ISO      B @S9S_MB_2U_LIB.S9S_MB_2U(SCH_1):GPU_BASE_HMC_READY_ISO

MOSFET_NCH_DUAL-PJT138K,SMLF,IA  I57  Q101
   3 GPU_FPGA_THERM_OVERT_ISO_N     D2 @S9S_MB_2U_LIB.S9S_MB_2U(SCH_1):GPU_FPGA_THERM_OVERT_ISO_N
   5 GPU_FPGA_THERM_OVERT     G2 @S9S_MB_2U_LIB.S9S_MB_2U(SCH_1):GPU_FPGA_THERM_OVERT
   4    GND     S2 @S9S_MB_2U_LIB.S9S_MB_2U(SCH_1):GND

Q_RES_0402LF-4.7K,5%,1/16W,CHIA  I59  R3439
   1 P3V3_AUX      A @S9S_MB_2U_LIB.S9S_MB_2U(SCH_1):P3V3_AUX
   2 GPU_FPGA_THERM_OVERT_ISO_N      B @S9S_MB_2U_LIB.S9S_MB_2U(SCH_1):GPU_FPGA_THERM_OVERT_ISO_N

Q_CAP_0402-1000PF,50V,5%,EMPTYA  I71  C1973
   1 GPU_BASE_HMC_READY_ISO      A @S9S_MB_2U_LIB.S9S_MB_2U(SCH_1):GPU_BASE_HMC_READY_ISO
   2    GND      B @S9S_MB_2U_LIB.S9S_MB_2U(SCH_1):GND

Q_CAP_0402-1000PF,50V,5%,EMPTYA  I74  C1974
   1 GPU_FPGA_THERM_OVERT_ISO_N      A @S9S_MB_2U_LIB.S9S_MB_2U(SCH_1):GPU_FPGA_THERM_OVERT_ISO_N
   2    GND      B @S9S_MB_2U_LIB.S9S_MB_2U(SCH_1):GND

Q_CAP_0402-1000PF,50V,5%,EMPTYA  I129  C1975
   1 GPU_HMC_PRSNT_ISO_N      A @S9S_MB_2U_LIB.S9S_MB_2U(SCH_1):GPU_HMC_PRSNT_ISO_N
   2    GND      B @S9S_MB_2U_LIB.S9S_MB_2U(SCH_1):GND

Q_RES_0402LF-100K,1%,1/16W,EMPA  I130  R3429
   1 P3V3_AUX      A @S9S_MB_2U_LIB.S9S_MB_2U(SCH_1):P3V3_AUX
   2 GPU_BASE_HMC_READY      B @S9S_MB_2U_LIB.S9S_MB_2U(SCH_1):GPU_BASE_HMC_READY

Q_RES_0402LF-54.9K,1%,1/16W,CHA  I131  R3463
   1 GPU_BASE_HMC_READY      A @S9S_MB_2U_LIB.S9S_MB_2U(SCH_1):GPU_BASE_HMC_READY
   2    GND      B @S9S_MB_2U_LIB.S9S_MB_2U(SCH_1):GND

Q_RES_0402LF-10K,1%,1/16W,CHIPA  I132  R3465
   1 P3V3_AUX      A @S9S_MB_2U_LIB.S9S_MB_2U(SCH_1):P3V3_AUX
   2 GPU_HMC_PRSNT_N      B @S9S_MB_2U_LIB.S9S_MB_2U(SCH_1):GPU_HMC_PRSNT_N

Q_RES_0402LF-100K,1%,1/16W,EMPA  I133  R3431
   1 GPU_HMC_PRSNT_N      A @S9S_MB_2U_LIB.S9S_MB_2U(SCH_1):GPU_HMC_PRSNT_N
   2    GND      B @S9S_MB_2U_LIB.S9S_MB_2U(SCH_1):GND

Q_RES_0402LF-54.9K,1%,1/16W,CHA  I134  R3464
   1 P3V3_AUX      A @S9S_MB_2U_LIB.S9S_MB_2U(SCH_1):P3V3_AUX
   2 GPU_FPGA_OVERT_N      B @S9S_MB_2U_LIB.S9S_MB_2U(SCH_1):GPU_FPGA_OVERT_N

MOSFET_NCH_DUAL-PJT138K,SMLF,IA  I135  Q106
   1    GND     S1 @S9S_MB_2U_LIB.S9S_MB_2U(SCH_1):GND
   2 GPU_WP_HW_CTRL_N     G1 @S9S_MB_2U_LIB.S9S_MB_2U(SCH_1):GPU_WP_HW_CTRL_N
   6 GPU_WP_HW_CTRL_ISO     D1 @S9S_MB_2U_LIB.S9S_MB_2U(SCH_1):GPU_WP_HW_CTRL_ISO

Q_RES_0402LF-10K,1%,1/16W,CHIPA  I144  R3471
   1 GPU_WP_HW_CTRL_N      A @S9S_MB_2U_LIB.S9S_MB_2U(SCH_1):GPU_WP_HW_CTRL_N
   2    GND      B @S9S_MB_2U_LIB.S9S_MB_2U(SCH_1):GND

Q_RES_0402LF-10K,1%,1/16W,EMPTA  I145  R3470
   1 P3V3_AUX      A @S9S_MB_2U_LIB.S9S_MB_2U(SCH_1):P3V3_AUX
   2 GPU_WP_HW_CTRL_N      B @S9S_MB_2U_LIB.S9S_MB_2U(SCH_1):GPU_WP_HW_CTRL_N

Q_RES_0402LF-0,5%,1/16W,EMPTY,A  I147  R3472
   1    GND      A @S9S_MB_2U_LIB.S9S_MB_2U(SCH_1):GND
   2 GPU_WP_HW_CTRL_ISO      B @S9S_MB_2U_LIB.S9S_MB_2U(SCH_1):GPU_WP_HW_CTRL_ISO

Q_CAP_0402-1000PF,50V,5%,EMPTYA  I152  C1978
   1 GPU_PRSNT_N_ISO      A @S9S_MB_2U_LIB.S9S_MB_2U(SCH_1):GPU_PRSNT_N_ISO
   2    GND      B @S9S_MB_2U_LIB.S9S_MB_2U(SCH_1):GND

Q_RES_0402LF-4.7K,5%,1/16W,CHIA  I154  R3475
   1 P3V3_AUX      A @S9S_MB_2U_LIB.S9S_MB_2U(SCH_1):P3V3_AUX
   2 GPU_PRSNT_N_ISO      B @S9S_MB_2U_LIB.S9S_MB_2U(SCH_1):GPU_PRSNT_N_ISO

MOSFET_NCH_DUAL-PJT138K,SMLF,IA  I157  Q107
   3 GPU_PRSNT_N_ISO     D2 @S9S_MB_2U_LIB.S9S_MB_2U(SCH_1):GPU_PRSNT_N_ISO
   5 GPU_PRSNT     G2 @S9S_MB_2U_LIB.S9S_MB_2U(SCH_1):GPU_PRSNT
   4    GND     S2 @S9S_MB_2U_LIB.S9S_MB_2U(SCH_1):GND

Q_RES_0402LF-4.7K,5%,1/16W,CHIA  I158  R3474
   1 P3V3_AUX      A @S9S_MB_2U_LIB.S9S_MB_2U(SCH_1):P3V3_AUX
   2 GPU_PRSNT      B @S9S_MB_2U_LIB.S9S_MB_2U(SCH_1):GPU_PRSNT

MOSFET_NCH_DUAL-PJT138K,SMLF,IA  I160  Q107
   1    GND     S1 @S9S_MB_2U_LIB.S9S_MB_2U(SCH_1):GND
   2 GPU_PRSNT_N     G1 @S9S_MB_2U_LIB.S9S_MB_2U(SCH_1):GPU_PRSNT_N
   6 GPU_PRSNT     D1 @S9S_MB_2U_LIB.S9S_MB_2U(SCH_1):GPU_PRSNT

Q_RES_0402LF-100K,1%,1/16W,EMPA  I163  R3473
   1 GPU_PRSNT_N      A @S9S_MB_2U_LIB.S9S_MB_2U(SCH_1):GPU_PRSNT_N
   2    GND      B @S9S_MB_2U_LIB.S9S_MB_2U(SCH_1):GND

Q_RES_0402LF-10K,1%,1/16W,CHIPA  I166  R3487
   1 P3V3_AUX      A @S9S_MB_2U_LIB.S9S_MB_2U(SCH_1):P3V3_AUX
   2 GPU_PRSNT_N      B @S9S_MB_2U_LIB.S9S_MB_2U(SCH_1):GPU_PRSNT_N

Q_RES_0402LF-54.9K,1%,1/16W,CHA  I167  R3498
   1 P3V3_AUX      A @S9S_MB_2U_LIB.S9S_MB_2U(SCH_1):P3V3_AUX
   2 GPU_FPGA_THERM_OVERT_N      B @S9S_MB_2U_LIB.S9S_MB_2U(SCH_1):GPU_FPGA_THERM_OVERT_N

MOSFET_NCH_DUAL-PJT138K,SMLF,IA  I168  Q108
   3 GPU_FPGA_EROT_FATALERR_ISO_N     D2 @S9S_MB_2U_LIB.S9S_MB_2U(SCH_1):GPU_FPGA_EROT_FATALERR_ISO_N
   5 GPU_FPGA_EROT_FATALERR     G2 @S9S_MB_2U_LIB.S9S_MB_2U(SCH_1):GPU_FPGA_EROT_FATALERR
   4    GND     S2 @S9S_MB_2U_LIB.S9S_MB_2U(SCH_1):GND

MOSFET_NCH_DUAL-PJT138K,SMLF,IA  I169  Q108
   1    GND     S1 @S9S_MB_2U_LIB.S9S_MB_2U(SCH_1):GND
   2 GPU_FPGA_EROT_FATALERR_N     G1 @S9S_MB_2U_LIB.S9S_MB_2U(SCH_1):GPU_FPGA_EROT_FATALERR_N
   6 GPU_FPGA_EROT_FATALERR     D1 @S9S_MB_2U_LIB.S9S_MB_2U(SCH_1):GPU_FPGA_EROT_FATALERR

Q_CAP_0402-1000PF,50V,5%,EMPTYA  I171  C1988
   1 GPU_FPGA_EROT_FATALERR_ISO_N      A @S9S_MB_2U_LIB.S9S_MB_2U(SCH_1):GPU_FPGA_EROT_FATALERR_ISO_N
   2    GND      B @S9S_MB_2U_LIB.S9S_MB_2U(SCH_1):GND

Q_RES_0402LF-4.7K,5%,1/16W,CHIA  I174  R3504
   1 P3V3_AUX      A @S9S_MB_2U_LIB.S9S_MB_2U(SCH_1):P3V3_AUX
   2 GPU_FPGA_EROT_FATALERR_ISO_N      B @S9S_MB_2U_LIB.S9S_MB_2U(SCH_1):GPU_FPGA_EROT_FATALERR_ISO_N

Q_RES_0402LF-4.7K,5%,1/16W,CHIA  I177  R3503
   1 P3V3_AUX      A @S9S_MB_2U_LIB.S9S_MB_2U(SCH_1):P3V3_AUX
   2 GPU_FPGA_EROT_FATALERR      B @S9S_MB_2U_LIB.S9S_MB_2U(SCH_1):GPU_FPGA_EROT_FATALERR

Q_RES_0402LF-100K,1%,1/16W,EMPA  I181  R3502
   1 GPU_FPGA_EROT_FATALERR_N      A @S9S_MB_2U_LIB.S9S_MB_2U(SCH_1):GPU_FPGA_EROT_FATALERR_N
   2    GND      B @S9S_MB_2U_LIB.S9S_MB_2U(SCH_1):GND

Q_RES_0402LF-54.9K,1%,1/16W,CHA  I184  R3525
   1 P3V3_AUX      A @S9S_MB_2U_LIB.S9S_MB_2U(SCH_1):P3V3_AUX
   2 GPU_FPGA_EROT_FATALERR_N      B @S9S_MB_2U_LIB.S9S_MB_2U(SCH_1):GPU_FPGA_EROT_FATALERR_N


DRAWING: @S9S_MB_2U_LIB.S9S_MB_2U(SCH_1):PAGE160 

74LVC2G17GW-74LVC2G17GW,SMLF,IA  I26  U253
   5 P3V3_AUX    VCC @S9S_MB_2U_LIB.S9S_MB_2U(SCH_1):P3V3_AUX
   4 GPU_BASE_STBY_EN_BUF_R     B1 @S9S_MB_2U_LIB.S9S_MB_2U(SCH_1):GPU_BASE_STBY_EN_BUF_R
   2    GND    GND @S9S_MB_2U_LIB.S9S_MB_2U(SCH_1):GND
   1 GPU_FPGA_BOOT_EN     A0 @S9S_MB_2U_LIB.S9S_MB_2U(SCH_1):GPU_FPGA_BOOT_EN
   3 GPU_BASE_STBY_EN     A1 @S9S_MB_2U_LIB.S9S_MB_2U(SCH_1):GPU_BASE_STBY_EN
   6 GPU_FPGA_BOOT_EN_BUF_R     B0 @S9S_MB_2U_LIB.S9S_MB_2U(SCH_1):GPU_FPGA_BOOT_EN_BUF_R

Q_CAP_0402-0.1UF,25V,10%,X7R,CA  I29  C1958
   1 P3V3_AUX      A @S9S_MB_2U_LIB.S9S_MB_2U(SCH_1):P3V3_AUX
   2    GND      B @S9S_MB_2U_LIB.S9S_MB_2U(SCH_1):GND

Q_RES_0402LF-100K,1%,1/16W,CHIA  I95  R3452
   1 GPU_BASE_STBY_EN      A @S9S_MB_2U_LIB.S9S_MB_2U(SCH_1):GPU_BASE_STBY_EN
   2    GND      B @S9S_MB_2U_LIB.S9S_MB_2U(SCH_1):GND

Q_RES_0402LF-10K,1%,1/16W,CHIPA  I123  R3457
   1 GPU_BASE_STBY_EN_BUF_R      A @S9S_MB_2U_LIB.S9S_MB_2U(SCH_1):GPU_BASE_STBY_EN_BUF_R
   2    GND      B @S9S_MB_2U_LIB.S9S_MB_2U(SCH_1):GND

Q_RES_0402LF-100K,1%,1/16W,EMPA  I124  R3456
   1 P3V3_AUX      A @S9S_MB_2U_LIB.S9S_MB_2U(SCH_1):P3V3_AUX
   2 GPU_BASE_STBY_EN_BUF_R      B @S9S_MB_2U_LIB.S9S_MB_2U(SCH_1):GPU_BASE_STBY_EN_BUF_R

Q_RES_0402LF-4.7K,5%,1/16W,EMPA  I127  R3451
   1 P3V3_AUX      A @S9S_MB_2U_LIB.S9S_MB_2U(SCH_1):P3V3_AUX
   2 GPU_BASE_STBY_EN      B @S9S_MB_2U_LIB.S9S_MB_2U(SCH_1):GPU_BASE_STBY_EN

Q_RES_0402LF-10K,1%,1/16W,CHIPA  I139  R3455
   1 RST_PERST_1_SWB_BUF_R_N      A @S9S_MB_2U_LIB.S9S_MB_2U(SCH_1):RST_PERST_1_SWB_BUF_R_N
   2    GND      B @S9S_MB_2U_LIB.S9S_MB_2U(SCH_1):GND

Q_CAP_0402-0.1UF,25V,10%,X7R,CA  I148  C1957
   1 P3V3_AUX      A @S9S_MB_2U_LIB.S9S_MB_2U(SCH_1):P3V3_AUX
   2    GND      B @S9S_MB_2U_LIB.S9S_MB_2U(SCH_1):GND

74LVC2G17GW-74LVC2G17GW,SMLF,IA  I153  U252
   5 P3V3_AUX    VCC @S9S_MB_2U_LIB.S9S_MB_2U(SCH_1):P3V3_AUX
   4 RST_PERST_1_SWB_BUF_R_N     B1 @S9S_MB_2U_LIB.S9S_MB_2U(SCH_1):RST_PERST_1_SWB_BUF_R_N
   2    GND    GND @S9S_MB_2U_LIB.S9S_MB_2U(SCH_1):GND
   1 RST_PERST_SWB_R_N     A0 @S9S_MB_2U_LIB.S9S_MB_2U(SCH_1):RST_PERST_SWB_R_N
   3 RST_PERST_SWB_R_N     A1 @S9S_MB_2U_LIB.S9S_MB_2U(SCH_1):RST_PERST_SWB_R_N
   6 RST_PERST_0_SWB_BUF_R_N     B0 @S9S_MB_2U_LIB.S9S_MB_2U(SCH_1):RST_PERST_0_SWB_BUF_R_N

Q_RES_0402LF-100K,1%,1/16W,EMPA  I164  R3453
   1 P3V3_AUX      A @S9S_MB_2U_LIB.S9S_MB_2U(SCH_1):P3V3_AUX
   2 GPU_FPGA_BOOT_EN_BUF_R      B @S9S_MB_2U_LIB.S9S_MB_2U(SCH_1):GPU_FPGA_BOOT_EN_BUF_R

Q_RES_0402LF-1K,1%,1/16W,CHIP,A  I165  R3454
   1 GPU_FPGA_BOOT_EN_BUF_R      A @S9S_MB_2U_LIB.S9S_MB_2U(SCH_1):GPU_FPGA_BOOT_EN_BUF_R
   2    GND      B @S9S_MB_2U_LIB.S9S_MB_2U(SCH_1):GND

Q_RES_0402LF-4.7K,5%,1/16W,EMPA  I168  R3448
   1 P3V3_AUX      A @S9S_MB_2U_LIB.S9S_MB_2U(SCH_1):P3V3_AUX
   2 GPU_FPGA_BOOT_EN      B @S9S_MB_2U_LIB.S9S_MB_2U(SCH_1):GPU_FPGA_BOOT_EN

Q_RES_0402LF-100K,1%,1/16W,CHIA  I170  R3449
   1 GPU_FPGA_BOOT_EN      A @S9S_MB_2U_LIB.S9S_MB_2U(SCH_1):GPU_FPGA_BOOT_EN
   2    GND      B @S9S_MB_2U_LIB.S9S_MB_2U(SCH_1):GND

74LVC2G17GW-74LVC2G17GW,SMLF,IA  I173  U256
   5 P3V3_AUX    VCC @S9S_MB_2U_LIB.S9S_MB_2U(SCH_1):P3V3_AUX
   4 FM_SWB_PWR_EN_R1_BUF     B1 @S9S_MB_2U_LIB.S9S_MB_2U(SCH_1):FM_SWB_PWR_EN_R1_BUF
   2    GND    GND @S9S_MB_2U_LIB.S9S_MB_2U(SCH_1):GND
   1 RST_PERST_SWB_R_N     A0 @S9S_MB_2U_LIB.S9S_MB_2U(SCH_1):RST_PERST_SWB_R_N
   3 FM_SWB_PWR_EN_R     A1 @S9S_MB_2U_LIB.S9S_MB_2U(SCH_1):FM_SWB_PWR_EN_R
   6 RST_PERST_2_SWB_BUF_R_N     B0 @S9S_MB_2U_LIB.S9S_MB_2U(SCH_1):RST_PERST_2_SWB_BUF_R_N

Q_CAP_0402-0.1UF,25V,10%,X7R,CA  I175  C1977
   1 P3V3_AUX      A @S9S_MB_2U_LIB.S9S_MB_2U(SCH_1):P3V3_AUX
   2    GND      B @S9S_MB_2U_LIB.S9S_MB_2U(SCH_1):GND

Q_RES_0402LF-10K,1%,1/16W,CHIPA  I181  R3467
   1 RST_PERST_0_SWB_BUF_R_N      A @S9S_MB_2U_LIB.S9S_MB_2U(SCH_1):RST_PERST_0_SWB_BUF_R_N
   2    GND      B @S9S_MB_2U_LIB.S9S_MB_2U(SCH_1):GND

Q_RES_0402LF-10K,1%,1/16W,CHIPA  I184  R3466
   1 RST_PERST_2_SWB_BUF_R_N      A @S9S_MB_2U_LIB.S9S_MB_2U(SCH_1):RST_PERST_2_SWB_BUF_R_N
   2    GND      B @S9S_MB_2U_LIB.S9S_MB_2U(SCH_1):GND

Q_RES_0402LF-100K,1%,1/16W,EMPA  I187  R2910
   1 P3V3_AUX      A @S9S_MB_2U_LIB.S9S_MB_2U(SCH_1):P3V3_AUX
   2 FM_SWB_PWR_EN_R      B @S9S_MB_2U_LIB.S9S_MB_2U(SCH_1):FM_SWB_PWR_EN_R

Q_RES_0402LF-4.7K,5%,1/16W,CHIA  I188  R2918
   1 FM_SWB_PWR_EN_R      A @S9S_MB_2U_LIB.S9S_MB_2U(SCH_1):FM_SWB_PWR_EN_R
   2    GND      B @S9S_MB_2U_LIB.S9S_MB_2U(SCH_1):GND

Q_RES_0402LF-4.7K,5%,1/16W,EMPA  I192  R2914
   1 P3V3_AUX      A @S9S_MB_2U_LIB.S9S_MB_2U(SCH_1):P3V3_AUX
   2 FM_SWB_PWR_EN_R1_BUF      B @S9S_MB_2U_LIB.S9S_MB_2U(SCH_1):FM_SWB_PWR_EN_R1_BUF

Q_RES_0402LF-4.7K,5%,1/16W,CHIA  I195  R2932
   1 FM_SWB_PWR_EN_R1_BUF      A @S9S_MB_2U_LIB.S9S_MB_2U(SCH_1):FM_SWB_PWR_EN_R1_BUF
   2    GND      B @S9S_MB_2U_LIB.S9S_MB_2U(SCH_1):GND

Q_RES_0402LF-49.9,1%,1/16W,CHIA  I197  R3468
   1 RST_PERST_2_SWB_BUF_R_N      A @S9S_MB_2U_LIB.S9S_MB_2U(SCH_1):RST_PERST_2_SWB_BUF_R_N
   2 RST_PERST_2_SWB_BUF_N      B @S9S_MB_2U_LIB.S9S_MB_2U(SCH_1):RST_PERST_2_SWB_BUF_N

Q_RES_0402LF-49.9,1%,1/16W,CHIA  I198  R3515
   1 FM_SWB_PWR_EN_R1_BUF      A @S9S_MB_2U_LIB.S9S_MB_2U(SCH_1):FM_SWB_PWR_EN_R1_BUF
   2 FM_SWB_PWR_EN_R_BUF      B @S9S_MB_2U_LIB.S9S_MB_2U(SCH_1):FM_SWB_PWR_EN_R_BUF

Q_RES_0402LF-49.9,1%,1/16W,CHIA  I199  R3469
   1 RST_PERST_0_SWB_BUF_R_N      A @S9S_MB_2U_LIB.S9S_MB_2U(SCH_1):RST_PERST_0_SWB_BUF_R_N
   2 RST_PERST_0_SWB_BUF_N      B @S9S_MB_2U_LIB.S9S_MB_2U(SCH_1):RST_PERST_0_SWB_BUF_N

Q_RES_0402LF-49.9,1%,1/16W,CHIA  I200  R3391
   1 RST_PERST_1_SWB_BUF_R_N      A @S9S_MB_2U_LIB.S9S_MB_2U(SCH_1):RST_PERST_1_SWB_BUF_R_N
   2 RST_PERST_1_SWB_BUF_N      B @S9S_MB_2U_LIB.S9S_MB_2U(SCH_1):RST_PERST_1_SWB_BUF_N

Q_RES_0402LF-49.9,1%,1/16W,CHIA  I201  R3390
   1 GPU_FPGA_BOOT_EN_BUF_R      A @S9S_MB_2U_LIB.S9S_MB_2U(SCH_1):GPU_FPGA_BOOT_EN_BUF_R
   2 GPU_FPGA_BOOT_EN_BUF      B @S9S_MB_2U_LIB.S9S_MB_2U(SCH_1):GPU_FPGA_BOOT_EN_BUF

Q_RES_0402LF-49.9,1%,1/16W,CHIA  I202  R3392
   1 GPU_BASE_STBY_EN_BUF_R      A @S9S_MB_2U_LIB.S9S_MB_2U(SCH_1):GPU_BASE_STBY_EN_BUF_R
   2 GPU_BASE_STBY_EN_BUF      B @S9S_MB_2U_LIB.S9S_MB_2U(SCH_1):GPU_BASE_STBY_EN_BUF


DRAWING: @S9S_MB_2U_LIB.S9S_MB_2U(SCH_1):PAGE147 

Q_RES_0402LF-0,5%,1/16W,CHIP,CA  I5  R3443
   1 GPU_PEX_STRAP1      A @S9S_MB_2U_LIB.S9S_MB_2U(SCH_1):GPU_PEX_STRAP1
   2    GND      B @S9S_MB_2U_LIB.S9S_MB_2U(SCH_1):GND

Q_RES_0402LF-0,5%,1/16W,EMPTY,A  I8  R3440
   1 GPU_BASE_ID0      A @S9S_MB_2U_LIB.S9S_MB_2U(SCH_1):GPU_BASE_ID0
   2    GND      B @S9S_MB_2U_LIB.S9S_MB_2U(SCH_1):GND

Q_RES_0402LF-100,1%,1/16W,EMPTA  I11  R2656
   1 HGX_DETECT_N_ISO      A @S9S_MB_2U_LIB.S9S_MB_2U(SCH_1):HGX_DETECT_N_ISO
   2    GND      B @S9S_MB_2U_LIB.S9S_MB_2U(SCH_1):GND

Q_RES_0402LF-0,5%,1/16W,CHIP,CA  I6  R3442
   1 GPU_PEX_STRAP0      A @S9S_MB_2U_LIB.S9S_MB_2U(SCH_1):GPU_PEX_STRAP0
   2    GND      B @S9S_MB_2U_LIB.S9S_MB_2U(SCH_1):GND

Q_RES_0402LF-0,5%,1/16W,CHIP,CA  I7  R3441
   1 GPU_BASE_ID1      A @S9S_MB_2U_LIB.S9S_MB_2U(SCH_1):GPU_BASE_ID1
   2    GND      B @S9S_MB_2U_LIB.S9S_MB_2U(SCH_1):GND

Q_CAP_0402-1000PF,50V,5%,EMPTYA  I15  C2372
   1 PRSNT_SWB_ISO_N      A @S9S_MB_2U_LIB.S9S_MB_2U(SCH_1):PRSNT_SWB_ISO_N
   2    GND      B @S9S_MB_2U_LIB.S9S_MB_2U(SCH_1):GND

Q_RES_0402LF-4.7K,5%,1/16W,CHIA  I18  R4726
   1 P3V3_AUX      A @S9S_MB_2U_LIB.S9S_MB_2U(SCH_1):P3V3_AUX
   2 PRSNT_SWB_ISO_N      B @S9S_MB_2U_LIB.S9S_MB_2U(SCH_1):PRSNT_SWB_ISO_N

MOSFET_NCH_DUAL-PJT138K,SMLF,IA  I20  Q151
   3 PRSNT_SWB_ISO_N     D2 @S9S_MB_2U_LIB.S9S_MB_2U(SCH_1):PRSNT_SWB_ISO_N
   5 PRSNT_SWB     G2 @S9S_MB_2U_LIB.S9S_MB_2U(SCH_1):PRSNT_SWB
   4    GND     S2 @S9S_MB_2U_LIB.S9S_MB_2U(SCH_1):GND

Q_CAP_0402-1000PF,50V,5%,EMPTYA  I22  C2373
   1 PRSNT_CABLE_SWB_B2_ISO_N      A @S9S_MB_2U_LIB.S9S_MB_2U(SCH_1):PRSNT_CABLE_SWB_B2_ISO_N
   2    GND      B @S9S_MB_2U_LIB.S9S_MB_2U(SCH_1):GND

Q_RES_0402LF-4.7K,5%,1/16W,CHIA  I25  R4733
   1 P3V3_AUX      A @S9S_MB_2U_LIB.S9S_MB_2U(SCH_1):P3V3_AUX
   2 PRSNT_CABLE_SWB_B2_ISO_N      B @S9S_MB_2U_LIB.S9S_MB_2U(SCH_1):PRSNT_CABLE_SWB_B2_ISO_N

MOSFET_NCH_DUAL-PJT138K,SMLF,IA  I26  Q152
   3 PRSNT_CABLE_SWB_B2_ISO_N     D2 @S9S_MB_2U_LIB.S9S_MB_2U(SCH_1):PRSNT_CABLE_SWB_B2_ISO_N
   5 PRSNT_CABLE_SWB_B2     G2 @S9S_MB_2U_LIB.S9S_MB_2U(SCH_1):PRSNT_CABLE_SWB_B2
   4    GND     S2 @S9S_MB_2U_LIB.S9S_MB_2U(SCH_1):GND

Q_RES_0402LF-4.7K,5%,1/16W,CHIA  I28  R4725
   1 P3V3_AUX      A @S9S_MB_2U_LIB.S9S_MB_2U(SCH_1):P3V3_AUX
   2 PRSNT_SWB      B @S9S_MB_2U_LIB.S9S_MB_2U(SCH_1):PRSNT_SWB

MOSFET_NCH_DUAL-PJT138K,SMLF,IA  I31  Q151
   1    GND     S1 @S9S_MB_2U_LIB.S9S_MB_2U(SCH_1):GND
   2 PRSNT_SWB_N     G1 @S9S_MB_2U_LIB.S9S_MB_2U(SCH_1):PRSNT_SWB_N
   6 PRSNT_SWB     D1 @S9S_MB_2U_LIB.S9S_MB_2U(SCH_1):PRSNT_SWB

Q_RES_0402LF-10K,1%,1/16W,CHIPA  I33  R4727
   1 P3V3_AUX      A @S9S_MB_2U_LIB.S9S_MB_2U(SCH_1):P3V3_AUX
   2 PRSNT_SWB_N      B @S9S_MB_2U_LIB.S9S_MB_2U(SCH_1):PRSNT_SWB_N

Q_RES_0402LF-100K,1%,1/16W,EMPA  I34  R4724
   1 PRSNT_SWB_N      A @S9S_MB_2U_LIB.S9S_MB_2U(SCH_1):PRSNT_SWB_N
   2    GND      B @S9S_MB_2U_LIB.S9S_MB_2U(SCH_1):GND

Q_RES_0402LF-4.7K,5%,1/16W,CHIA  I36  R4732
   1 P3V3_AUX      A @S9S_MB_2U_LIB.S9S_MB_2U(SCH_1):P3V3_AUX
   2 PRSNT_CABLE_SWB_B2      B @S9S_MB_2U_LIB.S9S_MB_2U(SCH_1):PRSNT_CABLE_SWB_B2

MOSFET_NCH_DUAL-PJT138K,SMLF,IA  I38  Q152
   1    GND     S1 @S9S_MB_2U_LIB.S9S_MB_2U(SCH_1):GND
   2 PRSNT_CABLE_SWB_B2_N     G1 @S9S_MB_2U_LIB.S9S_MB_2U(SCH_1):PRSNT_CABLE_SWB_B2_N
   6 PRSNT_CABLE_SWB_B2     D1 @S9S_MB_2U_LIB.S9S_MB_2U(SCH_1):PRSNT_CABLE_SWB_B2

Q_RES_0402LF-10K,1%,1/16W,CHIPA  I41  R4730
   1 P3V3_AUX      A @S9S_MB_2U_LIB.S9S_MB_2U(SCH_1):P3V3_AUX
   2 PRSNT_CABLE_SWB_B2_N      B @S9S_MB_2U_LIB.S9S_MB_2U(SCH_1):PRSNT_CABLE_SWB_B2_N

Q_RES_0402LF-100K,1%,1/16W,EMPA  I42  R4731
   1 PRSNT_CABLE_SWB_B2_N      A @S9S_MB_2U_LIB.S9S_MB_2U(SCH_1):PRSNT_CABLE_SWB_B2_N
   2    GND      B @S9S_MB_2U_LIB.S9S_MB_2U(SCH_1):GND

Q_CAP_0402-1000PF,50V,5%,EMPTYA  I47  C2374
   1 PRSNT_CABLE_SWB_B1_ISO_N      A @S9S_MB_2U_LIB.S9S_MB_2U(SCH_1):PRSNT_CABLE_SWB_B1_ISO_N
   2    GND      B @S9S_MB_2U_LIB.S9S_MB_2U(SCH_1):GND

Q_RES_0402LF-4.7K,5%,1/16W,CHIA  I50  R4740
   1 P3V3_AUX      A @S9S_MB_2U_LIB.S9S_MB_2U(SCH_1):P3V3_AUX
   2 PRSNT_CABLE_SWB_B1_ISO_N      B @S9S_MB_2U_LIB.S9S_MB_2U(SCH_1):PRSNT_CABLE_SWB_B1_ISO_N

MOSFET_NCH_DUAL-PJT138K,SMLF,IA  I51  Q153
   3 PRSNT_CABLE_SWB_B1_ISO_N     D2 @S9S_MB_2U_LIB.S9S_MB_2U(SCH_1):PRSNT_CABLE_SWB_B1_ISO_N
   5 PRSNT_CABLE_SWB_B1     G2 @S9S_MB_2U_LIB.S9S_MB_2U(SCH_1):PRSNT_CABLE_SWB_B1
   4    GND     S2 @S9S_MB_2U_LIB.S9S_MB_2U(SCH_1):GND

Q_RES_0402LF-4.7K,5%,1/16W,CHIA  I54  R4739
   1 P3V3_AUX      A @S9S_MB_2U_LIB.S9S_MB_2U(SCH_1):P3V3_AUX
   2 PRSNT_CABLE_SWB_B1      B @S9S_MB_2U_LIB.S9S_MB_2U(SCH_1):PRSNT_CABLE_SWB_B1

MOSFET_NCH_DUAL-PJT138K,SMLF,IA  I55  Q153
   1    GND     S1 @S9S_MB_2U_LIB.S9S_MB_2U(SCH_1):GND
   2 PRSNT_CABLE_SWB_B1_N     G1 @S9S_MB_2U_LIB.S9S_MB_2U(SCH_1):PRSNT_CABLE_SWB_B1_N
   6 PRSNT_CABLE_SWB_B1     D1 @S9S_MB_2U_LIB.S9S_MB_2U(SCH_1):PRSNT_CABLE_SWB_B1

Q_RES_0402LF-10K,1%,1/16W,CHIPA  I58  R4737
   1 P3V3_AUX      A @S9S_MB_2U_LIB.S9S_MB_2U(SCH_1):P3V3_AUX
   2 PRSNT_CABLE_SWB_B1_N      B @S9S_MB_2U_LIB.S9S_MB_2U(SCH_1):PRSNT_CABLE_SWB_B1_N

Q_RES_0402LF-100K,1%,1/16W,EMPA  I60  R4738
   1 PRSNT_CABLE_SWB_B1_N      A @S9S_MB_2U_LIB.S9S_MB_2U(SCH_1):PRSNT_CABLE_SWB_B1_N
   2    GND      B @S9S_MB_2U_LIB.S9S_MB_2U(SCH_1):GND

MOSFET_NCH_DUAL-PJT138K,SMLF,IA  I62  Q154
   3 PRSNT_CABLE_GPU_A3_ISO_N     D2 @S9S_MB_2U_LIB.S9S_MB_2U(SCH_1):PRSNT_CABLE_GPU_A3_ISO_N
   5 PRSNT_CABLE_GPU_A3     G2 @S9S_MB_2U_LIB.S9S_MB_2U(SCH_1):PRSNT_CABLE_GPU_A3
   4    GND     S2 @S9S_MB_2U_LIB.S9S_MB_2U(SCH_1):GND

Q_RES_0402LF-4.7K,5%,1/16W,CHIA  I65  R4801
   1 P3V3_AUX      A @S9S_MB_2U_LIB.S9S_MB_2U(SCH_1):P3V3_AUX
   2 PRSNT_CABLE_GPU_A3_ISO_N      B @S9S_MB_2U_LIB.S9S_MB_2U(SCH_1):PRSNT_CABLE_GPU_A3_ISO_N

Q_CAP_0402-1000PF,50V,5%,EMPTYA  I66  C2391
   1 PRSNT_CABLE_GPU_A3_ISO_N      A @S9S_MB_2U_LIB.S9S_MB_2U(SCH_1):PRSNT_CABLE_GPU_A3_ISO_N
   2    GND      B @S9S_MB_2U_LIB.S9S_MB_2U(SCH_1):GND

Q_RES_0402LF-4.7K,5%,1/16W,CHIA  I70  R4800
   1 P3V3_AUX      A @S9S_MB_2U_LIB.S9S_MB_2U(SCH_1):P3V3_AUX
   2 PRSNT_CABLE_GPU_A3      B @S9S_MB_2U_LIB.S9S_MB_2U(SCH_1):PRSNT_CABLE_GPU_A3

MOSFET_NCH_DUAL-PJT138K,SMLF,IA  I71  Q154
   1    GND     S1 @S9S_MB_2U_LIB.S9S_MB_2U(SCH_1):GND
   2 PRSNT_CABLE_GPU_A3_N     G1 @S9S_MB_2U_LIB.S9S_MB_2U(SCH_1):PRSNT_CABLE_GPU_A3_N
   6 PRSNT_CABLE_GPU_A3     D1 @S9S_MB_2U_LIB.S9S_MB_2U(SCH_1):PRSNT_CABLE_GPU_A3

Q_RES_0402LF-10K,1%,1/16W,CHIPA  I75  R4798
   1 P3V3_AUX      A @S9S_MB_2U_LIB.S9S_MB_2U(SCH_1):P3V3_AUX
   2 PRSNT_CABLE_GPU_A3_N      B @S9S_MB_2U_LIB.S9S_MB_2U(SCH_1):PRSNT_CABLE_GPU_A3_N

Q_RES_0402LF-100K,1%,1/16W,EMPA  I76  R4799
   1 PRSNT_CABLE_GPU_A3_N      A @S9S_MB_2U_LIB.S9S_MB_2U(SCH_1):PRSNT_CABLE_GPU_A3_N
   2    GND      B @S9S_MB_2U_LIB.S9S_MB_2U(SCH_1):GND


DRAWING: @S9S_MB_2U_LIB.S9S_MB_2U(SCH_1):PAGE296 

Q_CAP_0402-0.1UF,25V,10%,X7R,CA  I13  C1963
   1 P3V3_AUX      A @S9S_MB_2U_LIB.S9S_MB_2U(SCH_1):P3V3_AUX
   2    GND      B @S9S_MB_2U_LIB.S9S_MB_2U(SCH_1):GND

74LVC2G07DW7-74LVC2G07DW-7,SMLA  I16  U255
   1 GPU_NVS_PWR_BRAKE_N     1A @S9S_MB_2U_LIB.S9S_MB_2U(SCH_1):GPU_NVS_PWR_BRAKE_N
   3 GPU_FPGA_EROT_RST_N     2A @S9S_MB_2U_LIB.S9S_MB_2U(SCH_1):GPU_FPGA_EROT_RST_N
   6 GPU_NVS_PWR_BRAKE_N_R     1Y @S9S_MB_2U_LIB.S9S_MB_2U(SCH_1):GPU_NVS_PWR_BRAKE_N_R
   4 GPU_FPGA_EROT_RST_BUF_R_N     2Y @S9S_MB_2U_LIB.S9S_MB_2U(SCH_1):GPU_FPGA_EROT_RST_BUF_R_N
   2    GND    GND @S9S_MB_2U_LIB.S9S_MB_2U(SCH_1):GND
   5 P3V3_AUX    VCC @S9S_MB_2U_LIB.S9S_MB_2U(SCH_1):P3V3_AUX

Q_RES_0402LF-4.7K,5%,1/16W,CHIA  I29  R3459
   1 P3V3_AUX      A @S9S_MB_2U_LIB.S9S_MB_2U(SCH_1):P3V3_AUX
   2 GPU_NVS_PWR_BRAKE_N      B @S9S_MB_2U_LIB.S9S_MB_2U(SCH_1):GPU_NVS_PWR_BRAKE_N

Q_RES_0402LF-100K,1%,1/16W,EMPA  I31  R3460
   1 GPU_NVS_PWR_BRAKE_N      A @S9S_MB_2U_LIB.S9S_MB_2U(SCH_1):GPU_NVS_PWR_BRAKE_N
   2    GND      B @S9S_MB_2U_LIB.S9S_MB_2U(SCH_1):GND

Q_RES_0402LF-100K,1%,1/16W,EMPA  I33  R3462
   1 GPU_NVS_PWR_BRAKE_N_R      A @S9S_MB_2U_LIB.S9S_MB_2U(SCH_1):GPU_NVS_PWR_BRAKE_N_R
   2    GND      B @S9S_MB_2U_LIB.S9S_MB_2U(SCH_1):GND

Q_RES_0402LF-54.9K,1%,1/16W,CHA  I35  R3461
   1 P3V3_AUX      A @S9S_MB_2U_LIB.S9S_MB_2U(SCH_1):P3V3_AUX
   2 GPU_NVS_PWR_BRAKE_N_R      B @S9S_MB_2U_LIB.S9S_MB_2U(SCH_1):GPU_NVS_PWR_BRAKE_N_R

Q_RES_0402LF-33.2,1%,1/16W,CHIA  I37  R3397
   1 GPU_NVS_PWR_BRAKE_N_R      A @S9S_MB_2U_LIB.S9S_MB_2U(SCH_1):GPU_NVS_PWR_BRAKE_N_R
   2 GPU_NVS_PWR_BRAKE_N_BUF      B @S9S_MB_2U_LIB.S9S_MB_2U(SCH_1):GPU_NVS_PWR_BRAKE_N_BUF

Q_RES_0402LF-4.7K,5%,1/16W,CHIA  I40  R3488
   1 P3V3_AUX      A @S9S_MB_2U_LIB.S9S_MB_2U(SCH_1):P3V3_AUX
   2 GPU_FPGA_EROT_RST_N      B @S9S_MB_2U_LIB.S9S_MB_2U(SCH_1):GPU_FPGA_EROT_RST_N

Q_RES_0402LF-100K,1%,1/16W,EMPA  I42  R3489
   1 GPU_FPGA_EROT_RST_N      A @S9S_MB_2U_LIB.S9S_MB_2U(SCH_1):GPU_FPGA_EROT_RST_N
   2    GND      B @S9S_MB_2U_LIB.S9S_MB_2U(SCH_1):GND

Q_RES_0402LF-33.2,1%,1/16W,CHIA  I45  R3496
   1 GPU_FPGA_EROT_RST_BUF_R_N      A @S9S_MB_2U_LIB.S9S_MB_2U(SCH_1):GPU_FPGA_EROT_RST_BUF_R_N
   2 GPU_FPGA_EROT_RST_BUF_N      B @S9S_MB_2U_LIB.S9S_MB_2U(SCH_1):GPU_FPGA_EROT_RST_BUF_N

Q_RES_0402LF-54.9K,1%,1/16W,CHA  I47  R3492
   1 P3V3_AUX      A @S9S_MB_2U_LIB.S9S_MB_2U(SCH_1):P3V3_AUX
   2 GPU_FPGA_EROT_RST_BUF_R_N      B @S9S_MB_2U_LIB.S9S_MB_2U(SCH_1):GPU_FPGA_EROT_RST_BUF_R_N

Q_RES_0402LF-100K,1%,1/16W,EMPA  I48  R3493
   1 GPU_FPGA_EROT_RST_BUF_R_N      A @S9S_MB_2U_LIB.S9S_MB_2U(SCH_1):GPU_FPGA_EROT_RST_BUF_R_N
   2    GND      B @S9S_MB_2U_LIB.S9S_MB_2U(SCH_1):GND

74LVC2G07DW7-74LVC2G07DW-7,SMLA  I50  U257
   1 GPU_FPGA_EROT_RECOV_N     1A @S9S_MB_2U_LIB.S9S_MB_2U(SCH_1):GPU_FPGA_EROT_RECOV_N
   3    GND     2A @S9S_MB_2U_LIB.S9S_MB_2U(SCH_1):GND
   6 GPU_FPGA_EROT_RECOV_BUF_R_N     1Y @S9S_MB_2U_LIB.S9S_MB_2U(SCH_1):GPU_FPGA_EROT_RECOV_BUF_R_N
   4 NC_U257_2Y     2Y @S9S_MB_2U_LIB.S9S_MB_2U(SCH_1):NC_U257_2Y
   2    GND    GND @S9S_MB_2U_LIB.S9S_MB_2U(SCH_1):GND
   5 P3V3_AUX    VCC @S9S_MB_2U_LIB.S9S_MB_2U(SCH_1):P3V3_AUX

Q_RES_0402LF-33.2,1%,1/16W,CHIA  I53  R3497
   1 GPU_FPGA_EROT_RECOV_BUF_R_N      A @S9S_MB_2U_LIB.S9S_MB_2U(SCH_1):GPU_FPGA_EROT_RECOV_BUF_R_N
   2 GPU_FPGA_EROT_RECOV_BUF_N      B @S9S_MB_2U_LIB.S9S_MB_2U(SCH_1):GPU_FPGA_EROT_RECOV_BUF_N

Q_RES_0402LF-54.9K,1%,1/16W,CHA  I55  R3494
   1 P3V3_AUX      A @S9S_MB_2U_LIB.S9S_MB_2U(SCH_1):P3V3_AUX
   2 GPU_FPGA_EROT_RECOV_BUF_R_N      B @S9S_MB_2U_LIB.S9S_MB_2U(SCH_1):GPU_FPGA_EROT_RECOV_BUF_R_N

Q_RES_0402LF-4.7K,5%,1/16W,CHIA  I57  R3490
   1 P3V3_AUX      A @S9S_MB_2U_LIB.S9S_MB_2U(SCH_1):P3V3_AUX
   2 GPU_FPGA_EROT_RECOV_N      B @S9S_MB_2U_LIB.S9S_MB_2U(SCH_1):GPU_FPGA_EROT_RECOV_N

Q_RES_0402LF-100K,1%,1/16W,EMPA  I62  R3495
   1 GPU_FPGA_EROT_RECOV_BUF_R_N      A @S9S_MB_2U_LIB.S9S_MB_2U(SCH_1):GPU_FPGA_EROT_RECOV_BUF_R_N
   2    GND      B @S9S_MB_2U_LIB.S9S_MB_2U(SCH_1):GND

Q_CAP_0402-0.1UF,25V,10%,X7R,CA  I67  C1979
   1 P3V3_AUX      A @S9S_MB_2U_LIB.S9S_MB_2U(SCH_1):P3V3_AUX
   2    GND      B @S9S_MB_2U_LIB.S9S_MB_2U(SCH_1):GND

Q_RES_0402LF-100K,1%,1/16W,EMPA  I70  R3491
   1 GPU_FPGA_EROT_RECOV_N      A @S9S_MB_2U_LIB.S9S_MB_2U(SCH_1):GPU_FPGA_EROT_RECOV_N
   2    GND      B @S9S_MB_2U_LIB.S9S_MB_2U(SCH_1):GND


DRAWING: @S9S_MB_2U_LIB.S9S_MB_2U(SCH_1):PAGE220 

Q_RES_0402LF-33.2,1%,1/16W,CHIA  I3  R3587
   1 SMB_INA230_3V3AUX_SDA      A @S9S_MB_2U_LIB.S9S_MB_2U(SCH_1):SMB_INA230_3V3AUX_SDA
   2 SMB_INA230_1_3V3AUX_SDA_R      B @S9S_MB_2U_LIB.S9S_MB_2U(SCH_1):SMB_INA230_1_3V3AUX_SDA_R

Q_RES_0402LF-33.2,1%,1/16W,CHIA  I4  R3586
   1 SMB_INA230_3V3AUX_SCL      A @S9S_MB_2U_LIB.S9S_MB_2U(SCH_1):SMB_INA230_3V3AUX_SCL
   2 SMB_INA230_1_3V3AUX_SCL_R      B @S9S_MB_2U_LIB.S9S_MB_2U(SCH_1):SMB_INA230_1_3V3AUX_SCL_R

Q_RES_0402LF-33.2,1%,1/16W,CHIA  I11  R3589
   1 SMB_INA230_3V3AUX_SDA      A @S9S_MB_2U_LIB.S9S_MB_2U(SCH_1):SMB_INA230_3V3AUX_SDA
   2 SMB_INA230_2_3V3AUX_SDA_R      B @S9S_MB_2U_LIB.S9S_MB_2U(SCH_1):SMB_INA230_2_3V3AUX_SDA_R

Q_RES_0402LF-33.2,1%,1/16W,CHIA  I16  R3588
   1 SMB_INA230_3V3AUX_SCL      A @S9S_MB_2U_LIB.S9S_MB_2U(SCH_1):SMB_INA230_3V3AUX_SCL
   2 SMB_INA230_2_3V3AUX_SCL_R      B @S9S_MB_2U_LIB.S9S_MB_2U(SCH_1):SMB_INA230_2_3V3AUX_SCL_R

Q_RES_0402LF-33.2,1%,1/16W,CHIA  I17  R3590
   1 SMB_INA230_3V3AUX_SCL      A @S9S_MB_2U_LIB.S9S_MB_2U(SCH_1):SMB_INA230_3V3AUX_SCL
   2 SMB_INA230_3_3V3AUX_SCL_R      B @S9S_MB_2U_LIB.S9S_MB_2U(SCH_1):SMB_INA230_3_3V3AUX_SCL_R

Q_RES_0402LF-33.2,1%,1/16W,CHIA  I18  R3591
   1 SMB_INA230_3V3AUX_SDA      A @S9S_MB_2U_LIB.S9S_MB_2U(SCH_1):SMB_INA230_3V3AUX_SDA
   2 SMB_INA230_3_3V3AUX_SDA_R      B @S9S_MB_2U_LIB.S9S_MB_2U(SCH_1):SMB_INA230_3_3V3AUX_SDA_R

Q_RES_0402LF-33.2,1%,1/16W,CHIA  I19  R3593
   1 SMB_INA230_3V3AUX_SDA      A @S9S_MB_2U_LIB.S9S_MB_2U(SCH_1):SMB_INA230_3V3AUX_SDA
   2 SMB_INA230_5_3V3AUX_SDA_R      B @S9S_MB_2U_LIB.S9S_MB_2U(SCH_1):SMB_INA230_5_3V3AUX_SDA_R

Q_RES_0402LF-33.2,1%,1/16W,CHIA  I20  R3592
   1 SMB_INA230_3V3AUX_SCL      A @S9S_MB_2U_LIB.S9S_MB_2U(SCH_1):SMB_INA230_3V3AUX_SCL
   2 SMB_INA230_5_3V3AUX_SCL_R      B @S9S_MB_2U_LIB.S9S_MB_2U(SCH_1):SMB_INA230_5_3V3AUX_SCL_R

Q_RES_0402LF-33.2,1%,1/16W,CHIA  I21  R3594
   1 SMB_INA230_3V3AUX_SCL      A @S9S_MB_2U_LIB.S9S_MB_2U(SCH_1):SMB_INA230_3V3AUX_SCL
   2 SMB_INA230_4_3V3AUX_SCL_R      B @S9S_MB_2U_LIB.S9S_MB_2U(SCH_1):SMB_INA230_4_3V3AUX_SCL_R

Q_RES_0402LF-33.2,1%,1/16W,CHIA  I26  R3595
   1 SMB_INA230_3V3AUX_SDA      A @S9S_MB_2U_LIB.S9S_MB_2U(SCH_1):SMB_INA230_3V3AUX_SDA
   2 SMB_INA230_4_3V3AUX_SDA_R      B @S9S_MB_2U_LIB.S9S_MB_2U(SCH_1):SMB_INA230_4_3V3AUX_SDA_R


DRAWING: @S9S_MB_2U_LIB.S9S_MB_2U(SCH_1):PAGE163 

Q_CAP_0402-0.1UF,25V,10%,X7R,CA  I26  C2018
   1   P3V3      A @S9S_MB_2U_LIB.S9S_MB_2U(SCH_1):P3V3
   2    GND      B @S9S_MB_2U_LIB.S9S_MB_2U(SCH_1):GND

Q_RES_0402LF-10,1%,1/16W,CHIP,A  I33  R3575
   1 P3V3_M2_0      A @S9S_MB_2U_LIB.S9S_MB_2U(SCH_1):P3V3_M2_0
   2 VSENSE_P12V_INA230_4_INN      B @S9S_MB_2U_LIB.S9S_MB_2U(SCH_1):VSENSE_P12V_INA230_4_INN

Q_RES_0402LF-10,1%,1/16W,CHIP,A  I35  R3574
   1   P3V3      A @S9S_MB_2U_LIB.S9S_MB_2U(SCH_1):P3V3
   2 VSENSE_P12V_INA230_4_INP      B @S9S_MB_2U_LIB.S9S_MB_2U(SCH_1):VSENSE_P12V_INA230_4_INP

Q_RES_0402LF-4.7K,1%,1/16W,CHIA  I36  R3611
   1    GND      A @S9S_MB_2U_LIB.S9S_MB_2U(SCH_1):GND
   2 INA230_4_A0      B @S9S_MB_2U_LIB.S9S_MB_2U(SCH_1):INA230_4_A0

Q_RES_0402LF-33.2,1%,1/16W,CHIA  I37  R3573
   1 SMB_INA230_4_3V3AUX_SDA_R      A @S9S_MB_2U_LIB.S9S_MB_2U(SCH_1):SMB_INA230_4_3V3AUX_SDA_R
   2 SMB_INA230_4_3V3AUX_SDA_R1      B @S9S_MB_2U_LIB.S9S_MB_2U(SCH_1):SMB_INA230_4_3V3AUX_SDA_R1

Q_RES_0402LF-33.2,1%,1/16W,CHIA  I38  R3572
   1 SMB_INA230_4_3V3AUX_SCL_R      A @S9S_MB_2U_LIB.S9S_MB_2U(SCH_1):SMB_INA230_4_3V3AUX_SCL_R
   2 SMB_INA230_4_3V3AUX_SCL_R1      B @S9S_MB_2U_LIB.S9S_MB_2U(SCH_1):SMB_INA230_4_3V3AUX_SCL_R1

Q_RES_0402LF-0,5%,1/16W,CHIP,CA  I41  R3560
   1 M2_0_P3V3_ADC_ALERT_R      A @S9S_MB_2U_LIB.S9S_MB_2U(SCH_1):M2_0_P3V3_ADC_ALERT_R
   2 M2_0_P3V3_ADC_ALERT      B @S9S_MB_2U_LIB.S9S_MB_2U(SCH_1):M2_0_P3V3_ADC_ALERT

Q_CAP_0402-0.1UF,25V,10%,X7R,CA  I42  C2013
   1 P3V3_AUX      A @S9S_MB_2U_LIB.S9S_MB_2U(SCH_1):P3V3_AUX
   2    GND      B @S9S_MB_2U_LIB.S9S_MB_2U(SCH_1):GND

Q_RES_0402LF-4.7K,1%,1/16W,EMPA  I45  R3610
   1    GND      A @S9S_MB_2U_LIB.S9S_MB_2U(SCH_1):GND
   2 INA230_4_A1      B @S9S_MB_2U_LIB.S9S_MB_2U(SCH_1):INA230_4_A1

INA230AIRGTR-INA230AIRGTR,SMLFB  I46  U264
   9 P3V3_AUX     VS @S9S_MB_2U_LIB.S9S_MB_2U(SCH_1):P3V3_AUX
   1 INA230_4_A1     A1 @S9S_MB_2U_LIB.S9S_MB_2U(SCH_1):INA230_4_A1
   2 INA230_4_A0     A0 @S9S_MB_2U_LIB.S9S_MB_2U(SCH_1):INA230_4_A0
   5 SMB_INA230_4_3V3AUX_SCL_R1    SCL @S9S_MB_2U_LIB.S9S_MB_2U(SCH_1):SMB_INA230_4_3V3AUX_SCL_R1
   4 SMB_INA230_4_3V3AUX_SDA_R1    SDA @S9S_MB_2U_LIB.S9S_MB_2U(SCH_1):SMB_INA230_4_3V3AUX_SDA_R1
  11   P3V3    BUS @S9S_MB_2U_LIB.S9S_MB_2U(SCH_1):P3V3
  13 VSENSE_P12V_INA230_4_INP    IN+ @S9S_MB_2U_LIB.S9S_MB_2U(SCH_1):VSENSE_P12V_INA230_4_INP
  12 VSENSE_P12V_INA230_4_INN    IN- @S9S_MB_2U_LIB.S9S_MB_2U(SCH_1):VSENSE_P12V_INA230_4_INN
   3 M2_0_P3V3_ADC_ALERT_R  ALERT @S9S_MB_2U_LIB.S9S_MB_2U(SCH_1):M2_0_P3V3_ADC_ALERT_R
   6 NC_INA230_4_NC0    NC0 @S9S_MB_2U_LIB.S9S_MB_2U(SCH_1):NC_INA230_4_NC0
   7 NC_INA230_4_NC1    NC1 @S9S_MB_2U_LIB.S9S_MB_2U(SCH_1):NC_INA230_4_NC1
   8 NC_INA230_4_NC2    NC2 @S9S_MB_2U_LIB.S9S_MB_2U(SCH_1):NC_INA230_4_NC2
  14 NC_INA230_4_NC3    NC3 @S9S_MB_2U_LIB.S9S_MB_2U(SCH_1):NC_INA230_4_NC3
  15 NC_INA230_4_NC4    NC4 @S9S_MB_2U_LIB.S9S_MB_2U(SCH_1):NC_INA230_4_NC4
  16 NC_INA230_4_NC5    NC5 @S9S_MB_2U_LIB.S9S_MB_2U(SCH_1):NC_INA230_4_NC5
  10    GND    GND @S9S_MB_2U_LIB.S9S_MB_2U(SCH_1):GND
  TH    GND     TH @S9S_MB_2U_LIB.S9S_MB_2U(SCH_1):GND

Q_CAP_0402-0.1UF,25V,10%,X7R,CA  I49  C2019
   1 P12V_SCM_R      A @S9S_MB_2U_LIB.S9S_MB_2U(SCH_1):P12V_SCM_R
   2    GND      B @S9S_MB_2U_LIB.S9S_MB_2U(SCH_1):GND

Q_RES_0402LF-10,1%,1/16W,CHIP,A  I56  R3579
   1 P12V_SCM      A @S9S_MB_2U_LIB.S9S_MB_2U(SCH_1):P12V_SCM
   2 VSENSE_P12V_INA230_5_INN      B @S9S_MB_2U_LIB.S9S_MB_2U(SCH_1):VSENSE_P12V_INA230_5_INN

Q_RES_0402LF-10,1%,1/16W,CHIP,A  I58  R3578
   1 P12V_SCM_R      A @S9S_MB_2U_LIB.S9S_MB_2U(SCH_1):P12V_SCM_R
   2 VSENSE_P12V_INA230_5_INP      B @S9S_MB_2U_LIB.S9S_MB_2U(SCH_1):VSENSE_P12V_INA230_5_INP

Q_RES_0402LF-4.7K,1%,1/16W,EMPA  I59  R3613
   1    GND      A @S9S_MB_2U_LIB.S9S_MB_2U(SCH_1):GND
   2 INA230_5_A0      B @S9S_MB_2U_LIB.S9S_MB_2U(SCH_1):INA230_5_A0

Q_RES_0402LF-33.2,1%,1/16W,CHIA  I60  R3577
   1 SMB_INA230_5_3V3AUX_SDA_R      A @S9S_MB_2U_LIB.S9S_MB_2U(SCH_1):SMB_INA230_5_3V3AUX_SDA_R
   2 SMB_INA230_5_3V3AUX_SDA_R1      B @S9S_MB_2U_LIB.S9S_MB_2U(SCH_1):SMB_INA230_5_3V3AUX_SDA_R1

Q_RES_0402LF-33.2,1%,1/16W,CHIA  I61  R3576
   1 SMB_INA230_5_3V3AUX_SCL_R      A @S9S_MB_2U_LIB.S9S_MB_2U(SCH_1):SMB_INA230_5_3V3AUX_SCL_R
   2 SMB_INA230_5_3V3AUX_SCL_R1      B @S9S_MB_2U_LIB.S9S_MB_2U(SCH_1):SMB_INA230_5_3V3AUX_SCL_R1

Q_RES_0402LF-0,5%,1/16W,CHIP,CA  I64  R3561
   1 P12V_SCM_ADC_ALERT_R      A @S9S_MB_2U_LIB.S9S_MB_2U(SCH_1):P12V_SCM_ADC_ALERT_R
   2 P12V_SCM_ADC_ALERT      B @S9S_MB_2U_LIB.S9S_MB_2U(SCH_1):P12V_SCM_ADC_ALERT

Q_CAP_0402-0.1UF,25V,10%,X7R,CA  I65  C2014
   1 P3V3_AUX      A @S9S_MB_2U_LIB.S9S_MB_2U(SCH_1):P3V3_AUX
   2    GND      B @S9S_MB_2U_LIB.S9S_MB_2U(SCH_1):GND

Q_RES_0402LF-4.7K,1%,1/16W,EMPA  I68  R3612
   1    GND      A @S9S_MB_2U_LIB.S9S_MB_2U(SCH_1):GND
   2 INA230_5_A1      B @S9S_MB_2U_LIB.S9S_MB_2U(SCH_1):INA230_5_A1

INA230AIRGTR-INA230AIRGTR,SMLFB  I69  U265
   9 P3V3_AUX     VS @S9S_MB_2U_LIB.S9S_MB_2U(SCH_1):P3V3_AUX
   1 INA230_5_A1     A1 @S9S_MB_2U_LIB.S9S_MB_2U(SCH_1):INA230_5_A1
   2 INA230_5_A0     A0 @S9S_MB_2U_LIB.S9S_MB_2U(SCH_1):INA230_5_A0
   5 SMB_INA230_5_3V3AUX_SCL_R1    SCL @S9S_MB_2U_LIB.S9S_MB_2U(SCH_1):SMB_INA230_5_3V3AUX_SCL_R1
   4 SMB_INA230_5_3V3AUX_SDA_R1    SDA @S9S_MB_2U_LIB.S9S_MB_2U(SCH_1):SMB_INA230_5_3V3AUX_SDA_R1
  11 P12V_SCM_R    BUS @S9S_MB_2U_LIB.S9S_MB_2U(SCH_1):P12V_SCM_R
  13 VSENSE_P12V_INA230_5_INP    IN+ @S9S_MB_2U_LIB.S9S_MB_2U(SCH_1):VSENSE_P12V_INA230_5_INP
  12 VSENSE_P12V_INA230_5_INN    IN- @S9S_MB_2U_LIB.S9S_MB_2U(SCH_1):VSENSE_P12V_INA230_5_INN
   3 P12V_SCM_ADC_ALERT_R  ALERT @S9S_MB_2U_LIB.S9S_MB_2U(SCH_1):P12V_SCM_ADC_ALERT_R
   6 NC_INA230_5_NC0    NC0 @S9S_MB_2U_LIB.S9S_MB_2U(SCH_1):NC_INA230_5_NC0
   7 NC_INA230_5_NC1    NC1 @S9S_MB_2U_LIB.S9S_MB_2U(SCH_1):NC_INA230_5_NC1
   8 NC_INA230_5_NC2    NC2 @S9S_MB_2U_LIB.S9S_MB_2U(SCH_1):NC_INA230_5_NC2
  14 NC_INA230_5_NC3    NC3 @S9S_MB_2U_LIB.S9S_MB_2U(SCH_1):NC_INA230_5_NC3
  15 NC_INA230_5_NC4    NC4 @S9S_MB_2U_LIB.S9S_MB_2U(SCH_1):NC_INA230_5_NC4
  16 NC_INA230_5_NC5    NC5 @S9S_MB_2U_LIB.S9S_MB_2U(SCH_1):NC_INA230_5_NC5
  10    GND    GND @S9S_MB_2U_LIB.S9S_MB_2U(SCH_1):GND
  TH    GND     TH @S9S_MB_2U_LIB.S9S_MB_2U(SCH_1):GND

Q_CAP_0402-0.1UF,25V,10%,X7R,CA  I71  C2021
   1 VSENSE_P12V_INA230_4_INP      A @S9S_MB_2U_LIB.S9S_MB_2U(SCH_1):VSENSE_P12V_INA230_4_INP
   2 VSENSE_P12V_INA230_4_INN      B @S9S_MB_2U_LIB.S9S_MB_2U(SCH_1):VSENSE_P12V_INA230_4_INN

Q_CAP_0402-0.1UF,25V,10%,X7R,CA  I72  C2022
   1 VSENSE_P12V_INA230_5_INP      A @S9S_MB_2U_LIB.S9S_MB_2U(SCH_1):VSENSE_P12V_INA230_5_INP
   2 VSENSE_P12V_INA230_5_INN      B @S9S_MB_2U_LIB.S9S_MB_2U(SCH_1):VSENSE_P12V_INA230_5_INN

Q_RES_0402LF-4.7K,1%,1/16W,CHIA  I86  R3623
   1 P3V3_AUX      A @S9S_MB_2U_LIB.S9S_MB_2U(SCH_1):P3V3_AUX
   2 INA230_4_A1      B @S9S_MB_2U_LIB.S9S_MB_2U(SCH_1):INA230_4_A1

Q_RES_0402LF-4.7K,1%,1/16W,EMPA  I87  R3621
   1 P3V3_AUX      A @S9S_MB_2U_LIB.S9S_MB_2U(SCH_1):P3V3_AUX
   2 INA230_4_A0      B @S9S_MB_2U_LIB.S9S_MB_2U(SCH_1):INA230_4_A0

Q_RES_0402LF-4.7K,1%,1/16W,CHIA  I89  R3624
   1 P3V3_AUX      A @S9S_MB_2U_LIB.S9S_MB_2U(SCH_1):P3V3_AUX
   2 INA230_5_A1      B @S9S_MB_2U_LIB.S9S_MB_2U(SCH_1):INA230_5_A1

Q_RES_0402LF-4.7K,1%,1/16W,CHIA  I90  R3622
   1 P3V3_AUX      A @S9S_MB_2U_LIB.S9S_MB_2U(SCH_1):P3V3_AUX
   2 INA230_5_A0      B @S9S_MB_2U_LIB.S9S_MB_2U(SCH_1):INA230_5_A0

INA230AIRGTR-INA230AIRGTR,SMLFB  I94  U263
   9 P3V3_AUX     VS @S9S_MB_2U_LIB.S9S_MB_2U(SCH_1):P3V3_AUX
   1 INA230_3_A1     A1 @S9S_MB_2U_LIB.S9S_MB_2U(SCH_1):INA230_3_A1
   2 INA230_3_A0     A0 @S9S_MB_2U_LIB.S9S_MB_2U(SCH_1):INA230_3_A0
   5 SMB_INA230_3_3V3AUX_SCL_R1    SCL @S9S_MB_2U_LIB.S9S_MB_2U(SCH_1):SMB_INA230_3_3V3AUX_SCL_R1
   4 SMB_INA230_3_3V3AUX_SDA_R1    SDA @S9S_MB_2U_LIB.S9S_MB_2U(SCH_1):SMB_INA230_3_3V3AUX_SDA_R1
  11 P3V3_OCP_V3_2_R    BUS @S9S_MB_2U_LIB.S9S_MB_2U(SCH_1):P3V3_OCP_V3_2_R
  13 VSENSE_P12V_INA230_3_INP    IN+ @S9S_MB_2U_LIB.S9S_MB_2U(SCH_1):VSENSE_P12V_INA230_3_INP
  12 VSENSE_P12V_INA230_3_INN    IN- @S9S_MB_2U_LIB.S9S_MB_2U(SCH_1):VSENSE_P12V_INA230_3_INN
   3 OCP_V3_2_P3V3_ADC_ALERT_R  ALERT @S9S_MB_2U_LIB.S9S_MB_2U(SCH_1):OCP_V3_2_P3V3_ADC_ALERT_R
   6 NC_INA230_3_NC0    NC0 @S9S_MB_2U_LIB.S9S_MB_2U(SCH_1):NC_INA230_3_NC0
   7 NC_INA230_3_NC1    NC1 @S9S_MB_2U_LIB.S9S_MB_2U(SCH_1):NC_INA230_3_NC1
   8 NC_INA230_3_NC2    NC2 @S9S_MB_2U_LIB.S9S_MB_2U(SCH_1):NC_INA230_3_NC2
  14 NC_INA230_3_NC3    NC3 @S9S_MB_2U_LIB.S9S_MB_2U(SCH_1):NC_INA230_3_NC3
  15 NC_INA230_3_NC4    NC4 @S9S_MB_2U_LIB.S9S_MB_2U(SCH_1):NC_INA230_3_NC4
  16 NC_INA230_3_NC5    NC5 @S9S_MB_2U_LIB.S9S_MB_2U(SCH_1):NC_INA230_3_NC5
  10    GND    GND @S9S_MB_2U_LIB.S9S_MB_2U(SCH_1):GND
  TH    GND     TH @S9S_MB_2U_LIB.S9S_MB_2U(SCH_1):GND

Q_RES_0402LF-0,5%,1/16W,CHIP,CA  I96  R3559
   1 OCP_V3_2_P3V3_ADC_ALERT_R      A @S9S_MB_2U_LIB.S9S_MB_2U(SCH_1):OCP_V3_2_P3V3_ADC_ALERT_R
   2 OCP_V3_2_P3V3_ADC_ALERT      B @S9S_MB_2U_LIB.S9S_MB_2U(SCH_1):OCP_V3_2_P3V3_ADC_ALERT

Q_CAP_0402-0.1UF,25V,10%,X7R,CA  I98  C2012
   1 P3V3_AUX      A @S9S_MB_2U_LIB.S9S_MB_2U(SCH_1):P3V3_AUX
   2    GND      B @S9S_MB_2U_LIB.S9S_MB_2U(SCH_1):GND

Q_RES_0402LF-0,5%,1/16W,CHIP,CA  I100  R3620
   1 INA230_3_A0      A @S9S_MB_2U_LIB.S9S_MB_2U(SCH_1):INA230_3_A0
   2 SMB_INA230_3_3V3AUX_SCL_R1      B @S9S_MB_2U_LIB.S9S_MB_2U(SCH_1):SMB_INA230_3_3V3AUX_SCL_R1

Q_RES_0402LF-33.2,1%,1/16W,CHIA  I101  R3568
   1 SMB_INA230_3_3V3AUX_SCL_R      A @S9S_MB_2U_LIB.S9S_MB_2U(SCH_1):SMB_INA230_3_3V3AUX_SCL_R
   2 SMB_INA230_3_3V3AUX_SCL_R1      B @S9S_MB_2U_LIB.S9S_MB_2U(SCH_1):SMB_INA230_3_3V3AUX_SCL_R1

Q_RES_0402LF-33.2,1%,1/16W,CHIA  I102  R3569
   1 SMB_INA230_3_3V3AUX_SDA_R      A @S9S_MB_2U_LIB.S9S_MB_2U(SCH_1):SMB_INA230_3_3V3AUX_SDA_R
   2 SMB_INA230_3_3V3AUX_SDA_R1      B @S9S_MB_2U_LIB.S9S_MB_2U(SCH_1):SMB_INA230_3_3V3AUX_SDA_R1

Q_RES_0402LF-4.7K,1%,1/16W,CHIA  I103  R3608
   1    GND      A @S9S_MB_2U_LIB.S9S_MB_2U(SCH_1):GND
   2 INA230_3_A1      B @S9S_MB_2U_LIB.S9S_MB_2U(SCH_1):INA230_3_A1

Q_RES_0402LF-4.7K,1%,1/16W,EMPA  I104  R3609
   1    GND      A @S9S_MB_2U_LIB.S9S_MB_2U(SCH_1):GND
   2 INA230_3_A0      B @S9S_MB_2U_LIB.S9S_MB_2U(SCH_1):INA230_3_A0

Q_CAP_0402-0.1UF,25V,10%,X7R,CA  I108  C2020
   1 VSENSE_P12V_INA230_3_INP      A @S9S_MB_2U_LIB.S9S_MB_2U(SCH_1):VSENSE_P12V_INA230_3_INP
   2 VSENSE_P12V_INA230_3_INN      B @S9S_MB_2U_LIB.S9S_MB_2U(SCH_1):VSENSE_P12V_INA230_3_INN

Q_RES_0402LF-10,1%,1/16W,CHIP,A  I109  R3570
   1 P3V3_OCP_V3_2_R      A @S9S_MB_2U_LIB.S9S_MB_2U(SCH_1):P3V3_OCP_V3_2_R
   2 VSENSE_P12V_INA230_3_INP      B @S9S_MB_2U_LIB.S9S_MB_2U(SCH_1):VSENSE_P12V_INA230_3_INP

Q_RES_0402LF-10,1%,1/16W,CHIP,A  I110  R3571
   1 P3V3_OCP_V3_2      A @S9S_MB_2U_LIB.S9S_MB_2U(SCH_1):P3V3_OCP_V3_2
   2 VSENSE_P12V_INA230_3_INN      B @S9S_MB_2U_LIB.S9S_MB_2U(SCH_1):VSENSE_P12V_INA230_3_INN

Q_CAP_0402-0.1UF,25V,10%,X7R,CA  I114  C2017
   1 P3V3_OCP_V3_2_R      A @S9S_MB_2U_LIB.S9S_MB_2U(SCH_1):P3V3_OCP_V3_2_R
   2    GND      B @S9S_MB_2U_LIB.S9S_MB_2U(SCH_1):GND

Q_RES_0402LF-4.7K,1%,1/16W,CHIA  I122  R4091
   1 P3V3_AUX      A @S9S_MB_2U_LIB.S9S_MB_2U(SCH_1):P3V3_AUX
   2 P12V_SCM_ADC_ALERT_R      B @S9S_MB_2U_LIB.S9S_MB_2U(SCH_1):P12V_SCM_ADC_ALERT_R

Q_RES_0402LF-4.7K,1%,1/16W,CHIA  I124  R4090
   1 P3V3_AUX      A @S9S_MB_2U_LIB.S9S_MB_2U(SCH_1):P3V3_AUX
   2 M2_0_P3V3_ADC_ALERT_R      B @S9S_MB_2U_LIB.S9S_MB_2U(SCH_1):M2_0_P3V3_ADC_ALERT_R

Q_RES_0402LF-4.7K,1%,1/16W,CHIA  I126  R4092
   1 P3V3_AUX      A @S9S_MB_2U_LIB.S9S_MB_2U(SCH_1):P3V3_AUX
   2 OCP_V3_2_P3V3_ADC_ALERT_R      B @S9S_MB_2U_LIB.S9S_MB_2U(SCH_1):OCP_V3_2_P3V3_ADC_ALERT_R

Q_RES_2512LF-0.01,1%,1W,CHIP,CA  I127  R3633
   1 P3V3_OCP_V3_2      A @S9S_MB_2U_LIB.S9S_MB_2U(SCH_1):P3V3_OCP_V3_2
   2 P3V3_OCP_V3_2_R      B @S9S_MB_2U_LIB.S9S_MB_2U(SCH_1):P3V3_OCP_V3_2_R

Q_RES_2512LF-0.01,1%,1W,CHIP,CA  I128  R3634
   1 P3V3_M2_0      A @S9S_MB_2U_LIB.S9S_MB_2U(SCH_1):P3V3_M2_0
   2   P3V3      B @S9S_MB_2U_LIB.S9S_MB_2U(SCH_1):P3V3

Q_RES_2512LF-0.01,1%,1W,CHIP,CA  I129  R3635
   1 P12V_SCM      A @S9S_MB_2U_LIB.S9S_MB_2U(SCH_1):P12V_SCM
   2 P12V_SCM_R      B @S9S_MB_2U_LIB.S9S_MB_2U(SCH_1):P12V_SCM_R


DRAWING: @S9S_MB_2U_LIB.S9S_MB_2U(SCH_1):PAGE295 

INA230AIRGTR-INA230AIRGTR,SMLFB  I30  U266
   9 P3V3_AUX     VS @S9S_MB_2U_LIB.S9S_MB_2U(SCH_1):P3V3_AUX
   1 INA230_1_A1     A1 @S9S_MB_2U_LIB.S9S_MB_2U(SCH_1):INA230_1_A1
   2 INA230_1_A0     A0 @S9S_MB_2U_LIB.S9S_MB_2U(SCH_1):INA230_1_A0
   5 SMB_INA230_1_3V3AUX_SCL_R1    SCL @S9S_MB_2U_LIB.S9S_MB_2U(SCH_1):SMB_INA230_1_3V3AUX_SCL_R1
   4 SMB_INA230_1_3V3AUX_SDA_R1    SDA @S9S_MB_2U_LIB.S9S_MB_2U(SCH_1):SMB_INA230_1_3V3AUX_SDA_R1
  11 P3V3_OCP_SFF_R    BUS @S9S_MB_2U_LIB.S9S_MB_2U(SCH_1):P3V3_OCP_SFF_R
  13 VSENSE_P3V3_INA230_1_INP    IN+ @S9S_MB_2U_LIB.S9S_MB_2U(SCH_1):VSENSE_P3V3_INA230_1_INP
  12 VSENSE_P3V3_INA230_1_INN    IN- @S9S_MB_2U_LIB.S9S_MB_2U(SCH_1):VSENSE_P3V3_INA230_1_INN
   3 OCP_SFF_P3V3_ADC_ALERT_R  ALERT @S9S_MB_2U_LIB.S9S_MB_2U(SCH_1):OCP_SFF_P3V3_ADC_ALERT_R
   6 NC_INA230_1_NC0    NC0 @S9S_MB_2U_LIB.S9S_MB_2U(SCH_1):NC_INA230_1_NC0
   7 NC_INA230_1_NC1    NC1 @S9S_MB_2U_LIB.S9S_MB_2U(SCH_1):NC_INA230_1_NC1
   8 NC_INA230_1_NC2    NC2 @S9S_MB_2U_LIB.S9S_MB_2U(SCH_1):NC_INA230_1_NC2
  14 NC_INA230_1_NC3    NC3 @S9S_MB_2U_LIB.S9S_MB_2U(SCH_1):NC_INA230_1_NC3
  15 NC_INA230_1_NC4    NC4 @S9S_MB_2U_LIB.S9S_MB_2U(SCH_1):NC_INA230_1_NC4
  16 NC_INA230_1_NC5    NC5 @S9S_MB_2U_LIB.S9S_MB_2U(SCH_1):NC_INA230_1_NC5
  10    GND    GND @S9S_MB_2U_LIB.S9S_MB_2U(SCH_1):GND
  TH    GND     TH @S9S_MB_2U_LIB.S9S_MB_2U(SCH_1):GND

Q_RES_0402LF-4.7K,1%,1/16W,CHIA  I31  R3616
   1    GND      A @S9S_MB_2U_LIB.S9S_MB_2U(SCH_1):GND
   2 INA230_1_A1      B @S9S_MB_2U_LIB.S9S_MB_2U(SCH_1):INA230_1_A1

Q_CAP_0402-0.1UF,25V,10%,X7R,CA  I34  C2015
   1 P3V3_AUX      A @S9S_MB_2U_LIB.S9S_MB_2U(SCH_1):P3V3_AUX
   2    GND      B @S9S_MB_2U_LIB.S9S_MB_2U(SCH_1):GND

Q_RES_0402LF-0,5%,1/16W,CHIP,CA  I35  R3563
   1 OCP_SFF_P3V3_ADC_ALERT_R      A @S9S_MB_2U_LIB.S9S_MB_2U(SCH_1):OCP_SFF_P3V3_ADC_ALERT_R
   2 OCP_SFF_P3V3_ADC_ALERT      B @S9S_MB_2U_LIB.S9S_MB_2U(SCH_1):OCP_SFF_P3V3_ADC_ALERT

Q_RES_0402LF-33.2,1%,1/16W,CHIA  I38  R3600
   1 SMB_INA230_1_3V3AUX_SCL_R      A @S9S_MB_2U_LIB.S9S_MB_2U(SCH_1):SMB_INA230_1_3V3AUX_SCL_R
   2 SMB_INA230_1_3V3AUX_SCL_R1      B @S9S_MB_2U_LIB.S9S_MB_2U(SCH_1):SMB_INA230_1_3V3AUX_SCL_R1

Q_RES_0402LF-33.2,1%,1/16W,CHIA  I39  R3601
   1 SMB_INA230_1_3V3AUX_SDA_R      A @S9S_MB_2U_LIB.S9S_MB_2U(SCH_1):SMB_INA230_1_3V3AUX_SDA_R
   2 SMB_INA230_1_3V3AUX_SDA_R1      B @S9S_MB_2U_LIB.S9S_MB_2U(SCH_1):SMB_INA230_1_3V3AUX_SDA_R1

Q_RES_0402LF-4.7K,1%,1/16W,EMPA  I40  R3617
   1    GND      A @S9S_MB_2U_LIB.S9S_MB_2U(SCH_1):GND
   2 INA230_1_A0      B @S9S_MB_2U_LIB.S9S_MB_2U(SCH_1):INA230_1_A0

Q_RES_0402LF-10,1%,1/16W,CHIP,A  I41  R3602
   1 P3V3_OCP_SFF_R      A @S9S_MB_2U_LIB.S9S_MB_2U(SCH_1):P3V3_OCP_SFF_R
   2 VSENSE_P3V3_INA230_1_INP      B @S9S_MB_2U_LIB.S9S_MB_2U(SCH_1):VSENSE_P3V3_INA230_1_INP

Q_RES_0402LF-10,1%,1/16W,CHIP,A  I43  R3603
   1 P3V3_OCP_SFF      A @S9S_MB_2U_LIB.S9S_MB_2U(SCH_1):P3V3_OCP_SFF
   2 VSENSE_P3V3_INA230_1_INN      B @S9S_MB_2U_LIB.S9S_MB_2U(SCH_1):VSENSE_P3V3_INA230_1_INN

Q_CAP_0402-0.1UF,25V,10%,X7R,CA  I50  C2024
   1 P3V3_OCP_SFF_R      A @S9S_MB_2U_LIB.S9S_MB_2U(SCH_1):P3V3_OCP_SFF_R
   2    GND      B @S9S_MB_2U_LIB.S9S_MB_2U(SCH_1):GND

Q_CAP_0402-0.1UF,25V,10%,X7R,CA  I77  C2027
   1 VSENSE_P3V3_INA230_1_INP      A @S9S_MB_2U_LIB.S9S_MB_2U(SCH_1):VSENSE_P3V3_INA230_1_INP
   2 VSENSE_P3V3_INA230_1_INN      B @S9S_MB_2U_LIB.S9S_MB_2U(SCH_1):VSENSE_P3V3_INA230_1_INN

Q_RES_0402LF-4.7K,1%,1/16W,EMPA  I88  R3628
   1 P3V3_AUX      A @S9S_MB_2U_LIB.S9S_MB_2U(SCH_1):P3V3_AUX
   2 INA230_1_A1      B @S9S_MB_2U_LIB.S9S_MB_2U(SCH_1):INA230_1_A1

Q_RES_0402LF-4.7K,1%,1/16W,CHIA  I89  R3627
   1 P3V3_AUX      A @S9S_MB_2U_LIB.S9S_MB_2U(SCH_1):P3V3_AUX
   2 INA230_1_A0      B @S9S_MB_2U_LIB.S9S_MB_2U(SCH_1):INA230_1_A0

Q_RES_0402LF-0,5%,1/16W,CHIP,CA  I122  R3752
   1 E1S_0_P3V3_ADC_ALERT_R      A @S9S_MB_2U_LIB.S9S_MB_2U(SCH_1):E1S_0_P3V3_ADC_ALERT_R
   2 E1S_0_P3V3_ADC_ALERT      B @S9S_MB_2U_LIB.S9S_MB_2U(SCH_1):E1S_0_P3V3_ADC_ALERT

Q_CAP_0402-0.1UF,25V,10%,X7R,CA  I125  C2067
   1 P3V3_AUX      A @S9S_MB_2U_LIB.S9S_MB_2U(SCH_1):P3V3_AUX
   2    GND      B @S9S_MB_2U_LIB.S9S_MB_2U(SCH_1):GND

INA230AIRGTR-INA230AIRGTR,SMLFB  I129  U276
   9 P3V3_AUX     VS @S9S_MB_2U_LIB.S9S_MB_2U(SCH_1):P3V3_AUX
   1 INA230_2_A1     A1 @S9S_MB_2U_LIB.S9S_MB_2U(SCH_1):INA230_2_A1
   2 INA230_2_A0     A0 @S9S_MB_2U_LIB.S9S_MB_2U(SCH_1):INA230_2_A0
   5 SMB_INA230_2_3V3AUX_SCL_R1    SCL @S9S_MB_2U_LIB.S9S_MB_2U(SCH_1):SMB_INA230_2_3V3AUX_SCL_R1
   4 SMB_INA230_2_3V3AUX_SDA_R1    SDA @S9S_MB_2U_LIB.S9S_MB_2U(SCH_1):SMB_INA230_2_3V3AUX_SDA_R1
  11 P3V3_E1S_0_R    BUS @S9S_MB_2U_LIB.S9S_MB_2U(SCH_1):P3V3_E1S_0_R
  13 VSENSE_P3V3_INA230_2_INP    IN+ @S9S_MB_2U_LIB.S9S_MB_2U(SCH_1):VSENSE_P3V3_INA230_2_INP
  12 VSENSE_P3V3_INA230_2_INN    IN- @S9S_MB_2U_LIB.S9S_MB_2U(SCH_1):VSENSE_P3V3_INA230_2_INN
   3 E1S_0_P3V3_ADC_ALERT_R  ALERT @S9S_MB_2U_LIB.S9S_MB_2U(SCH_1):E1S_0_P3V3_ADC_ALERT_R
   6 NC_INA230_2_NC0    NC0 @S9S_MB_2U_LIB.S9S_MB_2U(SCH_1):NC_INA230_2_NC0
   7 NC_INA230_2_NC1    NC1 @S9S_MB_2U_LIB.S9S_MB_2U(SCH_1):NC_INA230_2_NC1
   8 NC_INA230_2_NC2    NC2 @S9S_MB_2U_LIB.S9S_MB_2U(SCH_1):NC_INA230_2_NC2
  14 NC_INA230_2_NC3    NC3 @S9S_MB_2U_LIB.S9S_MB_2U(SCH_1):NC_INA230_2_NC3
  15 NC_INA230_2_NC4    NC4 @S9S_MB_2U_LIB.S9S_MB_2U(SCH_1):NC_INA230_2_NC4
  16 NC_INA230_2_NC5    NC5 @S9S_MB_2U_LIB.S9S_MB_2U(SCH_1):NC_INA230_2_NC5
  10    GND    GND @S9S_MB_2U_LIB.S9S_MB_2U(SCH_1):GND
  TH    GND     TH @S9S_MB_2U_LIB.S9S_MB_2U(SCH_1):GND

Q_RES_0402LF-33.2,1%,1/16W,CHIA  I130  R3754
   1 SMB_INA230_2_3V3AUX_SCL_R      A @S9S_MB_2U_LIB.S9S_MB_2U(SCH_1):SMB_INA230_2_3V3AUX_SCL_R
   2 SMB_INA230_2_3V3AUX_SCL_R1      B @S9S_MB_2U_LIB.S9S_MB_2U(SCH_1):SMB_INA230_2_3V3AUX_SCL_R1

Q_RES_0402LF-33.2,1%,1/16W,CHIA  I131  R3756
   1 SMB_INA230_2_3V3AUX_SDA_R      A @S9S_MB_2U_LIB.S9S_MB_2U(SCH_1):SMB_INA230_2_3V3AUX_SDA_R
   2 SMB_INA230_2_3V3AUX_SDA_R1      B @S9S_MB_2U_LIB.S9S_MB_2U(SCH_1):SMB_INA230_2_3V3AUX_SDA_R1

Q_RES_0402LF-10,1%,1/16W,CHIP,A  I132  R3758
   1 P3V3_E1S_0_R      A @S9S_MB_2U_LIB.S9S_MB_2U(SCH_1):P3V3_E1S_0_R
   2 VSENSE_P3V3_INA230_2_INP      B @S9S_MB_2U_LIB.S9S_MB_2U(SCH_1):VSENSE_P3V3_INA230_2_INP

Q_CAP_0402-0.1UF,25V,10%,X7R,CA  I133  C2071
   1 VSENSE_P3V3_INA230_2_INP      A @S9S_MB_2U_LIB.S9S_MB_2U(SCH_1):VSENSE_P3V3_INA230_2_INP
   2 VSENSE_P3V3_INA230_2_INN      B @S9S_MB_2U_LIB.S9S_MB_2U(SCH_1):VSENSE_P3V3_INA230_2_INN

Q_RES_0402LF-10,1%,1/16W,CHIP,A  I134  R3760
   1 P3V3_E1S_0      A @S9S_MB_2U_LIB.S9S_MB_2U(SCH_1):P3V3_E1S_0
   2 VSENSE_P3V3_INA230_2_INN      B @S9S_MB_2U_LIB.S9S_MB_2U(SCH_1):VSENSE_P3V3_INA230_2_INN

Q_RES_0402LF-4.7K,1%,1/16W,EMPA  I135  R3764
   1    GND      A @S9S_MB_2U_LIB.S9S_MB_2U(SCH_1):GND
   2 INA230_2_A0      B @S9S_MB_2U_LIB.S9S_MB_2U(SCH_1):INA230_2_A0

Q_RES_0402LF-4.7K,1%,1/16W,CHIA  I136  R3763
   1    GND      A @S9S_MB_2U_LIB.S9S_MB_2U(SCH_1):GND
   2 INA230_2_A1      B @S9S_MB_2U_LIB.S9S_MB_2U(SCH_1):INA230_2_A1

Q_CAP_0402-0.1UF,25V,10%,X7R,CA  I142  C2069
   1 P3V3_E1S_0_R      A @S9S_MB_2U_LIB.S9S_MB_2U(SCH_1):P3V3_E1S_0_R
   2    GND      B @S9S_MB_2U_LIB.S9S_MB_2U(SCH_1):GND

Q_RES_0402LF-0,5%,1/16W,CHIP,CA  I146  R3751
   1 INA230_2_A0      A @S9S_MB_2U_LIB.S9S_MB_2U(SCH_1):INA230_2_A0
   2 SMB_INA230_2_3V3AUX_SDA_R1      B @S9S_MB_2U_LIB.S9S_MB_2U(SCH_1):SMB_INA230_2_3V3AUX_SDA_R1

Q_RES_0402LF-4.7K,1%,1/16W,CHIA  I149  R4093
   1 P3V3_AUX      A @S9S_MB_2U_LIB.S9S_MB_2U(SCH_1):P3V3_AUX
   2 E1S_0_P3V3_ADC_ALERT_R      B @S9S_MB_2U_LIB.S9S_MB_2U(SCH_1):E1S_0_P3V3_ADC_ALERT_R

Q_RES_0402LF-4.7K,1%,1/16W,CHIA  I151  R4094
   1 P3V3_AUX      A @S9S_MB_2U_LIB.S9S_MB_2U(SCH_1):P3V3_AUX
   2 OCP_SFF_P3V3_ADC_ALERT_R      B @S9S_MB_2U_LIB.S9S_MB_2U(SCH_1):OCP_SFF_P3V3_ADC_ALERT_R

Q_RES_2512LF-0.01,1%,1W,CHIP,CA  I152  R3645
   1 P3V3_OCP_SFF      A @S9S_MB_2U_LIB.S9S_MB_2U(SCH_1):P3V3_OCP_SFF
   2 P3V3_OCP_SFF_R      B @S9S_MB_2U_LIB.S9S_MB_2U(SCH_1):P3V3_OCP_SFF_R

Q_RES_2512LF-0.01,1%,1W,CHIP,CA  I153  R3767
   1 P3V3_E1S_0      A @S9S_MB_2U_LIB.S9S_MB_2U(SCH_1):P3V3_E1S_0
   2 P3V3_E1S_0_R      B @S9S_MB_2U_LIB.S9S_MB_2U(SCH_1):P3V3_E1S_0_R


DRAWING: @S9S_MB_2U_LIB.S9S_MB_2U(SCH_1):PAGE161 

Q_CAP_0402-0.1UF,25V,10%,X7R,CA  I16  C2010
   1 P3V3_AUX      A @S9S_MB_2U_LIB.S9S_MB_2U(SCH_1):P3V3_AUX
   2    GND      B @S9S_MB_2U_LIB.S9S_MB_2U(SCH_1):GND

Q_RES_0402LF-33.2,1%,1/16W,CHIA  I77  R4180
   1 SMB_LM75_0_3V3AUX_SCL      A @S9S_MB_2U_LIB.S9S_MB_2U(SCH_1):SMB_LM75_0_3V3AUX_SCL
   2 SMB_LM75_0_3V3AUX_SCL_R1      B @S9S_MB_2U_LIB.S9S_MB_2U(SCH_1):SMB_LM75_0_3V3AUX_SCL_R1

Q_RES_0402LF-33.2,1%,1/16W,CHIA  I78  R4183
   1 SMB_LM75_0_3V3AUX_SDA      A @S9S_MB_2U_LIB.S9S_MB_2U(SCH_1):SMB_LM75_0_3V3AUX_SDA
   2 SMB_LM75_0_3V3AUX_SDA_R1      B @S9S_MB_2U_LIB.S9S_MB_2U(SCH_1):SMB_LM75_0_3V3AUX_SDA_R1

Q_RES_0402LF-0,5%,1/16W,CHIP,CA  I79  R4215
   1 FM_THERMAL_ALERT_N      A @S9S_MB_2U_LIB.S9S_MB_2U(SCH_1):FM_THERMAL_ALERT_N
   2 FM_G751_0_ALERT_N      B @S9S_MB_2U_LIB.S9S_MB_2U(SCH_1):FM_G751_0_ALERT_N

Q_RES_0402LF-1K,1%,1/16W,CHIP,A  I81  R4199
   1 U270_0_ADD1      A @S9S_MB_2U_LIB.S9S_MB_2U(SCH_1):U270_0_ADD1
   2    GND      B @S9S_MB_2U_LIB.S9S_MB_2U(SCH_1):GND

Q_RES_0402LF-1K,1%,1/16W,EMPTYA  I82  R4198
   1 P3V3_AUX      A @S9S_MB_2U_LIB.S9S_MB_2U(SCH_1):P3V3_AUX
   2 U270_0_ADD1      B @S9S_MB_2U_LIB.S9S_MB_2U(SCH_1):U270_0_ADD1

Q_RES_0402LF-1K,1%,1/16W,CHIP,A  I85  R4207
   1 U270_0_ADD0      A @S9S_MB_2U_LIB.S9S_MB_2U(SCH_1):U270_0_ADD0
   2    GND      B @S9S_MB_2U_LIB.S9S_MB_2U(SCH_1):GND

Q_RES_0402LF-1K,1%,1/16W,EMPTYA  I86  R4206
   1 P3V3_AUX      A @S9S_MB_2U_LIB.S9S_MB_2U(SCH_1):P3V3_AUX
   2 U270_0_ADD0      B @S9S_MB_2U_LIB.S9S_MB_2U(SCH_1):U270_0_ADD0

Q_RES_0402LF-1K,1%,1/16W,CHIP,A  I89  R4191
   1 U270_0_ADD2      A @S9S_MB_2U_LIB.S9S_MB_2U(SCH_1):U270_0_ADD2
   2    GND      B @S9S_MB_2U_LIB.S9S_MB_2U(SCH_1):GND

Q_RES_0402LF-1K,1%,1/16W,EMPTYA  I91  R4190
   1 P3V3_AUX      A @S9S_MB_2U_LIB.S9S_MB_2U(SCH_1):P3V3_AUX
   2 U270_0_ADD2      B @S9S_MB_2U_LIB.S9S_MB_2U(SCH_1):U270_0_ADD2

Q_RES_0402LF-1K,1%,1/16W,EMPTYA  I94  R4204
   1 P3V3_AUX      A @S9S_MB_2U_LIB.S9S_MB_2U(SCH_1):P3V3_AUX
   2 U271_1_ADD0      B @S9S_MB_2U_LIB.S9S_MB_2U(SCH_1):U271_1_ADD0

Q_RES_0402LF-1K,1%,1/16W,EMPTYA  I95  R4196
   1 P3V3_AUX      A @S9S_MB_2U_LIB.S9S_MB_2U(SCH_1):P3V3_AUX
   2 U271_1_ADD1      B @S9S_MB_2U_LIB.S9S_MB_2U(SCH_1):U271_1_ADD1

Q_RES_0402LF-1K,1%,1/16W,CHIP,A  I96  R4205
   1 U271_1_ADD0      A @S9S_MB_2U_LIB.S9S_MB_2U(SCH_1):U271_1_ADD0
   2    GND      B @S9S_MB_2U_LIB.S9S_MB_2U(SCH_1):GND

Q_RES_0402LF-1K,1%,1/16W,CHIP,A  I98  R4197
   1 U271_1_ADD1      A @S9S_MB_2U_LIB.S9S_MB_2U(SCH_1):U271_1_ADD1
   2    GND      B @S9S_MB_2U_LIB.S9S_MB_2U(SCH_1):GND

Q_RES_0402LF-1K,1%,1/16W,EMPTYA  I101  R4188
   1 P3V3_AUX      A @S9S_MB_2U_LIB.S9S_MB_2U(SCH_1):P3V3_AUX
   2 U271_1_ADD2      B @S9S_MB_2U_LIB.S9S_MB_2U(SCH_1):U271_1_ADD2

Q_RES_0402LF-1K,1%,1/16W,CHIP,A  I102  R4189
   1 U271_1_ADD2      A @S9S_MB_2U_LIB.S9S_MB_2U(SCH_1):U271_1_ADD2
   2    GND      B @S9S_MB_2U_LIB.S9S_MB_2U(SCH_1):GND

Q_CAP_0402-0.1UF,25V,10%,X7R,CA  I104  C2276
   1 P3V3_AUX      A @S9S_MB_2U_LIB.S9S_MB_2U(SCH_1):P3V3_AUX
   2    GND      B @S9S_MB_2U_LIB.S9S_MB_2U(SCH_1):GND

Q_RES_0402LF-33.2,1%,1/16W,CHIA  I107  R4182
   1 SMB_LM75_1_3V3AUX_SDA      A @S9S_MB_2U_LIB.S9S_MB_2U(SCH_1):SMB_LM75_1_3V3AUX_SDA
   2 SMB_LM75_1_3V3AUX_SDA_R1      B @S9S_MB_2U_LIB.S9S_MB_2U(SCH_1):SMB_LM75_1_3V3AUX_SDA_R1

Q_RES_0402LF-0,5%,1/16W,CHIP,CA  I108  R4214
   1 FM_THERMAL_ALERT_N      A @S9S_MB_2U_LIB.S9S_MB_2U(SCH_1):FM_THERMAL_ALERT_N
   2 FM_G751_1_ALERT_N      B @S9S_MB_2U_LIB.S9S_MB_2U(SCH_1):FM_G751_1_ALERT_N

Q_RES_0402LF-33.2,1%,1/16W,CHIA  I109  R4179
   1 SMB_LM75_1_3V3AUX_SCL      A @S9S_MB_2U_LIB.S9S_MB_2U(SCH_1):SMB_LM75_1_3V3AUX_SCL
   2 SMB_LM75_1_3V3AUX_SCL_R1      B @S9S_MB_2U_LIB.S9S_MB_2U(SCH_1):SMB_LM75_1_3V3AUX_SCL_R1

Q_RES_0402LF-33.2,1%,1/16W,CHIA  I114  R4178
   1 SMB_LM75_2_3V3AUX_SCL      A @S9S_MB_2U_LIB.S9S_MB_2U(SCH_1):SMB_LM75_2_3V3AUX_SCL
   2 SMB_LM75_2_3V3AUX_SCL_R1      B @S9S_MB_2U_LIB.S9S_MB_2U(SCH_1):SMB_LM75_2_3V3AUX_SCL_R1

Q_RES_0402LF-0,5%,1/16W,CHIP,CA  I115  R4213
   1 FM_THERMAL_ALERT_N      A @S9S_MB_2U_LIB.S9S_MB_2U(SCH_1):FM_THERMAL_ALERT_N
   2 FM_LM75_2_ALERT_N      B @S9S_MB_2U_LIB.S9S_MB_2U(SCH_1):FM_LM75_2_ALERT_N

Q_RES_0402LF-33.2,1%,1/16W,CHIA  I116  R4181
   1 SMB_LM75_2_3V3AUX_SDA      A @S9S_MB_2U_LIB.S9S_MB_2U(SCH_1):SMB_LM75_2_3V3AUX_SDA
   2 SMB_LM75_2_3V3AUX_SDA_R1      B @S9S_MB_2U_LIB.S9S_MB_2U(SCH_1):SMB_LM75_2_3V3AUX_SDA_R1

Q_CAP_0402-0.1UF,25V,10%,X7R,CA  I119  C2275
   1 P3V3_AUX      A @S9S_MB_2U_LIB.S9S_MB_2U(SCH_1):P3V3_AUX
   2    GND      B @S9S_MB_2U_LIB.S9S_MB_2U(SCH_1):GND

Q_RES_0402LF-1K,1%,1/16W,CHIP,A  I121  R4187
   1 U272_2_ADD2      A @S9S_MB_2U_LIB.S9S_MB_2U(SCH_1):U272_2_ADD2
   2    GND      B @S9S_MB_2U_LIB.S9S_MB_2U(SCH_1):GND

Q_RES_0402LF-1K,1%,1/16W,EMPTYA  I122  R4186
   1 P3V3_AUX      A @S9S_MB_2U_LIB.S9S_MB_2U(SCH_1):P3V3_AUX
   2 U272_2_ADD2      B @S9S_MB_2U_LIB.S9S_MB_2U(SCH_1):U272_2_ADD2

Q_RES_0402LF-1K,1%,1/16W,CHIP,A  I125  R4195
   1 U272_2_ADD1      A @S9S_MB_2U_LIB.S9S_MB_2U(SCH_1):U272_2_ADD1
   2    GND      B @S9S_MB_2U_LIB.S9S_MB_2U(SCH_1):GND

Q_RES_0402LF-1K,1%,1/16W,CHIP,A  I127  R4203
   1 U272_2_ADD0      A @S9S_MB_2U_LIB.S9S_MB_2U(SCH_1):U272_2_ADD0
   2    GND      B @S9S_MB_2U_LIB.S9S_MB_2U(SCH_1):GND

Q_RES_0402LF-1K,1%,1/16W,EMPTYA  I128  R4194
   1 P3V3_AUX      A @S9S_MB_2U_LIB.S9S_MB_2U(SCH_1):P3V3_AUX
   2 U272_2_ADD1      B @S9S_MB_2U_LIB.S9S_MB_2U(SCH_1):U272_2_ADD1

Q_RES_0402LF-1K,1%,1/16W,EMPTYA  I129  R4202
   1 P3V3_AUX      A @S9S_MB_2U_LIB.S9S_MB_2U(SCH_1):P3V3_AUX
   2 U272_2_ADD0      B @S9S_MB_2U_LIB.S9S_MB_2U(SCH_1):U272_2_ADD0

Q_RES_0402LF-33.2,1%,1/16W,CHIA  I134  R3553
   1 SMB_LM75_3_3V3AUX_SCL      A @S9S_MB_2U_LIB.S9S_MB_2U(SCH_1):SMB_LM75_3_3V3AUX_SCL
   2 SMB_LM75_3_3V3AUX_SCL_R1      B @S9S_MB_2U_LIB.S9S_MB_2U(SCH_1):SMB_LM75_3_3V3AUX_SCL_R1

Q_RES_0402LF-0,5%,1/16W,CHIP,CA  I135  R4212
   1 FM_THERMAL_ALERT_N      A @S9S_MB_2U_LIB.S9S_MB_2U(SCH_1):FM_THERMAL_ALERT_N
   2 FM_LM75_3_ALERT_N      B @S9S_MB_2U_LIB.S9S_MB_2U(SCH_1):FM_LM75_3_ALERT_N

Q_RES_0402LF-33.2,1%,1/16W,CHIA  I136  R3554
   1 SMB_LM75_3_3V3AUX_SDA      A @S9S_MB_2U_LIB.S9S_MB_2U(SCH_1):SMB_LM75_3_3V3AUX_SDA
   2 SMB_LM75_3_3V3AUX_SDA_R1      B @S9S_MB_2U_LIB.S9S_MB_2U(SCH_1):SMB_LM75_3_3V3AUX_SDA_R1

Q_CAP_0402-0.1UF,25V,10%,X7R,CA  I139  C2274
   1 P3V3_AUX      A @S9S_MB_2U_LIB.S9S_MB_2U(SCH_1):P3V3_AUX
   2    GND      B @S9S_MB_2U_LIB.S9S_MB_2U(SCH_1):GND

Q_RES_0402LF-1K,1%,1/16W,CHIP,A  I141  R4185
   1 U273_3_ADD2      A @S9S_MB_2U_LIB.S9S_MB_2U(SCH_1):U273_3_ADD2
   2    GND      B @S9S_MB_2U_LIB.S9S_MB_2U(SCH_1):GND

Q_RES_0402LF-1K,1%,1/16W,EMPTYA  I142  R4184
   1 P3V3_AUX      A @S9S_MB_2U_LIB.S9S_MB_2U(SCH_1):P3V3_AUX
   2 U273_3_ADD2      B @S9S_MB_2U_LIB.S9S_MB_2U(SCH_1):U273_3_ADD2

Q_RES_0402LF-1K,1%,1/16W,CHIP,A  I145  R4193
   1 U273_3_ADD1      A @S9S_MB_2U_LIB.S9S_MB_2U(SCH_1):U273_3_ADD1
   2    GND      B @S9S_MB_2U_LIB.S9S_MB_2U(SCH_1):GND

Q_RES_0402LF-1K,1%,1/16W,CHIP,A  I147  R4201
   1 U273_3_ADD0      A @S9S_MB_2U_LIB.S9S_MB_2U(SCH_1):U273_3_ADD0
   2    GND      B @S9S_MB_2U_LIB.S9S_MB_2U(SCH_1):GND

Q_RES_0402LF-1K,1%,1/16W,EMPTYA  I148  R4192
   1 P3V3_AUX      A @S9S_MB_2U_LIB.S9S_MB_2U(SCH_1):P3V3_AUX
   2 U273_3_ADD1      B @S9S_MB_2U_LIB.S9S_MB_2U(SCH_1):U273_3_ADD1

Q_RES_0402LF-1K,1%,1/16W,EMPTYA  I149  R4200
   1 P3V3_AUX      A @S9S_MB_2U_LIB.S9S_MB_2U(SCH_1):P3V3_AUX
   2 U273_3_ADD0      B @S9S_MB_2U_LIB.S9S_MB_2U(SCH_1):U273_3_ADD0

LM75BD-LM75BD,SMLF,IC,AL0075BDA  I164  U270
   1 SMB_LM75_0_3V3AUX_SDA_R1    SDA @S9S_MB_2U_LIB.S9S_MB_2U(SCH_1):SMB_LM75_0_3V3AUX_SDA_R1
   2 SMB_LM75_0_3V3AUX_SCL_R1    SCL @S9S_MB_2U_LIB.S9S_MB_2U(SCH_1):SMB_LM75_0_3V3AUX_SCL_R1
   3 FM_G751_0_ALERT_N     OS @S9S_MB_2U_LIB.S9S_MB_2U(SCH_1):FM_G751_0_ALERT_N
   4    GND    GND @S9S_MB_2U_LIB.S9S_MB_2U(SCH_1):GND
   5 U270_0_ADD2     A2 @S9S_MB_2U_LIB.S9S_MB_2U(SCH_1):U270_0_ADD2
   6 U270_0_ADD1     A1 @S9S_MB_2U_LIB.S9S_MB_2U(SCH_1):U270_0_ADD1
   7 U270_0_ADD0     A0 @S9S_MB_2U_LIB.S9S_MB_2U(SCH_1):U270_0_ADD0
   8 P3V3_AUX    VCC @S9S_MB_2U_LIB.S9S_MB_2U(SCH_1):P3V3_AUX

LM75BD-LM75BD,SMLF,IC,AL0075BDA  I165  U271
   1 SMB_LM75_1_3V3AUX_SDA_R1    SDA @S9S_MB_2U_LIB.S9S_MB_2U(SCH_1):SMB_LM75_1_3V3AUX_SDA_R1
   2 SMB_LM75_1_3V3AUX_SCL_R1    SCL @S9S_MB_2U_LIB.S9S_MB_2U(SCH_1):SMB_LM75_1_3V3AUX_SCL_R1
   3 FM_G751_1_ALERT_N     OS @S9S_MB_2U_LIB.S9S_MB_2U(SCH_1):FM_G751_1_ALERT_N
   4    GND    GND @S9S_MB_2U_LIB.S9S_MB_2U(SCH_1):GND
   5 U271_1_ADD2     A2 @S9S_MB_2U_LIB.S9S_MB_2U(SCH_1):U271_1_ADD2
   6 U271_1_ADD1     A1 @S9S_MB_2U_LIB.S9S_MB_2U(SCH_1):U271_1_ADD1
   7 U271_1_ADD0     A0 @S9S_MB_2U_LIB.S9S_MB_2U(SCH_1):U271_1_ADD0
   8 P3V3_AUX    VCC @S9S_MB_2U_LIB.S9S_MB_2U(SCH_1):P3V3_AUX

LM75BD-LM75BD,SMLF,IC,AL0075BDA  I166  U272
   1 SMB_LM75_2_3V3AUX_SDA_R1    SDA @S9S_MB_2U_LIB.S9S_MB_2U(SCH_1):SMB_LM75_2_3V3AUX_SDA_R1
   2 SMB_LM75_2_3V3AUX_SCL_R1    SCL @S9S_MB_2U_LIB.S9S_MB_2U(SCH_1):SMB_LM75_2_3V3AUX_SCL_R1
   3 FM_LM75_2_ALERT_N     OS @S9S_MB_2U_LIB.S9S_MB_2U(SCH_1):FM_LM75_2_ALERT_N
   4    GND    GND @S9S_MB_2U_LIB.S9S_MB_2U(SCH_1):GND
   5 U272_2_ADD2     A2 @S9S_MB_2U_LIB.S9S_MB_2U(SCH_1):U272_2_ADD2
   6 U272_2_ADD1     A1 @S9S_MB_2U_LIB.S9S_MB_2U(SCH_1):U272_2_ADD1
   7 U272_2_ADD0     A0 @S9S_MB_2U_LIB.S9S_MB_2U(SCH_1):U272_2_ADD0
   8 P3V3_AUX    VCC @S9S_MB_2U_LIB.S9S_MB_2U(SCH_1):P3V3_AUX

LM75BD-LM75BD,SMLF,IC,AL0075BDA  I167  U273
   1 SMB_LM75_3_3V3AUX_SDA_R1    SDA @S9S_MB_2U_LIB.S9S_MB_2U(SCH_1):SMB_LM75_3_3V3AUX_SDA_R1
   2 SMB_LM75_3_3V3AUX_SCL_R1    SCL @S9S_MB_2U_LIB.S9S_MB_2U(SCH_1):SMB_LM75_3_3V3AUX_SCL_R1
   3 FM_LM75_3_ALERT_N     OS @S9S_MB_2U_LIB.S9S_MB_2U(SCH_1):FM_LM75_3_ALERT_N
   4    GND    GND @S9S_MB_2U_LIB.S9S_MB_2U(SCH_1):GND
   5 U273_3_ADD2     A2 @S9S_MB_2U_LIB.S9S_MB_2U(SCH_1):U273_3_ADD2
   6 U273_3_ADD1     A1 @S9S_MB_2U_LIB.S9S_MB_2U(SCH_1):U273_3_ADD1
   7 U273_3_ADD0     A0 @S9S_MB_2U_LIB.S9S_MB_2U(SCH_1):U273_3_ADD0
   8 P3V3_AUX    VCC @S9S_MB_2U_LIB.S9S_MB_2U(SCH_1):P3V3_AUX

Q_RES_0402LF-200K,1%,1/16W,CHIA  I168  R4211
   1 P3V3_AUX      A @S9S_MB_2U_LIB.S9S_MB_2U(SCH_1):P3V3_AUX
   2 FM_THERMAL_ALERT_N      B @S9S_MB_2U_LIB.S9S_MB_2U(SCH_1):FM_THERMAL_ALERT_N

Q_RES_0402LF-200K,1%,1/16W,EMPA  I169  R4209
   1 P3V3_AUX      A @S9S_MB_2U_LIB.S9S_MB_2U(SCH_1):P3V3_AUX
   2 FM_THERMAL_ALERT_N      B @S9S_MB_2U_LIB.S9S_MB_2U(SCH_1):FM_THERMAL_ALERT_N

Q_RES_0402LF-200K,1%,1/16W,EMPA  I170  R4210
   1 P3V3_AUX      A @S9S_MB_2U_LIB.S9S_MB_2U(SCH_1):P3V3_AUX
   2 FM_THERMAL_ALERT_N      B @S9S_MB_2U_LIB.S9S_MB_2U(SCH_1):FM_THERMAL_ALERT_N

Q_RES_0402LF-200K,1%,1/16W,EMPA  I171  R4208
   1 P3V3_AUX      A @S9S_MB_2U_LIB.S9S_MB_2U(SCH_1):P3V3_AUX
   2 FM_THERMAL_ALERT_N      B @S9S_MB_2U_LIB.S9S_MB_2U(SCH_1):FM_THERMAL_ALERT_N


DRAWING: @S9S_MB_2U_LIB.S9S_MB_2U(SCH_1):PAGE221 

Q_RES_0402LF-1K,1%,1/16W,CHIP,A  I2  R3704
   1 PCA9548_PCIE0_ADDR2      A @S9S_MB_2U_LIB.S9S_MB_2U(SCH_1):PCA9548_PCIE0_ADDR2
   2    GND      B @S9S_MB_2U_LIB.S9S_MB_2U(SCH_1):GND

Q_RES_0402LF-10K,1%,1/16W,EMPTA  I3  R3703
   1 P3V3_AUX      A @S9S_MB_2U_LIB.S9S_MB_2U(SCH_1):P3V3_AUX
   2 PCA9548_PCIE0_ADDR2      B @S9S_MB_2U_LIB.S9S_MB_2U(SCH_1):PCA9548_PCIE0_ADDR2

Q_RES_0402LF-1K,1%,1/16W,CHIP,A  I6  R3707
   1 PCA9548_PCIE0_ADDR1      A @S9S_MB_2U_LIB.S9S_MB_2U(SCH_1):PCA9548_PCIE0_ADDR1
   2    GND      B @S9S_MB_2U_LIB.S9S_MB_2U(SCH_1):GND

Q_RES_0402LF-1K,1%,1/16W,CHIP,A  I8  R3709
   1 PCA9548_PCIE0_ADDR0      A @S9S_MB_2U_LIB.S9S_MB_2U(SCH_1):PCA9548_PCIE0_ADDR0
   2    GND      B @S9S_MB_2U_LIB.S9S_MB_2U(SCH_1):GND

Q_RES_0402LF-10K,1%,1/16W,EMPTA  I9  R3706
   1 P3V3_AUX      A @S9S_MB_2U_LIB.S9S_MB_2U(SCH_1):P3V3_AUX
   2 PCA9548_PCIE0_ADDR1      B @S9S_MB_2U_LIB.S9S_MB_2U(SCH_1):PCA9548_PCIE0_ADDR1

Q_RES_0402LF-10K,1%,1/16W,EMPTA  I10  R3708
   1 P3V3_AUX      A @S9S_MB_2U_LIB.S9S_MB_2U(SCH_1):P3V3_AUX
   2 PCA9548_PCIE0_ADDR0      B @S9S_MB_2U_LIB.S9S_MB_2U(SCH_1):PCA9548_PCIE0_ADDR0

Q_RES_0402LF-2.2K,5%,1/16W,CHIA  I34  R3732
   1 P3V3_AUX      A @S9S_MB_2U_LIB.S9S_MB_2U(SCH_1):P3V3_AUX
   2 SMB_LM75_3_3V3AUX_SDA      B @S9S_MB_2U_LIB.S9S_MB_2U(SCH_1):SMB_LM75_3_3V3AUX_SDA

Q_RES_0402LF-2.2K,5%,1/16W,CHIA  I48  R3729
   1 P3V3_AUX      A @S9S_MB_2U_LIB.S9S_MB_2U(SCH_1):P3V3_AUX
   2 SMB_LM75_2_3V3AUX_SCL      B @S9S_MB_2U_LIB.S9S_MB_2U(SCH_1):SMB_LM75_2_3V3AUX_SCL

Q_RES_0402LF-2.2K,5%,1/16W,CHIA  I49  R3730
   1 P3V3_AUX      A @S9S_MB_2U_LIB.S9S_MB_2U(SCH_1):P3V3_AUX
   2 SMB_LM75_2_3V3AUX_SDA      B @S9S_MB_2U_LIB.S9S_MB_2U(SCH_1):SMB_LM75_2_3V3AUX_SDA

Q_RES_0402LF-2.2K,5%,1/16W,CHIA  I50  R3728
   1 P3V3_AUX      A @S9S_MB_2U_LIB.S9S_MB_2U(SCH_1):P3V3_AUX
   2 SMB_LM75_1_3V3AUX_SDA      B @S9S_MB_2U_LIB.S9S_MB_2U(SCH_1):SMB_LM75_1_3V3AUX_SDA

Q_RES_0402LF-2.2K,5%,1/16W,CHIA  I51  R3727
   1 P3V3_AUX      A @S9S_MB_2U_LIB.S9S_MB_2U(SCH_1):P3V3_AUX
   2 SMB_LM75_1_3V3AUX_SCL      B @S9S_MB_2U_LIB.S9S_MB_2U(SCH_1):SMB_LM75_1_3V3AUX_SCL

Q_RES_0402LF-2.2K,5%,1/16W,CHIA  I52  R3726
   1 P3V3_AUX      A @S9S_MB_2U_LIB.S9S_MB_2U(SCH_1):P3V3_AUX
   2 SMB_LM75_0_3V3AUX_SDA      B @S9S_MB_2U_LIB.S9S_MB_2U(SCH_1):SMB_LM75_0_3V3AUX_SDA

Q_RES_0402LF-2.2K,5%,1/16W,CHIA  I53  R3725
   1 P3V3_AUX      A @S9S_MB_2U_LIB.S9S_MB_2U(SCH_1):P3V3_AUX
   2 SMB_LM75_0_3V3AUX_SCL      B @S9S_MB_2U_LIB.S9S_MB_2U(SCH_1):SMB_LM75_0_3V3AUX_SCL

Q_RES_0402LF-2.2K,5%,1/16W,CHIA  I55  R3723
   1 P3V3_AUX      A @S9S_MB_2U_LIB.S9S_MB_2U(SCH_1):P3V3_AUX
   2 SMB_VR_3V3AUX_SCL      B @S9S_MB_2U_LIB.S9S_MB_2U(SCH_1):SMB_VR_3V3AUX_SCL

Q_RES_0402LF-2.2K,5%,1/16W,CHIA  I56  R3724
   1 P3V3_AUX      A @S9S_MB_2U_LIB.S9S_MB_2U(SCH_1):P3V3_AUX
   2 SMB_VR_3V3AUX_SDA      B @S9S_MB_2U_LIB.S9S_MB_2U(SCH_1):SMB_VR_3V3AUX_SDA

Q_RES_0402LF-2.2K,5%,1/16W,CHIA  I98  R3731
   1 P3V3_AUX      A @S9S_MB_2U_LIB.S9S_MB_2U(SCH_1):P3V3_AUX
   2 SMB_LM75_3_3V3AUX_SCL      B @S9S_MB_2U_LIB.S9S_MB_2U(SCH_1):SMB_LM75_3_3V3AUX_SCL

Q_RES_0402LF-2.2K,5%,1/16W,EMPA  I99  R4270
   1 P3V3_AUX      A @S9S_MB_2U_LIB.S9S_MB_2U(SCH_1):P3V3_AUX
   2 SMB_VR_SENSOR_3V3AUX_SDA      B @S9S_MB_2U_LIB.S9S_MB_2U(SCH_1):SMB_VR_SENSOR_3V3AUX_SDA

Q_RES_0402LF-2.2K,5%,1/16W,EMPA  I102  R4269
   1 P3V3_AUX      A @S9S_MB_2U_LIB.S9S_MB_2U(SCH_1):P3V3_AUX
   2 SMB_VR_SENSOR_3V3AUX_SCL      B @S9S_MB_2U_LIB.S9S_MB_2U(SCH_1):SMB_VR_SENSOR_3V3AUX_SCL

TCA9548APWR-TCA9548APWR,SMLF,IA  I103  U39
   1 PCA9548_PCIE0_ADDR0     A0 @S9S_MB_2U_LIB.S9S_MB_2U(SCH_1):PCA9548_PCIE0_ADDR0
   2 PCA9548_PCIE0_ADDR1     A1 @S9S_MB_2U_LIB.S9S_MB_2U(SCH_1):PCA9548_PCIE0_ADDR1
   3 PU_RST_SMB_PCIE2_N RESET# @S9S_MB_2U_LIB.S9S_MB_2U(SCH_1):PU_RST_SMB_PCIE2_N
   4 SMB_VR_3V3AUX_SDA_R6    SD0 @S9S_MB_2U_LIB.S9S_MB_2U(SCH_1):SMB_VR_3V3AUX_SDA_R6
   5 SMB_VR_3V3AUX_SCL_R6    SC0 @S9S_MB_2U_LIB.S9S_MB_2U(SCH_1):SMB_VR_3V3AUX_SCL_R6
   6 SMB_LM75_0_3V3AUX_SDA_R    SD1 @S9S_MB_2U_LIB.S9S_MB_2U(SCH_1):SMB_LM75_0_3V3AUX_SDA_R
   7 SMB_LM75_0_3V3AUX_SCL_R    SC1 @S9S_MB_2U_LIB.S9S_MB_2U(SCH_1):SMB_LM75_0_3V3AUX_SCL_R
   8 SMB_LM75_1_3V3AUX_SDA_R    SD2 @S9S_MB_2U_LIB.S9S_MB_2U(SCH_1):SMB_LM75_1_3V3AUX_SDA_R
   9 SMB_LM75_1_3V3AUX_SCL_R    SC2 @S9S_MB_2U_LIB.S9S_MB_2U(SCH_1):SMB_LM75_1_3V3AUX_SCL_R
  10 SMB_LM75_2_3V3AUX_SDA_R    SD3 @S9S_MB_2U_LIB.S9S_MB_2U(SCH_1):SMB_LM75_2_3V3AUX_SDA_R
  11 SMB_LM75_2_3V3AUX_SCL_R    SC3 @S9S_MB_2U_LIB.S9S_MB_2U(SCH_1):SMB_LM75_2_3V3AUX_SCL_R
  12    GND    GND @S9S_MB_2U_LIB.S9S_MB_2U(SCH_1):GND
  24 P3V3_AUX    VCC @S9S_MB_2U_LIB.S9S_MB_2U(SCH_1):P3V3_AUX
  23 SMB_VR_SENSOR_3V3AUX_SDA_R    SDA @S9S_MB_2U_LIB.S9S_MB_2U(SCH_1):SMB_VR_SENSOR_3V3AUX_SDA_R
  22 SMB_VR_SENSOR_3V3AUX_SCL_R    SCL @S9S_MB_2U_LIB.S9S_MB_2U(SCH_1):SMB_VR_SENSOR_3V3AUX_SCL_R
  21 PCA9548_PCIE0_ADDR2     A2 @S9S_MB_2U_LIB.S9S_MB_2U(SCH_1):PCA9548_PCIE0_ADDR2
  20     NC    SC7     NC
  19     NC    SD7     NC
  18     NC    SC6     NC
  17     NC    SD6     NC
  16     NC    SC5     NC
  15     NC    SD5     NC
  14 SMB_LM75_3_3V3AUX_SCL_R    SC4 @S9S_MB_2U_LIB.S9S_MB_2U(SCH_1):SMB_LM75_3_3V3AUX_SCL_R
  13 SMB_LM75_3_3V3AUX_SDA_R    SD4 @S9S_MB_2U_LIB.S9S_MB_2U(SCH_1):SMB_LM75_3_3V3AUX_SDA_R

Q_CAP_0402-0.1UF,25V,10%,X7R,CA  I106  C2056
   1 P3V3_AUX      A @S9S_MB_2U_LIB.S9S_MB_2U(SCH_1):P3V3_AUX
   2    GND      B @S9S_MB_2U_LIB.S9S_MB_2U(SCH_1):GND

Q_RES_0402LF-33.2,1%,1/16W,CHIA  I115  R3712
   1 SMB_VR_SENSOR_3V3AUX_SDA      A @S9S_MB_2U_LIB.S9S_MB_2U(SCH_1):SMB_VR_SENSOR_3V3AUX_SDA
   2 SMB_VR_SENSOR_3V3AUX_SDA_R      B @S9S_MB_2U_LIB.S9S_MB_2U(SCH_1):SMB_VR_SENSOR_3V3AUX_SDA_R

Q_RES_0402LF-33.2,1%,1/16W,CHIA  I116  R3711
   1 SMB_VR_SENSOR_3V3AUX_SCL      A @S9S_MB_2U_LIB.S9S_MB_2U(SCH_1):SMB_VR_SENSOR_3V3AUX_SCL
   2 SMB_VR_SENSOR_3V3AUX_SCL_R      B @S9S_MB_2U_LIB.S9S_MB_2U(SCH_1):SMB_VR_SENSOR_3V3AUX_SCL_R

Q_RES_0402LF-0,5%,1/16W,CHIP,CA  I119  R3722
   1 SMB_LM75_3_3V3AUX_SDA_R      A @S9S_MB_2U_LIB.S9S_MB_2U(SCH_1):SMB_LM75_3_3V3AUX_SDA_R
   2 SMB_LM75_3_3V3AUX_SDA      B @S9S_MB_2U_LIB.S9S_MB_2U(SCH_1):SMB_LM75_3_3V3AUX_SDA

Q_RES_0402LF-0,5%,1/16W,CHIP,CA  I120  R3721
   1 SMB_LM75_3_3V3AUX_SCL_R      A @S9S_MB_2U_LIB.S9S_MB_2U(SCH_1):SMB_LM75_3_3V3AUX_SCL_R
   2 SMB_LM75_3_3V3AUX_SCL      B @S9S_MB_2U_LIB.S9S_MB_2U(SCH_1):SMB_LM75_3_3V3AUX_SCL

Q_RES_0402LF-0,5%,1/16W,CHIP,CA  I137  R3713
   1 SMB_VR_3V3AUX_SCL_R6      A @S9S_MB_2U_LIB.S9S_MB_2U(SCH_1):SMB_VR_3V3AUX_SCL_R6
   2 SMB_VR_3V3AUX_SCL      B @S9S_MB_2U_LIB.S9S_MB_2U(SCH_1):SMB_VR_3V3AUX_SCL

Q_RES_0402LF-0,5%,1/16W,CHIP,CA  I138  R3714
   1 SMB_VR_3V3AUX_SDA_R6      A @S9S_MB_2U_LIB.S9S_MB_2U(SCH_1):SMB_VR_3V3AUX_SDA_R6
   2 SMB_VR_3V3AUX_SDA      B @S9S_MB_2U_LIB.S9S_MB_2U(SCH_1):SMB_VR_3V3AUX_SDA

Q_RES_0402LF-0,5%,1/16W,CHIP,CA  I139  R3715
   1 SMB_LM75_0_3V3AUX_SCL_R      A @S9S_MB_2U_LIB.S9S_MB_2U(SCH_1):SMB_LM75_0_3V3AUX_SCL_R
   2 SMB_LM75_0_3V3AUX_SCL      B @S9S_MB_2U_LIB.S9S_MB_2U(SCH_1):SMB_LM75_0_3V3AUX_SCL

Q_RES_0402LF-0,5%,1/16W,CHIP,CA  I140  R3716
   1 SMB_LM75_0_3V3AUX_SDA_R      A @S9S_MB_2U_LIB.S9S_MB_2U(SCH_1):SMB_LM75_0_3V3AUX_SDA_R
   2 SMB_LM75_0_3V3AUX_SDA      B @S9S_MB_2U_LIB.S9S_MB_2U(SCH_1):SMB_LM75_0_3V3AUX_SDA

Q_RES_0402LF-0,5%,1/16W,CHIP,CA  I141  R3717
   1 SMB_LM75_1_3V3AUX_SCL_R      A @S9S_MB_2U_LIB.S9S_MB_2U(SCH_1):SMB_LM75_1_3V3AUX_SCL_R
   2 SMB_LM75_1_3V3AUX_SCL      B @S9S_MB_2U_LIB.S9S_MB_2U(SCH_1):SMB_LM75_1_3V3AUX_SCL

Q_RES_0402LF-0,5%,1/16W,CHIP,CA  I142  R3718
   1 SMB_LM75_1_3V3AUX_SDA_R      A @S9S_MB_2U_LIB.S9S_MB_2U(SCH_1):SMB_LM75_1_3V3AUX_SDA_R
   2 SMB_LM75_1_3V3AUX_SDA      B @S9S_MB_2U_LIB.S9S_MB_2U(SCH_1):SMB_LM75_1_3V3AUX_SDA

Q_RES_0402LF-0,5%,1/16W,CHIP,CA  I143  R3719
   1 SMB_LM75_2_3V3AUX_SCL_R      A @S9S_MB_2U_LIB.S9S_MB_2U(SCH_1):SMB_LM75_2_3V3AUX_SCL_R
   2 SMB_LM75_2_3V3AUX_SCL      B @S9S_MB_2U_LIB.S9S_MB_2U(SCH_1):SMB_LM75_2_3V3AUX_SCL

Q_RES_0402LF-0,5%,1/16W,CHIP,CA  I144  R3720
   1 SMB_LM75_2_3V3AUX_SDA_R      A @S9S_MB_2U_LIB.S9S_MB_2U(SCH_1):SMB_LM75_2_3V3AUX_SDA_R
   2 SMB_LM75_2_3V3AUX_SDA      B @S9S_MB_2U_LIB.S9S_MB_2U(SCH_1):SMB_LM75_2_3V3AUX_SDA

Q_RES_0402LF-0,5%,1/16W,CHIP,CA  I145  R3710
   1 RST_SMB_SWITCH_N      A @S9S_MB_2U_LIB.S9S_MB_2U(SCH_1):RST_SMB_SWITCH_N
   2 PU_RST_SMB_PCIE2_N      B @S9S_MB_2U_LIB.S9S_MB_2U(SCH_1):PU_RST_SMB_PCIE2_N

Q_RES_0402LF-10K,1%,1/16W,EMPTA  I147  R3705
   1 P3V3_AUX      A @S9S_MB_2U_LIB.S9S_MB_2U(SCH_1):P3V3_AUX
   2 RST_SMB_SWITCH_N      B @S9S_MB_2U_LIB.S9S_MB_2U(SCH_1):RST_SMB_SWITCH_N


DRAWING: @S9S_MB_2U_LIB.S9S_MB_2U(SCH_1):PAGE297 

Q_RES_0402LF-0,5%,1/16W,CHIP,CA  I157  R2350
   1 FM_PS_EN_PLD_BUF1      A @S9S_MB_2U_LIB.S9S_MB_2U(SCH_1):FM_PS_EN_PLD_BUF1
   2 FM_PS_EN_PLD_BUF1_R1      B @S9S_MB_2U_LIB.S9S_MB_2U(SCH_1):FM_PS_EN_PLD_BUF1_R1

Q_RES_0402LF-10K,1%,1/16W,CHIPA  I159  R2304
   1 P3V3_AUX      A @S9S_MB_2U_LIB.S9S_MB_2U(SCH_1):P3V3_AUX
   2 E1S_0_PRSNT_N      B @S9S_MB_2U_LIB.S9S_MB_2U(SCH_1):E1S_0_PRSNT_N

74LVC1G126SE7-74LVC1G126SE-7,SA  I163  U145
   2 E1S_0_PRSNT      A @S9S_MB_2U_LIB.S9S_MB_2U(SCH_1):E1S_0_PRSNT
   4 E1S_0_EN      Y @S9S_MB_2U_LIB.S9S_MB_2U(SCH_1):E1S_0_EN
   5 P3V3_AUX    VCC @S9S_MB_2U_LIB.S9S_MB_2U(SCH_1):P3V3_AUX
   3    GND    GND @S9S_MB_2U_LIB.S9S_MB_2U(SCH_1):GND
   1 FM_PS_EN_PLD_BUF1_R1     OE @S9S_MB_2U_LIB.S9S_MB_2U(SCH_1):FM_PS_EN_PLD_BUF1_R1

Q_RES_0402LF-100K,1%,1/16W,CHIA  I165  R2457
   1 E1S_0_EN      A @S9S_MB_2U_LIB.S9S_MB_2U(SCH_1):E1S_0_EN
   2    GND      B @S9S_MB_2U_LIB.S9S_MB_2U(SCH_1):GND

Q_RES_0402LF-10K,1%,1/16W,CHIPA  I169  R2282
   1 P3V3_AUX      A @S9S_MB_2U_LIB.S9S_MB_2U(SCH_1):P3V3_AUX
   2 E1S_0_PRSNT      B @S9S_MB_2U_LIB.S9S_MB_2U(SCH_1):E1S_0_PRSNT

Q_CAP_0402-0.1UF,25V,10%,X7R,CA  I170  C1614
   1 P3V3_AUX      A @S9S_MB_2U_LIB.S9S_MB_2U(SCH_1):P3V3_AUX
   2    GND      B @S9S_MB_2U_LIB.S9S_MB_2U(SCH_1):GND

Q_CAP_C0805-22UF,16V,20%,X6S,CA  I237  C1277
   1 P12V_E1S_0      A @S9S_MB_2U_LIB.S9S_MB_2U(SCH_1):P12V_E1S_0
   2    GND      B @S9S_MB_2U_LIB.S9S_MB_2U(SCH_1):GND

Q_CAP_0402-0.1UF,25V,10%,X7R,CA  I245  C1283
   1 P3V3_E1S_0      A @S9S_MB_2U_LIB.S9S_MB_2U(SCH_1):P3V3_E1S_0
   2    GND      B @S9S_MB_2U_LIB.S9S_MB_2U(SCH_1):GND

Q_CAP_0402-0.1UF,25V,10%,X7R,CA  I247  C1282
   1 P3V3_E1S_0      A @S9S_MB_2U_LIB.S9S_MB_2U(SCH_1):P3V3_E1S_0
   2    GND      B @S9S_MB_2U_LIB.S9S_MB_2U(SCH_1):GND

Q_CAP_0402-0.1UF,25V,10%,X7R,CA  I252  C1279
   1 P12V_E1S_0      A @S9S_MB_2U_LIB.S9S_MB_2U(SCH_1):P12V_E1S_0
   2    GND      B @S9S_MB_2U_LIB.S9S_MB_2U(SCH_1):GND

Q_CAP_0402-0.1UF,25V,10%,X7R,CA  I258  C1278
   1 P12V_E1S_0      A @S9S_MB_2U_LIB.S9S_MB_2U(SCH_1):P12V_E1S_0
   2    GND      B @S9S_MB_2U_LIB.S9S_MB_2U(SCH_1):GND

Q_CAP_C0805-22UF,16V,20%,X6S,CA  I260  C1276
   1 P12V_E1S_0      A @S9S_MB_2U_LIB.S9S_MB_2U(SCH_1):P12V_E1S_0
   2    GND      B @S9S_MB_2U_LIB.S9S_MB_2U(SCH_1):GND

Q_RES_0402LF-10K,1%,1/16W,CHIPA  I264  R2317
   1 P3V3_E1S_0      A @S9S_MB_2U_LIB.S9S_MB_2U(SCH_1):P3V3_E1S_0
   2 PU_E1S_0_DUALPORT_EN_N      B @S9S_MB_2U_LIB.S9S_MB_2U(SCH_1):PU_E1S_0_DUALPORT_EN_N

Q_RES_0402LF-10K,1%,1/16W,CHIPA  I291  R3771
   1 P3V3_AUX      A @S9S_MB_2U_LIB.S9S_MB_2U(SCH_1):P3V3_AUX
   2 E1S_0_PWRDIS      B @S9S_MB_2U_LIB.S9S_MB_2U(SCH_1):E1S_0_PWRDIS

Q_RES_0402LF-1K,1%,1/16W,CHIP,A  I293  R2296
   1 E1S_0_PWRDIS      A @S9S_MB_2U_LIB.S9S_MB_2U(SCH_1):E1S_0_PWRDIS
   2    GND      B @S9S_MB_2U_LIB.S9S_MB_2U(SCH_1):GND

Q_RES_0402LF-4.7K,5%,1/16W,CHIA  I296  R2125
   1 P3V3_AUX      A @S9S_MB_2U_LIB.S9S_MB_2U(SCH_1):P3V3_AUX
   2 SMB_PCIE_E1S_ISO_EN      B @S9S_MB_2U_LIB.S9S_MB_2U(SCH_1):SMB_PCIE_E1S_ISO_EN

Q_RES_0402LF-4.7K,5%,1/16W,EMPA  I299  R3773
   1 P3V3_AUX      A @S9S_MB_2U_LIB.S9S_MB_2U(SCH_1):P3V3_AUX
   2 RST_SMB_E1S_0_N      B @S9S_MB_2U_LIB.S9S_MB_2U(SCH_1):RST_SMB_E1S_0_N

Q_RES_0402LF-0,5%,1/16W,CHIP,CA  I301  R3772
   1 RST_SMB_BUF_E1S_0_N      A @S9S_MB_2U_LIB.S9S_MB_2U(SCH_1):RST_SMB_BUF_E1S_0_N
   2 RST_SMB_E1S_0_N      B @S9S_MB_2U_LIB.S9S_MB_2U(SCH_1):RST_SMB_E1S_0_N

Q_RES_0402LF-0,5%,1/16W,CHIP,CA  I302  R2114
   1 SMB_PCIE_E1S_ISO_EN_R2      A @S9S_MB_2U_LIB.S9S_MB_2U(SCH_1):SMB_PCIE_E1S_ISO_EN_R2
   2 SMB_PCIE_E1S_ISO_EN      B @S9S_MB_2U_LIB.S9S_MB_2U(SCH_1):SMB_PCIE_E1S_ISO_EN

Q_CAP_0402-0.1UF,25V,10%,X7R,CA  I304  C1592
   1 P3V3_AUX      A @S9S_MB_2U_LIB.S9S_MB_2U(SCH_1):P3V3_AUX
   2    GND      B @S9S_MB_2U_LIB.S9S_MB_2U(SCH_1):GND

74LVC2G07DW7-74LVC2G07DW-7,SMLA  I305  U134
   1 RST_SMB_E1S_N     1A @S9S_MB_2U_LIB.S9S_MB_2U(SCH_1):RST_SMB_E1S_N
   3 RST_SMB_E1S_N     2A @S9S_MB_2U_LIB.S9S_MB_2U(SCH_1):RST_SMB_E1S_N
   6 RST_SMB_BUF_E1S_0_N     1Y @S9S_MB_2U_LIB.S9S_MB_2U(SCH_1):RST_SMB_BUF_E1S_0_N
   4 SMB_PCIE_E1S_ISO_EN_R2     2Y @S9S_MB_2U_LIB.S9S_MB_2U(SCH_1):SMB_PCIE_E1S_ISO_EN_R2
   2    GND    GND @S9S_MB_2U_LIB.S9S_MB_2U(SCH_1):GND
   5 P3V3_AUX    VCC @S9S_MB_2U_LIB.S9S_MB_2U(SCH_1):P3V3_AUX

Q_RES_0402LF-0,5%,1/16W,CHIP,CA  I307  R3775
   1 RST_SMB_SWITCH_N      A @S9S_MB_2U_LIB.S9S_MB_2U(SCH_1):RST_SMB_SWITCH_N
   2 RST_SMB_E1S_N      B @S9S_MB_2U_LIB.S9S_MB_2U(SCH_1):RST_SMB_E1S_N

Q_RES_0402LF-0,5%,1/16W,CHIP,CA  I309  R3779
   1 RST_PCIE_PCH_DEV_PERST_E1S_R_N      A @S9S_MB_2U_LIB.S9S_MB_2U(SCH_1):RST_PCIE_PCH_DEV_PERST_E1S_R_N
   2 RST_PCIE_PCH_E1S_PERST_N      B @S9S_MB_2U_LIB.S9S_MB_2U(SCH_1):RST_PCIE_PCH_E1S_PERST_N

Q_RES_0402LF-100,1%,1/16W,EMPTA  I311  R2426
   1 E1S_0_PERST1_CLKREQ_N      A @S9S_MB_2U_LIB.S9S_MB_2U(SCH_1):E1S_0_PERST1_CLKREQ_N
   2    GND      B @S9S_MB_2U_LIB.S9S_MB_2U(SCH_1):GND

Q_RES_0402LF-10K,1%,1/16W,CHIPA  I312  R1673
   1 P3V3_E1S_0      A @S9S_MB_2U_LIB.S9S_MB_2U(SCH_1):P3V3_E1S_0
   2 RST_SMB_E1S_0_N      B @S9S_MB_2U_LIB.S9S_MB_2U(SCH_1):RST_SMB_E1S_0_N

Q_RES_0402LF-10K,1%,1/16W,CHIPA  I313  R2287
   1 P3V3_E1S_0      A @S9S_MB_2U_LIB.S9S_MB_2U(SCH_1):P3V3_E1S_0
   2 E1S_0_PERST1_CLKREQ_N      B @S9S_MB_2U_LIB.S9S_MB_2U(SCH_1):E1S_0_PERST1_CLKREQ_N

MOSFET_NCH_GDS_ESD_PROTECTED-2A  I316  Q46
   D E1S_0_PRSNT      D @S9S_MB_2U_LIB.S9S_MB_2U(SCH_1):E1S_0_PRSNT
   G E1S_0_PRSNT_N      G @S9S_MB_2U_LIB.S9S_MB_2U(SCH_1):E1S_0_PRSNT_N
   S    GND      S @S9S_MB_2U_LIB.S9S_MB_2U(SCH_1):GND

SCONN56_123276793-SCONN56_1-23A  I318  J90
  B1 P12V_E1S_0 P12V_B1 @S9S_MB_2U_LIB.S9S_MB_2U(SCH_1):P12V_E1S_0
  B2 P12V_E1S_0 P12V_B2 @S9S_MB_2U_LIB.S9S_MB_2U(SCH_1):P12V_E1S_0
  B3 P12V_E1S_0 P12V_B3 @S9S_MB_2U_LIB.S9S_MB_2U(SCH_1):P12V_E1S_0
  B4 P12V_E1S_0 P12V_B4 @S9S_MB_2U_LIB.S9S_MB_2U(SCH_1):P12V_E1S_0
  B5 P12V_E1S_0 P12V_B5 @S9S_MB_2U_LIB.S9S_MB_2U(SCH_1):P12V_E1S_0
  B6 P12V_E1S_0 P12V_B6 @S9S_MB_2U_LIB.S9S_MB_2U(SCH_1):P12V_E1S_0
  A1    GND GND_A1 @S9S_MB_2U_LIB.S9S_MB_2U(SCH_1):GND
  A2    GND GND_A2 @S9S_MB_2U_LIB.S9S_MB_2U(SCH_1):GND
  A3    GND GND_A3 @S9S_MB_2U_LIB.S9S_MB_2U(SCH_1):GND
  A4    GND GND_A4 @S9S_MB_2U_LIB.S9S_MB_2U(SCH_1):GND
  A5    GND GND_A5 @S9S_MB_2U_LIB.S9S_MB_2U(SCH_1):GND
  A6    GND GND_A6 @S9S_MB_2U_LIB.S9S_MB_2U(SCH_1):GND
  B7 TP_E1S_0_MFG    MFG @S9S_MB_2U_LIB.S9S_MB_2U(SCH_1):TP_E1S_0_MFG
  B8 TP_E1S_0_RFU    RFU @S9S_MB_2U_LIB.S9S_MB_2U(SCH_1):TP_E1S_0_RFU
  B9 PU_E1S_0_DUALPORT_EN_N DUALPORTEN# @S9S_MB_2U_LIB.S9S_MB_2U(SCH_1):PU_E1S_0_DUALPORT_EN_N
 B11 P3V3_E1S_0 P3V3_AUX @S9S_MB_2U_LIB.S9S_MB_2U(SCH_1):P3V3_E1S_0
 B12 E1S_0_PWRDIS PWRDIS @S9S_MB_2U_LIB.S9S_MB_2U(SCH_1):E1S_0_PWRDIS
 B13    GND GND_B13 @S9S_MB_2U_LIB.S9S_MB_2U(SCH_1):GND
 B16    GND GND_B16 @S9S_MB_2U_LIB.S9S_MB_2U(SCH_1):GND
 B19    GND GND_B19 @S9S_MB_2U_LIB.S9S_MB_2U(SCH_1):GND
 B22    GND GND_B22 @S9S_MB_2U_LIB.S9S_MB_2U(SCH_1):GND
 B25    GND GND_B25 @S9S_MB_2U_LIB.S9S_MB_2U(SCH_1):GND
 B28    GND GND_B28 @S9S_MB_2U_LIB.S9S_MB_2U(SCH_1):GND
 B14 CLK_100M_E1S_0_DN REFCLK_N0 @S9S_MB_2U_LIB.S9S_MB_2U(SCH_1):CLK_100M_E1S_0_DN
 B15 CLK_100M_E1S_0_DP REFCLK_P0 @S9S_MB_2U_LIB.S9S_MB_2U(SCH_1):CLK_100M_E1S_0_DP
 B17 P3E_PCH_E1S_TX_C_DP<0> PET_N0 @S9S_MB_2U_LIB.S9S_MB_2U(SCH_1):P3E_PCH_E1S_TX_C_DP(0)
 B18 P3E_PCH_E1S_TX_C_DN<0> PET_P0 @S9S_MB_2U_LIB.S9S_MB_2U(SCH_1):P3E_PCH_E1S_TX_C_DN(0)
 B20 P3E_PCH_E1S_TX_C_DP<1> PET_N1 @S9S_MB_2U_LIB.S9S_MB_2U(SCH_1):P3E_PCH_E1S_TX_C_DP(1)
 B21 P3E_PCH_E1S_TX_C_DN<1> PET_P1 @S9S_MB_2U_LIB.S9S_MB_2U(SCH_1):P3E_PCH_E1S_TX_C_DN(1)
 B23 P3E_PCH_E1S_TX_C_DN<2> PET_N2 @S9S_MB_2U_LIB.S9S_MB_2U(SCH_1):P3E_PCH_E1S_TX_C_DN(2)
 B24 P3E_PCH_E1S_TX_C_DP<2> PET_P2 @S9S_MB_2U_LIB.S9S_MB_2U(SCH_1):P3E_PCH_E1S_TX_C_DP(2)
 B26 P3E_PCH_E1S_TX_C_DN<3> PET_N3 @S9S_MB_2U_LIB.S9S_MB_2U(SCH_1):P3E_PCH_E1S_TX_C_DN(3)
 B27 P3E_PCH_E1S_TX_C_DP<3> PET_P3 @S9S_MB_2U_LIB.S9S_MB_2U(SCH_1):P3E_PCH_E1S_TX_C_DP(3)
  A7 SMB_E1S_3V3AUX_ISO_SCL SMBCLK @S9S_MB_2U_LIB.S9S_MB_2U(SCH_1):SMB_E1S_3V3AUX_ISO_SCL
  A8 SMB_E1S_3V3AUX_ISO_SDA SMBDAT @S9S_MB_2U_LIB.S9S_MB_2U(SCH_1):SMB_E1S_3V3AUX_ISO_SDA
  A9 RST_SMB_E1S_0_N SMBRST# @S9S_MB_2U_LIB.S9S_MB_2U(SCH_1):RST_SMB_E1S_0_N
 A10 E1S_0_LED_ACT_N LED#_ACTIVITY @S9S_MB_2U_LIB.S9S_MB_2U(SCH_1):E1S_0_LED_ACT_N
 B10 RST_PCIE_PCH_E1S_PERST_N PERST0# @S9S_MB_2U_LIB.S9S_MB_2U(SCH_1):RST_PCIE_PCH_E1S_PERST_N
 A11 E1S_0_PERST1_CLKREQ_N PERST1#_CLKREQ# @S9S_MB_2U_LIB.S9S_MB_2U(SCH_1):E1S_0_PERST1_CLKREQ_N
 A12 E1S_0_PRSNT_N PRSNT0# @S9S_MB_2U_LIB.S9S_MB_2U(SCH_1):E1S_0_PRSNT_N
 A13    GND GND_A13 @S9S_MB_2U_LIB.S9S_MB_2U(SCH_1):GND
 A16    GND GND_A16 @S9S_MB_2U_LIB.S9S_MB_2U(SCH_1):GND
 A19    GND GND_A19 @S9S_MB_2U_LIB.S9S_MB_2U(SCH_1):GND
 A22    GND GND_A22 @S9S_MB_2U_LIB.S9S_MB_2U(SCH_1):GND
 A25    GND GND_A25 @S9S_MB_2U_LIB.S9S_MB_2U(SCH_1):GND
 A28    GND GND_A28 @S9S_MB_2U_LIB.S9S_MB_2U(SCH_1):GND
 A14 TP_CLK_100M_E1S_0_DN REFCLK_N1 @S9S_MB_2U_LIB.S9S_MB_2U(SCH_1):TP_CLK_100M_E1S_0_DN
 A15 TP_CLK_100M_E1S_0_DP REFCLK_P1 @S9S_MB_2U_LIB.S9S_MB_2U(SCH_1):TP_CLK_100M_E1S_0_DP
 A17 P3E_PCH_E1S_RX_DP<0> PER_N0 @S9S_MB_2U_LIB.S9S_MB_2U(SCH_1):P3E_PCH_E1S_RX_DP(0)
 A18 P3E_PCH_E1S_RX_DN<0> PER_P0 @S9S_MB_2U_LIB.S9S_MB_2U(SCH_1):P3E_PCH_E1S_RX_DN(0)
 A20 P3E_PCH_E1S_RX_DN<1> PER_N1 @S9S_MB_2U_LIB.S9S_MB_2U(SCH_1):P3E_PCH_E1S_RX_DN(1)
 A21 P3E_PCH_E1S_RX_DP<1> PER_P1 @S9S_MB_2U_LIB.S9S_MB_2U(SCH_1):P3E_PCH_E1S_RX_DP(1)
 A23 P3E_PCH_E1S_RX_DN<2> PER_N2 @S9S_MB_2U_LIB.S9S_MB_2U(SCH_1):P3E_PCH_E1S_RX_DN(2)
 A24 P3E_PCH_E1S_RX_DP<2> PER_P2 @S9S_MB_2U_LIB.S9S_MB_2U(SCH_1):P3E_PCH_E1S_RX_DP(2)
 A26 P3E_PCH_E1S_RX_DN<3> PER_N3 @S9S_MB_2U_LIB.S9S_MB_2U(SCH_1):P3E_PCH_E1S_RX_DN(3)
 A27 P3E_PCH_E1S_RX_DP<3> PER_P3 @S9S_MB_2U_LIB.S9S_MB_2U(SCH_1):P3E_PCH_E1S_RX_DP(3)
  G2    GND     G2 @S9S_MB_2U_LIB.S9S_MB_2U(SCH_1):GND
  G1    GND     G1 @S9S_MB_2U_LIB.S9S_MB_2U(SCH_1):GND

Q_CAP_0402-0.1UF,25V,10%,X7R,CA  I327  C2378
   1 P3V3_E1S_0      A @S9S_MB_2U_LIB.S9S_MB_2U(SCH_1):P3V3_E1S_0
   2    GND      B @S9S_MB_2U_LIB.S9S_MB_2U(SCH_1):GND

APX80929SAG7-APX809-29SAG-7,SMA  I329  U336
   3 P3V3_E1S_0    VCC @S9S_MB_2U_LIB.S9S_MB_2U(SCH_1):P3V3_E1S_0
   2 HP_E1S_0_P3V3_PWRGD RESET_L @S9S_MB_2U_LIB.S9S_MB_2U(SCH_1):HP_E1S_0_P3V3_PWRGD
   1    GND    GND @S9S_MB_2U_LIB.S9S_MB_2U(SCH_1):GND

Q_RES_0402LF-49.9,1%,1/16W,CHIA  I331  R4767
   1 HP_E1S_0_P3V3_PWRGD      A @S9S_MB_2U_LIB.S9S_MB_2U(SCH_1):HP_E1S_0_P3V3_PWRGD
   2 HP_E1S_0_P3V3_PWRGD_PLD      B @S9S_MB_2U_LIB.S9S_MB_2U(SCH_1):HP_E1S_0_P3V3_PWRGD_PLD


DRAWING: @S9S_MB_2U_LIB.S9S_MB_2U(SCH_1):PAGE213 

74LVC2G17GW-74LVC2G17GW,SMLF,IA  I2  U150
   5 P3V3_AUX    VCC @S9S_MB_2U_LIB.S9S_MB_2U(SCH_1):P3V3_AUX
   4 NC_U150_B1     B1 @S9S_MB_2U_LIB.S9S_MB_2U(SCH_1):NC_U150_B1
   2    GND    GND @S9S_MB_2U_LIB.S9S_MB_2U(SCH_1):GND
   1 FM_PS_EN_PLD_R     A0 @S9S_MB_2U_LIB.S9S_MB_2U(SCH_1):FM_PS_EN_PLD_R
   3 NC_U150_A1     A1 @S9S_MB_2U_LIB.S9S_MB_2U(SCH_1):NC_U150_A1
   6 FM_PS_EN_PLD_BUF1     B0 @S9S_MB_2U_LIB.S9S_MB_2U(SCH_1):FM_PS_EN_PLD_BUF1

Q_CAP_0402-0.1UF,25V,10%,X7R,CA  I5  C1619
   1 P3V3_AUX      A @S9S_MB_2U_LIB.S9S_MB_2U(SCH_1):P3V3_AUX
   2    GND      B @S9S_MB_2U_LIB.S9S_MB_2U(SCH_1):GND

Q_RES_0402LF-4.7K,5%,1/16W,EMPA  I7  R2355
   1 P3V3_AUX      A @S9S_MB_2U_LIB.S9S_MB_2U(SCH_1):P3V3_AUX
   2 FM_PS_EN_PLD_BUF1      B @S9S_MB_2U_LIB.S9S_MB_2U(SCH_1):FM_PS_EN_PLD_BUF1

Q_RES_0402LF-4.7K,5%,1/16W,CHIA  I18  R4604
   1 P3V3_AUX      A @S9S_MB_2U_LIB.S9S_MB_2U(SCH_1):P3V3_AUX
   2 PWRGD_PS_PWROK_PLD_N      B @S9S_MB_2U_LIB.S9S_MB_2U(SCH_1):PWRGD_PS_PWROK_PLD_N

MOSFET_NCH_DUAL-PJT138K,SMLF,IA  I21  Q144
   3 PWRGD_PS_PWROK_PLD_ISO     D2 @S9S_MB_2U_LIB.S9S_MB_2U(SCH_1):PWRGD_PS_PWROK_PLD_ISO
   5 PWRGD_PS_PWROK_PLD_N     G2 @S9S_MB_2U_LIB.S9S_MB_2U(SCH_1):PWRGD_PS_PWROK_PLD_N
   4    GND     S2 @S9S_MB_2U_LIB.S9S_MB_2U(SCH_1):GND

Q_RES_0402LF-4.7K,5%,1/16W,CHIA  I22  R4605
   1 P3V3_AUX      A @S9S_MB_2U_LIB.S9S_MB_2U(SCH_1):P3V3_AUX
   2 PWRGD_PS_PWROK_PLD_ISO      B @S9S_MB_2U_LIB.S9S_MB_2U(SCH_1):PWRGD_PS_PWROK_PLD_ISO

MOSFET_NCH_DUAL-PJT138K,SMLF,IA  I27  Q144
   1    GND     S1 @S9S_MB_2U_LIB.S9S_MB_2U(SCH_1):GND
   2 PWRGD_PS_PWROK_PLD     G1 @S9S_MB_2U_LIB.S9S_MB_2U(SCH_1):PWRGD_PS_PWROK_PLD
   6 PWRGD_PS_PWROK_PLD_N     D1 @S9S_MB_2U_LIB.S9S_MB_2U(SCH_1):PWRGD_PS_PWROK_PLD_N

Q_RES_0402LF-33.2,1%,1/16W,CHIA  I29  R1446
   1 PWRGD_PS_PWROK_PLD_ISO      A @S9S_MB_2U_LIB.S9S_MB_2U(SCH_1):PWRGD_PS_PWROK_PLD_ISO
   2 PWRGD_PS_PWROK_PLD_ISO_R      B @S9S_MB_2U_LIB.S9S_MB_2U(SCH_1):PWRGD_PS_PWROK_PLD_ISO_R

Q_RES_0402LF-10K,1%,1/16W,CHIPA  I32  R4719
   1 P3V3_AUX      A @S9S_MB_2U_LIB.S9S_MB_2U(SCH_1):P3V3_AUX
   2 FM_AC_PWR_BTN_PLD_ISO_N      B @S9S_MB_2U_LIB.S9S_MB_2U(SCH_1):FM_AC_PWR_BTN_PLD_ISO_N

Q_RES_0402LF-33.2,1%,1/16W,EMPA  I33  R4718
   1 FM_AC_PWR_BTN_PLD_ISO_R_N      A @S9S_MB_2U_LIB.S9S_MB_2U(SCH_1):FM_AC_PWR_BTN_PLD_ISO_R_N
   2 FM_AC_PWR_BTN_PLD_ISO_N      B @S9S_MB_2U_LIB.S9S_MB_2U(SCH_1):FM_AC_PWR_BTN_PLD_ISO_N

Q_CAP_0402-0.1UF,25V,10%,EMPTYA  I35  C2370
   1 P3V3_AUX      A @S9S_MB_2U_LIB.S9S_MB_2U(SCH_1):P3V3_AUX
   2    GND      B @S9S_MB_2U_LIB.S9S_MB_2U(SCH_1):GND

74LVC2G07DW7-74LVC2G07DW-7,SMLB  I37  U332
   1 FM_AC_PWR_BTN_PLD_N     1A @S9S_MB_2U_LIB.S9S_MB_2U(SCH_1):FM_AC_PWR_BTN_PLD_N
   3    GND     2A @S9S_MB_2U_LIB.S9S_MB_2U(SCH_1):GND
   6 FM_AC_PWR_BTN_PLD_ISO_R_N     1Y @S9S_MB_2U_LIB.S9S_MB_2U(SCH_1):FM_AC_PWR_BTN_PLD_ISO_R_N
   4 NC_UXX_2Y     2Y @S9S_MB_2U_LIB.S9S_MB_2U(SCH_1):NC_UXX_2Y
   2    GND    GND @S9S_MB_2U_LIB.S9S_MB_2U(SCH_1):GND
   5 P3V3_AUX    VCC @S9S_MB_2U_LIB.S9S_MB_2U(SCH_1):P3V3_AUX

Q_RES_0402LF-8.45K,1%,1/16W,EMA  I40  R4716
   1 P3V3_AUX      A @S9S_MB_2U_LIB.S9S_MB_2U(SCH_1):P3V3_AUX
   2 FM_AC_PWR_BTN_R_N      B @S9S_MB_2U_LIB.S9S_MB_2U(SCH_1):FM_AC_PWR_BTN_R_N

Q_RES_0402LF-0,5%,1/16W,EMPTY,A  I41  R4717
   1 FM_AC_PWR_BTN_R_N      A @S9S_MB_2U_LIB.S9S_MB_2U(SCH_1):FM_AC_PWR_BTN_R_N
   2 FM_AC_PWR_BTN_PLD_N      B @S9S_MB_2U_LIB.S9S_MB_2U(SCH_1):FM_AC_PWR_BTN_PLD_N

Q_CAP_C0402-1UF,25V,10%,EMPTY,A  I42  C2369
   1 FM_AC_PWR_BTN_R_N      A @S9S_MB_2U_LIB.S9S_MB_2U(SCH_1):FM_AC_PWR_BTN_R_N
   2    GND      B @S9S_MB_2U_LIB.S9S_MB_2U(SCH_1):GND


DRAWING: @S9S_MB_2U_LIB.S9S_MB_2U(SCH_1):PAGE236 

Q_RES_0402LF-0,5%,1/16W,EMPTY,A  I46  R3845
   1 HP_LVC3_OCP_V3_1_EN      A @S9S_MB_2U_LIB.S9S_MB_2U(SCH_1):HP_LVC3_OCP_V3_1_EN
   2 P3V3_OCP_EN_1_R2      B @S9S_MB_2U_LIB.S9S_MB_2U(SCH_1):P3V3_OCP_EN_1_R2

Q_CAP_C0402-39PF,50V,5%,EMPTY,A  I42  PC2157
   1 P3V3_OCP_MODE_1      A @S9S_MB_2U_LIB.S9S_MB_2U(SCH_1):P3V3_OCP_MODE_1
   2    GND      B @S9S_MB_2U_LIB.S9S_MB_2U(SCH_1):GND

Q_CAP_0402-100PF,50V,5%,EMPTY,A  I52  PC2162
   1 P3V3_OCP_GATE_1      A @S9S_MB_2U_LIB.S9S_MB_2U(SCH_1):P3V3_OCP_GATE_1
   2    GND      B @S9S_MB_2U_LIB.S9S_MB_2U(SCH_1):GND

Q_RES_0402LF-71.5K,1%,1/16W,EMA  I43  PR3844
   1 P3V3_OCP_MODE_1      A @S9S_MB_2U_LIB.S9S_MB_2U(SCH_1):P3V3_OCP_MODE_1
   2    GND      B @S9S_MB_2U_LIB.S9S_MB_2U(SCH_1):GND

Q_CAP_0402-0.068UF,16V,10%,EMPA  I49  PC2161
   1 P3V3_OCP_DVDT_1      A @S9S_MB_2U_LIB.S9S_MB_2U(SCH_1):P3V3_OCP_DVDT_1
   2    GND      B @S9S_MB_2U_LIB.S9S_MB_2U(SCH_1):GND

MP5016GQHLZ-MP5016GQH-L-Z,SMLFA  I50  PU205
   9 P3V3_OCP_EN_1_R2     EN @S9S_MB_2U_LIB.S9S_MB_2U(SCH_1):P3V3_OCP_EN_1_R2
   5 P3V3_OCP_MODE_1   MODE @S9S_MB_2U_LIB.S9S_MB_2U(SCH_1):P3V3_OCP_MODE_1
   4 P3V3_OCP_ILIMIT_1 ILIMIT @S9S_MB_2U_LIB.S9S_MB_2U(SCH_1):P3V3_OCP_ILIMIT_1
   3    GND    GND @S9S_MB_2U_LIB.S9S_MB_2U(SCH_1):GND
 1_2 P3V3_AUX    VCC @S9S_MB_2U_LIB.S9S_MB_2U(SCH_1):P3V3_AUX
  10 P3V3_OCP_DVDT_1  DV_DT @S9S_MB_2U_LIB.S9S_MB_2U(SCH_1):P3V3_OCP_DVDT_1
   8 P3V3_OCP_GATE_1   GATE @S9S_MB_2U_LIB.S9S_MB_2U(SCH_1):P3V3_OCP_GATE_1
 6_7 P3V3_OCP_SFF_R SOURCE @S9S_MB_2U_LIB.S9S_MB_2U(SCH_1):P3V3_OCP_SFF_R

Q_CAP_C0402-1UF,25V,10%,EMPTY,A  I55  PC2159
   1 P3V3_AUX      A @S9S_MB_2U_LIB.S9S_MB_2U(SCH_1):P3V3_AUX
   2    GND      B @S9S_MB_2U_LIB.S9S_MB_2U(SCH_1):GND

Q_RES_0402LF-1.33K,1%,1/16W,EMA  I45  PR3846
   1    GND      A @S9S_MB_2U_LIB.S9S_MB_2U(SCH_1):GND
   2 P3V3_OCP_ILIMIT_1      B @S9S_MB_2U_LIB.S9S_MB_2U(SCH_1):P3V3_OCP_ILIMIT_1

Q_CAP_C0805-10UF,16V,10%,EMPTYB  I54  PC2163
   1 P3V3_OCP_SFF_R      A @S9S_MB_2U_LIB.S9S_MB_2U(SCH_1):P3V3_OCP_SFF_R
   2    GND      B @S9S_MB_2U_LIB.S9S_MB_2U(SCH_1):GND

Q_CAP_0402-0.22UF,16V,10%,X7R,A  I60  PC2153
   1 P12V_OCP_TIMER_1      A @S9S_MB_2U_LIB.S9S_MB_2U(SCH_1):P12V_OCP_TIMER_1
   2    GND      B @S9S_MB_2U_LIB.S9S_MB_2U(SCH_1):GND

Q_RES_0402LF-14.3K,1%,1/16W,CHA  I62  PR3835
   1 P12V_OCP_ISET_1      A @S9S_MB_2U_LIB.S9S_MB_2U(SCH_1):P12V_OCP_ISET_1
   2    GND      B @S9S_MB_2U_LIB.S9S_MB_2U(SCH_1):GND

Q_CAP_C0402-0.047UF,25V,10%,X7A  I63  PC2155
   1 P12V_OCP_SS_1      A @S9S_MB_2U_LIB.S9S_MB_2U(SCH_1):P12V_OCP_SS_1
   2    GND      B @S9S_MB_2U_LIB.S9S_MB_2U(SCH_1):GND

Q_RES_0402LF-0,5%,1/16W,CHIP,CA  I65  R3834
   1 HP_LVC3_OCP_V3_1_EN      A @S9S_MB_2U_LIB.S9S_MB_2U(SCH_1):HP_LVC3_OCP_V3_1_EN
   2 P12V_OCP_EN_1_R2      B @S9S_MB_2U_LIB.S9S_MB_2U(SCH_1):P12V_OCP_EN_1_R2

Q_CAP_C0402-1UF,25V,10%,X6S,CHA  I68  PC2154
   1 P12V_AUX      A @S9S_MB_2U_LIB.S9S_MB_2U(SCH_1):P12V_AUX
   2    GND      B @S9S_MB_2U_LIB.S9S_MB_2U(SCH_1):GND

RS31312R-RS31312R,SMLF,IC,AL03A  I70  PU204
  20 P12V_OCP_SFF VOUT_20 @S9S_MB_2U_LIB.S9S_MB_2U(SCH_1):P12V_OCP_SFF
21_22 P12V_AUX VIN_21_22 @S9S_MB_2U_LIB.S9S_MB_2U(SCH_1):P12V_AUX
  19 P12V_OCP_SFF VOUT_19 @S9S_MB_2U_LIB.S9S_MB_2U(SCH_1):P12V_OCP_SFF
  18 P12V_OCP_SFF VOUT_18 @S9S_MB_2U_LIB.S9S_MB_2U(SCH_1):P12V_OCP_SFF
  17 P12V_OCP_SFF VOUT_17 @S9S_MB_2U_LIB.S9S_MB_2U(SCH_1):P12V_OCP_SFF
  16 P12V_OCP_SFF VOUT_16 @S9S_MB_2U_LIB.S9S_MB_2U(SCH_1):P12V_OCP_SFF
  15 P12V_OCP_SFF VOUT_15 @S9S_MB_2U_LIB.S9S_MB_2U(SCH_1):P12V_OCP_SFF
  14 P12V_OCP_SFF VOUT_14 @S9S_MB_2U_LIB.S9S_MB_2U(SCH_1):P12V_OCP_SFF
  12 P12V_OCP_AVIN_PD_1   AVIN @S9S_MB_2U_LIB.S9S_MB_2U(SCH_1):P12V_OCP_AVIN_PD_1
  13 P12V_OCP_SFF VOUT_13 @S9S_MB_2U_LIB.S9S_MB_2U(SCH_1):P12V_OCP_SFF
  11 P12V_OCP_OV_FB_1     OV @S9S_MB_2U_LIB.S9S_MB_2U(SCH_1):P12V_OCP_OV_FB_1
  10 HP_LVC3_OCP_V3_1_P12V_PWRGD     PG @S9S_MB_2U_LIB.S9S_MB_2U(SCH_1):HP_LVC3_OCP_V3_1_P12V_PWRGD
   9 P12V_OCP_FLTB_1   FLTB @S9S_MB_2U_LIB.S9S_MB_2U(SCH_1):P12V_OCP_FLTB_1
   8 P12V_OCP_IMON_1   IMON @S9S_MB_2U_LIB.S9S_MB_2U(SCH_1):P12V_OCP_IMON_1
  23 P12V_AUX VIN_23 @S9S_MB_2U_LIB.S9S_MB_2U(SCH_1):P12V_AUX
  24 P12V_AUX VIN_24 @S9S_MB_2U_LIB.S9S_MB_2U(SCH_1):P12V_AUX
  25 P12V_AUX VIN_25 @S9S_MB_2U_LIB.S9S_MB_2U(SCH_1):P12V_AUX
  26 P12V_AUX VIN_26 @S9S_MB_2U_LIB.S9S_MB_2U(SCH_1):P12V_AUX
   1 P12V_OCP_EN_1_R2     EN @S9S_MB_2U_LIB.S9S_MB_2U(SCH_1):P12V_OCP_EN_1_R2
   2    GND LOADEN @S9S_MB_2U_LIB.S9S_MB_2U(SCH_1):GND
   3    GND   ENTM @S9S_MB_2U_LIB.S9S_MB_2U(SCH_1):GND
   4 P12V_OCP_TIMER_1  TIMER @S9S_MB_2U_LIB.S9S_MB_2U(SCH_1):P12V_OCP_TIMER_1
   5 P12V_OCP_ISET_1   ISET @S9S_MB_2U_LIB.S9S_MB_2U(SCH_1):P12V_OCP_ISET_1
   6 P12V_OCP_SS_1     SS @S9S_MB_2U_LIB.S9S_MB_2U(SCH_1):P12V_OCP_SS_1
   7    GND    GND @S9S_MB_2U_LIB.S9S_MB_2U(SCH_1):GND

Q_RES_0402LF-17.4K,1%,1/16W,CHA  I72  PR3837
   1 P12V_OCP_IMON_1      A @S9S_MB_2U_LIB.S9S_MB_2U(SCH_1):P12V_OCP_IMON_1
   2    GND      B @S9S_MB_2U_LIB.S9S_MB_2U(SCH_1):GND

Q_CAP_C0402-100NF,50V,10%,X7R,A  I74  PC2156
   1 P12V_OCP_IMON_1      A @S9S_MB_2U_LIB.S9S_MB_2U(SCH_1):P12V_OCP_IMON_1
   2    GND      B @S9S_MB_2U_LIB.S9S_MB_2U(SCH_1):GND

Q_RES_0402LF-10K,1%,1/16W,CHIPA  I75  PR3839
   1 P12V_OCP_FLTB_1      A @S9S_MB_2U_LIB.S9S_MB_2U(SCH_1):P12V_OCP_FLTB_1
   2 P3V3_AUX      B @S9S_MB_2U_LIB.S9S_MB_2U(SCH_1):P3V3_AUX

Q_RES_0402LF-10K,1%,1/16W,CHIPA  I76  R4532
   1 P3V3_AUX      A @S9S_MB_2U_LIB.S9S_MB_2U(SCH_1):P3V3_AUX
   2 HP_LVC3_OCP_V3_1_P12V_PWRGD      B @S9S_MB_2U_LIB.S9S_MB_2U(SCH_1):HP_LVC3_OCP_V3_1_P12V_PWRGD

Q_RES_0402LF-100,1%,1/16W,EMPTA  I77  PR3838
   1 P12V_OCP_SFF      A @S9S_MB_2U_LIB.S9S_MB_2U(SCH_1):P12V_OCP_SFF
   2 P12V_OCP_AVIN_PD_1      B @S9S_MB_2U_LIB.S9S_MB_2U(SCH_1):P12V_OCP_AVIN_PD_1

Q_RES_0402LF-0,5%,1/16W,CHIP,CA  I81  R3872
   1 P12V_OCP_IMON_1      A @S9S_MB_2U_LIB.S9S_MB_2U(SCH_1):P12V_OCP_IMON_1
   2 P12V_OCP_SFF_ISENSE_MPS_TIC      B @S9S_MB_2U_LIB.S9S_MB_2U(SCH_1):P12V_OCP_SFF_ISENSE_MPS_TIC

Q_RES_0402LF-0,5%,1/16W,EMPTY,A  I82  R3871
   1 P12V_OCP_IMON_1      A @S9S_MB_2U_LIB.S9S_MB_2U(SCH_1):P12V_OCP_IMON_1
   2 P12V_OCP_SFF_ISENSE_MPS_MAM      B @S9S_MB_2U_LIB.S9S_MB_2U(SCH_1):P12V_OCP_SFF_ISENSE_MPS_MAM

Q_RES_0402LF-10K,1%,1/16W,CHIPA  I83  PR3842
   1 P12V_OCP_OV_FB_1      A @S9S_MB_2U_LIB.S9S_MB_2U(SCH_1):P12V_OCP_OV_FB_1
   2    GND      B @S9S_MB_2U_LIB.S9S_MB_2U(SCH_1):GND

Q_RES_0402LF-71.5K,1%,1/16W,EMA  I85  PR3840
   1 P12V_OCP_SFF      A @S9S_MB_2U_LIB.S9S_MB_2U(SCH_1):P12V_OCP_SFF
   2 P12V_OCP_OV_FB_1      B @S9S_MB_2U_LIB.S9S_MB_2U(SCH_1):P12V_OCP_OV_FB_1

Q_RES_0402LF-120K,1%,1/16W,CHIA  I86  PR3841
   1 P12V_AUX      A @S9S_MB_2U_LIB.S9S_MB_2U(SCH_1):P12V_AUX
   2 P12V_OCP_OV_FB_1      B @S9S_MB_2U_LIB.S9S_MB_2U(SCH_1):P12V_OCP_OV_FB_1

Q_CAP_C0603-2.2UF,16V,20%,X7R,A  I88  PC2158
   1 P12V_OCP_AVIN_PD_1      A @S9S_MB_2U_LIB.S9S_MB_2U(SCH_1):P12V_OCP_AVIN_PD_1
   2    GND      B @S9S_MB_2U_LIB.S9S_MB_2U(SCH_1):GND

Q_RES_0603LF-49.9,1%,1/10W,CHIA  I89  PR3843
   1 P12V_AUX      A @S9S_MB_2U_LIB.S9S_MB_2U(SCH_1):P12V_AUX
   2 P12V_OCP_AVIN_PD_1      B @S9S_MB_2U_LIB.S9S_MB_2U(SCH_1):P12V_OCP_AVIN_PD_1

Q_CAP_0402-0.1UF,25V,10%,X7R,CA  I91  PC2160
   1 P12V_OCP_SFF      A @S9S_MB_2U_LIB.S9S_MB_2U(SCH_1):P12V_OCP_SFF
   2    GND      B @S9S_MB_2U_LIB.S9S_MB_2U(SCH_1):GND


DRAWING: @S9S_MB_2U_LIB.S9S_MB_2U(SCH_1):PAGE324 

Q_RES_0402LF-0,5%,1/16W,CHIP,CA  I21  R4064
   1 E1S_0_EN      A @S9S_MB_2U_LIB.S9S_MB_2U(SCH_1):E1S_0_EN
   2 P12V_E1S_EN_0_R      B @S9S_MB_2U_LIB.S9S_MB_2U(SCH_1):P12V_E1S_EN_0_R

Q_RES_0402LF-2.49K,1%,1/16W,CHA  I34  PR3969
   1 P3V3_E1S_CB_0      A @S9S_MB_2U_LIB.S9S_MB_2U(SCH_1):P3V3_E1S_CB_0
   2    GND      B @S9S_MB_2U_LIB.S9S_MB_2U(SCH_1):GND

Q_RES_0402LF-10,1%,1/16W,CHIP,A  I39  PR3967
   1 P3V3_AUX      A @S9S_MB_2U_LIB.S9S_MB_2U(SCH_1):P3V3_AUX
   2 P3V3_E1S_VCC_0      B @S9S_MB_2U_LIB.S9S_MB_2U(SCH_1):P3V3_E1S_VCC_0

Q_RES_0402LF-10M,1%,1/16W,CHIPA  I43  PR4527
   1 P3V3_E1S_0_R      A @S9S_MB_2U_LIB.S9S_MB_2U(SCH_1):P3V3_E1S_0_R
   2 P3V3_E1S_GATE_0      B @S9S_MB_2U_LIB.S9S_MB_2U(SCH_1):P3V3_E1S_GATE_0

Q_CAP_C0402-6800PF,50V,10%,X7RA  I45  PC2216
   1 P3V3_E1S_GATE_0      A @S9S_MB_2U_LIB.S9S_MB_2U(SCH_1):P3V3_E1S_GATE_0
   2    GND      B @S9S_MB_2U_LIB.S9S_MB_2U(SCH_1):GND

SCHOTTKY_AC-B340A-13-F,SMLF,ICA  I46  PD113
   A    GND      A @S9S_MB_2U_LIB.S9S_MB_2U(SCH_1):GND
   C P3V3_E1S_0_R      C @S9S_MB_2U_LIB.S9S_MB_2U(SCH_1):P3V3_E1S_0_R

Q_RES_0402LF-100K,1%,1/16W,CHIA  I48  R3977
   1 P3V3_AUX      A @S9S_MB_2U_LIB.S9S_MB_2U(SCH_1):P3V3_AUX
   2 P3V3_E1S_FAULT_0      B @S9S_MB_2U_LIB.S9S_MB_2U(SCH_1):P3V3_E1S_FAULT_0

Q_RES_0402LF-10,1%,1/16W,EMPTYA  I61  PR3966
   1 P12V_AUX      A @S9S_MB_2U_LIB.S9S_MB_2U(SCH_1):P12V_AUX
   2 P12V_E1S_VCC_0      B @S9S_MB_2U_LIB.S9S_MB_2U(SCH_1):P12V_E1S_VCC_0

MAX15090BEWIT-MAX15090BEWI+T,SA  I62  PU294
  A2 P12V_E1S_VCC_0    VCC @S9S_MB_2U_LIB.S9S_MB_2U(SCH_1):P12V_E1S_VCC_0
  A3 P12V_AUX  IN_A3 @S9S_MB_2U_LIB.S9S_MB_2U(SCH_1):P12V_AUX
  A5 P12V_AUX  IN_A5 @S9S_MB_2U_LIB.S9S_MB_2U(SCH_1):P12V_AUX
  B3 P12V_AUX  IN_B3 @S9S_MB_2U_LIB.S9S_MB_2U(SCH_1):P12V_AUX
  B5 P12V_AUX  IN_B5 @S9S_MB_2U_LIB.S9S_MB_2U(SCH_1):P12V_AUX
  C3 P12V_AUX  IN_C3 @S9S_MB_2U_LIB.S9S_MB_2U(SCH_1):P12V_AUX
  C5 P12V_AUX  IN_C5 @S9S_MB_2U_LIB.S9S_MB_2U(SCH_1):P12V_AUX
  D5 P12V_AUX  IN_D5 @S9S_MB_2U_LIB.S9S_MB_2U(SCH_1):P12V_AUX
  B1 P12V_E1S_CB_0     CB @S9S_MB_2U_LIB.S9S_MB_2U(SCH_1):P12V_E1S_CB_0
  B7    GND    EN# @S9S_MB_2U_LIB.S9S_MB_2U(SCH_1):GND
  D1 P12V_E1S_REG_0    REG @S9S_MB_2U_LIB.S9S_MB_2U(SCH_1):P12V_E1S_REG_0
  D2 P12V_E1S_UV_0     UV @S9S_MB_2U_LIB.S9S_MB_2U(SCH_1):P12V_E1S_UV_0
  D3 P12V_E1S_OV_0     OV @S9S_MB_2U_LIB.S9S_MB_2U(SCH_1):P12V_E1S_OV_0
  A1 P12V_E1S_SENSE_0 ISENSE @S9S_MB_2U_LIB.S9S_MB_2U(SCH_1):P12V_E1S_SENSE_0
  A4 P12V_E1S_0 OUT_A4 @S9S_MB_2U_LIB.S9S_MB_2U(SCH_1):P12V_E1S_0
  B4 P12V_E1S_0 OUT_B4 @S9S_MB_2U_LIB.S9S_MB_2U(SCH_1):P12V_E1S_0
  B6 P12V_E1S_0 OUT_B6 @S9S_MB_2U_LIB.S9S_MB_2U(SCH_1):P12V_E1S_0
  C4 P12V_E1S_0 OUT_C4 @S9S_MB_2U_LIB.S9S_MB_2U(SCH_1):P12V_E1S_0
  C6 P12V_E1S_0 OUT_C6 @S9S_MB_2U_LIB.S9S_MB_2U(SCH_1):P12V_E1S_0
  D4 P12V_E1S_0 OUT_D4 @S9S_MB_2U_LIB.S9S_MB_2U(SCH_1):P12V_E1S_0
  D6 P12V_E1S_0 OUT_D6 @S9S_MB_2U_LIB.S9S_MB_2U(SCH_1):P12V_E1S_0
  A6 P12V_E1S_GATE_0   GATE @S9S_MB_2U_LIB.S9S_MB_2U(SCH_1):P12V_E1S_GATE_0
  A7    GND   CDLY @S9S_MB_2U_LIB.S9S_MB_2U(SCH_1):GND
  B2    GND GND_B2 @S9S_MB_2U_LIB.S9S_MB_2U(SCH_1):GND
  C1    GND GND_C1 @S9S_MB_2U_LIB.S9S_MB_2U(SCH_1):GND
  C2    GND GND_C2 @S9S_MB_2U_LIB.S9S_MB_2U(SCH_1):GND
  C7 P12V_E1S_FAULT_0 FAULT# @S9S_MB_2U_LIB.S9S_MB_2U(SCH_1):P12V_E1S_FAULT_0
  D7 P12V_E1S_PWRGD_0     PG @S9S_MB_2U_LIB.S9S_MB_2U(SCH_1):P12V_E1S_PWRGD_0

Q_RES_0402LF-0,5%,1/16W,EMPTY,A  I67  R3974
   1 P12V_E1S_SENSE_0      A @S9S_MB_2U_LIB.S9S_MB_2U(SCH_1):P12V_E1S_SENSE_0
   2 P12V_E1S_0_ISENSE_MAM_MAM      B @S9S_MB_2U_LIB.S9S_MB_2U(SCH_1):P12V_E1S_0_ISENSE_MAM_MAM

Q_RES_0402LF-10M,1%,1/16W,EMPTA  I70  PR4528
   1 P12V_E1S_0      A @S9S_MB_2U_LIB.S9S_MB_2U(SCH_1):P12V_E1S_0
   2 P12V_E1S_GATE_0      B @S9S_MB_2U_LIB.S9S_MB_2U(SCH_1):P12V_E1S_GATE_0

SCHOTTKY_AC-B340A-13-F,SMLF,ICA  I71  PD112
   A    GND      A @S9S_MB_2U_LIB.S9S_MB_2U(SCH_1):GND
   C P12V_E1S_0      C @S9S_MB_2U_LIB.S9S_MB_2U(SCH_1):P12V_E1S_0

Q_RES_0402LF-0,5%,1/16W,CHIP,CA  I1  R4063
   1 E1S_0_EN      A @S9S_MB_2U_LIB.S9S_MB_2U(SCH_1):E1S_0_EN
   2 P3V3_E1S_EN_1_R      B @S9S_MB_2U_LIB.S9S_MB_2U(SCH_1):P3V3_E1S_EN_1_R

MOSFET_NCH_DUAL-PJT138K,SMLF,IA  I4  Q126
   3 P3V3_E1S_UV_0_R     D2 @S9S_MB_2U_LIB.S9S_MB_2U(SCH_1):P3V3_E1S_UV_0_R
   5 P3V3_E1S_0_EN_G     G2 @S9S_MB_2U_LIB.S9S_MB_2U(SCH_1):P3V3_E1S_0_EN_G
   4    GND     S2 @S9S_MB_2U_LIB.S9S_MB_2U(SCH_1):GND

Q_RES_0402LF-10K,1%,1/16W,CHIPA  I6  R4072
   1 P12V_AUX      A @S9S_MB_2U_LIB.S9S_MB_2U(SCH_1):P12V_AUX
   2 P3V3_E1S_0_EN_G      B @S9S_MB_2U_LIB.S9S_MB_2U(SCH_1):P3V3_E1S_0_EN_G

Q_RES_0402LF-4.7K,5%,1/16W,CHIA  I9  R4073
   1 P12V_E1S_EN_0_R      A @S9S_MB_2U_LIB.S9S_MB_2U(SCH_1):P12V_E1S_EN_0_R
   2    GND      B @S9S_MB_2U_LIB.S9S_MB_2U(SCH_1):GND

Q_RES_0402LF-15K,1%,1/16W,CHIPA  I13  PR3965
   1 P3V3_E1S_OV_0      A @S9S_MB_2U_LIB.S9S_MB_2U(SCH_1):P3V3_E1S_OV_0
   2    GND      B @S9S_MB_2U_LIB.S9S_MB_2U(SCH_1):GND

Q_RES_0402LF-7.15K,1%,1/16W,CHA  I14  PR3964
   1 P3V3_E1S_UV_0      A @S9S_MB_2U_LIB.S9S_MB_2U(SCH_1):P3V3_E1S_UV_0
   2 P3V3_E1S_OV_0      B @S9S_MB_2U_LIB.S9S_MB_2U(SCH_1):P3V3_E1S_OV_0

Q_CAP_C0402-1UF,25V,10%,X6S,CHA  I17  PC2208
   1 P3V3_AUX      A @S9S_MB_2U_LIB.S9S_MB_2U(SCH_1):P3V3_AUX
   2    GND      B @S9S_MB_2U_LIB.S9S_MB_2U(SCH_1):GND

Q_CAP_C0402-1UF,25V,10%,EMPTY,A  I60  PC2209
   1 P12V_E1S_VCC_0      A @S9S_MB_2U_LIB.S9S_MB_2U(SCH_1):P12V_E1S_VCC_0
   2    GND      B @S9S_MB_2U_LIB.S9S_MB_2U(SCH_1):GND

Q_RES_0402LF-0,5%,1/16W,EMPTY,A  I65  R3975
   1 P12V_E1S_SENSE_0      A @S9S_MB_2U_LIB.S9S_MB_2U(SCH_1):P12V_E1S_SENSE_0
   2 P12V_E1S_0_ISENSE_MAM_TIC      B @S9S_MB_2U_LIB.S9S_MB_2U(SCH_1):P12V_E1S_0_ISENSE_MAM_TIC

Q_CAP_C0402-3900PF,50V,10%,EMPA  I66  PC2215
   1 P12V_E1S_GATE_0      A @S9S_MB_2U_LIB.S9S_MB_2U(SCH_1):P12V_E1S_GATE_0
   2    GND      B @S9S_MB_2U_LIB.S9S_MB_2U(SCH_1):GND

Q_RES_0402LF-0,5%,1/16W,EMPTY,A  I68  R3972
   1 P12V_E1S_PWRGD_0      A @S9S_MB_2U_LIB.S9S_MB_2U(SCH_1):P12V_E1S_PWRGD_0
   2 HP_LVC3_E1S_0_HSC_PWRGD      B @S9S_MB_2U_LIB.S9S_MB_2U(SCH_1):HP_LVC3_E1S_0_HSC_PWRGD

Q_RES_0402LF-10K,1%,1/16W,EMPTA  I22  R4074
   1 P12V_AUX      A @S9S_MB_2U_LIB.S9S_MB_2U(SCH_1):P12V_AUX
   2 P12V_E1S_0_EN_G      B @S9S_MB_2U_LIB.S9S_MB_2U(SCH_1):P12V_E1S_0_EN_G

Q_RES_0402LF-15K,1%,1/16W,EMPTA  I28  PR3962
   1 P12V_E1S_OV_0      A @S9S_MB_2U_LIB.S9S_MB_2U(SCH_1):P12V_E1S_OV_0
   2    GND      B @S9S_MB_2U_LIB.S9S_MB_2U(SCH_1):GND

Q_CAP_C0402-1UF,25V,10%,X6S,CHA  I31  PC2207
   1 P12V_AUX      A @S9S_MB_2U_LIB.S9S_MB_2U(SCH_1):P12V_AUX
   2    GND      B @S9S_MB_2U_LIB.S9S_MB_2U(SCH_1):GND

Q_CAP_C0402-1UF,25V,10%,X6S,CHA  I37  PC2210
   1 P3V3_E1S_VCC_0      A @S9S_MB_2U_LIB.S9S_MB_2U(SCH_1):P3V3_E1S_VCC_0
   2    GND      B @S9S_MB_2U_LIB.S9S_MB_2U(SCH_1):GND

Q_RES_0402LF-9.76K,1%,1/16W,CHA  I41  PR3971
   1 P3V3_E1S_SENSE_0      A @S9S_MB_2U_LIB.S9S_MB_2U(SCH_1):P3V3_E1S_SENSE_0
   2    GND      B @S9S_MB_2U_LIB.S9S_MB_2U(SCH_1):GND

Q_RES_0402LF-0,5%,1/16W,CHIP,CA  I44  R3973
   1 P3V3_E1S_PWRGD_0      A @S9S_MB_2U_LIB.S9S_MB_2U(SCH_1):P3V3_E1S_PWRGD_0
   2 TP_P3V3_E1S_PWRGD_0      B @S9S_MB_2U_LIB.S9S_MB_2U(SCH_1):TP_P3V3_E1S_PWRGD_0

Q_RES_0402LF-100K,1%,1/16W,CHIA  I50  R3979
   1 P3V3_AUX      A @S9S_MB_2U_LIB.S9S_MB_2U(SCH_1):P3V3_AUX
   2 TP_P3V3_E1S_PWRGD_0      B @S9S_MB_2U_LIB.S9S_MB_2U(SCH_1):TP_P3V3_E1S_PWRGD_0

Q_CAP_C0402-0.01UF,50V,10%,EMPA  I69  PC2214
   1 P12V_E1S_0      A @S9S_MB_2U_LIB.S9S_MB_2U(SCH_1):P12V_E1S_0
   2 P12V_E1S_GATE_0      B @S9S_MB_2U_LIB.S9S_MB_2U(SCH_1):P12V_E1S_GATE_0

Q_CAP_0402-0.1UF,25V,10%,X7R,CA  I75  PC2217
   1 P12V_E1S_0      A @S9S_MB_2U_LIB.S9S_MB_2U(SCH_1):P12V_E1S_0
   2    GND      B @S9S_MB_2U_LIB.S9S_MB_2U(SCH_1):GND

Q_RES_0402LF-100K,1%,1/16W,EMPA  I76  R3978
   1 P3V3_AUX      A @S9S_MB_2U_LIB.S9S_MB_2U(SCH_1):P3V3_AUX
   2 HP_LVC3_E1S_0_HSC_PWRGD      B @S9S_MB_2U_LIB.S9S_MB_2U(SCH_1):HP_LVC3_E1S_0_HSC_PWRGD

Q_CAP_C0805-10UF,16V,10%,X6S,CC  I78  PC2219
   1 P12V_E1S_0      A @S9S_MB_2U_LIB.S9S_MB_2U(SCH_1):P12V_E1S_0
   2    GND      B @S9S_MB_2U_LIB.S9S_MB_2U(SCH_1):GND

MOSFET_NCH_DUAL-PJT138K,SMLF,IA  I3  Q126
   1    GND     S1 @S9S_MB_2U_LIB.S9S_MB_2U(SCH_1):GND
   2 P3V3_E1S_EN_1_R     G1 @S9S_MB_2U_LIB.S9S_MB_2U(SCH_1):P3V3_E1S_EN_1_R
   6 P3V3_E1S_0_EN_G     D1 @S9S_MB_2U_LIB.S9S_MB_2U(SCH_1):P3V3_E1S_0_EN_G

MOSFET_NCH_DUAL-PJT138K,SMLF,EA  I10  Q127
   1    GND     S1 @S9S_MB_2U_LIB.S9S_MB_2U(SCH_1):GND
   2 P12V_E1S_EN_0_R     G1 @S9S_MB_2U_LIB.S9S_MB_2U(SCH_1):P12V_E1S_EN_0_R
   6 P12V_E1S_0_EN_G     D1 @S9S_MB_2U_LIB.S9S_MB_2U(SCH_1):P12V_E1S_0_EN_G

Q_RES_0402LF-0,5%,1/16W,CHIP,CA  I15  R3959
   1 P3V3_E1S_UV_0_R      A @S9S_MB_2U_LIB.S9S_MB_2U(SCH_1):P3V3_E1S_UV_0_R
   2 P3V3_E1S_UV_0      B @S9S_MB_2U_LIB.S9S_MB_2U(SCH_1):P3V3_E1S_UV_0

Q_RES_0402LF-25.5K,1%,1/16W,CHA  I18  PR3963
   1 P3V3_AUX      A @S9S_MB_2U_LIB.S9S_MB_2U(SCH_1):P3V3_AUX
   2 P3V3_E1S_UV_0      B @S9S_MB_2U_LIB.S9S_MB_2U(SCH_1):P3V3_E1S_UV_0

MOSFET_NCH_DUAL-PJT138K,SMLF,EA  I24  Q127
   3 P12V_E1S_UV_0_R     D2 @S9S_MB_2U_LIB.S9S_MB_2U(SCH_1):P12V_E1S_UV_0_R
   5 P12V_E1S_0_EN_G     G2 @S9S_MB_2U_LIB.S9S_MB_2U(SCH_1):P12V_E1S_0_EN_G
   4    GND     S2 @S9S_MB_2U_LIB.S9S_MB_2U(SCH_1):GND

Q_RES_0402LF-0,5%,1/16W,EMPTY,A  I26  R3958
   1 P12V_E1S_UV_0_R      A @S9S_MB_2U_LIB.S9S_MB_2U(SCH_1):P12V_E1S_UV_0_R
   2 P12V_E1S_UV_0      B @S9S_MB_2U_LIB.S9S_MB_2U(SCH_1):P12V_E1S_UV_0

Q_RES_0402LF-160K,1%,1/16W,EMPA  I32  PR3960
   1 P12V_AUX      A @S9S_MB_2U_LIB.S9S_MB_2U(SCH_1):P12V_AUX
   2 P12V_E1S_UV_0      B @S9S_MB_2U_LIB.S9S_MB_2U(SCH_1):P12V_E1S_UV_0

MAX15090BEWIT-MAX15090BEWI+T,SB  I35  PU295
  A2 P3V3_E1S_VCC_0    VCC @S9S_MB_2U_LIB.S9S_MB_2U(SCH_1):P3V3_E1S_VCC_0
  A3 P3V3_AUX  IN_A3 @S9S_MB_2U_LIB.S9S_MB_2U(SCH_1):P3V3_AUX
  A5 P3V3_AUX  IN_A5 @S9S_MB_2U_LIB.S9S_MB_2U(SCH_1):P3V3_AUX
  B3 P3V3_AUX  IN_B3 @S9S_MB_2U_LIB.S9S_MB_2U(SCH_1):P3V3_AUX
  B5 P3V3_AUX  IN_B5 @S9S_MB_2U_LIB.S9S_MB_2U(SCH_1):P3V3_AUX
  C3 P3V3_AUX  IN_C3 @S9S_MB_2U_LIB.S9S_MB_2U(SCH_1):P3V3_AUX
  C5 P3V3_AUX  IN_C5 @S9S_MB_2U_LIB.S9S_MB_2U(SCH_1):P3V3_AUX
  D5 P3V3_AUX  IN_D5 @S9S_MB_2U_LIB.S9S_MB_2U(SCH_1):P3V3_AUX
  B1 P3V3_E1S_CB_0     CB @S9S_MB_2U_LIB.S9S_MB_2U(SCH_1):P3V3_E1S_CB_0
  B7    GND    EN# @S9S_MB_2U_LIB.S9S_MB_2U(SCH_1):GND
  D1 P3V3_E1S_REG_0    REG @S9S_MB_2U_LIB.S9S_MB_2U(SCH_1):P3V3_E1S_REG_0
  D2 P3V3_E1S_UV_0     UV @S9S_MB_2U_LIB.S9S_MB_2U(SCH_1):P3V3_E1S_UV_0
  D3 P3V3_E1S_OV_0     OV @S9S_MB_2U_LIB.S9S_MB_2U(SCH_1):P3V3_E1S_OV_0
  A1 P3V3_E1S_SENSE_0 ISENSE @S9S_MB_2U_LIB.S9S_MB_2U(SCH_1):P3V3_E1S_SENSE_0
  A4 P3V3_E1S_0_R OUT_A4 @S9S_MB_2U_LIB.S9S_MB_2U(SCH_1):P3V3_E1S_0_R
  B4 P3V3_E1S_0_R OUT_B4 @S9S_MB_2U_LIB.S9S_MB_2U(SCH_1):P3V3_E1S_0_R
  B6 P3V3_E1S_0_R OUT_B6 @S9S_MB_2U_LIB.S9S_MB_2U(SCH_1):P3V3_E1S_0_R
  C4 P3V3_E1S_0_R OUT_C4 @S9S_MB_2U_LIB.S9S_MB_2U(SCH_1):P3V3_E1S_0_R
  C6 P3V3_E1S_0_R OUT_C6 @S9S_MB_2U_LIB.S9S_MB_2U(SCH_1):P3V3_E1S_0_R
  D4 P3V3_E1S_0_R OUT_D4 @S9S_MB_2U_LIB.S9S_MB_2U(SCH_1):P3V3_E1S_0_R
  D6 P3V3_E1S_0_R OUT_D6 @S9S_MB_2U_LIB.S9S_MB_2U(SCH_1):P3V3_E1S_0_R
  A6 P3V3_E1S_GATE_0   GATE @S9S_MB_2U_LIB.S9S_MB_2U(SCH_1):P3V3_E1S_GATE_0
  A7    GND   CDLY @S9S_MB_2U_LIB.S9S_MB_2U(SCH_1):GND
  B2    GND GND_B2 @S9S_MB_2U_LIB.S9S_MB_2U(SCH_1):GND
  C1    GND GND_C1 @S9S_MB_2U_LIB.S9S_MB_2U(SCH_1):GND
  C2    GND GND_C2 @S9S_MB_2U_LIB.S9S_MB_2U(SCH_1):GND
  C7 P3V3_E1S_FAULT_0 FAULT# @S9S_MB_2U_LIB.S9S_MB_2U(SCH_1):P3V3_E1S_FAULT_0
  D7 P3V3_E1S_PWRGD_0     PG @S9S_MB_2U_LIB.S9S_MB_2U(SCH_1):P3V3_E1S_PWRGD_0

Q_CAP_C0402-1UF,25V,10%,X6S,CHA  I38  PC2212
   1    GND      A @S9S_MB_2U_LIB.S9S_MB_2U(SCH_1):GND
   2 P3V3_E1S_REG_0      B @S9S_MB_2U_LIB.S9S_MB_2U(SCH_1):P3V3_E1S_REG_0

Q_CAP_C0402-0.01UF,50V,10%,EMPA  I42  PC2213
   1 P3V3_E1S_0_R      A @S9S_MB_2U_LIB.S9S_MB_2U(SCH_1):P3V3_E1S_0_R
   2 P3V3_E1S_GATE_0      B @S9S_MB_2U_LIB.S9S_MB_2U(SCH_1):P3V3_E1S_GATE_0

Q_CAP_0402-0.1UF,25V,10%,X7R,CA  I52  PC2218
   1 P3V3_E1S_0_R      A @S9S_MB_2U_LIB.S9S_MB_2U(SCH_1):P3V3_E1S_0_R
   2    GND      B @S9S_MB_2U_LIB.S9S_MB_2U(SCH_1):GND

Q_CAP_C0805-10UF,16V,10%,X6S,CB  I53  PC2220
   1 P3V3_E1S_0_R      A @S9S_MB_2U_LIB.S9S_MB_2U(SCH_1):P3V3_E1S_0_R
   2    GND      B @S9S_MB_2U_LIB.S9S_MB_2U(SCH_1):GND

Q_CAP_C0402-1UF,25V,10%,EMPTY,A  I57  PC2211
   1    GND      A @S9S_MB_2U_LIB.S9S_MB_2U(SCH_1):GND
   2 P12V_E1S_REG_0      B @S9S_MB_2U_LIB.S9S_MB_2U(SCH_1):P12V_E1S_REG_0

Q_RES_0402LF-9.31K,1%,1/16W,EMA  I59  PR3968
   1 P12V_E1S_CB_0      A @S9S_MB_2U_LIB.S9S_MB_2U(SCH_1):P12V_E1S_CB_0
   2    GND      B @S9S_MB_2U_LIB.S9S_MB_2U(SCH_1):GND

Q_RES_0402LF-2.67K,1%,1/16W,EMA  I64  PR3970
   1 P12V_E1S_SENSE_0      A @S9S_MB_2U_LIB.S9S_MB_2U(SCH_1):P12V_E1S_SENSE_0
   2    GND      B @S9S_MB_2U_LIB.S9S_MB_2U(SCH_1):GND

Q_RES_0402LF-100K,1%,1/16W,EMPA  I73  R3976
   1 P3V3_AUX      A @S9S_MB_2U_LIB.S9S_MB_2U(SCH_1):P3V3_AUX
   2 P12V_E1S_FAULT_0      B @S9S_MB_2U_LIB.S9S_MB_2U(SCH_1):P12V_E1S_FAULT_0

Q_CAP_C0805-10UF,16V,10%,X6S,CC  I79  PC2280
   1 P12V_E1S_0      A @S9S_MB_2U_LIB.S9S_MB_2U(SCH_1):P12V_E1S_0
   2    GND      B @S9S_MB_2U_LIB.S9S_MB_2U(SCH_1):GND

DIODE_TVS-SMF14A,SMLF,IC,BCSMFA  I84  PD114
   A    GND      A @S9S_MB_2U_LIB.S9S_MB_2U(SCH_1):GND
   C P12V_AUX      C @S9S_MB_2U_LIB.S9S_MB_2U(SCH_1):P12V_AUX

Q_RES_0402LF-6.8K,1%,1/16W,EMPA  I85  PR3961
   1 P12V_E1S_UV_0      A @S9S_MB_2U_LIB.S9S_MB_2U(SCH_1):P12V_E1S_UV_0
   2 P12V_E1S_OV_0      B @S9S_MB_2U_LIB.S9S_MB_2U(SCH_1):P12V_E1S_OV_0


DRAWING: @S9S_MB_2U_LIB.S9S_MB_2U(SCH_1):PAGE323 

Q_CAP_C0402-39PF,50V,5%,EMPTY,A  I3  PC2197
   1 P3V3_E1S_MODE_0      A @S9S_MB_2U_LIB.S9S_MB_2U(SCH_1):P3V3_E1S_MODE_0
   2    GND      B @S9S_MB_2U_LIB.S9S_MB_2U(SCH_1):GND

Q_CAP_C0402-1UF,25V,10%,EMPTY,A  I9  PC2200
   1 P3V3_AUX      A @S9S_MB_2U_LIB.S9S_MB_2U(SCH_1):P3V3_AUX
   2    GND      B @S9S_MB_2U_LIB.S9S_MB_2U(SCH_1):GND

Q_CAP_C0805-10UF,16V,10%,EMPTYB  I34  PC2204
   1 P3V3_E1S_0_R      A @S9S_MB_2U_LIB.S9S_MB_2U(SCH_1):P3V3_E1S_0_R
   2    GND      B @S9S_MB_2U_LIB.S9S_MB_2U(SCH_1):GND

Q_RES_0402LF-0,5%,1/16W,CHIP,CA  I45  R3943
   1 E1S_0_EN      A @S9S_MB_2U_LIB.S9S_MB_2U(SCH_1):E1S_0_EN
   2 P12V_E1S_EN_0_R2      B @S9S_MB_2U_LIB.S9S_MB_2U(SCH_1):P12V_E1S_EN_0_R2

Q_RES_0402LF-71.5K,1%,1/16W,EMA  I4  PR3945
   1 P3V3_E1S_MODE_0      A @S9S_MB_2U_LIB.S9S_MB_2U(SCH_1):P3V3_E1S_MODE_0
   2    GND      B @S9S_MB_2U_LIB.S9S_MB_2U(SCH_1):GND

Q_RES_0402LF-0,5%,1/16W,EMPTY,A  I5  R3946
   1 E1S_0_EN      A @S9S_MB_2U_LIB.S9S_MB_2U(SCH_1):E1S_0_EN
   2 P3V3_E1S_EN_0_R2      B @S9S_MB_2U_LIB.S9S_MB_2U(SCH_1):P3V3_E1S_EN_0_R2

Q_CAP_0402-0.068UF,16V,10%,EMPA  I30  PC2201
   1 P3V3_E1S_DVDT_0      A @S9S_MB_2U_LIB.S9S_MB_2U(SCH_1):P3V3_E1S_DVDT_0
   2    GND      B @S9S_MB_2U_LIB.S9S_MB_2U(SCH_1):GND

Q_CAP_0402-100PF,50V,5%,EMPTY,A  I32  PC2203
   1 P3V3_E1S_GATE_0_PU293      A @S9S_MB_2U_LIB.S9S_MB_2U(SCH_1):P3V3_E1S_GATE_0_PU293
   2    GND      B @S9S_MB_2U_LIB.S9S_MB_2U(SCH_1):GND

MP5016GQHLZ-MP5016GQH-L-Z,SMLFA  I31  PU293
   9 P3V3_E1S_EN_0_R2     EN @S9S_MB_2U_LIB.S9S_MB_2U(SCH_1):P3V3_E1S_EN_0_R2
   5 P3V3_E1S_MODE_0   MODE @S9S_MB_2U_LIB.S9S_MB_2U(SCH_1):P3V3_E1S_MODE_0
   4 P3V3_E1S_ILIMIT_0 ILIMIT @S9S_MB_2U_LIB.S9S_MB_2U(SCH_1):P3V3_E1S_ILIMIT_0
   3    GND    GND @S9S_MB_2U_LIB.S9S_MB_2U(SCH_1):GND
 1_2 P3V3_AUX    VCC @S9S_MB_2U_LIB.S9S_MB_2U(SCH_1):P3V3_AUX
  10 P3V3_E1S_DVDT_0  DV_DT @S9S_MB_2U_LIB.S9S_MB_2U(SCH_1):P3V3_E1S_DVDT_0
   8 P3V3_E1S_GATE_0_PU293   GATE @S9S_MB_2U_LIB.S9S_MB_2U(SCH_1):P3V3_E1S_GATE_0_PU293
 6_7 P3V3_E1S_0_R SOURCE @S9S_MB_2U_LIB.S9S_MB_2U(SCH_1):P3V3_E1S_0_R

Q_CAP_0402-0.22UF,16V,10%,X7R,A  I37  PC2196
   1 P12V_E1S_TIMER_0      A @S9S_MB_2U_LIB.S9S_MB_2U(SCH_1):P12V_E1S_TIMER_0
   2    GND      B @S9S_MB_2U_LIB.S9S_MB_2U(SCH_1):GND

Q_RES_0402LF-46.4K,1%,1/16W,CHA  I40  PR3944
   1 P12V_E1S_ISET_0      A @S9S_MB_2U_LIB.S9S_MB_2U(SCH_1):P12V_E1S_ISET_0
   2    GND      B @S9S_MB_2U_LIB.S9S_MB_2U(SCH_1):GND

Q_CAP_C0402-560PF,50V,10%,X7R,A  I42  PC2341
   1 P12V_E1S_ISET_0_R      A @S9S_MB_2U_LIB.S9S_MB_2U(SCH_1):P12V_E1S_ISET_0_R
   2    GND      B @S9S_MB_2U_LIB.S9S_MB_2U(SCH_1):GND

Q_CAP_C0402-0.047UF,25V,10%,X7A  I47  PC2281
   1 P12V_E1S_SS_0      A @S9S_MB_2U_LIB.S9S_MB_2U(SCH_1):P12V_E1S_SS_0
   2    GND      B @S9S_MB_2U_LIB.S9S_MB_2U(SCH_1):GND

RS31312R-RS31312R,SMLF,IC,AL03A  I49  PU292
  20 P12V_E1S_0 VOUT_20 @S9S_MB_2U_LIB.S9S_MB_2U(SCH_1):P12V_E1S_0
21_22 P12V_AUX VIN_21_22 @S9S_MB_2U_LIB.S9S_MB_2U(SCH_1):P12V_AUX
  19 P12V_E1S_0 VOUT_19 @S9S_MB_2U_LIB.S9S_MB_2U(SCH_1):P12V_E1S_0
  18 P12V_E1S_0 VOUT_18 @S9S_MB_2U_LIB.S9S_MB_2U(SCH_1):P12V_E1S_0
  17 P12V_E1S_0 VOUT_17 @S9S_MB_2U_LIB.S9S_MB_2U(SCH_1):P12V_E1S_0
  16 P12V_E1S_0 VOUT_16 @S9S_MB_2U_LIB.S9S_MB_2U(SCH_1):P12V_E1S_0
  15 P12V_E1S_0 VOUT_15 @S9S_MB_2U_LIB.S9S_MB_2U(SCH_1):P12V_E1S_0
  14 P12V_E1S_0 VOUT_14 @S9S_MB_2U_LIB.S9S_MB_2U(SCH_1):P12V_E1S_0
  12 P12V_E1S_AVIN_PD_0   AVIN @S9S_MB_2U_LIB.S9S_MB_2U(SCH_1):P12V_E1S_AVIN_PD_0
  13 P12V_E1S_0 VOUT_13 @S9S_MB_2U_LIB.S9S_MB_2U(SCH_1):P12V_E1S_0
  11 P12V_E1S_OV_FB_0     OV @S9S_MB_2U_LIB.S9S_MB_2U(SCH_1):P12V_E1S_OV_FB_0
  10 HP_LVC3_E1S_0_HSC_PWRGD     PG @S9S_MB_2U_LIB.S9S_MB_2U(SCH_1):HP_LVC3_E1S_0_HSC_PWRGD
   9 P12V_E1S_FLTB_0   FLTB @S9S_MB_2U_LIB.S9S_MB_2U(SCH_1):P12V_E1S_FLTB_0
   8 P12V_E1S_IMON_0   IMON @S9S_MB_2U_LIB.S9S_MB_2U(SCH_1):P12V_E1S_IMON_0
  23 P12V_AUX VIN_23 @S9S_MB_2U_LIB.S9S_MB_2U(SCH_1):P12V_AUX
  24 P12V_AUX VIN_24 @S9S_MB_2U_LIB.S9S_MB_2U(SCH_1):P12V_AUX
  25 P12V_AUX VIN_25 @S9S_MB_2U_LIB.S9S_MB_2U(SCH_1):P12V_AUX
  26 P12V_AUX VIN_26 @S9S_MB_2U_LIB.S9S_MB_2U(SCH_1):P12V_AUX
   1 P12V_E1S_EN_0_R2     EN @S9S_MB_2U_LIB.S9S_MB_2U(SCH_1):P12V_E1S_EN_0_R2
   2    GND LOADEN @S9S_MB_2U_LIB.S9S_MB_2U(SCH_1):GND
   3    GND   ENTM @S9S_MB_2U_LIB.S9S_MB_2U(SCH_1):GND
   4 P12V_E1S_TIMER_0  TIMER @S9S_MB_2U_LIB.S9S_MB_2U(SCH_1):P12V_E1S_TIMER_0
   5 P12V_E1S_ISET_0   ISET @S9S_MB_2U_LIB.S9S_MB_2U(SCH_1):P12V_E1S_ISET_0
   6 P12V_E1S_SS_0     SS @S9S_MB_2U_LIB.S9S_MB_2U(SCH_1):P12V_E1S_SS_0
   7    GND    GND @S9S_MB_2U_LIB.S9S_MB_2U(SCH_1):GND

Q_CAP_C0402-1UF,25V,10%,X6S,CHA  I51  PC2198
   1 P12V_AUX      A @S9S_MB_2U_LIB.S9S_MB_2U(SCH_1):P12V_AUX
   2    GND      B @S9S_MB_2U_LIB.S9S_MB_2U(SCH_1):GND

Q_RES_0402LF-10K,1%,1/16W,CHIPA  I54  PR3951
   1 P12V_E1S_FLTB_0      A @S9S_MB_2U_LIB.S9S_MB_2U(SCH_1):P12V_E1S_FLTB_0
   2 P3V3_AUX      B @S9S_MB_2U_LIB.S9S_MB_2U(SCH_1):P3V3_AUX

Q_CAP_C0402-100NF,50V,10%,X7R,A  I56  PC2202
   1 P12V_E1S_IMON_0      A @S9S_MB_2U_LIB.S9S_MB_2U(SCH_1):P12V_E1S_IMON_0
   2    GND      B @S9S_MB_2U_LIB.S9S_MB_2U(SCH_1):GND

Q_RES_0402LF-2.8K,1%,1/16W,EMPA  I6  PR3947
   1    GND      A @S9S_MB_2U_LIB.S9S_MB_2U(SCH_1):GND
   2 P3V3_E1S_ILIMIT_0      B @S9S_MB_2U_LIB.S9S_MB_2U(SCH_1):P3V3_E1S_ILIMIT_0

Q_RES_0402LF-20K,1%,1/16W,CHIPA  I43  PR4541
   1 P12V_E1S_ISET_0      A @S9S_MB_2U_LIB.S9S_MB_2U(SCH_1):P12V_E1S_ISET_0
   2 P12V_E1S_ISET_0_R      B @S9S_MB_2U_LIB.S9S_MB_2U(SCH_1):P12V_E1S_ISET_0_R

Q_RES_0402LF-56K,1%,1/16W,CHIPA  I53  PR3949
   1 P12V_E1S_IMON_0      A @S9S_MB_2U_LIB.S9S_MB_2U(SCH_1):P12V_E1S_IMON_0
   2    GND      B @S9S_MB_2U_LIB.S9S_MB_2U(SCH_1):GND

Q_RES_0402LF-100,1%,1/16W,EMPTA  I55  PR3950
   1 P12V_E1S_0      A @S9S_MB_2U_LIB.S9S_MB_2U(SCH_1):P12V_E1S_0
   2 P12V_E1S_AVIN_PD_0      B @S9S_MB_2U_LIB.S9S_MB_2U(SCH_1):P12V_E1S_AVIN_PD_0

Q_RES_0402LF-10K,1%,1/16W,CHIPA  I58  PR3954
   1 P12V_E1S_OV_FB_0      A @S9S_MB_2U_LIB.S9S_MB_2U(SCH_1):P12V_E1S_OV_FB_0
   2    GND      B @S9S_MB_2U_LIB.S9S_MB_2U(SCH_1):GND

Q_RES_0402LF-71.5K,1%,1/16W,EMA  I62  PR3952
   1 P12V_E1S_0      A @S9S_MB_2U_LIB.S9S_MB_2U(SCH_1):P12V_E1S_0
   2 P12V_E1S_OV_FB_0      B @S9S_MB_2U_LIB.S9S_MB_2U(SCH_1):P12V_E1S_OV_FB_0

Q_RES_0402LF-120K,1%,1/16W,CHIA  I63  PR3953
   1 P12V_AUX      A @S9S_MB_2U_LIB.S9S_MB_2U(SCH_1):P12V_AUX
   2 P12V_E1S_OV_FB_0      B @S9S_MB_2U_LIB.S9S_MB_2U(SCH_1):P12V_E1S_OV_FB_0

Q_RES_0402LF-10K,1%,1/16W,CHIPA  I64  R3948
   1 P3V3_AUX      A @S9S_MB_2U_LIB.S9S_MB_2U(SCH_1):P3V3_AUX
   2 HP_LVC3_E1S_0_HSC_PWRGD      B @S9S_MB_2U_LIB.S9S_MB_2U(SCH_1):HP_LVC3_E1S_0_HSC_PWRGD

Q_RES_0402LF-0,5%,1/16W,CHIP,CA  I66  R3956
   1 P12V_E1S_IMON_0      A @S9S_MB_2U_LIB.S9S_MB_2U(SCH_1):P12V_E1S_IMON_0
   2 P12V_E1S_0_ISENSE_MPS_TIC      B @S9S_MB_2U_LIB.S9S_MB_2U(SCH_1):P12V_E1S_0_ISENSE_MPS_TIC

Q_RES_0402LF-0,5%,1/16W,EMPTY,A  I67  R3955
   1 P12V_E1S_IMON_0      A @S9S_MB_2U_LIB.S9S_MB_2U(SCH_1):P12V_E1S_IMON_0
   2 P12V_E1S_0_ISENSE_MPS_MAM      B @S9S_MB_2U_LIB.S9S_MB_2U(SCH_1):P12V_E1S_0_ISENSE_MPS_MAM

Q_CAP_C0603-2.2UF,16V,20%,X7R,A  I69  PC2205
   1 P12V_E1S_AVIN_PD_0      A @S9S_MB_2U_LIB.S9S_MB_2U(SCH_1):P12V_E1S_AVIN_PD_0
   2    GND      B @S9S_MB_2U_LIB.S9S_MB_2U(SCH_1):GND

Q_RES_0603LF-49.9,1%,1/10W,CHIA  I70  PR3957
   1 P12V_AUX      A @S9S_MB_2U_LIB.S9S_MB_2U(SCH_1):P12V_AUX
   2 P12V_E1S_AVIN_PD_0      B @S9S_MB_2U_LIB.S9S_MB_2U(SCH_1):P12V_E1S_AVIN_PD_0

Q_CAP_0402-0.1UF,25V,10%,X7R,CA  I73  PC2206
   1 P12V_E1S_0      A @S9S_MB_2U_LIB.S9S_MB_2U(SCH_1):P12V_E1S_0
   2    GND      B @S9S_MB_2U_LIB.S9S_MB_2U(SCH_1):GND


DRAWING: @S9S_MB_2U_LIB.S9S_MB_2U(SCH_1):PAGE325 

Q_CAP_0402-1NF,50V,10%,EMPTY,CA  I11  PC2349
   1 HSC_OCREF      A @S9S_MB_2U_LIB.S9S_MB_2U(SCH_1):HSC_OCREF
   2 AGND_HSC      B @S9S_MB_2U_LIB.S9S_MB_2U(SCH_1):AGND_HSC

Q_RES_0402LF-2K,0.1%,1/16W,CHIA  I12  PR3987
   1 HSC_CS_4      A @S9S_MB_2U_LIB.S9S_MB_2U(SCH_1):HSC_CS_4
   2 AGND_HSC      B @S9S_MB_2U_LIB.S9S_MB_2U(SCH_1):AGND_HSC

Q_RES_0402LF-2K,0.1%,1/16W,CHIA  I13  PR3991
   1 HSC_IMON      A @S9S_MB_2U_LIB.S9S_MB_2U(SCH_1):HSC_IMON
   2 AGND_HSC      B @S9S_MB_2U_LIB.S9S_MB_2U(SCH_1):AGND_HSC

Q_RES_0402LF-0,5%,1/16W,CHIP,CA  I16  PR3989
   1 HSC_SCREF      A @S9S_MB_2U_LIB.S9S_MB_2U(SCH_1):HSC_SCREF
   2 HSC_SCREF_4      B @S9S_MB_2U_LIB.S9S_MB_2U(SCH_1):HSC_SCREF_4

Q_RES_0402LF-0,5%,1/16W,CHIP,CA  I21  PR3980
   1 HSC_VDD_R_3      A @S9S_MB_2U_LIB.S9S_MB_2U(SCH_1):HSC_VDD_R_3
   2 HSC_VDD      B @S9S_MB_2U_LIB.S9S_MB_2U(SCH_1):HSC_VDD

Q_RES_0402LF-2K,0.1%,1/16W,CHIA  I34  PR3990
   1 HSC_IMON      A @S9S_MB_2U_LIB.S9S_MB_2U(SCH_1):HSC_IMON
   2 AGND_HSC      B @S9S_MB_2U_LIB.S9S_MB_2U(SCH_1):AGND_HSC

Q_RES_0402LF-0,5%,1/16W,CHIP,CA  I39  PR3995
   1 HSC_FLT_TYPE_4      A @S9S_MB_2U_LIB.S9S_MB_2U(SCH_1):HSC_FLT_TYPE_4
   2 HSC_FLT_TYPE      B @S9S_MB_2U_LIB.S9S_MB_2U(SCH_1):HSC_FLT_TYPE

MP5991GLUZ-MP5991GLU-Z,SMLF,ICA  I17  PU297
   9 P12V_PSU   VIN1 @S9S_MB_2U_LIB.S9S_MB_2U(SCH_1):P12V_PSU
  10 P12V_PSU   VIN2 @S9S_MB_2U_LIB.S9S_MB_2U(SCH_1):P12V_PSU
  11 P12V_PSU   VIN3 @S9S_MB_2U_LIB.S9S_MB_2U(SCH_1):P12V_PSU
  12 P12V_PSU   VIN4 @S9S_MB_2U_LIB.S9S_MB_2U(SCH_1):P12V_PSU
  13 P12V_PSU   VIN5 @S9S_MB_2U_LIB.S9S_MB_2U(SCH_1):P12V_PSU
   4 HSC_ON     ON @S9S_MB_2U_LIB.S9S_MB_2U(SCH_1):HSC_ON
  24 HSC_OCREF  OCREF @S9S_MB_2U_LIB.S9S_MB_2U(SCH_1):HSC_OCREF
  23 HSC_CS_4     CS @S9S_MB_2U_LIB.S9S_MB_2U(SCH_1):HSC_CS_4
  22 HSC_IMON   IMON @S9S_MB_2U_LIB.S9S_MB_2U(SCH_1):HSC_IMON
  21 HSC_VDD_R_4  VDD33 @S9S_MB_2U_LIB.S9S_MB_2U(SCH_1):HSC_VDD_R_4
  20 AGND_HSC    GND @S9S_MB_2U_LIB.S9S_MB_2U(SCH_1):AGND_HSC
  19 HSC_SS     SS @S9S_MB_2U_LIB.S9S_MB_2U(SCH_1):HSC_SS
   5 HSC_FAULT    GOK @S9S_MB_2U_LIB.S9S_MB_2U(SCH_1):HSC_FAULT
  18 HSC_VTEMP  VTEMP @S9S_MB_2U_LIB.S9S_MB_2U(SCH_1):HSC_VTEMP
   1 P12V_AUX  VOUT1 @S9S_MB_2U_LIB.S9S_MB_2U(SCH_1):P12V_AUX
   2 P12V_AUX  VOUT2 @S9S_MB_2U_LIB.S9S_MB_2U(SCH_1):P12V_AUX
  25 P12V_AUX  VOUT3 @S9S_MB_2U_LIB.S9S_MB_2U(SCH_1):P12V_AUX
  26 P12V_AUX  VOUT4 @S9S_MB_2U_LIB.S9S_MB_2U(SCH_1):P12V_AUX
   3 HSC_D_OC_4   D_OC @S9S_MB_2U_LIB.S9S_MB_2U(SCH_1):HSC_D_OC_4
  14 P12V_PSU   VIN6 @S9S_MB_2U_LIB.S9S_MB_2U(SCH_1):P12V_PSU
  15 P12V_PSU   VIN7 @S9S_MB_2U_LIB.S9S_MB_2U(SCH_1):P12V_PSU
  16 P12V_PSU   VIN8 @S9S_MB_2U_LIB.S9S_MB_2U(SCH_1):P12V_PSU
  33 P12V_PSU   VIN9 @S9S_MB_2U_LIB.S9S_MB_2U(SCH_1):P12V_PSU
  27 P12V_AUX  VOUT5 @S9S_MB_2U_LIB.S9S_MB_2U(SCH_1):P12V_AUX
  28 P12V_AUX  VOUT6 @S9S_MB_2U_LIB.S9S_MB_2U(SCH_1):P12V_AUX
  29 P12V_AUX  VOUT7 @S9S_MB_2U_LIB.S9S_MB_2U(SCH_1):P12V_AUX
  30 P12V_AUX  VOUT8 @S9S_MB_2U_LIB.S9S_MB_2U(SCH_1):P12V_AUX
  31 P12V_AUX  VOUT9 @S9S_MB_2U_LIB.S9S_MB_2U(SCH_1):P12V_AUX
  32 P12V_AUX VOUT10 @S9S_MB_2U_LIB.S9S_MB_2U(SCH_1):P12V_AUX
   8 HSC_MODE_4   MODE @S9S_MB_2U_LIB.S9S_MB_2U(SCH_1):HSC_MODE_4
  17 HSC_SCREF_4 SCREF_OCWREF @S9S_MB_2U_LIB.S9S_MB_2U(SCH_1):HSC_SCREF_4
   6 HSC_FLT_TYPE_4 FLT_TYPE @S9S_MB_2U_LIB.S9S_MB_2U(SCH_1):HSC_FLT_TYPE_4
   7 HSC_NC1_4    NC1 @S9S_MB_2U_LIB.S9S_MB_2U(SCH_1):HSC_NC1_4

Q_RES_0402LF-0,5%,1/16W,CHIP,CA  I49  PR3993
   1 HSC_FLT_TYPE_3      A @S9S_MB_2U_LIB.S9S_MB_2U(SCH_1):HSC_FLT_TYPE_3
   2 HSC_FLT_TYPE      B @S9S_MB_2U_LIB.S9S_MB_2U(SCH_1):HSC_FLT_TYPE

Q_CAP_C0402-1UF,25V,10%,X6S,CHA  I4  PC2223
   1 HSC_VDD_R_4      A @S9S_MB_2U_LIB.S9S_MB_2U(SCH_1):HSC_VDD_R_4
   2 AGND_HSC      B @S9S_MB_2U_LIB.S9S_MB_2U(SCH_1):AGND_HSC

Q_RES_0402LF-2K,0.1%,1/16W,CHIA  I30  PR3986
   1 HSC_CS_3      A @S9S_MB_2U_LIB.S9S_MB_2U(SCH_1):HSC_CS_3
   2 AGND_HSC      B @S9S_MB_2U_LIB.S9S_MB_2U(SCH_1):AGND_HSC

MP5991GLUZ-MP5991GLU-Z,SMLF,ICA  I35  PU296
   9 P12V_PSU   VIN1 @S9S_MB_2U_LIB.S9S_MB_2U(SCH_1):P12V_PSU
  10 P12V_PSU   VIN2 @S9S_MB_2U_LIB.S9S_MB_2U(SCH_1):P12V_PSU
  11 P12V_PSU   VIN3 @S9S_MB_2U_LIB.S9S_MB_2U(SCH_1):P12V_PSU
  12 P12V_PSU   VIN4 @S9S_MB_2U_LIB.S9S_MB_2U(SCH_1):P12V_PSU
  13 P12V_PSU   VIN5 @S9S_MB_2U_LIB.S9S_MB_2U(SCH_1):P12V_PSU
   4 HSC_ON     ON @S9S_MB_2U_LIB.S9S_MB_2U(SCH_1):HSC_ON
  24 HSC_OCREF  OCREF @S9S_MB_2U_LIB.S9S_MB_2U(SCH_1):HSC_OCREF
  23 HSC_CS_3     CS @S9S_MB_2U_LIB.S9S_MB_2U(SCH_1):HSC_CS_3
  22 HSC_IMON   IMON @S9S_MB_2U_LIB.S9S_MB_2U(SCH_1):HSC_IMON
  21 HSC_VDD_R_3  VDD33 @S9S_MB_2U_LIB.S9S_MB_2U(SCH_1):HSC_VDD_R_3
  20 AGND_HSC    GND @S9S_MB_2U_LIB.S9S_MB_2U(SCH_1):AGND_HSC
  19 HSC_SS     SS @S9S_MB_2U_LIB.S9S_MB_2U(SCH_1):HSC_SS
   5 HSC_FAULT    GOK @S9S_MB_2U_LIB.S9S_MB_2U(SCH_1):HSC_FAULT
  18 HSC_VTEMP  VTEMP @S9S_MB_2U_LIB.S9S_MB_2U(SCH_1):HSC_VTEMP
   1 P12V_AUX  VOUT1 @S9S_MB_2U_LIB.S9S_MB_2U(SCH_1):P12V_AUX
   2 P12V_AUX  VOUT2 @S9S_MB_2U_LIB.S9S_MB_2U(SCH_1):P12V_AUX
  25 P12V_AUX  VOUT3 @S9S_MB_2U_LIB.S9S_MB_2U(SCH_1):P12V_AUX
  26 P12V_AUX  VOUT4 @S9S_MB_2U_LIB.S9S_MB_2U(SCH_1):P12V_AUX
   3 HSC_D_OC_3   D_OC @S9S_MB_2U_LIB.S9S_MB_2U(SCH_1):HSC_D_OC_3
  14 P12V_PSU   VIN6 @S9S_MB_2U_LIB.S9S_MB_2U(SCH_1):P12V_PSU
  15 P12V_PSU   VIN7 @S9S_MB_2U_LIB.S9S_MB_2U(SCH_1):P12V_PSU
  16 P12V_PSU   VIN8 @S9S_MB_2U_LIB.S9S_MB_2U(SCH_1):P12V_PSU
  33 P12V_PSU   VIN9 @S9S_MB_2U_LIB.S9S_MB_2U(SCH_1):P12V_PSU
  27 P12V_AUX  VOUT5 @S9S_MB_2U_LIB.S9S_MB_2U(SCH_1):P12V_AUX
  28 P12V_AUX  VOUT6 @S9S_MB_2U_LIB.S9S_MB_2U(SCH_1):P12V_AUX
  29 P12V_AUX  VOUT7 @S9S_MB_2U_LIB.S9S_MB_2U(SCH_1):P12V_AUX
  30 P12V_AUX  VOUT8 @S9S_MB_2U_LIB.S9S_MB_2U(SCH_1):P12V_AUX
  31 P12V_AUX  VOUT9 @S9S_MB_2U_LIB.S9S_MB_2U(SCH_1):P12V_AUX
  32 P12V_AUX VOUT10 @S9S_MB_2U_LIB.S9S_MB_2U(SCH_1):P12V_AUX
   8 HSC_MODE_3   MODE @S9S_MB_2U_LIB.S9S_MB_2U(SCH_1):HSC_MODE_3
  17 HSC_SCREF_3 SCREF_OCWREF @S9S_MB_2U_LIB.S9S_MB_2U(SCH_1):HSC_SCREF_3
   6 HSC_FLT_TYPE_3 FLT_TYPE @S9S_MB_2U_LIB.S9S_MB_2U(SCH_1):HSC_FLT_TYPE_3
   7 HSC_NC1_3    NC1 @S9S_MB_2U_LIB.S9S_MB_2U(SCH_1):HSC_NC1_3

Q_RES_0402LF-0,5%,1/16W,CHIP,CA  I40  PR3994
   1 HSC_D_OC_4      A @S9S_MB_2U_LIB.S9S_MB_2U(SCH_1):HSC_D_OC_4
   2 HSC_D_OC_R      B @S9S_MB_2U_LIB.S9S_MB_2U(SCH_1):HSC_D_OC_R

Q_RES_0402LF-0,5%,1/16W,CHIP,CA  I50  PR3992
   1 HSC_D_OC_3      A @S9S_MB_2U_LIB.S9S_MB_2U(SCH_1):HSC_D_OC_3
   2 HSC_D_OC_R      B @S9S_MB_2U_LIB.S9S_MB_2U(SCH_1):HSC_D_OC_R

Q_CAP_0402-0.068UF,16V,10%,X7RA  I38  PC2227
   1 HSC_SS      A @S9S_MB_2U_LIB.S9S_MB_2U(SCH_1):HSC_SS
   2 AGND_HSC      B @S9S_MB_2U_LIB.S9S_MB_2U(SCH_1):AGND_HSC

Q_CAP_C0402-1UF,25V,10%,X6S,CHA  I19  PC3272
   1 HSC_VDD_R_3      A @S9S_MB_2U_LIB.S9S_MB_2U(SCH_1):HSC_VDD_R_3
   2 AGND_HSC      B @S9S_MB_2U_LIB.S9S_MB_2U(SCH_1):AGND_HSC

Q_CAP_0402-220PF,50V,10%,EMPTYA  I23  PC2224
   1 HSC_ON      A @S9S_MB_2U_LIB.S9S_MB_2U(SCH_1):HSC_ON
   2 AGND_HSC      B @S9S_MB_2U_LIB.S9S_MB_2U(SCH_1):AGND_HSC

Q_CAP_0402-1NF,50V,10%,EMPTY,CA  I29  PC2350
   1 HSC_OCREF      A @S9S_MB_2U_LIB.S9S_MB_2U(SCH_1):HSC_OCREF
   2 AGND_HSC      B @S9S_MB_2U_LIB.S9S_MB_2U(SCH_1):AGND_HSC

Q_RES_0402LF-120K,1%,1/16W,CHIA  I32  PR3982
   1 AGND_HSC      A @S9S_MB_2U_LIB.S9S_MB_2U(SCH_1):AGND_HSC
   2 HSC_MODE_3      B @S9S_MB_2U_LIB.S9S_MB_2U(SCH_1):HSC_MODE_3

Q_CAP_0402-220PF,50V,10%,EMPTYA  I2  PC2225
   1 HSC_ON      A @S9S_MB_2U_LIB.S9S_MB_2U(SCH_1):HSC_ON
   2 AGND_HSC      B @S9S_MB_2U_LIB.S9S_MB_2U(SCH_1):AGND_HSC

Q_RES_0402LF-0,5%,1/16W,CHIP,CA  I5  PR3981
   1 HSC_VDD_R_4      A @S9S_MB_2U_LIB.S9S_MB_2U(SCH_1):HSC_VDD_R_4
   2 HSC_VDD      B @S9S_MB_2U_LIB.S9S_MB_2U(SCH_1):HSC_VDD

Q_RES_0402LF-120K,1%,1/16W,CHIA  I14  PR3984
   1 AGND_HSC      A @S9S_MB_2U_LIB.S9S_MB_2U(SCH_1):AGND_HSC
   2 HSC_MODE_4      B @S9S_MB_2U_LIB.S9S_MB_2U(SCH_1):HSC_MODE_4

Q_RES_0402LF-0,5%,1/16W,CHIP,CA  I33  PR3988
   1 HSC_SCREF      A @S9S_MB_2U_LIB.S9S_MB_2U(SCH_1):HSC_SCREF
   2 HSC_SCREF_3      B @S9S_MB_2U_LIB.S9S_MB_2U(SCH_1):HSC_SCREF_3

Q_CAP_0402-0.068UF,16V,10%,X7RA  I48  PC2226
   1 HSC_SS      A @S9S_MB_2U_LIB.S9S_MB_2U(SCH_1):HSC_SS
   2 AGND_HSC      B @S9S_MB_2U_LIB.S9S_MB_2U(SCH_1):AGND_HSC


DRAWING: @S9S_MB_2U_LIB.S9S_MB_2U(SCH_1):PAGE229 

Q_RES_0402LF-17.8K,1%,1/16W,EMA  I63  PR4004
   1 P12V_SCM_CB      A @S9S_MB_2U_LIB.S9S_MB_2U(SCH_1):P12V_SCM_CB
   2    GND      B @S9S_MB_2U_LIB.S9S_MB_2U(SCH_1):GND

Q_RES_0402LF-160K,1%,1/16W,EMPA  I67  PR4000
   1 P12V_AUX      A @S9S_MB_2U_LIB.S9S_MB_2U(SCH_1):P12V_AUX
   2 P12V_SCM_UV      B @S9S_MB_2U_LIB.S9S_MB_2U(SCH_1):P12V_SCM_UV

Q_RES_0402LF-1.33K,1%,1/16W,EMA  I72  PR4008
   1 P12V_SCM_SENSE      A @S9S_MB_2U_LIB.S9S_MB_2U(SCH_1):P12V_SCM_SENSE
   2    GND      B @S9S_MB_2U_LIB.S9S_MB_2U(SCH_1):GND

Q_RES_0402LF-20K,1%,1/16W,CHIPA  I12  PR4540
   1 P12V_SCM_ISET      A @S9S_MB_2U_LIB.S9S_MB_2U(SCH_1):P12V_SCM_ISET
   2 P12V_SCM_ISET_R      B @S9S_MB_2U_LIB.S9S_MB_2U(SCH_1):P12V_SCM_ISET_R

Q_RES_0402LF-0,5%,1/16W,CHIP,CA  I14  R3998
   1 P12V_SCM_EN      A @S9S_MB_2U_LIB.S9S_MB_2U(SCH_1):P12V_SCM_EN
   2 P12V_SCM_EN_R2      B @S9S_MB_2U_LIB.S9S_MB_2U(SCH_1):P12V_SCM_EN_R2

Q_RES_0402LF-0,5%,1/16W,CHIP,CA  I17  R3996
   1 VIRTUAL_RESEAT_FPGA_N      A @S9S_MB_2U_LIB.S9S_MB_2U(SCH_1):VIRTUAL_RESEAT_FPGA_N
   2 P12V_SCM_EN      B @S9S_MB_2U_LIB.S9S_MB_2U(SCH_1):P12V_SCM_EN

Q_RES_0402LF-10K,1%,1/16W,CHIPA  I18  R1857
   1 P3V3_AUX      A @S9S_MB_2U_LIB.S9S_MB_2U(SCH_1):P3V3_AUX
   2 P12V_SCM_EN      B @S9S_MB_2U_LIB.S9S_MB_2U(SCH_1):P12V_SCM_EN

MOSFET_NCH_DUAL-PJT138K,SMLF,EA  I21  Q125
   1    GND     S1 @S9S_MB_2U_LIB.S9S_MB_2U(SCH_1):GND
   2 P12V_SCM_EN_R     G1 @S9S_MB_2U_LIB.S9S_MB_2U(SCH_1):P12V_SCM_EN_R
   6 P12V_SCM_EN_G     D1 @S9S_MB_2U_LIB.S9S_MB_2U(SCH_1):P12V_SCM_EN_G

Q_RES_0402LF-30.1K,1%,1/16W,CHA  I34  PR4005
   1 P12V_SCM_IMON      A @S9S_MB_2U_LIB.S9S_MB_2U(SCH_1):P12V_SCM_IMON
   2    GND      B @S9S_MB_2U_LIB.S9S_MB_2U(SCH_1):GND

Q_CAP_C0402-1UF,25V,10%,X6S,CHA  I37  PC2231
   1 P12V_AUX      A @S9S_MB_2U_LIB.S9S_MB_2U(SCH_1):P12V_AUX
   2    GND      B @S9S_MB_2U_LIB.S9S_MB_2U(SCH_1):GND

Q_CAP_C0402-100NF,50V,10%,X7R,A  I42  PC2235
   1 P12V_SCM_IMON      A @S9S_MB_2U_LIB.S9S_MB_2U(SCH_1):P12V_SCM_IMON
   2    GND      B @S9S_MB_2U_LIB.S9S_MB_2U(SCH_1):GND

Q_RES_0402LF-10K,1%,1/16W,CHIPA  I48  PR4007
   1 P12V_SCM_FLTB_N      A @S9S_MB_2U_LIB.S9S_MB_2U(SCH_1):P12V_SCM_FLTB_N
   2 P3V3_AUX      B @S9S_MB_2U_LIB.S9S_MB_2U(SCH_1):P3V3_AUX

Q_RES_0402LF-10K,1%,1/16W,CHIPA  I50  PR4011
   1 P12V_SCM_OV_FB      A @S9S_MB_2U_LIB.S9S_MB_2U(SCH_1):P12V_SCM_OV_FB
   2    GND      B @S9S_MB_2U_LIB.S9S_MB_2U(SCH_1):GND

Q_RES_0402LF-10K,1%,1/16W,CHIPA  I2  R1854
   1 P3V3_AUX      A @S9S_MB_2U_LIB.S9S_MB_2U(SCH_1):P3V3_AUX
   2 FM_SCM_PRSNT1_N      B @S9S_MB_2U_LIB.S9S_MB_2U(SCH_1):FM_SCM_PRSNT1_N

Q_RES_0402LF-100,1%,1/16W,CHIPA  I3  R1856
   1 FM_SCM_PRSNT1_N      A @S9S_MB_2U_LIB.S9S_MB_2U(SCH_1):FM_SCM_PRSNT1_N
   2 FM_SCM_PRSNT1_R_N      B @S9S_MB_2U_LIB.S9S_MB_2U(SCH_1):FM_SCM_PRSNT1_R_N

Q_CAP_0402-0.22UF,16V,10%,X7R,A  I8  PC2229
   1 P12V_SCM_TIMER      A @S9S_MB_2U_LIB.S9S_MB_2U(SCH_1):P12V_SCM_TIMER
   2    GND      B @S9S_MB_2U_LIB.S9S_MB_2U(SCH_1):GND

Q_RES_0402LF-24.3K,1%,1/16W,CHA  I11  PR3999
   1 P12V_SCM_ISET      A @S9S_MB_2U_LIB.S9S_MB_2U(SCH_1):P12V_SCM_ISET
   2    GND      B @S9S_MB_2U_LIB.S9S_MB_2U(SCH_1):GND

Q_RES_0402LF-0,5%,1/16W,EMPTY,A  I20  R4062
   1 P12V_SCM_EN      A @S9S_MB_2U_LIB.S9S_MB_2U(SCH_1):P12V_SCM_EN
   2 P12V_SCM_EN_R      B @S9S_MB_2U_LIB.S9S_MB_2U(SCH_1):P12V_SCM_EN_R

Q_RES_0402LF-0,5%,1/16W,EMPTY,A  I27  R3997
   1 P12V_SCM_UV_R      A @S9S_MB_2U_LIB.S9S_MB_2U(SCH_1):P12V_SCM_UV_R
   2 P12V_SCM_UV      B @S9S_MB_2U_LIB.S9S_MB_2U(SCH_1):P12V_SCM_UV

DIODE_TVS-SMF14A,SMLF,IC,BCSMFA  I29  PD115
   A    GND      A @S9S_MB_2U_LIB.S9S_MB_2U(SCH_1):GND
   C P12V_AUX      C @S9S_MB_2U_LIB.S9S_MB_2U(SCH_1):P12V_AUX

Q_CAP_C0402-1UF,25V,10%,X6S,CHA  I31  PC2230
   1 P12V_AUX      A @S9S_MB_2U_LIB.S9S_MB_2U(SCH_1):P12V_AUX
   2    GND      B @S9S_MB_2U_LIB.S9S_MB_2U(SCH_1):GND

Q_CAP_C0402-0.047UF,25V,10%,X7A  I33  PC2232
   1 P12V_SCM_SS      A @S9S_MB_2U_LIB.S9S_MB_2U(SCH_1):P12V_SCM_SS
   2    GND      B @S9S_MB_2U_LIB.S9S_MB_2U(SCH_1):GND

Q_RES_0402LF-71.5K,1%,1/16W,EMA  I51  PR4009
   1 P12V_SCM_R      A @S9S_MB_2U_LIB.S9S_MB_2U(SCH_1):P12V_SCM_R
   2 P12V_SCM_OV_FB      B @S9S_MB_2U_LIB.S9S_MB_2U(SCH_1):P12V_SCM_OV_FB

Q_RES_0402LF-120K,1%,1/16W,CHIA  I52  PR4010
   1 P12V_AUX      A @S9S_MB_2U_LIB.S9S_MB_2U(SCH_1):P12V_AUX
   2 P12V_SCM_OV_FB      B @S9S_MB_2U_LIB.S9S_MB_2U(SCH_1):P12V_SCM_OV_FB

Q_CAP_C0603-2.2UF,16V,20%,X7R,A  I53  PC2239
   1 P12V_SCM_AVIN_PD      A @S9S_MB_2U_LIB.S9S_MB_2U(SCH_1):P12V_SCM_AVIN_PD
   2    GND      B @S9S_MB_2U_LIB.S9S_MB_2U(SCH_1):GND

Q_CAP_C0402-1UF,25V,10%,EMPTY,A  I66  PC2234
   1    GND      A @S9S_MB_2U_LIB.S9S_MB_2U(SCH_1):GND
   2 P12V_SCM_REG      B @S9S_MB_2U_LIB.S9S_MB_2U(SCH_1):P12V_SCM_REG

Q_CAP_C0402-1UF,25V,10%,EMPTY,A  I68  PC2233
   1 P12V_SCM_VCC      A @S9S_MB_2U_LIB.S9S_MB_2U(SCH_1):P12V_SCM_VCC
   2    GND      B @S9S_MB_2U_LIB.S9S_MB_2U(SCH_1):GND

Q_CAP_C0402-0.01UF,50V,10%,EMPA  I73  PC2236
   1 P12V_SCM_R      A @S9S_MB_2U_LIB.S9S_MB_2U(SCH_1):P12V_SCM_R
   2 P12V_SCM_GATE      B @S9S_MB_2U_LIB.S9S_MB_2U(SCH_1):P12V_SCM_GATE

Q_RES_0402LF-0,5%,1/16W,EMPTY,A  I74  PR4012
   1 P12V_SCM_PWRGD      A @S9S_MB_2U_LIB.S9S_MB_2U(SCH_1):P12V_SCM_PWRGD
   2 HP_LVC3_SCM_HSC_PWRGD      B @S9S_MB_2U_LIB.S9S_MB_2U(SCH_1):HP_LVC3_SCM_HSC_PWRGD

Q_RES_0402LF-100K,1%,1/16W,EMPA  I79  R4013
   1 P3V3_AUX      A @S9S_MB_2U_LIB.S9S_MB_2U(SCH_1):P3V3_AUX
   2 P12V_SCM_FAULT_R_N      B @S9S_MB_2U_LIB.S9S_MB_2U(SCH_1):P12V_SCM_FAULT_R_N

Q_RES_0402LF-100K,1%,1/16W,EMPA  I81  R4015
   1 P3V3_AUX      A @S9S_MB_2U_LIB.S9S_MB_2U(SCH_1):P3V3_AUX
   2 HP_LVC3_SCM_HSC_PWRGD      B @S9S_MB_2U_LIB.S9S_MB_2U(SCH_1):HP_LVC3_SCM_HSC_PWRGD

Q_CAP_C0402-560PF,50V,10%,X7R,A  I7  PC2340
   1 P12V_SCM_ISET_R      A @S9S_MB_2U_LIB.S9S_MB_2U(SCH_1):P12V_SCM_ISET_R
   2    GND      B @S9S_MB_2U_LIB.S9S_MB_2U(SCH_1):GND

Q_RES_0402LF-10,1%,1/16W,EMPTYA  I70  PR4003
   1 P12V_AUX      A @S9S_MB_2U_LIB.S9S_MB_2U(SCH_1):P12V_AUX
   2 P12V_SCM_VCC      B @S9S_MB_2U_LIB.S9S_MB_2U(SCH_1):P12V_SCM_VCC

Q_RES_0402LF-10M,1%,1/16W,EMPTA  I76  PR4526
   1 P12V_SCM_R      A @S9S_MB_2U_LIB.S9S_MB_2U(SCH_1):P12V_SCM_R
   2 P12V_SCM_GATE      B @S9S_MB_2U_LIB.S9S_MB_2U(SCH_1):P12V_SCM_GATE

Q_CAP_0402-0.1UF,25V,10%,X7R,CA  I83  PC2238
   1 P12V_SCM_R      A @S9S_MB_2U_LIB.S9S_MB_2U(SCH_1):P12V_SCM_R
   2    GND      B @S9S_MB_2U_LIB.S9S_MB_2U(SCH_1):GND

MOSFET_NCH_GDS_ESD_PROTECTED-2A  I9  Q39
   D P12V_SCM_EN      D @S9S_MB_2U_LIB.S9S_MB_2U(SCH_1):P12V_SCM_EN
   G FM_SCM_PRSNT1_R_N      G @S9S_MB_2U_LIB.S9S_MB_2U(SCH_1):FM_SCM_PRSNT1_R_N
   S    GND      S @S9S_MB_2U_LIB.S9S_MB_2U(SCH_1):GND

Q_RES_0402LF-10K,1%,1/16W,EMPTA  I24  R4071
   1 P12V_AUX      A @S9S_MB_2U_LIB.S9S_MB_2U(SCH_1):P12V_AUX
   2 P12V_SCM_EN_G      B @S9S_MB_2U_LIB.S9S_MB_2U(SCH_1):P12V_SCM_EN_G

MOSFET_NCH_DUAL-PJT138K,SMLF,EA  I26  Q125
   3 P12V_SCM_UV_R     D2 @S9S_MB_2U_LIB.S9S_MB_2U(SCH_1):P12V_SCM_UV_R
   5 P12V_SCM_EN_G     G2 @S9S_MB_2U_LIB.S9S_MB_2U(SCH_1):P12V_SCM_EN_G
   4    GND     S2 @S9S_MB_2U_LIB.S9S_MB_2U(SCH_1):GND

Q_RES_0402LF-100,1%,1/16W,EMPTA  I39  PR4006
   1 P12V_SCM_R      A @S9S_MB_2U_LIB.S9S_MB_2U(SCH_1):P12V_SCM_R
   2 P12V_SCM_AVIN_PD      B @S9S_MB_2U_LIB.S9S_MB_2U(SCH_1):P12V_SCM_AVIN_PD

Q_RES_0402LF-0,5%,1/16W,CHIP,CA  I44  R4709
   1 P12V_SCM_FLTB_N      A @S9S_MB_2U_LIB.S9S_MB_2U(SCH_1):P12V_SCM_FLTB_N
   2 P12V_SCM_FAULT_R_N      B @S9S_MB_2U_LIB.S9S_MB_2U(SCH_1):P12V_SCM_FAULT_R_N

Q_RES_0603LF-49.9,1%,1/10W,CHIA  I54  PR4014
   1 P12V_AUX      A @S9S_MB_2U_LIB.S9S_MB_2U(SCH_1):P12V_AUX
   2 P12V_SCM_AVIN_PD      B @S9S_MB_2U_LIB.S9S_MB_2U(SCH_1):P12V_SCM_AVIN_PD

Q_CAP_0402-0.1UF,25V,10%,X7R,CA  I57  PC2241
   1 P12V_SCM_R      A @S9S_MB_2U_LIB.S9S_MB_2U(SCH_1):P12V_SCM_R
   2    GND      B @S9S_MB_2U_LIB.S9S_MB_2U(SCH_1):GND

Q_RES_0402LF-15K,1%,1/16W,EMPTA  I61  PR4002
   1 P12V_SCM_OV      A @S9S_MB_2U_LIB.S9S_MB_2U(SCH_1):P12V_SCM_OV
   2    GND      B @S9S_MB_2U_LIB.S9S_MB_2U(SCH_1):GND

Q_RES_0402LF-6.8K,1%,1/16W,EMPA  I64  PR4001
   1 P12V_SCM_UV      A @S9S_MB_2U_LIB.S9S_MB_2U(SCH_1):P12V_SCM_UV
   2 P12V_SCM_OV      B @S9S_MB_2U_LIB.S9S_MB_2U(SCH_1):P12V_SCM_OV

MAX15090BEWIT-MAX15090BEWI+T,SA  I69  PU300
  A2 P12V_SCM_VCC    VCC @S9S_MB_2U_LIB.S9S_MB_2U(SCH_1):P12V_SCM_VCC
  A3 P12V_AUX  IN_A3 @S9S_MB_2U_LIB.S9S_MB_2U(SCH_1):P12V_AUX
  A5 P12V_AUX  IN_A5 @S9S_MB_2U_LIB.S9S_MB_2U(SCH_1):P12V_AUX
  B3 P12V_AUX  IN_B3 @S9S_MB_2U_LIB.S9S_MB_2U(SCH_1):P12V_AUX
  B5 P12V_AUX  IN_B5 @S9S_MB_2U_LIB.S9S_MB_2U(SCH_1):P12V_AUX
  C3 P12V_AUX  IN_C3 @S9S_MB_2U_LIB.S9S_MB_2U(SCH_1):P12V_AUX
  C5 P12V_AUX  IN_C5 @S9S_MB_2U_LIB.S9S_MB_2U(SCH_1):P12V_AUX
  D5 P12V_AUX  IN_D5 @S9S_MB_2U_LIB.S9S_MB_2U(SCH_1):P12V_AUX
  B1 P12V_SCM_CB     CB @S9S_MB_2U_LIB.S9S_MB_2U(SCH_1):P12V_SCM_CB
  B7    GND    EN# @S9S_MB_2U_LIB.S9S_MB_2U(SCH_1):GND
  D1 P12V_SCM_REG    REG @S9S_MB_2U_LIB.S9S_MB_2U(SCH_1):P12V_SCM_REG
  D2 P12V_SCM_UV     UV @S9S_MB_2U_LIB.S9S_MB_2U(SCH_1):P12V_SCM_UV
  D3 P12V_SCM_OV     OV @S9S_MB_2U_LIB.S9S_MB_2U(SCH_1):P12V_SCM_OV
  A1 P12V_SCM_SENSE ISENSE @S9S_MB_2U_LIB.S9S_MB_2U(SCH_1):P12V_SCM_SENSE
  A4 P12V_SCM_R OUT_A4 @S9S_MB_2U_LIB.S9S_MB_2U(SCH_1):P12V_SCM_R
  B4 P12V_SCM_R OUT_B4 @S9S_MB_2U_LIB.S9S_MB_2U(SCH_1):P12V_SCM_R
  B6 P12V_SCM_R OUT_B6 @S9S_MB_2U_LIB.S9S_MB_2U(SCH_1):P12V_SCM_R
  C4 P12V_SCM_R OUT_C4 @S9S_MB_2U_LIB.S9S_MB_2U(SCH_1):P12V_SCM_R
  C6 P12V_SCM_R OUT_C6 @S9S_MB_2U_LIB.S9S_MB_2U(SCH_1):P12V_SCM_R
  D4 P12V_SCM_R OUT_D4 @S9S_MB_2U_LIB.S9S_MB_2U(SCH_1):P12V_SCM_R
  D6 P12V_SCM_R OUT_D6 @S9S_MB_2U_LIB.S9S_MB_2U(SCH_1):P12V_SCM_R
  A6 P12V_SCM_GATE   GATE @S9S_MB_2U_LIB.S9S_MB_2U(SCH_1):P12V_SCM_GATE
  A7    GND   CDLY @S9S_MB_2U_LIB.S9S_MB_2U(SCH_1):GND
  B2    GND GND_B2 @S9S_MB_2U_LIB.S9S_MB_2U(SCH_1):GND
  C1    GND GND_C1 @S9S_MB_2U_LIB.S9S_MB_2U(SCH_1):GND
  C2    GND GND_C2 @S9S_MB_2U_LIB.S9S_MB_2U(SCH_1):GND
  C7 P12V_SCM_FAULT_N FAULT# @S9S_MB_2U_LIB.S9S_MB_2U(SCH_1):P12V_SCM_FAULT_N
  D7 P12V_SCM_PWRGD     PG @S9S_MB_2U_LIB.S9S_MB_2U(SCH_1):P12V_SCM_PWRGD

Q_CAP_C0402-3900PF,50V,10%,EMPA  I75  PC2237
   1 P12V_SCM_GATE      A @S9S_MB_2U_LIB.S9S_MB_2U(SCH_1):P12V_SCM_GATE
   2    GND      B @S9S_MB_2U_LIB.S9S_MB_2U(SCH_1):GND

Q_RES_0402LF-0,5%,1/16W,EMPTY,A  I77  R4708
   1 P12V_SCM_FAULT_N      A @S9S_MB_2U_LIB.S9S_MB_2U(SCH_1):P12V_SCM_FAULT_N
   2 P12V_SCM_FAULT_R_N      B @S9S_MB_2U_LIB.S9S_MB_2U(SCH_1):P12V_SCM_FAULT_R_N

SCHOTTKY_AC-B340A-13-F,SMLF,ICA  I82  PD116
   A    GND      A @S9S_MB_2U_LIB.S9S_MB_2U(SCH_1):GND
   C P12V_SCM_R      C @S9S_MB_2U_LIB.S9S_MB_2U(SCH_1):P12V_SCM_R

Q_CAP_C0805-10UF,16V,10%,X6S,CC  I84  PC2240
   1 P12V_SCM_R      A @S9S_MB_2U_LIB.S9S_MB_2U(SCH_1):P12V_SCM_R
   2    GND      B @S9S_MB_2U_LIB.S9S_MB_2U(SCH_1):GND

Q_CAP_C0805-22UF,16V,20%,X6S,CC  I88  PC2242
   1 P12V_SCM_R      A @S9S_MB_2U_LIB.S9S_MB_2U(SCH_1):P12V_SCM_R
   2    GND      B @S9S_MB_2U_LIB.S9S_MB_2U(SCH_1):GND

RS31312R-RS31312R,SMLF,IC,AL03A  I90  PU299
  20 P12V_SCM_R VOUT_20 @S9S_MB_2U_LIB.S9S_MB_2U(SCH_1):P12V_SCM_R
21_22 P12V_AUX VIN_21_22 @S9S_MB_2U_LIB.S9S_MB_2U(SCH_1):P12V_AUX
  19 P12V_SCM_R VOUT_19 @S9S_MB_2U_LIB.S9S_MB_2U(SCH_1):P12V_SCM_R
  18 P12V_SCM_R VOUT_18 @S9S_MB_2U_LIB.S9S_MB_2U(SCH_1):P12V_SCM_R
  17 P12V_SCM_R VOUT_17 @S9S_MB_2U_LIB.S9S_MB_2U(SCH_1):P12V_SCM_R
  16 P12V_SCM_R VOUT_16 @S9S_MB_2U_LIB.S9S_MB_2U(SCH_1):P12V_SCM_R
  15 P12V_SCM_R VOUT_15 @S9S_MB_2U_LIB.S9S_MB_2U(SCH_1):P12V_SCM_R
  14 P12V_SCM_R VOUT_14 @S9S_MB_2U_LIB.S9S_MB_2U(SCH_1):P12V_SCM_R
  12 P12V_SCM_AVIN_PD   AVIN @S9S_MB_2U_LIB.S9S_MB_2U(SCH_1):P12V_SCM_AVIN_PD
  13 P12V_SCM_R VOUT_13 @S9S_MB_2U_LIB.S9S_MB_2U(SCH_1):P12V_SCM_R
  11 P12V_SCM_OV_FB     OV @S9S_MB_2U_LIB.S9S_MB_2U(SCH_1):P12V_SCM_OV_FB
  10 HP_LVC3_SCM_HSC_PWRGD_R     PG @S9S_MB_2U_LIB.S9S_MB_2U(SCH_1):HP_LVC3_SCM_HSC_PWRGD_R
   9 P12V_SCM_FLTB_N   FLTB @S9S_MB_2U_LIB.S9S_MB_2U(SCH_1):P12V_SCM_FLTB_N
   8 P12V_SCM_IMON   IMON @S9S_MB_2U_LIB.S9S_MB_2U(SCH_1):P12V_SCM_IMON
  23 P12V_AUX VIN_23 @S9S_MB_2U_LIB.S9S_MB_2U(SCH_1):P12V_AUX
  24 P12V_AUX VIN_24 @S9S_MB_2U_LIB.S9S_MB_2U(SCH_1):P12V_AUX
  25 P12V_AUX VIN_25 @S9S_MB_2U_LIB.S9S_MB_2U(SCH_1):P12V_AUX
  26 P12V_AUX VIN_26 @S9S_MB_2U_LIB.S9S_MB_2U(SCH_1):P12V_AUX
   1 P12V_SCM_EN_R2     EN @S9S_MB_2U_LIB.S9S_MB_2U(SCH_1):P12V_SCM_EN_R2
   2    GND LOADEN @S9S_MB_2U_LIB.S9S_MB_2U(SCH_1):GND
   3    GND   ENTM @S9S_MB_2U_LIB.S9S_MB_2U(SCH_1):GND
   4 P12V_SCM_TIMER  TIMER @S9S_MB_2U_LIB.S9S_MB_2U(SCH_1):P12V_SCM_TIMER
   5 P12V_SCM_ISET   ISET @S9S_MB_2U_LIB.S9S_MB_2U(SCH_1):P12V_SCM_ISET
   6 P12V_SCM_SS     SS @S9S_MB_2U_LIB.S9S_MB_2U(SCH_1):P12V_SCM_SS
   7    GND    GND @S9S_MB_2U_LIB.S9S_MB_2U(SCH_1):GND

Q_RES_0402LF-0,5%,1/16W,CHIP,CA  I91  R4770
   1 HP_LVC3_SCM_HSC_PWRGD_R      A @S9S_MB_2U_LIB.S9S_MB_2U(SCH_1):HP_LVC3_SCM_HSC_PWRGD_R
   2 HP_LVC3_SCM_HSC_PWRGD      B @S9S_MB_2U_LIB.S9S_MB_2U(SCH_1):HP_LVC3_SCM_HSC_PWRGD

Q_RES_0402LF-10K,1%,1/16W,CHIPA  I92  R3836
   1 P3V3_AUX      A @S9S_MB_2U_LIB.S9S_MB_2U(SCH_1):P3V3_AUX
   2 HP_LVC3_SCM_HSC_PWRGD_R      B @S9S_MB_2U_LIB.S9S_MB_2U(SCH_1):HP_LVC3_SCM_HSC_PWRGD_R


DRAWING: @S9S_MB_2U_LIB.S9S_MB_2U(SCH_1):PAGE321 

Q_RES_0402LF-1K,1%,1/16W,CHIP,A  I77  R4029
   1 PD_CPU0_ERRS_DIR      A @S9S_MB_2U_LIB.S9S_MB_2U(SCH_1):PD_CPU0_ERRS_DIR
   2    GND      B @S9S_MB_2U_LIB.S9S_MB_2U(SCH_1):GND

Q_RES_0402LF-33.2,1%,1/16W,CHIA  I78  R4021
   1 PWRGD_CPUPWRGD_LVC2_R      A @S9S_MB_2U_LIB.S9S_MB_2U(SCH_1):PWRGD_CPUPWRGD_LVC2_R
   2 PWRGD_CPUPWRGD_LVC2_R1      B @S9S_MB_2U_LIB.S9S_MB_2U(SCH_1):PWRGD_CPUPWRGD_LVC2_R1

Q_RES_0402LF-33.2,1%,1/16W,CHIA  I79  R4022
   1 H_CPU_RMCA_LVC2_R1_N      A @S9S_MB_2U_LIB.S9S_MB_2U(SCH_1):H_CPU_RMCA_LVC2_R1_N
   2 H_CPU_RMCA_LVC2_R2_N      B @S9S_MB_2U_LIB.S9S_MB_2U(SCH_1):H_CPU_RMCA_LVC2_R2_N

Q_RES_0402LF-33.2,1%,1/16W,CHIA  I80  R4023
   1 H_CPU_CATERR_LVC2_R1_N      A @S9S_MB_2U_LIB.S9S_MB_2U(SCH_1):H_CPU_CATERR_LVC2_R1_N
   2 H_CPU_CATERR_LVC2_R2_N      B @S9S_MB_2U_LIB.S9S_MB_2U(SCH_1):H_CPU_CATERR_LVC2_R2_N

Q_CAP_0402-0.1UF,25V,10%,X7R,CA  I83  C2249
   1 P0V62_CPU0_ERRS_VREF      A @S9S_MB_2U_LIB.S9S_MB_2U(SCH_1):P0V62_CPU0_ERRS_VREF
   2    GND      B @S9S_MB_2U_LIB.S9S_MB_2U(SCH_1):GND

Q_CAP_C0402-1UF,25V,10%,X6S,CHA  I85  C2243
   1   P3V3      A @S9S_MB_2U_LIB.S9S_MB_2U(SCH_1):P3V3
   2    GND      B @S9S_MB_2U_LIB.S9S_MB_2U(SCH_1):GND

GTL2014PW-GTL2014PW,SMLF,IC,ALA  I91  U301
   2 H_CPU_CATERR_LVC1_R_N     B0 @S9S_MB_2U_LIB.S9S_MB_2U(SCH_1):H_CPU_CATERR_LVC1_R_N
   3 H_CPU_CATERR_LVC1_R_N     B1 @S9S_MB_2U_LIB.S9S_MB_2U(SCH_1):H_CPU_CATERR_LVC1_R_N
   5 H_CPU_RMCA_LVC1_R_N     B2 @S9S_MB_2U_LIB.S9S_MB_2U(SCH_1):H_CPU_RMCA_LVC1_R_N
   6 PWRGD_CPUPWRGD_LVC1     B3 @S9S_MB_2U_LIB.S9S_MB_2U(SCH_1):PWRGD_CPUPWRGD_LVC1
  11    GND  GND_2 @S9S_MB_2U_LIB.S9S_MB_2U(SCH_1):GND
   8    GND  GND_1 @S9S_MB_2U_LIB.S9S_MB_2U(SCH_1):GND
   7    GND  GND_0 @S9S_MB_2U_LIB.S9S_MB_2U(SCH_1):GND
   9 PWRGD_CPUPWRGD_LVC2_R     A3 @S9S_MB_2U_LIB.S9S_MB_2U(SCH_1):PWRGD_CPUPWRGD_LVC2_R
  10 H_CPU_RMCA_LVC2_R1_N     A2 @S9S_MB_2U_LIB.S9S_MB_2U(SCH_1):H_CPU_RMCA_LVC2_R1_N
  12 H_CPU_CATERR_LVC2_R1_N     A1 @S9S_MB_2U_LIB.S9S_MB_2U(SCH_1):H_CPU_CATERR_LVC2_R1_N
  13 H_CPU_CATERR_LVC2_BMC_R_N     A0 @S9S_MB_2U_LIB.S9S_MB_2U(SCH_1):H_CPU_CATERR_LVC2_BMC_R_N
   1 PD_CPU0_ERRS_DIR    DIR @S9S_MB_2U_LIB.S9S_MB_2U(SCH_1):PD_CPU0_ERRS_DIR
   4 P0V62_CPU0_ERRS_VREF   VREF @S9S_MB_2U_LIB.S9S_MB_2U(SCH_1):P0V62_CPU0_ERRS_VREF
  14   P3V3    VCC @S9S_MB_2U_LIB.S9S_MB_2U(SCH_1):P3V3

Q_RES_0402LF-4.32K,1%,1/16W,CHA  I97  R4016
   1   P3V3      A @S9S_MB_2U_LIB.S9S_MB_2U(SCH_1):P3V3
   2 P0V62_CPU0_ERRS_VREF      B @S9S_MB_2U_LIB.S9S_MB_2U(SCH_1):P0V62_CPU0_ERRS_VREF

Q_RES_0402LF-1K,1%,1/16W,CHIP,A  I98  R4019
   1 P0V62_CPU0_ERRS_VREF      A @S9S_MB_2U_LIB.S9S_MB_2U(SCH_1):P0V62_CPU0_ERRS_VREF
   2    GND      B @S9S_MB_2U_LIB.S9S_MB_2U(SCH_1):GND

Q_RES_0402LF-33.2,1%,1/16W,CHIA  I101  R4621
   1 H_CPU_CATERR_LVC2_BMC_R_N      A @S9S_MB_2U_LIB.S9S_MB_2U(SCH_1):H_CPU_CATERR_LVC2_BMC_R_N
   2 H_CPU_CATERR_LVC2_BMC_N      B @S9S_MB_2U_LIB.S9S_MB_2U(SCH_1):H_CPU_CATERR_LVC2_BMC_N


DRAWING: @S9S_MB_2U_LIB.S9S_MB_2U(SCH_1):PAGE322 

Q_CAP_C0402-1UF,25V,10%,X6S,CHA  I9  C2246
   1 P3V3_AUX      A @S9S_MB_2U_LIB.S9S_MB_2U(SCH_1):P3V3_AUX
   2    GND      B @S9S_MB_2U_LIB.S9S_MB_2U(SCH_1):GND

GTL2014PW-GTL2014PW,SMLF,IC,ALA  I27  U304
   2 RST_CPU0_DRAM_GH_PLD_N     B0 @S9S_MB_2U_LIB.S9S_MB_2U(SCH_1):RST_CPU0_DRAM_GH_PLD_N
   3 RST_CPU0_DRAM_EF_PLD_N     B1 @S9S_MB_2U_LIB.S9S_MB_2U(SCH_1):RST_CPU0_DRAM_EF_PLD_N
   5 RST_CPU0_DRAM_CD_PLD_N     B2 @S9S_MB_2U_LIB.S9S_MB_2U(SCH_1):RST_CPU0_DRAM_CD_PLD_N
   6 RST_CPU0_DRAM_AB_PLD_N     B3 @S9S_MB_2U_LIB.S9S_MB_2U(SCH_1):RST_CPU0_DRAM_AB_PLD_N
  11    GND  GND_2 @S9S_MB_2U_LIB.S9S_MB_2U(SCH_1):GND
   8    GND  GND_1 @S9S_MB_2U_LIB.S9S_MB_2U(SCH_1):GND
   7    GND  GND_0 @S9S_MB_2U_LIB.S9S_MB_2U(SCH_1):GND
   9 RST_CPU0_DRAM_AB_PLD_LVT3_R_N     A3 @S9S_MB_2U_LIB.S9S_MB_2U(SCH_1):RST_CPU0_DRAM_AB_PLD_LVT3_R_N
  10 RST_CPU0_DRAM_CD_PLD_LVT3_R_N     A2 @S9S_MB_2U_LIB.S9S_MB_2U(SCH_1):RST_CPU0_DRAM_CD_PLD_LVT3_R_N
  12 RST_CPU0_DRAM_EF_PLD_LVT3_R_N     A1 @S9S_MB_2U_LIB.S9S_MB_2U(SCH_1):RST_CPU0_DRAM_EF_PLD_LVT3_R_N
  13 RST_CPU0_DRAM_GH_PLD_LVT3_R_N     A0 @S9S_MB_2U_LIB.S9S_MB_2U(SCH_1):RST_CPU0_DRAM_GH_PLD_LVT3_R_N
   1 PD_GTL2014_BMC_JTAG_DIR_0    DIR @S9S_MB_2U_LIB.S9S_MB_2U(SCH_1):PD_GTL2014_BMC_JTAG_DIR_0
   4 P0V62_CPU0_RST_DDR_VREF   VREF @S9S_MB_2U_LIB.S9S_MB_2U(SCH_1):P0V62_CPU0_RST_DDR_VREF
  14 P3V3_AUX    VCC @S9S_MB_2U_LIB.S9S_MB_2U(SCH_1):P3V3_AUX

Q_RES_0402LF-33.2,1%,1/16W,CHIA  I36  R4045
   1 RST_CPU0_DRAM_GH_PLD_LVT3_R_N      A @S9S_MB_2U_LIB.S9S_MB_2U(SCH_1):RST_CPU0_DRAM_GH_PLD_LVT3_R_N
   2 RST_CPU0_DRAM_GH_PLD_LVT3_N      B @S9S_MB_2U_LIB.S9S_MB_2U(SCH_1):RST_CPU0_DRAM_GH_PLD_LVT3_N

Q_RES_0402LF-33.2,1%,1/16W,CHIA  I37  R4044
   1 RST_CPU0_DRAM_EF_PLD_LVT3_R_N      A @S9S_MB_2U_LIB.S9S_MB_2U(SCH_1):RST_CPU0_DRAM_EF_PLD_LVT3_R_N
   2 RST_CPU0_DRAM_EF_PLD_LVT3_N      B @S9S_MB_2U_LIB.S9S_MB_2U(SCH_1):RST_CPU0_DRAM_EF_PLD_LVT3_N

Q_RES_0402LF-33.2,1%,1/16W,CHIA  I38  R4043
   1 RST_CPU0_DRAM_CD_PLD_LVT3_R_N      A @S9S_MB_2U_LIB.S9S_MB_2U(SCH_1):RST_CPU0_DRAM_CD_PLD_LVT3_R_N
   2 RST_CPU0_DRAM_CD_PLD_LVT3_N      B @S9S_MB_2U_LIB.S9S_MB_2U(SCH_1):RST_CPU0_DRAM_CD_PLD_LVT3_N

Q_RES_0402LF-33.2,1%,1/16W,CHIA  I39  R4042
   1 RST_CPU0_DRAM_AB_PLD_LVT3_R_N      A @S9S_MB_2U_LIB.S9S_MB_2U(SCH_1):RST_CPU0_DRAM_AB_PLD_LVT3_R_N
   2 RST_CPU0_DRAM_AB_PLD_LVT3_N      B @S9S_MB_2U_LIB.S9S_MB_2U(SCH_1):RST_CPU0_DRAM_AB_PLD_LVT3_N

GTL2014PW-GTL2014PW,SMLF,IC,ALA  I44  U305
   2 RST_CPU1_DRAM_GH_PLD_N     B0 @S9S_MB_2U_LIB.S9S_MB_2U(SCH_1):RST_CPU1_DRAM_GH_PLD_N
   3 RST_CPU1_DRAM_EF_PLD_N     B1 @S9S_MB_2U_LIB.S9S_MB_2U(SCH_1):RST_CPU1_DRAM_EF_PLD_N
   5 RST_CPU1_DRAM_CD_PLD_N     B2 @S9S_MB_2U_LIB.S9S_MB_2U(SCH_1):RST_CPU1_DRAM_CD_PLD_N
   6 RST_CPU1_DRAM_AB_PLD_N     B3 @S9S_MB_2U_LIB.S9S_MB_2U(SCH_1):RST_CPU1_DRAM_AB_PLD_N
  11    GND  GND_2 @S9S_MB_2U_LIB.S9S_MB_2U(SCH_1):GND
   8    GND  GND_1 @S9S_MB_2U_LIB.S9S_MB_2U(SCH_1):GND
   7    GND  GND_0 @S9S_MB_2U_LIB.S9S_MB_2U(SCH_1):GND
   9 RST_CPU1_DRAM_AB_PLD_LVT3_R_N     A3 @S9S_MB_2U_LIB.S9S_MB_2U(SCH_1):RST_CPU1_DRAM_AB_PLD_LVT3_R_N
  10 RST_CPU1_DRAM_CD_PLD_LVT3_R_N     A2 @S9S_MB_2U_LIB.S9S_MB_2U(SCH_1):RST_CPU1_DRAM_CD_PLD_LVT3_R_N
  12 RST_CPU1_DRAM_EF_PLD_LVT3_R_N     A1 @S9S_MB_2U_LIB.S9S_MB_2U(SCH_1):RST_CPU1_DRAM_EF_PLD_LVT3_R_N
  13 RST_CPU1_DRAM_GH_PLD_LVT3_R_N     A0 @S9S_MB_2U_LIB.S9S_MB_2U(SCH_1):RST_CPU1_DRAM_GH_PLD_LVT3_R_N
   1 PD_GTL2014_BMC_JTAG_DIR_1    DIR @S9S_MB_2U_LIB.S9S_MB_2U(SCH_1):PD_GTL2014_BMC_JTAG_DIR_1
   4 P0V62_CPU1_RST_DDR_VREF   VREF @S9S_MB_2U_LIB.S9S_MB_2U(SCH_1):P0V62_CPU1_RST_DDR_VREF
  14 P3V3_AUX    VCC @S9S_MB_2U_LIB.S9S_MB_2U(SCH_1):P3V3_AUX

Q_RES_0402LF-33.2,1%,1/16W,CHIA  I52  R4046
   1 RST_CPU1_DRAM_AB_PLD_LVT3_R_N      A @S9S_MB_2U_LIB.S9S_MB_2U(SCH_1):RST_CPU1_DRAM_AB_PLD_LVT3_R_N
   2 RST_CPU1_DRAM_AB_PLD_LVT3_N      B @S9S_MB_2U_LIB.S9S_MB_2U(SCH_1):RST_CPU1_DRAM_AB_PLD_LVT3_N

Q_RES_0402LF-33.2,1%,1/16W,CHIA  I53  R4047
   1 RST_CPU1_DRAM_CD_PLD_LVT3_R_N      A @S9S_MB_2U_LIB.S9S_MB_2U(SCH_1):RST_CPU1_DRAM_CD_PLD_LVT3_R_N
   2 RST_CPU1_DRAM_CD_PLD_LVT3_N      B @S9S_MB_2U_LIB.S9S_MB_2U(SCH_1):RST_CPU1_DRAM_CD_PLD_LVT3_N

Q_RES_0402LF-33.2,1%,1/16W,CHIA  I54  R4049
   1 RST_CPU1_DRAM_GH_PLD_LVT3_R_N      A @S9S_MB_2U_LIB.S9S_MB_2U(SCH_1):RST_CPU1_DRAM_GH_PLD_LVT3_R_N
   2 RST_CPU1_DRAM_GH_PLD_LVT3_N      B @S9S_MB_2U_LIB.S9S_MB_2U(SCH_1):RST_CPU1_DRAM_GH_PLD_LVT3_N

Q_RES_0402LF-33.2,1%,1/16W,CHIA  I55  R4048
   1 RST_CPU1_DRAM_EF_PLD_LVT3_R_N      A @S9S_MB_2U_LIB.S9S_MB_2U(SCH_1):RST_CPU1_DRAM_EF_PLD_LVT3_R_N
   2 RST_CPU1_DRAM_EF_PLD_LVT3_N      B @S9S_MB_2U_LIB.S9S_MB_2U(SCH_1):RST_CPU1_DRAM_EF_PLD_LVT3_N

Q_CAP_C0402-1UF,25V,10%,X6S,CHA  I59  C2247
   1 P3V3_AUX      A @S9S_MB_2U_LIB.S9S_MB_2U(SCH_1):P3V3_AUX
   2    GND      B @S9S_MB_2U_LIB.S9S_MB_2U(SCH_1):GND

Q_RES_0402LF-1K,1%,1/16W,CHIP,A  I66  R4053
   1 PD_GTL2014_BMC_JTAG_DIR_0      A @S9S_MB_2U_LIB.S9S_MB_2U(SCH_1):PD_GTL2014_BMC_JTAG_DIR_0
   2    GND      B @S9S_MB_2U_LIB.S9S_MB_2U(SCH_1):GND

Q_RES_0402LF-1K,1%,1/16W,CHIP,A  I67  R4054
   1 PD_GTL2014_BMC_JTAG_DIR_1      A @S9S_MB_2U_LIB.S9S_MB_2U(SCH_1):PD_GTL2014_BMC_JTAG_DIR_1
   2    GND      B @S9S_MB_2U_LIB.S9S_MB_2U(SCH_1):GND

GTL2014PW-GTL2014PW,SMLF,IC,ALA  I80  U306
   2 PD_GTL2014_ERROR_B0     B0 @S9S_MB_2U_LIB.S9S_MB_2U(SCH_1):PD_GTL2014_ERROR_B0
   3 H_CPU_ERR2_LVC1_N     B1 @S9S_MB_2U_LIB.S9S_MB_2U(SCH_1):H_CPU_ERR2_LVC1_N
   5 H_CPU_ERR1_LVC1_N     B2 @S9S_MB_2U_LIB.S9S_MB_2U(SCH_1):H_CPU_ERR1_LVC1_N
   6 H_CPU_ERR0_LVC1_N     B3 @S9S_MB_2U_LIB.S9S_MB_2U(SCH_1):H_CPU_ERR0_LVC1_N
  11    GND  GND_2 @S9S_MB_2U_LIB.S9S_MB_2U(SCH_1):GND
   8    GND  GND_1 @S9S_MB_2U_LIB.S9S_MB_2U(SCH_1):GND
   7    GND  GND_0 @S9S_MB_2U_LIB.S9S_MB_2U(SCH_1):GND
   9 H_CPU_ERR0_LVC2_R_N     A3 @S9S_MB_2U_LIB.S9S_MB_2U(SCH_1):H_CPU_ERR0_LVC2_R_N
  10 H_CPU_ERR1_LVC2_R_N     A2 @S9S_MB_2U_LIB.S9S_MB_2U(SCH_1):H_CPU_ERR1_LVC2_R_N
  12 H_CPU_ERR2_LVC2_R_N     A1 @S9S_MB_2U_LIB.S9S_MB_2U(SCH_1):H_CPU_ERR2_LVC2_R_N
  13 NC_U306_A0     A0 @S9S_MB_2U_LIB.S9S_MB_2U(SCH_1):NC_U306_A0
   1 PD_CPU1_ERRS_U306_DIR    DIR @S9S_MB_2U_LIB.S9S_MB_2U(SCH_1):PD_CPU1_ERRS_U306_DIR
   4 P0V62_CPU0_ERRS_U306_VREF   VREF @S9S_MB_2U_LIB.S9S_MB_2U(SCH_1):P0V62_CPU0_ERRS_U306_VREF
  14   P3V3    VCC @S9S_MB_2U_LIB.S9S_MB_2U(SCH_1):P3V3

Q_CAP_C0402-1UF,25V,10%,X6S,CHA  I83  C2248
   1   P3V3      A @S9S_MB_2U_LIB.S9S_MB_2U(SCH_1):P3V3
   2    GND      B @S9S_MB_2U_LIB.S9S_MB_2U(SCH_1):GND

Q_RES_0402LF-1K,1%,1/16W,CHIP,A  I91  R4055
   1 PD_CPU1_ERRS_U306_DIR      A @S9S_MB_2U_LIB.S9S_MB_2U(SCH_1):PD_CPU1_ERRS_U306_DIR
   2    GND      B @S9S_MB_2U_LIB.S9S_MB_2U(SCH_1):GND

Q_RES_0402LF-33.2,1%,1/16W,CHIA  I94  R4051
   1 H_CPU_ERR1_LVC2_R_N      A @S9S_MB_2U_LIB.S9S_MB_2U(SCH_1):H_CPU_ERR1_LVC2_R_N
   2 H_CPU_ERR1_LVC2_N      B @S9S_MB_2U_LIB.S9S_MB_2U(SCH_1):H_CPU_ERR1_LVC2_N

Q_CAP_0402-0.1UF,25V,10%,X7R,CA  I101  C2252
   1 P0V62_CPU0_RST_DDR_VREF      A @S9S_MB_2U_LIB.S9S_MB_2U(SCH_1):P0V62_CPU0_RST_DDR_VREF
   2    GND      B @S9S_MB_2U_LIB.S9S_MB_2U(SCH_1):GND

Q_CAP_0402-0.1UF,25V,10%,X7R,CA  I106  C2253
   1 P0V62_CPU1_RST_DDR_VREF      A @S9S_MB_2U_LIB.S9S_MB_2U(SCH_1):P0V62_CPU1_RST_DDR_VREF
   2    GND      B @S9S_MB_2U_LIB.S9S_MB_2U(SCH_1):GND

Q_CAP_0402-0.1UF,25V,10%,X7R,CA  I111  C2254
   1 P0V62_CPU0_ERRS_U306_VREF      A @S9S_MB_2U_LIB.S9S_MB_2U(SCH_1):P0V62_CPU0_ERRS_U306_VREF
   2    GND      B @S9S_MB_2U_LIB.S9S_MB_2U(SCH_1):GND

Q_RES_0402LF-4.32K,1%,1/16W,CHA  I128  R4036
   1 P3V3_AUX      A @S9S_MB_2U_LIB.S9S_MB_2U(SCH_1):P3V3_AUX
   2 P0V62_CPU0_RST_DDR_VREF      B @S9S_MB_2U_LIB.S9S_MB_2U(SCH_1):P0V62_CPU0_RST_DDR_VREF

Q_RES_0402LF-1K,1%,1/16W,CHIP,A  I129  R4039
   1 P0V62_CPU0_RST_DDR_VREF      A @S9S_MB_2U_LIB.S9S_MB_2U(SCH_1):P0V62_CPU0_RST_DDR_VREF
   2    GND      B @S9S_MB_2U_LIB.S9S_MB_2U(SCH_1):GND

Q_RES_0402LF-4.32K,1%,1/16W,CHA  I130  R4037
   1 P3V3_AUX      A @S9S_MB_2U_LIB.S9S_MB_2U(SCH_1):P3V3_AUX
   2 P0V62_CPU1_RST_DDR_VREF      B @S9S_MB_2U_LIB.S9S_MB_2U(SCH_1):P0V62_CPU1_RST_DDR_VREF

Q_RES_0402LF-1K,1%,1/16W,CHIP,A  I131  R4040
   1 P0V62_CPU1_RST_DDR_VREF      A @S9S_MB_2U_LIB.S9S_MB_2U(SCH_1):P0V62_CPU1_RST_DDR_VREF
   2    GND      B @S9S_MB_2U_LIB.S9S_MB_2U(SCH_1):GND

Q_RES_0402LF-0,5%,1/16W,CHIP,CA  I157  R344
   1 H_CPU0_ERR2_LVC1_R_N      A @S9S_MB_2U_LIB.S9S_MB_2U(SCH_1):H_CPU0_ERR2_LVC1_R_N
   2 H_CPU_ERR2_LVC1_R_N      B @S9S_MB_2U_LIB.S9S_MB_2U(SCH_1):H_CPU_ERR2_LVC1_R_N

Q_RES_0402LF-0,5%,1/16W,CHIP,CA  I158  R345
   1 H_CPU1_ERR2_LVC1_R_N      A @S9S_MB_2U_LIB.S9S_MB_2U(SCH_1):H_CPU1_ERR2_LVC1_R_N
   2 H_CPU_ERR2_LVC1_R_N      B @S9S_MB_2U_LIB.S9S_MB_2U(SCH_1):H_CPU_ERR2_LVC1_R_N

Q_RES_0402LF-0,5%,1/16W,CHIP,CA  I159  R336
   1 H_CPU0_ERR0_LVC1_R_N      A @S9S_MB_2U_LIB.S9S_MB_2U(SCH_1):H_CPU0_ERR0_LVC1_R_N
   2 H_CPU_ERR0_LVC1_R_N      B @S9S_MB_2U_LIB.S9S_MB_2U(SCH_1):H_CPU_ERR0_LVC1_R_N

Q_RES_0402LF-0,5%,1/16W,CHIP,CA  I160  R337
   1 H_CPU1_ERR0_LVC1_R_N      A @S9S_MB_2U_LIB.S9S_MB_2U(SCH_1):H_CPU1_ERR0_LVC1_R_N
   2 H_CPU_ERR0_LVC1_R_N      B @S9S_MB_2U_LIB.S9S_MB_2U(SCH_1):H_CPU_ERR0_LVC1_R_N

Q_RES_0402LF-0,5%,1/16W,CHIP,CA  I163  R341
   1 H_CPU1_ERR1_LVC1_R_N      A @S9S_MB_2U_LIB.S9S_MB_2U(SCH_1):H_CPU1_ERR1_LVC1_R_N
   2 H_CPU_ERR1_LVC1_R_N      B @S9S_MB_2U_LIB.S9S_MB_2U(SCH_1):H_CPU_ERR1_LVC1_R_N

Q_RES_0402LF-0,5%,1/16W,CHIP,CA  I164  R340
   1 H_CPU0_ERR1_LVC1_R_N      A @S9S_MB_2U_LIB.S9S_MB_2U(SCH_1):H_CPU0_ERR1_LVC1_R_N
   2 H_CPU_ERR1_LVC1_R_N      B @S9S_MB_2U_LIB.S9S_MB_2U(SCH_1):H_CPU_ERR1_LVC1_R_N

Q_RES_0402LF-150,1%,1/16W,CHIPA  I169  R4390
   1 PVNN_TERM_CPU0      A @S9S_MB_2U_LIB.S9S_MB_2U(SCH_1):PVNN_TERM_CPU0
   2 H_CPU_ERR0_LVC1_R_N      B @S9S_MB_2U_LIB.S9S_MB_2U(SCH_1):H_CPU_ERR0_LVC1_R_N

Q_RES_0402LF-0,5%,1/16W,CHIP,CA  I171  R346
   1 H_CPU_ERR2_LVC1_R_N      A @S9S_MB_2U_LIB.S9S_MB_2U(SCH_1):H_CPU_ERR2_LVC1_R_N
   2 H_CPU_ERR2_LVC1_N      B @S9S_MB_2U_LIB.S9S_MB_2U(SCH_1):H_CPU_ERR2_LVC1_N

Q_RES_0402LF-0,5%,1/16W,CHIP,CA  I172  R342
   1 H_CPU_ERR1_LVC1_R_N      A @S9S_MB_2U_LIB.S9S_MB_2U(SCH_1):H_CPU_ERR1_LVC1_R_N
   2 H_CPU_ERR1_LVC1_N      B @S9S_MB_2U_LIB.S9S_MB_2U(SCH_1):H_CPU_ERR1_LVC1_N

Q_RES_0402LF-0,5%,1/16W,CHIP,CA  I173  R338
   1 H_CPU_ERR0_LVC1_R_N      A @S9S_MB_2U_LIB.S9S_MB_2U(SCH_1):H_CPU_ERR0_LVC1_R_N
   2 H_CPU_ERR0_LVC1_N      B @S9S_MB_2U_LIB.S9S_MB_2U(SCH_1):H_CPU_ERR0_LVC1_N

Q_RES_0402LF-150,1%,1/16W,CHIPA  I174  R4388
   1 PVNN_TERM_CPU0      A @S9S_MB_2U_LIB.S9S_MB_2U(SCH_1):PVNN_TERM_CPU0
   2 H_CPU_ERR1_LVC1_R_N      B @S9S_MB_2U_LIB.S9S_MB_2U(SCH_1):H_CPU_ERR1_LVC1_R_N

Q_RES_0402LF-150,1%,1/16W,CHIPA  I177  R4389
   1 PVNN_TERM_CPU0      A @S9S_MB_2U_LIB.S9S_MB_2U(SCH_1):PVNN_TERM_CPU0
   2 H_CPU_ERR2_LVC1_R_N      B @S9S_MB_2U_LIB.S9S_MB_2U(SCH_1):H_CPU_ERR2_LVC1_R_N

Q_RES_0402LF-1K,1%,1/16W,CHIP,A  I181  R4041
   1 P0V62_CPU0_ERRS_U306_VREF      A @S9S_MB_2U_LIB.S9S_MB_2U(SCH_1):P0V62_CPU0_ERRS_U306_VREF
   2    GND      B @S9S_MB_2U_LIB.S9S_MB_2U(SCH_1):GND

Q_RES_0402LF-4.32K,1%,1/16W,CHA  I182  R4038
   1   P3V3      A @S9S_MB_2U_LIB.S9S_MB_2U(SCH_1):P3V3
   2 P0V62_CPU0_ERRS_U306_VREF      B @S9S_MB_2U_LIB.S9S_MB_2U(SCH_1):P0V62_CPU0_ERRS_U306_VREF

Q_RES_0402LF-33.2,1%,1/16W,CHIA  I183  R4392
   1 H_CPU_ERR0_LVC2_R_N      A @S9S_MB_2U_LIB.S9S_MB_2U(SCH_1):H_CPU_ERR0_LVC2_R_N
   2 H_CPU_ERR0_PCH_R_N      B @S9S_MB_2U_LIB.S9S_MB_2U(SCH_1):H_CPU_ERR0_PCH_R_N

Q_RES_0402LF-33.2,1%,1/16W,CHIA  I184  R4050
   1 H_CPU_ERR0_LVC2_R_N      A @S9S_MB_2U_LIB.S9S_MB_2U(SCH_1):H_CPU_ERR0_LVC2_R_N
   2 H_CPU_ERR0_LVC2_N      B @S9S_MB_2U_LIB.S9S_MB_2U(SCH_1):H_CPU_ERR0_LVC2_N

Q_RES_0402LF-33.2,1%,1/16W,CHIA  I187  R4052
   1 H_CPU_ERR2_LVC2_R_N      A @S9S_MB_2U_LIB.S9S_MB_2U(SCH_1):H_CPU_ERR2_LVC2_R_N
   2 H_CPU_ERR2_LVC2_N      B @S9S_MB_2U_LIB.S9S_MB_2U(SCH_1):H_CPU_ERR2_LVC2_N

Q_RES_0402LF-33.2,1%,1/16W,CHIA  I188  R4393
   1 H_CPU_ERR1_LVC2_R_N      A @S9S_MB_2U_LIB.S9S_MB_2U(SCH_1):H_CPU_ERR1_LVC2_R_N
   2 H_CPU_ERR1_PCH_R_N      B @S9S_MB_2U_LIB.S9S_MB_2U(SCH_1):H_CPU_ERR1_PCH_R_N

Q_RES_0402LF-33.2,1%,1/16W,CHIA  I189  R4394
   1 H_CPU_ERR2_LVC2_R_N      A @S9S_MB_2U_LIB.S9S_MB_2U(SCH_1):H_CPU_ERR2_LVC2_R_N
   2 H_CPU_ERR2_PCH_R_N      B @S9S_MB_2U_LIB.S9S_MB_2U(SCH_1):H_CPU_ERR2_PCH_R_N

Q_RES_0402LF-150,1%,1/16W,CHIPA  I190  R4391
   1 PD_GTL2014_ERROR_B0      A @S9S_MB_2U_LIB.S9S_MB_2U(SCH_1):PD_GTL2014_ERROR_B0
   2    GND      B @S9S_MB_2U_LIB.S9S_MB_2U(SCH_1):GND


DRAWING: @S9S_MB_2U_LIB.S9S_MB_2U(SCH_1):PAGE153 

Q_RES_0402LF-1K,1%,1/16W,CHIP,A  I22  R1908
   1 P3V3_AUX      A @S9S_MB_2U_LIB.S9S_MB_2U(SCH_1):P3V3_AUX
   2 OCP_SFF_PRSNT3_R_N      B @S9S_MB_2U_LIB.S9S_MB_2U(SCH_1):OCP_SFF_PRSNT3_R_N

Q_RES_0402LF-0,5%,1/16W,CHIP,CA  I45  R4752
   1 HP_LVC3_OCP_V3_1_PRSNT2_N_R      A @S9S_MB_2U_LIB.S9S_MB_2U(SCH_1):HP_LVC3_OCP_V3_1_PRSNT2_N_R
   2 HP_LVC3_OCP_V3_1_PRSNT2_PLD_N      B @S9S_MB_2U_LIB.S9S_MB_2U(SCH_1):HP_LVC3_OCP_V3_1_PRSNT2_PLD_N

Q_RES_0402LF-0,5%,1/16W,CHIP,CA  I47  R1147
   1 HP_LVC3_OCP_V3_1_PRSNT2_N_R      A @S9S_MB_2U_LIB.S9S_MB_2U(SCH_1):HP_LVC3_OCP_V3_1_PRSNT2_N_R
   2 HP_LVC3_OCP_V3_1_ATTN_OUT_SW_N      B @S9S_MB_2U_LIB.S9S_MB_2U(SCH_1):HP_LVC3_OCP_V3_1_ATTN_OUT_SW_N

Q_RES_0402LF-30.1K,1%,1/16W,EMA  I49  PR5484
   1 P12V_OCP_CB_1      A @S9S_MB_2U_LIB.S9S_MB_2U(SCH_1):P12V_OCP_CB_1
   2    GND      B @S9S_MB_2U_LIB.S9S_MB_2U(SCH_1):GND

Q_CAP_C0402-1UF,25V,10%,EMPTY,A  I54  PC2087
   1    GND      A @S9S_MB_2U_LIB.S9S_MB_2U(SCH_1):GND
   2 P12V_OCP_REG_1      B @S9S_MB_2U_LIB.S9S_MB_2U(SCH_1):P12V_OCP_REG_1

Q_CAP_C0402-1UF,25V,10%,EMPTY,A  I55  PC2085
   1 P12V_OCP_VCC_1      A @S9S_MB_2U_LIB.S9S_MB_2U(SCH_1):P12V_OCP_VCC_1
   2    GND      B @S9S_MB_2U_LIB.S9S_MB_2U(SCH_1):GND

Q_RES_0402LF-25.5K,1%,1/16W,CHA  I70  PR3789
   1 P3V3_AUX      A @S9S_MB_2U_LIB.S9S_MB_2U(SCH_1):P3V3_AUX
   2 P3V3_OCP_UV_1      B @S9S_MB_2U_LIB.S9S_MB_2U(SCH_1):P3V3_OCP_UV_1

Q_RES_0402LF-10K,1%,1/16W,CHIPA  I74  R1150
   1 P3V3_AUX      A @S9S_MB_2U_LIB.S9S_MB_2U(SCH_1):P3V3_AUX
   2 HP_LVC3_OCP_V3_1_PRSNT2_N      B @S9S_MB_2U_LIB.S9S_MB_2U(SCH_1):HP_LVC3_OCP_V3_1_PRSNT2_N

Q_RES_0402LF-10K,1%,1/16W,CHIPA  I76  R4762
   1 P3V3_AUX      A @S9S_MB_2U_LIB.S9S_MB_2U(SCH_1):P3V3_AUX
   2 HP_LVC3_OCP_V3_1_PRSNT2_PLD_N      B @S9S_MB_2U_LIB.S9S_MB_2U(SCH_1):HP_LVC3_OCP_V3_1_PRSNT2_PLD_N

Q_RES_0402LF-845,1%,1/16W,EMPTA  I80  PR3781
   1 P12V_OCP_SENSE_1      A @S9S_MB_2U_LIB.S9S_MB_2U(SCH_1):P12V_OCP_SENSE_1
   2    GND      B @S9S_MB_2U_LIB.S9S_MB_2U(SCH_1):GND

Q_CAP_C0402-0.01UF,50V,10%,EMPA  I81  PC2088
   1 P12V_OCP_SFF      A @S9S_MB_2U_LIB.S9S_MB_2U(SCH_1):P12V_OCP_SFF
   2 P12V_OCP_GATE_1      B @S9S_MB_2U_LIB.S9S_MB_2U(SCH_1):P12V_OCP_GATE_1

Q_CAP_0402-0.1UF,25V,10%,X7R,CA  I93  PC2092
   1 P12V_OCP_SFF      A @S9S_MB_2U_LIB.S9S_MB_2U(SCH_1):P12V_OCP_SFF
   2    GND      B @S9S_MB_2U_LIB.S9S_MB_2U(SCH_1):GND

Q_CAP_C0805-10UF,16V,10%,X6S,CC  I96  PC2082
   1 P12V_OCP_SFF      A @S9S_MB_2U_LIB.S9S_MB_2U(SCH_1):P12V_OCP_SFF
   2    GND      B @S9S_MB_2U_LIB.S9S_MB_2U(SCH_1):GND

Q_CAP_C0402-6800PF,50V,10%,X7RA  I107  PC2089
   1 P3V3_OCP_GATE_PU202_1      A @S9S_MB_2U_LIB.S9S_MB_2U(SCH_1):P3V3_OCP_GATE_PU202_1
   2    GND      B @S9S_MB_2U_LIB.S9S_MB_2U(SCH_1):GND

Q_RES_0402LF-0,5%,1/16W,EMPTY,A  I4  R4061
   1 HP_LVC3_OCP_V3_1_EN      A @S9S_MB_2U_LIB.S9S_MB_2U(SCH_1):HP_LVC3_OCP_V3_1_EN
   2 P12V_OCP_EN_1_R      B @S9S_MB_2U_LIB.S9S_MB_2U(SCH_1):P12V_OCP_EN_1_R

MOSFET_NCH_DUAL-PJT138K,SMLF,EA  I17  Q123
   3 P12V_OCP_UV_1_R     D2 @S9S_MB_2U_LIB.S9S_MB_2U(SCH_1):P12V_OCP_UV_1_R
   5 P12V_OCP_1_EN_G     G2 @S9S_MB_2U_LIB.S9S_MB_2U(SCH_1):P12V_OCP_1_EN_G
   4    GND     S2 @S9S_MB_2U_LIB.S9S_MB_2U(SCH_1):GND

Q_RES_0402LF-4.7K,5%,1/16W,CHIA  I20  R4069
   1 P3V3_OCP_EN_1_R      A @S9S_MB_2U_LIB.S9S_MB_2U(SCH_1):P3V3_OCP_EN_1_R
   2    GND      B @S9S_MB_2U_LIB.S9S_MB_2U(SCH_1):GND

74LVC2G07DW7-74LVC2G07DW-7,SMLA  I23  U212
   1 OCP_SFF_PRSNT2_R_N     1A @S9S_MB_2U_LIB.S9S_MB_2U(SCH_1):OCP_SFF_PRSNT2_R_N
   3 OCP_SFF_PRSNT3_R_N     2A @S9S_MB_2U_LIB.S9S_MB_2U(SCH_1):OCP_SFF_PRSNT3_R_N
   6 HP_LVC3_OCP_V3_1_PRSNT2_N_R     1Y @S9S_MB_2U_LIB.S9S_MB_2U(SCH_1):HP_LVC3_OCP_V3_1_PRSNT2_N_R
   4 HP_LVC3_OCP_V3_1_PRSNT2_N_R     2Y @S9S_MB_2U_LIB.S9S_MB_2U(SCH_1):HP_LVC3_OCP_V3_1_PRSNT2_N_R
   2    GND    GND @S9S_MB_2U_LIB.S9S_MB_2U(SCH_1):GND
   5 P3V3_AUX    VCC @S9S_MB_2U_LIB.S9S_MB_2U(SCH_1):P3V3_AUX

74LVC2G07DW7-74LVC2G07DW-7,SMLA  I26  U211
   1 OCP_SFF_PRSNT0_R_N     1A @S9S_MB_2U_LIB.S9S_MB_2U(SCH_1):OCP_SFF_PRSNT0_R_N
   3 OCP_SFF_PRSNT1_R_N     2A @S9S_MB_2U_LIB.S9S_MB_2U(SCH_1):OCP_SFF_PRSNT1_R_N
   6 HP_LVC3_OCP_V3_1_PRSNT2_N_R     1Y @S9S_MB_2U_LIB.S9S_MB_2U(SCH_1):HP_LVC3_OCP_V3_1_PRSNT2_N_R
   4 HP_LVC3_OCP_V3_1_PRSNT2_N_R     2Y @S9S_MB_2U_LIB.S9S_MB_2U(SCH_1):HP_LVC3_OCP_V3_1_PRSNT2_N_R
   2    GND    GND @S9S_MB_2U_LIB.S9S_MB_2U(SCH_1):GND
   5 P3V3_AUX    VCC @S9S_MB_2U_LIB.S9S_MB_2U(SCH_1):P3V3_AUX

Q_CAP_0402-0.1UF,25V,10%,X7R,CA  I27  C593
   1 P3V3_AUX      A @S9S_MB_2U_LIB.S9S_MB_2U(SCH_1):P3V3_AUX
   2    GND      B @S9S_MB_2U_LIB.S9S_MB_2U(SCH_1):GND

DIODE_TVS-SMF14A,SMLF,IC,BCSMFA  I38  PD101
   A    GND      A @S9S_MB_2U_LIB.S9S_MB_2U(SCH_1):GND
   C P12V_AUX      C @S9S_MB_2U_LIB.S9S_MB_2U(SCH_1):P12V_AUX

Q_RES_0402LF-6.8K,1%,1/16W,EMPA  I41  PR3787
   1 P12V_OCP_UV_1      A @S9S_MB_2U_LIB.S9S_MB_2U(SCH_1):P12V_OCP_UV_1
   2 P12V_OCP_OV_1      B @S9S_MB_2U_LIB.S9S_MB_2U(SCH_1):P12V_OCP_OV_1

Q_RES_0402LF-10K,1%,1/16W,CHIPA  I50  R1149
   1 P3V3_AUX      A @S9S_MB_2U_LIB.S9S_MB_2U(SCH_1):P3V3_AUX
   2 HP_LVC3_OCP_V3_1_ATTN_OUT_SW_N      B @S9S_MB_2U_LIB.S9S_MB_2U(SCH_1):HP_LVC3_OCP_V3_1_ATTN_OUT_SW_N

Q_RES_0402LF-15K,1%,1/16W,CHIPA  I58  PR3791
   1 P3V3_OCP_OV_1      A @S9S_MB_2U_LIB.S9S_MB_2U(SCH_1):P3V3_OCP_OV_1
   2    GND      B @S9S_MB_2U_LIB.S9S_MB_2U(SCH_1):GND

Q_RES_0402LF-10K,1%,1/16W,CHIPA  I62  R4070
   1 P12V_AUX      A @S9S_MB_2U_LIB.S9S_MB_2U(SCH_1):P12V_AUX
   2 P3V3_OCP_1_EN_G      B @S9S_MB_2U_LIB.S9S_MB_2U(SCH_1):P3V3_OCP_1_EN_G

Q_CAP_C0402-1UF,25V,10%,X6S,CHA  I71  PC2086
   1 P3V3_OCP_VCC_1      A @S9S_MB_2U_LIB.S9S_MB_2U(SCH_1):P3V3_OCP_VCC_1
   2    GND      B @S9S_MB_2U_LIB.S9S_MB_2U(SCH_1):GND

Q_CAP_C0402-1UF,25V,10%,X6S,CHA  I72  PC2093
   1    GND      A @S9S_MB_2U_LIB.S9S_MB_2U(SCH_1):GND
   2 P3V3_OCP_REG_1      B @S9S_MB_2U_LIB.S9S_MB_2U(SCH_1):P3V3_OCP_REG_1

Q_RES_0402LF-0,5%,1/16W,EMPTY,A  I82  R3144
   1 P12V_OCP_PWRGD_1      A @S9S_MB_2U_LIB.S9S_MB_2U(SCH_1):P12V_OCP_PWRGD_1
   2 HP_LVC3_OCP_V3_1_P12V_PWRGD      B @S9S_MB_2U_LIB.S9S_MB_2U(SCH_1):HP_LVC3_OCP_V3_1_P12V_PWRGD

Q_RES_0402LF-0,5%,1/16W,EMPTY,A  I87  R3869
   1 P12V_OCP_SENSE_1      A @S9S_MB_2U_LIB.S9S_MB_2U(SCH_1):P12V_OCP_SENSE_1
   2 P12V_OCP_SFF_ISENSE_MAM_MAM      B @S9S_MB_2U_LIB.S9S_MB_2U(SCH_1):P12V_OCP_SFF_ISENSE_MAM_MAM

Q_RES_0402LF-0,5%,1/16W,EMPTY,A  I88  R3870
   1 P12V_OCP_SENSE_1      A @S9S_MB_2U_LIB.S9S_MB_2U(SCH_1):P12V_OCP_SENSE_1
   2 P12V_OCP_SFF_ISENSE_MAM_TIC      B @S9S_MB_2U_LIB.S9S_MB_2U(SCH_1):P12V_OCP_SFF_ISENSE_MAM_TIC

Q_RES_0402LF-100K,1%,1/16W,EMPA  I90  R3799
   1 P3V3_AUX      A @S9S_MB_2U_LIB.S9S_MB_2U(SCH_1):P3V3_AUX
   2 P12V_OCP_FAULT_1      B @S9S_MB_2U_LIB.S9S_MB_2U(SCH_1):P12V_OCP_FAULT_1

Q_RES_0402LF-100K,1%,1/16W,EMPA  I92  R3797
   1 P3V3_AUX      A @S9S_MB_2U_LIB.S9S_MB_2U(SCH_1):P3V3_AUX
   2 HP_LVC3_OCP_V3_1_P12V_PWRGD      B @S9S_MB_2U_LIB.S9S_MB_2U(SCH_1):HP_LVC3_OCP_V3_1_P12V_PWRGD

Q_CAP_C0402-0.01UF,50V,10%,EMPA  I101  PC2144
   1 P3V3_OCP_SFF_R      A @S9S_MB_2U_LIB.S9S_MB_2U(SCH_1):P3V3_OCP_SFF_R
   2 P3V3_OCP_GATE_PU202_1      B @S9S_MB_2U_LIB.S9S_MB_2U(SCH_1):P3V3_OCP_GATE_PU202_1

Q_RES_0402LF-4.53K,1%,1/16W,CHA  I102  PR5481
   1 P3V3_OCP_SENSE_1      A @S9S_MB_2U_LIB.S9S_MB_2U(SCH_1):P3V3_OCP_SENSE_1
   2    GND      B @S9S_MB_2U_LIB.S9S_MB_2U(SCH_1):GND

Q_RES_0402LF-10M,1%,1/16W,CHIPA  I103  PR4525
   1 P3V3_OCP_SFF_R      A @S9S_MB_2U_LIB.S9S_MB_2U(SCH_1):P3V3_OCP_SFF_R
   2 P3V3_OCP_GATE_PU202_1      B @S9S_MB_2U_LIB.S9S_MB_2U(SCH_1):P3V3_OCP_GATE_PU202_1

SCHOTTKY_AC-B340A-13-F,SMLF,ICA  I104  PD103
   A    GND      A @S9S_MB_2U_LIB.S9S_MB_2U(SCH_1):GND
   C P3V3_OCP_SFF_R      C @S9S_MB_2U_LIB.S9S_MB_2U(SCH_1):P3V3_OCP_SFF_R

Q_RES_0402LF-0,5%,1/16W,CHIP,CA  I105  R3794
   1 P3V3_OCP_PWRGD_1      A @S9S_MB_2U_LIB.S9S_MB_2U(SCH_1):P3V3_OCP_PWRGD_1
   2 OCP_V3_1_P3V3_PWRGD      B @S9S_MB_2U_LIB.S9S_MB_2U(SCH_1):OCP_V3_1_P3V3_PWRGD

Q_RES_0402LF-1K,1%,1/16W,CHIP,A  I7  R1906
   1 P3V3_AUX      A @S9S_MB_2U_LIB.S9S_MB_2U(SCH_1):P3V3_AUX
   2 OCP_SFF_PRSNT2_R_N      B @S9S_MB_2U_LIB.S9S_MB_2U(SCH_1):OCP_SFF_PRSNT2_R_N

MOSFET_NCH_DUAL-PJT138K,SMLF,EA  I9  Q123
   1    GND     S1 @S9S_MB_2U_LIB.S9S_MB_2U(SCH_1):GND
   2 P12V_OCP_EN_1_R     G1 @S9S_MB_2U_LIB.S9S_MB_2U(SCH_1):P12V_OCP_EN_1_R
   6 P12V_OCP_1_EN_G     D1 @S9S_MB_2U_LIB.S9S_MB_2U(SCH_1):P12V_OCP_1_EN_G

Q_RES_0402LF-1K,1%,1/16W,CHIP,A  I13  R1905
   1 P3V3_AUX      A @S9S_MB_2U_LIB.S9S_MB_2U(SCH_1):P3V3_AUX
   2 OCP_SFF_PRSNT0_R_N      B @S9S_MB_2U_LIB.S9S_MB_2U(SCH_1):OCP_SFF_PRSNT0_R_N

Q_RES_0402LF-10K,1%,1/16W,EMPTA  I15  R4068
   1 P12V_AUX      A @S9S_MB_2U_LIB.S9S_MB_2U(SCH_1):P12V_AUX
   2 P12V_OCP_1_EN_G      B @S9S_MB_2U_LIB.S9S_MB_2U(SCH_1):P12V_OCP_1_EN_G

Q_RES_0402LF-0,5%,1/16W,CHIP,CA  I19  R5487
   1 HP_LVC3_OCP_V3_1_EN      A @S9S_MB_2U_LIB.S9S_MB_2U(SCH_1):HP_LVC3_OCP_V3_1_EN
   2 P3V3_OCP_EN_1_R      B @S9S_MB_2U_LIB.S9S_MB_2U(SCH_1):P3V3_OCP_EN_1_R

MOSFET_NCH_DUAL-PJT138K,SMLF,IA  I21  Q124
   1    GND     S1 @S9S_MB_2U_LIB.S9S_MB_2U(SCH_1):GND
   2 P3V3_OCP_EN_1_R     G1 @S9S_MB_2U_LIB.S9S_MB_2U(SCH_1):P3V3_OCP_EN_1_R
   6 P3V3_OCP_1_EN_G     D1 @S9S_MB_2U_LIB.S9S_MB_2U(SCH_1):P3V3_OCP_1_EN_G

Q_RES_0402LF-1K,1%,1/16W,CHIP,A  I25  R1907
   1 P3V3_AUX      A @S9S_MB_2U_LIB.S9S_MB_2U(SCH_1):P3V3_AUX
   2 OCP_SFF_PRSNT1_R_N      B @S9S_MB_2U_LIB.S9S_MB_2U(SCH_1):OCP_SFF_PRSNT1_R_N

Q_CAP_0402-0.1UF,25V,10%,X7R,CA  I30  C592
   1 P3V3_AUX      A @S9S_MB_2U_LIB.S9S_MB_2U(SCH_1):P3V3_AUX
   2    GND      B @S9S_MB_2U_LIB.S9S_MB_2U(SCH_1):GND

Q_RES_0402LF-15K,1%,1/16W,EMPTA  I33  PR3788
   1 P12V_OCP_OV_1      A @S9S_MB_2U_LIB.S9S_MB_2U(SCH_1):P12V_OCP_OV_1
   2    GND      B @S9S_MB_2U_LIB.S9S_MB_2U(SCH_1):GND

MOSFET_NCH_DUAL-PJT138K,SMLF,IA  I36  Q124
   3 P3V3_OCP_UV_1_R1     D2 @S9S_MB_2U_LIB.S9S_MB_2U(SCH_1):P3V3_OCP_UV_1_R1
   5 P3V3_OCP_1_EN_G     G2 @S9S_MB_2U_LIB.S9S_MB_2U(SCH_1):P3V3_OCP_1_EN_G
   4    GND     S2 @S9S_MB_2U_LIB.S9S_MB_2U(SCH_1):GND

Q_RES_0402LF-0,5%,1/16W,EMPTY,A  I39  R3784
   1 P12V_OCP_UV_1_R      A @S9S_MB_2U_LIB.S9S_MB_2U(SCH_1):P12V_OCP_UV_1_R
   2 P12V_OCP_UV_1      B @S9S_MB_2U_LIB.S9S_MB_2U(SCH_1):P12V_OCP_UV_1

Q_RES_0402LF-160K,1%,1/16W,EMPA  I42  PR3786
   1 P12V_AUX      A @S9S_MB_2U_LIB.S9S_MB_2U(SCH_1):P12V_AUX
   2 P12V_OCP_UV_1      B @S9S_MB_2U_LIB.S9S_MB_2U(SCH_1):P12V_OCP_UV_1

Q_CAP_C0402-1UF,25V,10%,X6S,CHA  I44  PC2079
   1 P12V_AUX      A @S9S_MB_2U_LIB.S9S_MB_2U(SCH_1):P12V_AUX
   2    GND      B @S9S_MB_2U_LIB.S9S_MB_2U(SCH_1):GND

Q_RES_0402LF-0,5%,1/16W,CHIP,CA  I46  R1148
   1 HP_LVC3_OCP_V3_1_PRSNT2_N_R      A @S9S_MB_2U_LIB.S9S_MB_2U(SCH_1):HP_LVC3_OCP_V3_1_PRSNT2_N_R
   2 HP_LVC3_OCP_V3_1_PRSNT2_N      B @S9S_MB_2U_LIB.S9S_MB_2U(SCH_1):HP_LVC3_OCP_V3_1_PRSNT2_N

MAX15090BEWIT-MAX15090BEWI+T,SA  I51  PU203
  A2 P12V_OCP_VCC_1    VCC @S9S_MB_2U_LIB.S9S_MB_2U(SCH_1):P12V_OCP_VCC_1
  A3 P12V_AUX  IN_A3 @S9S_MB_2U_LIB.S9S_MB_2U(SCH_1):P12V_AUX
  A5 P12V_AUX  IN_A5 @S9S_MB_2U_LIB.S9S_MB_2U(SCH_1):P12V_AUX
  B3 P12V_AUX  IN_B3 @S9S_MB_2U_LIB.S9S_MB_2U(SCH_1):P12V_AUX
  B5 P12V_AUX  IN_B5 @S9S_MB_2U_LIB.S9S_MB_2U(SCH_1):P12V_AUX
  C3 P12V_AUX  IN_C3 @S9S_MB_2U_LIB.S9S_MB_2U(SCH_1):P12V_AUX
  C5 P12V_AUX  IN_C5 @S9S_MB_2U_LIB.S9S_MB_2U(SCH_1):P12V_AUX
  D5 P12V_AUX  IN_D5 @S9S_MB_2U_LIB.S9S_MB_2U(SCH_1):P12V_AUX
  B1 P12V_OCP_CB_1     CB @S9S_MB_2U_LIB.S9S_MB_2U(SCH_1):P12V_OCP_CB_1
  B7    GND    EN# @S9S_MB_2U_LIB.S9S_MB_2U(SCH_1):GND
  D1 P12V_OCP_REG_1    REG @S9S_MB_2U_LIB.S9S_MB_2U(SCH_1):P12V_OCP_REG_1
  D2 P12V_OCP_UV_1     UV @S9S_MB_2U_LIB.S9S_MB_2U(SCH_1):P12V_OCP_UV_1
  D3 P12V_OCP_OV_1     OV @S9S_MB_2U_LIB.S9S_MB_2U(SCH_1):P12V_OCP_OV_1
  A1 P12V_OCP_SENSE_1 ISENSE @S9S_MB_2U_LIB.S9S_MB_2U(SCH_1):P12V_OCP_SENSE_1
  A4 P12V_OCP_SFF OUT_A4 @S9S_MB_2U_LIB.S9S_MB_2U(SCH_1):P12V_OCP_SFF
  B4 P12V_OCP_SFF OUT_B4 @S9S_MB_2U_LIB.S9S_MB_2U(SCH_1):P12V_OCP_SFF
  B6 P12V_OCP_SFF OUT_B6 @S9S_MB_2U_LIB.S9S_MB_2U(SCH_1):P12V_OCP_SFF
  C4 P12V_OCP_SFF OUT_C4 @S9S_MB_2U_LIB.S9S_MB_2U(SCH_1):P12V_OCP_SFF
  C6 P12V_OCP_SFF OUT_C6 @S9S_MB_2U_LIB.S9S_MB_2U(SCH_1):P12V_OCP_SFF
  D4 P12V_OCP_SFF OUT_D4 @S9S_MB_2U_LIB.S9S_MB_2U(SCH_1):P12V_OCP_SFF
  D6 P12V_OCP_SFF OUT_D6 @S9S_MB_2U_LIB.S9S_MB_2U(SCH_1):P12V_OCP_SFF
  A6 P12V_OCP_GATE_1   GATE @S9S_MB_2U_LIB.S9S_MB_2U(SCH_1):P12V_OCP_GATE_1
  A7    GND   CDLY @S9S_MB_2U_LIB.S9S_MB_2U(SCH_1):GND
  B2    GND GND_B2 @S9S_MB_2U_LIB.S9S_MB_2U(SCH_1):GND
  C1    GND GND_C1 @S9S_MB_2U_LIB.S9S_MB_2U(SCH_1):GND
  C2    GND GND_C2 @S9S_MB_2U_LIB.S9S_MB_2U(SCH_1):GND
  C7 P12V_OCP_FAULT_1 FAULT# @S9S_MB_2U_LIB.S9S_MB_2U(SCH_1):P12V_OCP_FAULT_1
  D7 P12V_OCP_PWRGD_1     PG @S9S_MB_2U_LIB.S9S_MB_2U(SCH_1):P12V_OCP_PWRGD_1

Q_RES_0402LF-10,1%,1/16W,EMPTYA  I56  PR3792
   1 P12V_AUX      A @S9S_MB_2U_LIB.S9S_MB_2U(SCH_1):P12V_AUX
   2 P12V_OCP_VCC_1      B @S9S_MB_2U_LIB.S9S_MB_2U(SCH_1):P12V_OCP_VCC_1

Q_RES_0402LF-5.36K,1%,1/16W,CHA  I60  PR3780
   1 P3V3_OCP_CB_1      A @S9S_MB_2U_LIB.S9S_MB_2U(SCH_1):P3V3_OCP_CB_1
   2    GND      B @S9S_MB_2U_LIB.S9S_MB_2U(SCH_1):GND

MAX15090BEWIT-MAX15090BEWI+T,SB  I61  PU202
  A2 P3V3_OCP_VCC_1    VCC @S9S_MB_2U_LIB.S9S_MB_2U(SCH_1):P3V3_OCP_VCC_1
  A3 P3V3_AUX  IN_A3 @S9S_MB_2U_LIB.S9S_MB_2U(SCH_1):P3V3_AUX
  A5 P3V3_AUX  IN_A5 @S9S_MB_2U_LIB.S9S_MB_2U(SCH_1):P3V3_AUX
  B3 P3V3_AUX  IN_B3 @S9S_MB_2U_LIB.S9S_MB_2U(SCH_1):P3V3_AUX
  B5 P3V3_AUX  IN_B5 @S9S_MB_2U_LIB.S9S_MB_2U(SCH_1):P3V3_AUX
  C3 P3V3_AUX  IN_C3 @S9S_MB_2U_LIB.S9S_MB_2U(SCH_1):P3V3_AUX
  C5 P3V3_AUX  IN_C5 @S9S_MB_2U_LIB.S9S_MB_2U(SCH_1):P3V3_AUX
  D5 P3V3_AUX  IN_D5 @S9S_MB_2U_LIB.S9S_MB_2U(SCH_1):P3V3_AUX
  B1 P3V3_OCP_CB_1     CB @S9S_MB_2U_LIB.S9S_MB_2U(SCH_1):P3V3_OCP_CB_1
  B7    GND    EN# @S9S_MB_2U_LIB.S9S_MB_2U(SCH_1):GND
  D1 P3V3_OCP_REG_1    REG @S9S_MB_2U_LIB.S9S_MB_2U(SCH_1):P3V3_OCP_REG_1
  D2 P3V3_OCP_UV_1     UV @S9S_MB_2U_LIB.S9S_MB_2U(SCH_1):P3V3_OCP_UV_1
  D3 P3V3_OCP_OV_1     OV @S9S_MB_2U_LIB.S9S_MB_2U(SCH_1):P3V3_OCP_OV_1
  A1 P3V3_OCP_SENSE_1 ISENSE @S9S_MB_2U_LIB.S9S_MB_2U(SCH_1):P3V3_OCP_SENSE_1
  A4 P3V3_OCP_SFF_R OUT_A4 @S9S_MB_2U_LIB.S9S_MB_2U(SCH_1):P3V3_OCP_SFF_R
  B4 P3V3_OCP_SFF_R OUT_B4 @S9S_MB_2U_LIB.S9S_MB_2U(SCH_1):P3V3_OCP_SFF_R
  B6 P3V3_OCP_SFF_R OUT_B6 @S9S_MB_2U_LIB.S9S_MB_2U(SCH_1):P3V3_OCP_SFF_R
  C4 P3V3_OCP_SFF_R OUT_C4 @S9S_MB_2U_LIB.S9S_MB_2U(SCH_1):P3V3_OCP_SFF_R
  C6 P3V3_OCP_SFF_R OUT_C6 @S9S_MB_2U_LIB.S9S_MB_2U(SCH_1):P3V3_OCP_SFF_R
  D4 P3V3_OCP_SFF_R OUT_D4 @S9S_MB_2U_LIB.S9S_MB_2U(SCH_1):P3V3_OCP_SFF_R
  D6 P3V3_OCP_SFF_R OUT_D6 @S9S_MB_2U_LIB.S9S_MB_2U(SCH_1):P3V3_OCP_SFF_R
  A6 P3V3_OCP_GATE_PU202_1   GATE @S9S_MB_2U_LIB.S9S_MB_2U(SCH_1):P3V3_OCP_GATE_PU202_1
  A7    GND   CDLY @S9S_MB_2U_LIB.S9S_MB_2U(SCH_1):GND
  B2    GND GND_B2 @S9S_MB_2U_LIB.S9S_MB_2U(SCH_1):GND
  C1    GND GND_C1 @S9S_MB_2U_LIB.S9S_MB_2U(SCH_1):GND
  C2    GND GND_C2 @S9S_MB_2U_LIB.S9S_MB_2U(SCH_1):GND
  C7 P3V3_OCP_FAULT_1 FAULT# @S9S_MB_2U_LIB.S9S_MB_2U(SCH_1):P3V3_OCP_FAULT_1
  D7 P3V3_OCP_PWRGD_1     PG @S9S_MB_2U_LIB.S9S_MB_2U(SCH_1):P3V3_OCP_PWRGD_1

Q_RES_0402LF-0,5%,1/16W,CHIP,CA  I64  R3785
   1 P3V3_OCP_UV_1_R1      A @S9S_MB_2U_LIB.S9S_MB_2U(SCH_1):P3V3_OCP_UV_1_R1
   2 P3V3_OCP_UV_1      B @S9S_MB_2U_LIB.S9S_MB_2U(SCH_1):P3V3_OCP_UV_1

Q_CAP_C0402-1UF,25V,10%,X6S,CHA  I66  PC5328
   1 P3V3_AUX      A @S9S_MB_2U_LIB.S9S_MB_2U(SCH_1):P3V3_AUX
   2    GND      B @S9S_MB_2U_LIB.S9S_MB_2U(SCH_1):GND

Q_RES_0402LF-7.15K,1%,1/16W,CHA  I68  PR3790
   1 P3V3_OCP_UV_1      A @S9S_MB_2U_LIB.S9S_MB_2U(SCH_1):P3V3_OCP_UV_1
   2 P3V3_OCP_OV_1      B @S9S_MB_2U_LIB.S9S_MB_2U(SCH_1):P3V3_OCP_OV_1

Q_RES_0402LF-10,1%,1/16W,CHIP,A  I73  PR3798
   1 P3V3_AUX      A @S9S_MB_2U_LIB.S9S_MB_2U(SCH_1):P3V3_AUX
   2 P3V3_OCP_VCC_1      B @S9S_MB_2U_LIB.S9S_MB_2U(SCH_1):P3V3_OCP_VCC_1

Q_CAP_C0402-3900PF,50V,10%,EMPA  I83  PC4056
   1 P12V_OCP_GATE_1      A @S9S_MB_2U_LIB.S9S_MB_2U(SCH_1):P12V_OCP_GATE_1
   2    GND      B @S9S_MB_2U_LIB.S9S_MB_2U(SCH_1):GND

Q_RES_0402LF-10M,1%,1/16W,EMPTA  I84  PR4524
   1 P12V_OCP_SFF      A @S9S_MB_2U_LIB.S9S_MB_2U(SCH_1):P12V_OCP_SFF
   2 P12V_OCP_GATE_1      B @S9S_MB_2U_LIB.S9S_MB_2U(SCH_1):P12V_OCP_GATE_1

SCHOTTKY_AC-B340A-13-F,SMLF,ICA  I86  PD102
   A    GND      A @S9S_MB_2U_LIB.S9S_MB_2U(SCH_1):GND
   C P12V_OCP_SFF      C @S9S_MB_2U_LIB.S9S_MB_2U(SCH_1):P12V_OCP_SFF

Q_CAP_C0805-22UF,16V,20%,X6S,CC  I94  PC2080
   1 P12V_OCP_SFF      A @S9S_MB_2U_LIB.S9S_MB_2U(SCH_1):P12V_OCP_SFF
   2    GND      B @S9S_MB_2U_LIB.S9S_MB_2U(SCH_1):GND

Q_RES_0402LF-100K,1%,1/16W,CHIA  I108  R3796
   1 P3V3_AUX      A @S9S_MB_2U_LIB.S9S_MB_2U(SCH_1):P3V3_AUX
   2 P3V3_OCP_FAULT_1      B @S9S_MB_2U_LIB.S9S_MB_2U(SCH_1):P3V3_OCP_FAULT_1

Q_RES_0402LF-100K,1%,1/16W,CHIA  I110  R3783
   1 P3V3_AUX      A @S9S_MB_2U_LIB.S9S_MB_2U(SCH_1):P3V3_AUX
   2 OCP_V3_1_P3V3_PWRGD      B @S9S_MB_2U_LIB.S9S_MB_2U(SCH_1):OCP_V3_1_P3V3_PWRGD

Q_CAP_0402-0.1UF,25V,10%,X7R,CA  I111  PC2091
   1 P3V3_OCP_SFF_R      A @S9S_MB_2U_LIB.S9S_MB_2U(SCH_1):P3V3_OCP_SFF_R
   2    GND      B @S9S_MB_2U_LIB.S9S_MB_2U(SCH_1):GND

Q_CAP_C0805-10UF,16V,10%,X6S,CB  I113  PC2081
   1 P3V3_OCP_SFF_R      A @S9S_MB_2U_LIB.S9S_MB_2U(SCH_1):P3V3_OCP_SFF_R
   2    GND      B @S9S_MB_2U_LIB.S9S_MB_2U(SCH_1):GND


DRAWING: @S9S_MB_2U_LIB.S9S_MB_2U(SCH_1):PAGE246 

Q_CAP_C0402-100NF,50V,10%,X7R,A  I2  C1172
   1    P5V      A @S9S_MB_2U_LIB.S9S_MB_2U(SCH_1):P5V
   2    GND      B @S9S_MB_2U_LIB.S9S_MB_2U(SCH_1):GND

RT9818C44GV-RT9818C-44GV,SMLF,A  I4  U99
   3    P5V    VDD @S9S_MB_2U_LIB.S9S_MB_2U(SCH_1):P5V
   1 PWRGD_P5V RESET# @S9S_MB_2U_LIB.S9S_MB_2U(SCH_1):PWRGD_P5V
   2    GND    GND @S9S_MB_2U_LIB.S9S_MB_2U(SCH_1):GND

Q_RES_0402LF-10K,1%,1/16W,CHIPA  I6  R1655
   1 P12V_AUX      A @S9S_MB_2U_LIB.S9S_MB_2U(SCH_1):P12V_AUX
   2 PWRGD_P5V_ISO_R      B @S9S_MB_2U_LIB.S9S_MB_2U(SCH_1):PWRGD_P5V_ISO_R

Q_RES_0402LF-0,5%,1/16W,CHIP,CA  I9  R1640
   1 FM_P5V_EN      A @S9S_MB_2U_LIB.S9S_MB_2U(SCH_1):FM_P5V_EN
   2 VR_P5V_EN      B @S9S_MB_2U_LIB.S9S_MB_2U(SCH_1):VR_P5V_EN

Q_RES_0402LF-0,5%,1/16W,EMPTY,A  I10  R1607
   1 FM_PS_EN_PLD_R      A @S9S_MB_2U_LIB.S9S_MB_2U(SCH_1):FM_PS_EN_PLD_R
   2 VR_P5V_EN      B @S9S_MB_2U_LIB.S9S_MB_2U(SCH_1):VR_P5V_EN

Q_CAP_C0402-100NF,50V,10%,X7R,A  I11  C1042
   1 P5V_AUX      A @S9S_MB_2U_LIB.S9S_MB_2U(SCH_1):P5V_AUX
   2    GND      B @S9S_MB_2U_LIB.S9S_MB_2U(SCH_1):GND

Q_RES_0402LF-100K,1%,1/16W,CHIA  I14  R1641
   1 VR_P5V_EN      A @S9S_MB_2U_LIB.S9S_MB_2U(SCH_1):VR_P5V_EN
   2    GND      B @S9S_MB_2U_LIB.S9S_MB_2U(SCH_1):GND

Q_RES_0402LF-100K,1%,1/16W,CHIA  I17  R1643
   1 P12V_AUX      A @S9S_MB_2U_LIB.S9S_MB_2U(SCH_1):P12V_AUX
   2 VR_P5V_EN_N      B @S9S_MB_2U_LIB.S9S_MB_2U(SCH_1):VR_P5V_EN_N

Q_RES_0402LF-10K,1%,1/16W,CHIPA  I22  R1642
   1 P12V_AUX      A @S9S_MB_2U_LIB.S9S_MB_2U(SCH_1):P12V_AUX
   2 VR_P5V_EN_D_R      B @S9S_MB_2U_LIB.S9S_MB_2U(SCH_1):VR_P5V_EN_D_R

Q_CAP_C0805-10UF,16V,10%,X6S,CA  I24  C1170
   1 P5V_AUX      A @S9S_MB_2U_LIB.S9S_MB_2U(SCH_1):P5V_AUX
   2    GND      B @S9S_MB_2U_LIB.S9S_MB_2U(SCH_1):GND

Q_CAP_C0805-10UF,16V,10%,EMPTYA  I25  C1171
   1 P5V_AUX      A @S9S_MB_2U_LIB.S9S_MB_2U(SCH_1):P5V_AUX
   2    GND      B @S9S_MB_2U_LIB.S9S_MB_2U(SCH_1):GND

Q_RES_0402LF-1K,1%,1/16W,CHIP,A  I27  R1654
   1 VR_P5V_EN_D_R      A @S9S_MB_2U_LIB.S9S_MB_2U(SCH_1):VR_P5V_EN_D_R
   2 VR_P5V_EN_D_R1      B @S9S_MB_2U_LIB.S9S_MB_2U(SCH_1):VR_P5V_EN_D_R1

MOSFET_NCH_1D3S-PSMNR58-30YLH,A  I30  Q57
   3    P5V      3 @S9S_MB_2U_LIB.S9S_MB_2U(SCH_1):P5V
   5 P5V_AUX      5 @S9S_MB_2U_LIB.S9S_MB_2U(SCH_1):P5V_AUX
   2    P5V      2 @S9S_MB_2U_LIB.S9S_MB_2U(SCH_1):P5V
   4 VR_P5V_EN_D_R      4 @S9S_MB_2U_LIB.S9S_MB_2U(SCH_1):VR_P5V_EN_D_R
   1    P5V      1 @S9S_MB_2U_LIB.S9S_MB_2U(SCH_1):P5V

BAT547F-BAT547F,SMLF,IC,BC0BATA  I32  D7
   1   P3V3      1 @S9S_MB_2U_LIB.S9S_MB_2U(SCH_1):P3V3
   3    P5V      3 @S9S_MB_2U_LIB.S9S_MB_2U(SCH_1):P5V

Q_CAP_C0402-100NF,50V,10%,X7R,A  I44  C1227
   1    P5V      A @S9S_MB_2U_LIB.S9S_MB_2U(SCH_1):P5V
   2    GND      B @S9S_MB_2U_LIB.S9S_MB_2U(SCH_1):GND

Q_CAP_C0805-10UF,16V,10%,X6S,CA  I45  C1331
   1    P5V      A @S9S_MB_2U_LIB.S9S_MB_2U(SCH_1):P5V
   2    GND      B @S9S_MB_2U_LIB.S9S_MB_2U(SCH_1):GND

Q_CAP_C0402-100NF,50V,10%,X7R,A  I48  C1332
   1 P3V3_AUX      A @S9S_MB_2U_LIB.S9S_MB_2U(SCH_1):P3V3_AUX
   2    GND      B @S9S_MB_2U_LIB.S9S_MB_2U(SCH_1):GND

Q_CAP_C0805-10UF,16V,10%,X6S,CA  I49  C1333
   1 P3V3_AUX      A @S9S_MB_2U_LIB.S9S_MB_2U(SCH_1):P3V3_AUX
   2    GND      B @S9S_MB_2U_LIB.S9S_MB_2U(SCH_1):GND

Q_CAP_C0805-10UF,16V,10%,EMPTYA  I50  C1338
   1 P3V3_AUX      A @S9S_MB_2U_LIB.S9S_MB_2U(SCH_1):P3V3_AUX
   2    GND      B @S9S_MB_2U_LIB.S9S_MB_2U(SCH_1):GND

MOSFET_NCH_1D3S-PSMNR58-30YLH,A  I51  Q56
   3   P3V3      3 @S9S_MB_2U_LIB.S9S_MB_2U(SCH_1):P3V3
   5 P3V3_AUX      5 @S9S_MB_2U_LIB.S9S_MB_2U(SCH_1):P3V3_AUX
   2   P3V3      2 @S9S_MB_2U_LIB.S9S_MB_2U(SCH_1):P3V3
   4 PWRGD_P5V_ISO_R      4 @S9S_MB_2U_LIB.S9S_MB_2U(SCH_1):PWRGD_P5V_ISO_R
   1   P3V3      1 @S9S_MB_2U_LIB.S9S_MB_2U(SCH_1):P3V3

Q_CAP_C0402-100NF,50V,10%,X7R,A  I58  C1339
   1   P3V3      A @S9S_MB_2U_LIB.S9S_MB_2U(SCH_1):P3V3
   2    GND      B @S9S_MB_2U_LIB.S9S_MB_2U(SCH_1):GND

Q_CAP_C0805-10UF,16V,10%,X6S,CA  I61  C1340
   1   P3V3      A @S9S_MB_2U_LIB.S9S_MB_2U(SCH_1):P3V3
   2    GND      B @S9S_MB_2U_LIB.S9S_MB_2U(SCH_1):GND

MOSFET_NCH_GDS_ESD_PROTECTED-2A  I67  U324
   D VR_P5V_EN_D      D @S9S_MB_2U_LIB.S9S_MB_2U(SCH_1):VR_P5V_EN_D
   G VR_P5V_EN_N      G @S9S_MB_2U_LIB.S9S_MB_2U(SCH_1):VR_P5V_EN_N
   S    GND      S @S9S_MB_2U_LIB.S9S_MB_2U(SCH_1):GND

Q_CAP_C0402-0.22UF,25V,10%,X7RA  I68  C1226
   1 VR_P5V_EN_D_R      A @S9S_MB_2U_LIB.S9S_MB_2U(SCH_1):VR_P5V_EN_D_R
   2    GND      B @S9S_MB_2U_LIB.S9S_MB_2U(SCH_1):GND

MOSFET_NCH_DUAL-PJT138K,SMLF,IA  I69  Q37
   1    GND     S1 @S9S_MB_2U_LIB.S9S_MB_2U(SCH_1):GND
   2 VR_P5V_EN     G1 @S9S_MB_2U_LIB.S9S_MB_2U(SCH_1):VR_P5V_EN
   6 VR_P5V_EN_N     D1 @S9S_MB_2U_LIB.S9S_MB_2U(SCH_1):VR_P5V_EN_N

MOSFET_NCH_DUAL-PJT138K,SMLF,IA  I76  Q37
   3 VR_P5V_EN_D_R1     D2 @S9S_MB_2U_LIB.S9S_MB_2U(SCH_1):VR_P5V_EN_D_R1
   5 VR_P5V_EN_N     G2 @S9S_MB_2U_LIB.S9S_MB_2U(SCH_1):VR_P5V_EN_N
   4    GND     S2 @S9S_MB_2U_LIB.S9S_MB_2U(SCH_1):GND

Q_RES_1206LF-243,1%,1/4W,CHIP,A  I77  R4638
   1    P5V      A @S9S_MB_2U_LIB.S9S_MB_2U(SCH_1):P5V
   2 VR_P5V_EN_D      B @S9S_MB_2U_LIB.S9S_MB_2U(SCH_1):VR_P5V_EN_D

Q_RES_1206LF-243,1%,1/4W,CHIP,A  I78  R4639
   1    P5V      A @S9S_MB_2U_LIB.S9S_MB_2U(SCH_1):P5V
   2 VR_P5V_EN_D      B @S9S_MB_2U_LIB.S9S_MB_2U(SCH_1):VR_P5V_EN_D

Q_RES_1206LF-243,1%,1/4W,CHIP,A  I79  R4640
   1    P5V      A @S9S_MB_2U_LIB.S9S_MB_2U(SCH_1):P5V
   2 VR_P5V_EN_D      B @S9S_MB_2U_LIB.S9S_MB_2U(SCH_1):VR_P5V_EN_D

Q_RES_1206LF-243,1%,1/4W,CHIP,A  I80  R4641
   1    P5V      A @S9S_MB_2U_LIB.S9S_MB_2U(SCH_1):P5V
   2 VR_P5V_EN_D      B @S9S_MB_2U_LIB.S9S_MB_2U(SCH_1):VR_P5V_EN_D

Q_RES_0402LF-10K,1%,1/16W,EMPTA  I89  R1706
   1   P3V3      A @S9S_MB_2U_LIB.S9S_MB_2U(SCH_1):P3V3
   2 PWRGD_P3V3_R1      B @S9S_MB_2U_LIB.S9S_MB_2U(SCH_1):PWRGD_P3V3_R1

Q_RES_0402LF-33.2,1%,1/16W,CHIA  I91  R4677
   1 PWRGD_P3V3_R1      A @S9S_MB_2U_LIB.S9S_MB_2U(SCH_1):PWRGD_P3V3_R1
   2 PWRGD_P3V3      B @S9S_MB_2U_LIB.S9S_MB_2U(SCH_1):PWRGD_P3V3

Q_CAP_C0402-0.22UF,25V,10%,X7RA  I94  C2359
   1 PWRGD_P5V_ISO_R      A @S9S_MB_2U_LIB.S9S_MB_2U(SCH_1):PWRGD_P5V_ISO_R
   2    GND      B @S9S_MB_2U_LIB.S9S_MB_2U(SCH_1):GND

Q_RES_0402LF-10K,1%,1/16W,CHIPA  I96  R4679
   1    P5V      A @S9S_MB_2U_LIB.S9S_MB_2U(SCH_1):P5V
   2 PWRGD_P5V      B @S9S_MB_2U_LIB.S9S_MB_2U(SCH_1):PWRGD_P5V

MOSFET_NCH_DUAL-PJT138K,SMLF,IA  I98  Q236
   3 PWRGD_P5V_ISO     D2 @S9S_MB_2U_LIB.S9S_MB_2U(SCH_1):PWRGD_P5V_ISO
   5 PWRGD_P5V_N     G2 @S9S_MB_2U_LIB.S9S_MB_2U(SCH_1):PWRGD_P5V_N
   4    GND     S2 @S9S_MB_2U_LIB.S9S_MB_2U(SCH_1):GND

MOSFET_NCH_DUAL-PJT138K,SMLF,IA  I99  Q236
   1    GND     S1 @S9S_MB_2U_LIB.S9S_MB_2U(SCH_1):GND
   2 PWRGD_P5V     G1 @S9S_MB_2U_LIB.S9S_MB_2U(SCH_1):PWRGD_P5V
   6 PWRGD_P5V_N     D1 @S9S_MB_2U_LIB.S9S_MB_2U(SCH_1):PWRGD_P5V_N

Q_RES_0402LF-100K,1%,1/16W,CHIA  I102  R4680
   1 P12V_AUX      A @S9S_MB_2U_LIB.S9S_MB_2U(SCH_1):P12V_AUX
   2 PWRGD_P5V_N      B @S9S_MB_2U_LIB.S9S_MB_2U(SCH_1):PWRGD_P5V_N

Q_RES_0402LF-1K,1%,1/16W,CHIP,A  I104  R4678
   1 PWRGD_P5V_ISO_R      A @S9S_MB_2U_LIB.S9S_MB_2U(SCH_1):PWRGD_P5V_ISO_R
   2 PWRGD_P5V_ISO      B @S9S_MB_2U_LIB.S9S_MB_2U(SCH_1):PWRGD_P5V_ISO

APX80929SAG7-APX809-29SAG-7,SMA  I105  U330
   3   P3V3    VCC @S9S_MB_2U_LIB.S9S_MB_2U(SCH_1):P3V3
   2 PWRGD_P3V3_R1 RESET_L @S9S_MB_2U_LIB.S9S_MB_2U(SCH_1):PWRGD_P3V3_R1
   1    GND    GND @S9S_MB_2U_LIB.S9S_MB_2U(SCH_1):GND

Q_CAP_0402-0.1UF,25V,10%,X7R,CA  I107  C2360
   1   P3V3      A @S9S_MB_2U_LIB.S9S_MB_2U(SCH_1):P3V3
   2    GND      B @S9S_MB_2U_LIB.S9S_MB_2U(SCH_1):GND

Q_RES_0402LF-100K,1%,1/16W,CHIA  I109  R4681
   1 PWRGD_P3V3_R1      A @S9S_MB_2U_LIB.S9S_MB_2U(SCH_1):PWRGD_P3V3_R1
   2    GND      B @S9S_MB_2U_LIB.S9S_MB_2U(SCH_1):GND

Q_RES_0402LF-100K,1%,1/16W,CHIA  I112  R4682
   1 PWRGD_P5V      A @S9S_MB_2U_LIB.S9S_MB_2U(SCH_1):PWRGD_P5V
   2    GND      B @S9S_MB_2U_LIB.S9S_MB_2U(SCH_1):GND


DRAWING: @S9S_MB_2U_LIB.S9S_MB_2U(SCH_1):PAGE261 

ISL99390FRZTR5935-ISL99390FRZ-A  I12  PU44_P0_2
  34 PVCCINFAON_CPU0_APWM2    PWM @S9S_MB_2U_LIB.S9S_MB_2U(SCH_1):PVCCINFAON_CPU0_APWM2
  39 PVCCINFAON_CPU0_VREF  REFIN @S9S_MB_2U_LIB.S9S_MB_2U(SCH_1):PVCCINFAON_CPU0_VREF
   3 PVCCINFAON_CPU0_VDD2    VCC @S9S_MB_2U_LIB.S9S_MB_2U(SCH_1):PVCCINFAON_CPU0_VDD2
   2    GND   AGND @S9S_MB_2U_LIB.S9S_MB_2U(SCH_1):GND
  33 SW_PVCCINFAON_CPU0_BOOT2   BOOT @S9S_MB_2U_LIB.S9S_MB_2U(SCH_1):SW_PVCCINFAON_CPU0_BOOT2
25_29 SW_P12V_PVCCINFAON_CPU0_FLT   VIN1 @S9S_MB_2U_LIB.S9S_MB_2U(SCH_1):SW_P12V_PVCCINFAON_CPU0_FLT
  32 SW_PVCCINFAON_CPU0_BOOTR2  PHASE @S9S_MB_2U_LIB.S9S_MB_2U(SCH_1):SW_PVCCINFAON_CPU0_BOOTR2
   4 PVCCFA_EHV_CPU0_PVCC   PVCC @S9S_MB_2U_LIB.S9S_MB_2U(SCH_1):PVCCFA_EHV_CPU0_PVCC
  36 PVCCINFAON_CPU0_ATSEN TOUT_FLT @S9S_MB_2U_LIB.S9S_MB_2U(SCH_1):PVCCINFAON_CPU0_ATSEN
  38 PVCCINFAON_CPU0_ACSP2   IOUT @S9S_MB_2U_LIB.S9S_MB_2U(SCH_1):PVCCINFAON_CPU0_ACSP2
  37 PVCCINFAON_CPU0_LSET2   LSET @S9S_MB_2U_LIB.S9S_MB_2U(SCH_1):PVCCINFAON_CPU0_LSET2
10_19 SW_PVCCINFAON_CPU0_SW2     SW @S9S_MB_2U_LIB.S9S_MB_2U(SCH_1):SW_PVCCINFAON_CPU0_SW2
   5    GND  PGND1 @S9S_MB_2U_LIB.S9S_MB_2U(SCH_1):GND
  30 SW_P12V_PVCCINFAON_CPU0_FLT   VIN2 @S9S_MB_2U_LIB.S9S_MB_2U(SCH_1):SW_P12V_PVCCINFAON_CPU0_FLT
   1 PVCCINFAON_CPU0_VOS2    VOS @S9S_MB_2U_LIB.S9S_MB_2U(SCH_1):PVCCINFAON_CPU0_VOS2
  40    GND  PGND3 @S9S_MB_2U_LIB.S9S_MB_2U(SCH_1):GND
  35 PVCCINFAON_CPU0_VDD2     EN @S9S_MB_2U_LIB.S9S_MB_2U(SCH_1):PVCCINFAON_CPU0_VDD2
  31     NC    DNC     NC
   6     NC    GL1     NC
  41     NC    GL2     NC
7_9-20_24    GND  PGND2 @S9S_MB_2U_LIB.S9S_MB_2U(SCH_1):GND

Q_CAP_0402-0.1UF,25V,10%,X7R,CA  I25  PC1347
   1    GND      A @S9S_MB_2U_LIB.S9S_MB_2U(SCH_1):GND
   2 PVCCINFAON_CPU0_VREF      B @S9S_MB_2U_LIB.S9S_MB_2U(SCH_1):PVCCINFAON_CPU0_VREF

Q_RES_0402LF-2.2,1%,1/16W,CHIPA  I26  PR101
   1 PVCCFA_EHV_CPU0_PVCC      A @S9S_MB_2U_LIB.S9S_MB_2U(SCH_1):PVCCFA_EHV_CPU0_PVCC
   2 PVCCINFAON_CPU0_VDD1      B @S9S_MB_2U_LIB.S9S_MB_2U(SCH_1):PVCCINFAON_CPU0_VDD1

Q_RES_0402LF-0,5%,1/16W,CHIP,CA  I31  PR1777
   1 PVCCINFAON_CPU0_VOS2      A @S9S_MB_2U_LIB.S9S_MB_2U(SCH_1):PVCCINFAON_CPU0_VOS2
   2 PVCCINFAON_CPU0      B @S9S_MB_2U_LIB.S9S_MB_2U(SCH_1):PVCCINFAON_CPU0

Q_CAP_0402-3300PF,50V,10%,X7R,A  I32  PC190_P0_2
   1 SW_P12V_PVCCINFAON_CPU0_FLT      A @S9S_MB_2U_LIB.S9S_MB_2U(SCH_1):SW_P12V_PVCCINFAON_CPU0_FLT
   2    GND      B @S9S_MB_2U_LIB.S9S_MB_2U(SCH_1):GND

Q_RES_0402LF-3.3,1%,1/16W,CHIPA  I34  PR1775
   1 SW_PVCCINFAON_CPU0_BOOT2      A @S9S_MB_2U_LIB.S9S_MB_2U(SCH_1):SW_PVCCINFAON_CPU0_BOOT2
   2 SW_PVCCINFAON_CPU0_BOOT2_R      B @S9S_MB_2U_LIB.S9S_MB_2U(SCH_1):SW_PVCCINFAON_CPU0_BOOT2_R

Q_CAP_C0402-1UF,16V,10%,X6S,CHA  I35  PC192_P0_2
   1 SW_P12V_PVCCINFAON_CPU0_FLT      A @S9S_MB_2U_LIB.S9S_MB_2U(SCH_1):SW_P12V_PVCCINFAON_CPU0_FLT
   2    GND      B @S9S_MB_2U_LIB.S9S_MB_2U(SCH_1):GND

Q_CAP_C0805-22UF,16V,20%,X6S,CA  I36  PC196_P0_2
   1 SW_P12V_PVCCINFAON_CPU0_FLT      A @S9S_MB_2U_LIB.S9S_MB_2U(SCH_1):SW_P12V_PVCCINFAON_CPU0_FLT
   2    GND      B @S9S_MB_2U_LIB.S9S_MB_2U(SCH_1):GND

Q_CAP_C0805-22UF,16V,20%,X6S,CA  I37  PC198_P0_2
   1 SW_P12V_PVCCINFAON_CPU0_FLT      A @S9S_MB_2U_LIB.S9S_MB_2U(SCH_1):SW_P12V_PVCCINFAON_CPU0_FLT
   2    GND      B @S9S_MB_2U_LIB.S9S_MB_2U(SCH_1):GND

Q_CAP_C0402-100NF,50V,10%,X7R,A  I38  PC194
   1 SW_PVCCINFAON_CPU0_BOOT2_R      A @S9S_MB_2U_LIB.S9S_MB_2U(SCH_1):SW_PVCCINFAON_CPU0_BOOT2_R
   2 SW_PVCCINFAON_CPU0_BOOTR2      B @S9S_MB_2U_LIB.S9S_MB_2U(SCH_1):SW_PVCCINFAON_CPU0_BOOTR2

Q_INDUCTOR_SMLF-120NH/69A,IND,A  I39  PL5
   2 PVCCINFAON_CPU0      2 @S9S_MB_2U_LIB.S9S_MB_2U(SCH_1):PVCCINFAON_CPU0
   1 SW_PVCCINFAON_CPU0_SW2      1 @S9S_MB_2U_LIB.S9S_MB_2U(SCH_1):SW_PVCCINFAON_CPU0_SW2

Q_CAP_C0805-22UF,4V,20%,X6S,CHA  I40  PC203_P0_2
   1 PVCCINFAON_CPU0      A @S9S_MB_2U_LIB.S9S_MB_2U(SCH_1):PVCCINFAON_CPU0
   2    GND      B @S9S_MB_2U_LIB.S9S_MB_2U(SCH_1):GND

Q_CAP_0402-3300PF,50V,10%,X7R,A  I45  PC189_P0_1
   1 SW_P12V_PVCCINFAON_CPU0_FLT      A @S9S_MB_2U_LIB.S9S_MB_2U(SCH_1):SW_P12V_PVCCINFAON_CPU0_FLT
   2    GND      B @S9S_MB_2U_LIB.S9S_MB_2U(SCH_1):GND

Q_RES_0402LF-0,5%,1/16W,CHIP,CA  I46  PR1776
   1 PVCCINFAON_CPU0_VOS1      A @S9S_MB_2U_LIB.S9S_MB_2U(SCH_1):PVCCINFAON_CPU0_VOS1
   2 PVCCINFAON_CPU0      B @S9S_MB_2U_LIB.S9S_MB_2U(SCH_1):PVCCINFAON_CPU0

Q_RES_0402LF-3.3,1%,1/16W,CHIPA  I47  PR1774
   1 SW_PVCCINFAON_CPU0_BOOT1      A @S9S_MB_2U_LIB.S9S_MB_2U(SCH_1):SW_PVCCINFAON_CPU0_BOOT1
   2 SW_PVCCINFAON_CPU0_BOOT1_R      B @S9S_MB_2U_LIB.S9S_MB_2U(SCH_1):SW_PVCCINFAON_CPU0_BOOT1_R

Q_CAP_C0402-1UF,16V,10%,X6S,CHA  I48  PC191_P0_1
   1 SW_P12V_PVCCINFAON_CPU0_FLT      A @S9S_MB_2U_LIB.S9S_MB_2U(SCH_1):SW_P12V_PVCCINFAON_CPU0_FLT
   2    GND      B @S9S_MB_2U_LIB.S9S_MB_2U(SCH_1):GND

Q_CAP_C0805-22UF,16V,20%,X6S,CA  I49  PC195_P0_1
   1 SW_P12V_PVCCINFAON_CPU0_FLT      A @S9S_MB_2U_LIB.S9S_MB_2U(SCH_1):SW_P12V_PVCCINFAON_CPU0_FLT
   2    GND      B @S9S_MB_2U_LIB.S9S_MB_2U(SCH_1):GND

Q_CAP_C0805-22UF,16V,20%,X6S,CA  I50  PC197_P0_1
   1 SW_P12V_PVCCINFAON_CPU0_FLT      A @S9S_MB_2U_LIB.S9S_MB_2U(SCH_1):SW_P12V_PVCCINFAON_CPU0_FLT
   2    GND      B @S9S_MB_2U_LIB.S9S_MB_2U(SCH_1):GND

Q_CAP_C0402-100NF,50V,10%,X7R,A  I51  PC193
   1 SW_PVCCINFAON_CPU0_BOOT1_R      A @S9S_MB_2U_LIB.S9S_MB_2U(SCH_1):SW_PVCCINFAON_CPU0_BOOT1_R
   2 SW_PVCCINFAON_CPU0_BOOTR1      B @S9S_MB_2U_LIB.S9S_MB_2U(SCH_1):SW_PVCCINFAON_CPU0_BOOTR1

Q_INDUCTOR_SMLF-120NH/69A,IND,A  I52  PL4
   2 PVCCINFAON_CPU0      2 @S9S_MB_2U_LIB.S9S_MB_2U(SCH_1):PVCCINFAON_CPU0
   1 SW_PVCCINFAON_CPU0_SW1      1 @S9S_MB_2U_LIB.S9S_MB_2U(SCH_1):SW_PVCCINFAON_CPU0_SW1

Q_CAP_C0805-22UF,4V,20%,X6S,CHA  I56  PC202_P0_1
   1 PVCCINFAON_CPU0      A @S9S_MB_2U_LIB.S9S_MB_2U(SCH_1):PVCCINFAON_CPU0
   2    GND      B @S9S_MB_2U_LIB.S9S_MB_2U(SCH_1):GND

Q_CAPP_THLF-560UF,2.5V,20%,OSCA  I66  PC1574
   1 PVCCINFAON_CPU0      A @S9S_MB_2U_LIB.S9S_MB_2U(SCH_1):PVCCINFAON_CPU0
   2    GND      B @S9S_MB_2U_LIB.S9S_MB_2U(SCH_1):GND

Q_CAPP_THLF-560UF,2.5V,20%,OSCA  I67  PC1576
   1 PVCCINFAON_CPU0      A @S9S_MB_2U_LIB.S9S_MB_2U(SCH_1):PVCCINFAON_CPU0
   2    GND      B @S9S_MB_2U_LIB.S9S_MB_2U(SCH_1):GND

Q_CAPP_SMLF-330UF,2V,35%,SPCAPA  I68  PC1573
   1 PVCCINFAON_CPU0      A @S9S_MB_2U_LIB.S9S_MB_2U(SCH_1):PVCCINFAON_CPU0
   2    GND      B @S9S_MB_2U_LIB.S9S_MB_2U(SCH_1):GND

Q_CAPP_THLF-270UF,16V,20%,OSCOA  I74  PC207
   1 SW_P12V_PVCCINFAON_CPU0_FLT      A @S9S_MB_2U_LIB.S9S_MB_2U(SCH_1):SW_P12V_PVCCINFAON_CPU0_FLT
   2    GND      B @S9S_MB_2U_LIB.S9S_MB_2U(SCH_1):GND

Q_RES_0402LF-2.2,1%,1/16W,CHIPA  I14  PR102
   1 PVCCFA_EHV_CPU0_PVCC      A @S9S_MB_2U_LIB.S9S_MB_2U(SCH_1):PVCCFA_EHV_CPU0_PVCC
   2 PVCCINFAON_CPU0_VDD2      B @S9S_MB_2U_LIB.S9S_MB_2U(SCH_1):PVCCINFAON_CPU0_VDD2

Q_CAP_C0402-2.2UF,10V,10%,X6S,A  I29  PC2947
   1 PVCCFA_EHV_CPU0_PVCC      A @S9S_MB_2U_LIB.S9S_MB_2U(SCH_1):PVCCFA_EHV_CPU0_PVCC
   2    GND      B @S9S_MB_2U_LIB.S9S_MB_2U(SCH_1):GND

Q_CAP_C0805-22UF,4V,20%,X6S,CHA  I41  PC205_P0_2
   1 PVCCINFAON_CPU0      A @S9S_MB_2U_LIB.S9S_MB_2U(SCH_1):PVCCINFAON_CPU0
   2    GND      B @S9S_MB_2U_LIB.S9S_MB_2U(SCH_1):GND

Q_CAP_C0402-100NF,50V,10%,X7R,A  I60  PC1655
   1 P12V_AUX      A @S9S_MB_2U_LIB.S9S_MB_2U(SCH_1):P12V_AUX
   2    GND      B @S9S_MB_2U_LIB.S9S_MB_2U(SCH_1):GND

Q_INDUCTOR_SMLF-100NH/16A,IND,A  I62  PL6
   2 SW_P12V_PVCCINFAON_CPU0_FLT      2 @S9S_MB_2U_LIB.S9S_MB_2U(SCH_1):SW_P12V_PVCCINFAON_CPU0_FLT
   1 P12V_AUX      1 @S9S_MB_2U_LIB.S9S_MB_2U(SCH_1):P12V_AUX

Q_CAPP_SMLF-330UF,2V,35%,SPCAPA  I69  PC1575
   1 PVCCINFAON_CPU0      A @S9S_MB_2U_LIB.S9S_MB_2U(SCH_1):PVCCINFAON_CPU0
   2    GND      B @S9S_MB_2U_LIB.S9S_MB_2U(SCH_1):GND

Q_CAPP_THLF-270UF,16V,20%,OSCOA  I75  PC208
   1 SW_P12V_PVCCINFAON_CPU0_FLT      A @S9S_MB_2U_LIB.S9S_MB_2U(SCH_1):SW_P12V_PVCCINFAON_CPU0_FLT
   2    GND      B @S9S_MB_2U_LIB.S9S_MB_2U(SCH_1):GND

ISL99390FRZTR5935-ISL99390FRZ-A  I79  PU43_P0_1
  34 PVCCINFAON_CPU0_APWM1    PWM @S9S_MB_2U_LIB.S9S_MB_2U(SCH_1):PVCCINFAON_CPU0_APWM1
  39 PVCCINFAON_CPU0_VREF  REFIN @S9S_MB_2U_LIB.S9S_MB_2U(SCH_1):PVCCINFAON_CPU0_VREF
   3 PVCCINFAON_CPU0_VDD1    VCC @S9S_MB_2U_LIB.S9S_MB_2U(SCH_1):PVCCINFAON_CPU0_VDD1
   2    GND   AGND @S9S_MB_2U_LIB.S9S_MB_2U(SCH_1):GND
  33 SW_PVCCINFAON_CPU0_BOOT1   BOOT @S9S_MB_2U_LIB.S9S_MB_2U(SCH_1):SW_PVCCINFAON_CPU0_BOOT1
25_29 SW_P12V_PVCCINFAON_CPU0_FLT   VIN1 @S9S_MB_2U_LIB.S9S_MB_2U(SCH_1):SW_P12V_PVCCINFAON_CPU0_FLT
  32 SW_PVCCINFAON_CPU0_BOOTR1  PHASE @S9S_MB_2U_LIB.S9S_MB_2U(SCH_1):SW_PVCCINFAON_CPU0_BOOTR1
   4 PVCCFA_EHV_CPU0_PVCC   PVCC @S9S_MB_2U_LIB.S9S_MB_2U(SCH_1):PVCCFA_EHV_CPU0_PVCC
  36 PVCCINFAON_CPU0_ATSEN TOUT_FLT @S9S_MB_2U_LIB.S9S_MB_2U(SCH_1):PVCCINFAON_CPU0_ATSEN
  38 PVCCINFAON_CPU0_ACSP1   IOUT @S9S_MB_2U_LIB.S9S_MB_2U(SCH_1):PVCCINFAON_CPU0_ACSP1
  37 PVCCINFAON_CPU0_LSET1   LSET @S9S_MB_2U_LIB.S9S_MB_2U(SCH_1):PVCCINFAON_CPU0_LSET1
10_19 SW_PVCCINFAON_CPU0_SW1     SW @S9S_MB_2U_LIB.S9S_MB_2U(SCH_1):SW_PVCCINFAON_CPU0_SW1
   5    GND  PGND1 @S9S_MB_2U_LIB.S9S_MB_2U(SCH_1):GND
  30 SW_P12V_PVCCINFAON_CPU0_FLT   VIN2 @S9S_MB_2U_LIB.S9S_MB_2U(SCH_1):SW_P12V_PVCCINFAON_CPU0_FLT
   1 PVCCINFAON_CPU0_VOS1    VOS @S9S_MB_2U_LIB.S9S_MB_2U(SCH_1):PVCCINFAON_CPU0_VOS1
  40    GND  PGND3 @S9S_MB_2U_LIB.S9S_MB_2U(SCH_1):GND
  35 PVCCINFAON_CPU0_VDD1     EN @S9S_MB_2U_LIB.S9S_MB_2U(SCH_1):PVCCINFAON_CPU0_VDD1
  31     NC    DNC     NC
   6     NC    GL1     NC
  41     NC    GL2     NC
7_9-20_24    GND  PGND2 @S9S_MB_2U_LIB.S9S_MB_2U(SCH_1):GND

Q_RES_0402LF-8.87K,1%,1/16W,EMA  I2  PR1707
   1 PVCCINFAON_CPU0_LSET2      A @S9S_MB_2U_LIB.S9S_MB_2U(SCH_1):PVCCINFAON_CPU0_LSET2
   2    GND      B @S9S_MB_2U_LIB.S9S_MB_2U(SCH_1):GND

Q_RES_0402LF-8.87K,1%,1/16W,EMA  I5  PR1708
   1 PVCCINFAON_CPU0_LSET1      A @S9S_MB_2U_LIB.S9S_MB_2U(SCH_1):PVCCINFAON_CPU0_LSET1
   2    GND      B @S9S_MB_2U_LIB.S9S_MB_2U(SCH_1):GND

Q_CAP_0402-0.1UF,25V,10%,X7R,CA  I11  PC1346
   1    GND      A @S9S_MB_2U_LIB.S9S_MB_2U(SCH_1):GND
   2 PVCCINFAON_CPU0_VREF      B @S9S_MB_2U_LIB.S9S_MB_2U(SCH_1):PVCCINFAON_CPU0_VREF

Q_CAP_C0402-2.2UF,10V,10%,X6S,A  I13  PC188
   1 PVCCINFAON_CPU0_VDD2      A @S9S_MB_2U_LIB.S9S_MB_2U(SCH_1):PVCCINFAON_CPU0_VDD2
   2    GND      B @S9S_MB_2U_LIB.S9S_MB_2U(SCH_1):GND

Q_CAP_C0402-2.2UF,10V,10%,X6S,A  I16  PC2946
   1 PVCCFA_EHV_CPU0_PVCC      A @S9S_MB_2U_LIB.S9S_MB_2U(SCH_1):PVCCFA_EHV_CPU0_PVCC
   2    GND      B @S9S_MB_2U_LIB.S9S_MB_2U(SCH_1):GND

Q_CAP_C0402-2.2UF,10V,10%,X6S,A  I24  PC187
   1 PVCCINFAON_CPU0_VDD1      A @S9S_MB_2U_LIB.S9S_MB_2U(SCH_1):PVCCINFAON_CPU0_VDD1
   2    GND      B @S9S_MB_2U_LIB.S9S_MB_2U(SCH_1):GND

Q_CAP_C0402-100NF,50V,10%,X7R,A  I54  PC199_P0_1
   1 PVCCINFAON_CPU0      A @S9S_MB_2U_LIB.S9S_MB_2U(SCH_1):PVCCINFAON_CPU0
   2    GND      B @S9S_MB_2U_LIB.S9S_MB_2U(SCH_1):GND

Q_CAP_C0805-22UF,4V,20%,X6S,CHA  I57  PC204_P0_1
   1 PVCCINFAON_CPU0      A @S9S_MB_2U_LIB.S9S_MB_2U(SCH_1):PVCCINFAON_CPU0
   2    GND      B @S9S_MB_2U_LIB.S9S_MB_2U(SCH_1):GND

Q_RES_0402LF-499,1%,1/16W,CHIPA  I63  PR4226
   1 PVCCINFAON_CPU0      A @S9S_MB_2U_LIB.S9S_MB_2U(SCH_1):PVCCINFAON_CPU0
   2    GND      B @S9S_MB_2U_LIB.S9S_MB_2U(SCH_1):GND

Q_CAPP_THLF-560UF,2.5V,20%,OSCA  I70  PC1579
   1 PVCCINFAON_CPU0      A @S9S_MB_2U_LIB.S9S_MB_2U(SCH_1):PVCCINFAON_CPU0
   2    GND      B @S9S_MB_2U_LIB.S9S_MB_2U(SCH_1):GND


DRAWING: @S9S_MB_2U_LIB.S9S_MB_2U(SCH_1):PAGE265 

Q_RES_0402LF-8.87K,1%,1/16W,EMA  I3  PR2718
   1 PVCCD_HV_CPU0_LSET1      A @S9S_MB_2U_LIB.S9S_MB_2U(SCH_1):PVCCD_HV_CPU0_LSET1
   2    GND      B @S9S_MB_2U_LIB.S9S_MB_2U(SCH_1):GND

ISL99390FRZTR5935-ISL99390FRZ-A  I8  PU36
  34 PVCCD_HV_CPU0_APWM1    PWM @S9S_MB_2U_LIB.S9S_MB_2U(SCH_1):PVCCD_HV_CPU0_APWM1
  39 PVCCD_HV_CPU0_VREF  REFIN @S9S_MB_2U_LIB.S9S_MB_2U(SCH_1):PVCCD_HV_CPU0_VREF
   3 PVCCD_HV_CPU0_VDD1    VCC @S9S_MB_2U_LIB.S9S_MB_2U(SCH_1):PVCCD_HV_CPU0_VDD1
   2    GND   AGND @S9S_MB_2U_LIB.S9S_MB_2U(SCH_1):GND
  33 SW_PVCCD_HV_CPU0_BOOT1   BOOT @S9S_MB_2U_LIB.S9S_MB_2U(SCH_1):SW_PVCCD_HV_CPU0_BOOT1
25_29 SW_P12V_PVCCINFAON_CPU0_FLT   VIN1 @S9S_MB_2U_LIB.S9S_MB_2U(SCH_1):SW_P12V_PVCCINFAON_CPU0_FLT
  32 SW_PVCCD_HV_CPU0_BOOTR1  PHASE @S9S_MB_2U_LIB.S9S_MB_2U(SCH_1):SW_PVCCD_HV_CPU0_BOOTR1
   4 PVCCFA_EHV_CPU0_PVCC   PVCC @S9S_MB_2U_LIB.S9S_MB_2U(SCH_1):PVCCFA_EHV_CPU0_PVCC
  36 PVCCD_HV_CPU0_ATSEN TOUT_FLT @S9S_MB_2U_LIB.S9S_MB_2U(SCH_1):PVCCD_HV_CPU0_ATSEN
  38 PVCCD_HV_CPU0_ACSP1   IOUT @S9S_MB_2U_LIB.S9S_MB_2U(SCH_1):PVCCD_HV_CPU0_ACSP1
  37 PVCCD_HV_CPU0_LSET1   LSET @S9S_MB_2U_LIB.S9S_MB_2U(SCH_1):PVCCD_HV_CPU0_LSET1
10_19 SW_PVCCD_HV_CPU0_SW1     SW @S9S_MB_2U_LIB.S9S_MB_2U(SCH_1):SW_PVCCD_HV_CPU0_SW1
   5    GND  PGND1 @S9S_MB_2U_LIB.S9S_MB_2U(SCH_1):GND
  30 SW_P12V_PVCCINFAON_CPU0_FLT   VIN2 @S9S_MB_2U_LIB.S9S_MB_2U(SCH_1):SW_P12V_PVCCINFAON_CPU0_FLT
   1 PVCCD_HV_CPU0_VOS    VOS @S9S_MB_2U_LIB.S9S_MB_2U(SCH_1):PVCCD_HV_CPU0_VOS
  40    GND  PGND3 @S9S_MB_2U_LIB.S9S_MB_2U(SCH_1):GND
  35 PVCCD_HV_CPU0_VDD1     EN @S9S_MB_2U_LIB.S9S_MB_2U(SCH_1):PVCCD_HV_CPU0_VDD1
  31     NC    DNC     NC
   6     NC    GL1     NC
  41     NC    GL2     NC
7_9-20_24    GND  PGND2 @S9S_MB_2U_LIB.S9S_MB_2U(SCH_1):GND

Q_CAP_C0402-2.2UF,10V,10%,X6S,A  I11  PC633
   1 PVCCD_HV_CPU0_VDD1      A @S9S_MB_2U_LIB.S9S_MB_2U(SCH_1):PVCCD_HV_CPU0_VDD1
   2    GND      B @S9S_MB_2U_LIB.S9S_MB_2U(SCH_1):GND

Q_RES_0402LF-0,5%,1/16W,CHIP,CA  I17  PR1785
   1 PVCCD_HV_CPU0_VOS      A @S9S_MB_2U_LIB.S9S_MB_2U(SCH_1):PVCCD_HV_CPU0_VOS
   2 PVCCD_HV_CPU0      B @S9S_MB_2U_LIB.S9S_MB_2U(SCH_1):PVCCD_HV_CPU0

Q_CAP_0402-3300PF,50V,10%,X7R,A  I18  PC634
   1 SW_P12V_PVCCINFAON_CPU0_FLT      A @S9S_MB_2U_LIB.S9S_MB_2U(SCH_1):SW_P12V_PVCCINFAON_CPU0_FLT
   2    GND      B @S9S_MB_2U_LIB.S9S_MB_2U(SCH_1):GND

Q_RES_0402LF-3.3,1%,1/16W,CHIPA  I19  PR1784
   1 SW_PVCCD_HV_CPU0_BOOT1      A @S9S_MB_2U_LIB.S9S_MB_2U(SCH_1):SW_PVCCD_HV_CPU0_BOOT1
   2 SW_PVCCD_HV_CPU0_BOOT1_R      B @S9S_MB_2U_LIB.S9S_MB_2U(SCH_1):SW_PVCCD_HV_CPU0_BOOT1_R

Q_CAP_C0402-1UF,16V,10%,X6S,CHA  I20  PC635
   1 SW_P12V_PVCCINFAON_CPU0_FLT      A @S9S_MB_2U_LIB.S9S_MB_2U(SCH_1):SW_P12V_PVCCINFAON_CPU0_FLT
   2    GND      B @S9S_MB_2U_LIB.S9S_MB_2U(SCH_1):GND

Q_CAP_C0805-22UF,16V,20%,X6S,CA  I21  PC637
   1 SW_P12V_PVCCINFAON_CPU0_FLT      A @S9S_MB_2U_LIB.S9S_MB_2U(SCH_1):SW_P12V_PVCCINFAON_CPU0_FLT
   2    GND      B @S9S_MB_2U_LIB.S9S_MB_2U(SCH_1):GND

Q_CAP_C0402-100NF,50V,10%,X7R,A  I22  PC636
   1 SW_PVCCD_HV_CPU0_BOOT1_R      A @S9S_MB_2U_LIB.S9S_MB_2U(SCH_1):SW_PVCCD_HV_CPU0_BOOT1_R
   2 SW_PVCCD_HV_CPU0_BOOTR1      B @S9S_MB_2U_LIB.S9S_MB_2U(SCH_1):SW_PVCCD_HV_CPU0_BOOTR1

Q_CAP_C0805-22UF,16V,20%,X6S,CA  I23  PC638
   1 SW_P12V_PVCCINFAON_CPU0_FLT      A @S9S_MB_2U_LIB.S9S_MB_2U(SCH_1):SW_P12V_PVCCINFAON_CPU0_FLT
   2    GND      B @S9S_MB_2U_LIB.S9S_MB_2U(SCH_1):GND

Q_CAP_C0805-22UF,4V,20%,X6S,CHA  I25  PC641
   1 PVCCD_HV_CPU0      A @S9S_MB_2U_LIB.S9S_MB_2U(SCH_1):PVCCD_HV_CPU0
   2    GND      B @S9S_MB_2U_LIB.S9S_MB_2U(SCH_1):GND

Q_CAPP_SMLF-330UF,2V,35%,SPCAPA  I26  PC1910
   1 PVCCD_HV_CPU0      A @S9S_MB_2U_LIB.S9S_MB_2U(SCH_1):PVCCD_HV_CPU0
   2    GND      B @S9S_MB_2U_LIB.S9S_MB_2U(SCH_1):GND

Q_CAP_C0805-22UF,4V,20%,X6S,CHA  I28  PC642
   1 PVCCD_HV_CPU0      A @S9S_MB_2U_LIB.S9S_MB_2U(SCH_1):PVCCD_HV_CPU0
   2    GND      B @S9S_MB_2U_LIB.S9S_MB_2U(SCH_1):GND

Q_CAP_C0805-22UF,4V,20%,X6S,CHA  I29  PC1
   1 PVCCD_HV_CPU0      A @S9S_MB_2U_LIB.S9S_MB_2U(SCH_1):PVCCD_HV_CPU0
   2    GND      B @S9S_MB_2U_LIB.S9S_MB_2U(SCH_1):GND

Q_CAPP_THLF-560UF,2.5V,20%,OSCA  I34  PC1645
   1 PVCCD_HV_CPU0      A @S9S_MB_2U_LIB.S9S_MB_2U(SCH_1):PVCCD_HV_CPU0
   2    GND      B @S9S_MB_2U_LIB.S9S_MB_2U(SCH_1):GND

Q_RES_0402LF-499,1%,1/16W,CHIPA  I37  PR4237
   1 PVCCD_HV_CPU0      A @S9S_MB_2U_LIB.S9S_MB_2U(SCH_1):PVCCD_HV_CPU0
   2    GND      B @S9S_MB_2U_LIB.S9S_MB_2U(SCH_1):GND

Q_RES_0402LF-2.2,1%,1/16W,CHIPA  I12  PR380
   1 PVCCFA_EHV_CPU0_PVCC      A @S9S_MB_2U_LIB.S9S_MB_2U(SCH_1):PVCCFA_EHV_CPU0_PVCC
   2 PVCCD_HV_CPU0_VDD1      B @S9S_MB_2U_LIB.S9S_MB_2U(SCH_1):PVCCD_HV_CPU0_VDD1

Q_CAP_C0402-2.2UF,10V,10%,X6S,A  I14  PC2948
   1 PVCCFA_EHV_CPU0_PVCC      A @S9S_MB_2U_LIB.S9S_MB_2U(SCH_1):PVCCFA_EHV_CPU0_PVCC
   2    GND      B @S9S_MB_2U_LIB.S9S_MB_2U(SCH_1):GND

Q_CAP_C0402-100NF,50V,10%,X7R,A  I24  PC639
   1 PVCCD_HV_CPU0      A @S9S_MB_2U_LIB.S9S_MB_2U(SCH_1):PVCCD_HV_CPU0
   2    GND      B @S9S_MB_2U_LIB.S9S_MB_2U(SCH_1):GND

Q_CAPP_THLF-560UF,2.5V,20%,OSCA  I27  PC1644
   1 PVCCD_HV_CPU0      A @S9S_MB_2U_LIB.S9S_MB_2U(SCH_1):PVCCD_HV_CPU0
   2    GND      B @S9S_MB_2U_LIB.S9S_MB_2U(SCH_1):GND

Q_CAP_0402-0.1UF,25V,10%,X7R,CA  I7  PC1354
   1    GND      A @S9S_MB_2U_LIB.S9S_MB_2U(SCH_1):GND
   2 PVCCD_HV_CPU0_VREF      B @S9S_MB_2U_LIB.S9S_MB_2U(SCH_1):PVCCD_HV_CPU0_VREF

Q_INDUCTOR_SMLF-120NH/69A,IND,A  I30  PL35
   2 PVCCD_HV_CPU0      2 @S9S_MB_2U_LIB.S9S_MB_2U(SCH_1):PVCCD_HV_CPU0
   1 SW_PVCCD_HV_CPU0_SW1      1 @S9S_MB_2U_LIB.S9S_MB_2U(SCH_1):SW_PVCCD_HV_CPU0_SW1


DRAWING: @S9S_MB_2U_LIB.S9S_MB_2U(SCH_1):PAGE268 

Q_RES_0402LF-0,5%,1/16W,CHIP,CA  I19  PR1
   1    GND      A @S9S_MB_2U_LIB.S9S_MB_2U(SCH_1):GND
   2    GND      B @S9S_MB_2U_LIB.S9S_MB_2U(SCH_1):GND

Q_CAP_C0402-0.22UF,25V,10%,X7RA  I26  PC1275
   1 SW_PVNN_MAIN_CPU0_BST_R      A @S9S_MB_2U_LIB.S9S_MB_2U(SCH_1):SW_PVNN_MAIN_CPU0_BST_R
   2 SW_PVNN_MAIN_CPU0_SW      B @S9S_MB_2U_LIB.S9S_MB_2U(SCH_1):SW_PVNN_MAIN_CPU0_SW

Q_RES_0402LF-8.25K,0.1%,1/16W,A  I36  PR501
   1 PVNN_MAIN_CPU0_FB      A @S9S_MB_2U_LIB.S9S_MB_2U(SCH_1):PVNN_MAIN_CPU0_FB
   2 PVNN_MAIN_CPU0_FB_RC      B @S9S_MB_2U_LIB.S9S_MB_2U(SCH_1):PVNN_MAIN_CPU0_FB_RC

Q_RES_0402LF-0,5%,1/16W,EMPTY,A  I40  PR4698
   1 PVNN_MAIN_CPU0_FB_RC      A @S9S_MB_2U_LIB.S9S_MB_2U(SCH_1):PVNN_MAIN_CPU0_FB_RC
   2 PVNN_MAIN_CPU0      B @S9S_MB_2U_LIB.S9S_MB_2U(SCH_1):PVNN_MAIN_CPU0

Q_RES_0402LF-0,5%,1/16W,CHIP,CA  I27  PR4271
   1 SW_PVNN_MAIN_CPU0_BST      A @S9S_MB_2U_LIB.S9S_MB_2U(SCH_1):SW_PVNN_MAIN_CPU0_BST
   2 SW_PVNN_MAIN_CPU0_BST_R      B @S9S_MB_2U_LIB.S9S_MB_2U(SCH_1):SW_PVNN_MAIN_CPU0_BST_R

Q_CAP_0402-1000PF,50V,5%,X7R,TA  I31  C1296
   1 PWRGD_PVNN_MAIN_CPU0      A @S9S_MB_2U_LIB.S9S_MB_2U(SCH_1):PWRGD_PVNN_MAIN_CPU0
   2    GND      B @S9S_MB_2U_LIB.S9S_MB_2U(SCH_1):GND

Q_RES_0402LF-2K,1%,1/16W,CHIP,A  I11  R1445
   1 FM_PVNN_MAIN_CPU0_EN      A @S9S_MB_2U_LIB.S9S_MB_2U(SCH_1):FM_PVNN_MAIN_CPU0_EN
   2    GND      B @S9S_MB_2U_LIB.S9S_MB_2U(SCH_1):GND

Q_CAP_0402-3300PF,50V,10%,X7R,A  I25  PC27
   1 PVNN_MAIN_CPU0_REF      A @S9S_MB_2U_LIB.S9S_MB_2U(SCH_1):PVNN_MAIN_CPU0_REF
   2    GND      B @S9S_MB_2U_LIB.S9S_MB_2U(SCH_1):GND

Q_CAP_0402-680PF,50V,10%,X7R,TA  I35  PC237
   1 PVNN_MAIN_CPU0_FB      A @S9S_MB_2U_LIB.S9S_MB_2U(SCH_1):PVNN_MAIN_CPU0_FB
   2 PVNN_MAIN_CPU0_FB_RC      B @S9S_MB_2U_LIB.S9S_MB_2U(SCH_1):PVNN_MAIN_CPU0_FB_RC

Q_CAP_C0805-22UF,4V,20%,X6S,CHA  I42  PC1278
   1 PVNN_MAIN_CPU0      A @S9S_MB_2U_LIB.S9S_MB_2U(SCH_1):PVNN_MAIN_CPU0
   2    GND      B @S9S_MB_2U_LIB.S9S_MB_2U(SCH_1):GND

Q_RES_0402LF-0,5%,1/16W,CHIP,CA  I33  R1652
   1 PWRGD_PVNN_MAIN_CPU0_R      A @S9S_MB_2U_LIB.S9S_MB_2U(SCH_1):PWRGD_PVNN_MAIN_CPU0_R
   2 PWRGD_PVNN_MAIN_CPU0      B @S9S_MB_2U_LIB.S9S_MB_2U(SCH_1):PWRGD_PVNN_MAIN_CPU0

Q_CAP_0402-0.01UF,25V,10%,X7R,A  I39  PC1420
   1 PVNN_MAIN_CPU0_FB_RC      A @S9S_MB_2U_LIB.S9S_MB_2U(SCH_1):PVNN_MAIN_CPU0_FB_RC
   2    GND      B @S9S_MB_2U_LIB.S9S_MB_2U(SCH_1):GND

Q_RES_0402LF-0,5%,1/16W,CHIP,CA  I41  PR4683
   1 PVNN_MAIN_CPU0_FB_RC      A @S9S_MB_2U_LIB.S9S_MB_2U(SCH_1):PVNN_MAIN_CPU0_FB_RC
   2 PVNN_MAIN_CPU0      B @S9S_MB_2U_LIB.S9S_MB_2U(SCH_1):PVNN_MAIN_CPU0

Q_CAP_0402-1000PF,50V,5%,EMPTYA  I4  C1307
   1 FM_PVNN_MAIN_CPU0_EN      A @S9S_MB_2U_LIB.S9S_MB_2U(SCH_1):FM_PVNN_MAIN_CPU0_EN
   2    GND      B @S9S_MB_2U_LIB.S9S_MB_2U(SCH_1):GND

Q_RES_0402LF-0,5%,1/16W,CHIP,CA  I10  PR3339
   1 P3V3_AUX      A @S9S_MB_2U_LIB.S9S_MB_2U(SCH_1):P3V3_AUX
   2 PVNN_MAIN_CPU0_VCC      B @S9S_MB_2U_LIB.S9S_MB_2U(SCH_1):PVNN_MAIN_CPU0_VCC

Q_CAP_C0805-22UF,16V,20%,X6S,CA  I15  PC1273
   1 SW_P12V_PVCCINFAON_CPU0_FLT      A @S9S_MB_2U_LIB.S9S_MB_2U(SCH_1):SW_P12V_PVCCINFAON_CPU0_FLT
   2    GND      B @S9S_MB_2U_LIB.S9S_MB_2U(SCH_1):GND

Q_CAP_C0402-1UF,16V,10%,X6S,CHA  I23  PC1274
   1 SW_P12V_PVCCINFAON_CPU0_FLT      A @S9S_MB_2U_LIB.S9S_MB_2U(SCH_1):SW_P12V_PVCCINFAON_CPU0_FLT
   2    GND      B @S9S_MB_2U_LIB.S9S_MB_2U(SCH_1):GND

Q_RES_0402LF-12.4K,0.1%,1/16W,A  I28  PR50
   1 PVNN_MAIN_CPU0_FB      A @S9S_MB_2U_LIB.S9S_MB_2U(SCH_1):PVNN_MAIN_CPU0_FB
   2    GND      B @S9S_MB_2U_LIB.S9S_MB_2U(SCH_1):GND

Q_RES_0402LF-10K,1%,1/16W,CHIPA  I32  R2409
   1 P3V3_AUX      A @S9S_MB_2U_LIB.S9S_MB_2U(SCH_1):P3V3_AUX
   2 PWRGD_PVNN_MAIN_CPU0_R      B @S9S_MB_2U_LIB.S9S_MB_2U(SCH_1):PWRGD_PVNN_MAIN_CPU0_R

Q_CAP_C0805-22UF,4V,20%,X6S,CHA  I43  PC1279
   1 PVNN_MAIN_CPU0      A @S9S_MB_2U_LIB.S9S_MB_2U(SCH_1):PVNN_MAIN_CPU0
   2    GND      B @S9S_MB_2U_LIB.S9S_MB_2U(SCH_1):GND

Q_RES_0402LF-10K,1%,1/16W,EMPTA  I5  R2338
   1 P3V3_AUX      A @S9S_MB_2U_LIB.S9S_MB_2U(SCH_1):P3V3_AUX
   2 FM_PVNN_MAIN_CPU0_EN      B @S9S_MB_2U_LIB.S9S_MB_2U(SCH_1):FM_PVNN_MAIN_CPU0_EN

Q_CAP_C0402-1UF,25V,10%,X6S,CHA  I7  PC2221
   1 PVNN_MAIN_CPU0_VCC      A @S9S_MB_2U_LIB.S9S_MB_2U(SCH_1):PVNN_MAIN_CPU0_VCC
   2    GND      B @S9S_MB_2U_LIB.S9S_MB_2U(SCH_1):GND

Q_RES_0402LF-60.4K,1%,1/16W,CHA  I9  PR1301
   1 PVNN_MAIN_CPU0_MODE      A @S9S_MB_2U_LIB.S9S_MB_2U(SCH_1):PVNN_MAIN_CPU0_MODE
   2    GND      B @S9S_MB_2U_LIB.S9S_MB_2U(SCH_1):GND

Q_CAP_C0805-22UF,16V,20%,X6S,CA  I13  PC1272
   1 SW_P12V_PVCCINFAON_CPU0_FLT      A @S9S_MB_2U_LIB.S9S_MB_2U(SCH_1):SW_P12V_PVCCINFAON_CPU0_FLT
   2    GND      B @S9S_MB_2U_LIB.S9S_MB_2U(SCH_1):GND

Q_RES_0402LF-22.6K,1%,1/16W,CHA  I21  PR1303
   1 PVNN_MAIN_CPU0_CS      A @S9S_MB_2U_LIB.S9S_MB_2U(SCH_1):PVNN_MAIN_CPU0_CS
   2    GND      B @S9S_MB_2U_LIB.S9S_MB_2U(SCH_1):GND

RS53317LR-RS53317LR,SMLF,IC,ALA  I22  PU81
   3 SW_P12V_PVCCINFAON_CPU0_FLT    VIN @S9S_MB_2U_LIB.S9S_MB_2U(SCH_1):SW_P12V_PVCCINFAON_CPU0_FLT
   9 PWRGD_PVNN_MAIN_CPU0_R  PGOOD @S9S_MB_2U_LIB.S9S_MB_2U(SCH_1):PWRGD_PVNN_MAIN_CPU0_R
  14    GND  PGND2 @S9S_MB_2U_LIB.S9S_MB_2U(SCH_1):GND
   5 FM_PVNN_MAIN_CPU0_EN     EN @S9S_MB_2U_LIB.S9S_MB_2U(SCH_1):FM_PVNN_MAIN_CPU0_EN
  10 SW_PVNN_MAIN_CPU0_BST    BST @S9S_MB_2U_LIB.S9S_MB_2U(SCH_1):SW_PVNN_MAIN_CPU0_BST
   6 PVNN_MAIN_CPU0_FB     FB @S9S_MB_2U_LIB.S9S_MB_2U(SCH_1):PVNN_MAIN_CPU0_FB
   7    GND   AGND @S9S_MB_2U_LIB.S9S_MB_2U(SCH_1):GND
  13 PVNN_MAIN_CPU0_VCC    VCC @S9S_MB_2U_LIB.S9S_MB_2U(SCH_1):PVNN_MAIN_CPU0_VCC
   1    GND  PGND1 @S9S_MB_2U_LIB.S9S_MB_2U(SCH_1):GND
  11 SW_PVNN_MAIN_CPU0_SW    SW2 @S9S_MB_2U_LIB.S9S_MB_2U(SCH_1):SW_PVNN_MAIN_CPU0_SW
   8 PVNN_MAIN_CPU0_REF    REF @S9S_MB_2U_LIB.S9S_MB_2U(SCH_1):PVNN_MAIN_CPU0_REF
  12 PVNN_MAIN_CPU0_MODE   MODE @S9S_MB_2U_LIB.S9S_MB_2U(SCH_1):PVNN_MAIN_CPU0_MODE
   4 PVNN_MAIN_CPU0_CS     CS @S9S_MB_2U_LIB.S9S_MB_2U(SCH_1):PVNN_MAIN_CPU0_CS
   2 SW_PVNN_MAIN_CPU0_SW    SW1 @S9S_MB_2U_LIB.S9S_MB_2U(SCH_1):SW_PVNN_MAIN_CPU0_SW

Q_INDUCTOR_SMLF-4.7UH,IND,CV-4B  I29  PL120
   2 PVNN_MAIN_CPU0      2 @S9S_MB_2U_LIB.S9S_MB_2U(SCH_1):PVNN_MAIN_CPU0
   1 SW_PVNN_MAIN_CPU0_SW      1 @S9S_MB_2U_LIB.S9S_MB_2U(SCH_1):SW_PVNN_MAIN_CPU0_SW

Q_CAP_C0402-100NF,50V,10%,X7R,A  I37  PC1276
   1 PVNN_MAIN_CPU0      A @S9S_MB_2U_LIB.S9S_MB_2U(SCH_1):PVNN_MAIN_CPU0
   2    GND      B @S9S_MB_2U_LIB.S9S_MB_2U(SCH_1):GND

Q_CAP_C0805-22UF,4V,20%,X6S,CHA  I38  PC1277
   1 PVNN_MAIN_CPU0      A @S9S_MB_2U_LIB.S9S_MB_2U(SCH_1):PVNN_MAIN_CPU0
   2    GND      B @S9S_MB_2U_LIB.S9S_MB_2U(SCH_1):GND

Q_CAP_C0805-22UF,4V,20%,X6S,CHA  I47  PC1206
   1 PVNN_MAIN_CPU0      A @S9S_MB_2U_LIB.S9S_MB_2U(SCH_1):PVNN_MAIN_CPU0
   2    GND      B @S9S_MB_2U_LIB.S9S_MB_2U(SCH_1):GND


DRAWING: @S9S_MB_2U_LIB.S9S_MB_2U(SCH_1):PAGE282 

Q_RES_0402LF-100,1%,1/16W,CHIPA  I29  R2593
   1 PVNN_TERM_CPU1      A @S9S_MB_2U_LIB.S9S_MB_2U(SCH_1):PVNN_TERM_CPU1
   2 SVID_DIO1_CPU1_R      B @S9S_MB_2U_LIB.S9S_MB_2U(SCH_1):SVID_DIO1_CPU1_R

Q_RES_0402LF-49.9,1%,1/16W,CHIA  I33  R1718
   1 PVNN_TERM_CPU1      A @S9S_MB_2U_LIB.S9S_MB_2U(SCH_1):PVNN_TERM_CPU1
   2 SVID_CLK1_CPU1_R      B @S9S_MB_2U_LIB.S9S_MB_2U(SCH_1):SVID_CLK1_CPU1_R

Q_RES_0402LF-0,5%,1/16W,CHIP,CA  I38  R2582
   1 SMB_VR_3V3AUX_SDA_R      A @S9S_MB_2U_LIB.S9S_MB_2U(SCH_1):SMB_VR_3V3AUX_SDA_R
   2 SMB_DIO_PVCCD_HV_CPU1      B @S9S_MB_2U_LIB.S9S_MB_2U(SCH_1):SMB_DIO_PVCCD_HV_CPU1

Q_RES_0402LF-1K,1%,1/16W,CHIP,A  I46  R2575
   1 P3V3_AUX      A @S9S_MB_2U_LIB.S9S_MB_2U(SCH_1):P3V3_AUX
   2 PWRGD_PVCCD_HV_CPU1_R      B @S9S_MB_2U_LIB.S9S_MB_2U(SCH_1):PWRGD_PVCCD_HV_CPU1_R

Q_RES_0402LF-1K,1%,1/16W,EMPTYA  I48  PR218
   1 PVCCD_HV_CPU1_ISENSE_N      A @S9S_MB_2U_LIB.S9S_MB_2U(SCH_1):PVCCD_HV_CPU1_ISENSE_N
   2    GND      B @S9S_MB_2U_LIB.S9S_MB_2U(SCH_1):GND

Q_CAP_0402-0.1UF,25V,10%,X7R,CA  I50  PC390
   1 PVCCD_HV_CPU1_ISENSE_N      A @S9S_MB_2U_LIB.S9S_MB_2U(SCH_1):PVCCD_HV_CPU1_ISENSE_N
   2    GND      B @S9S_MB_2U_LIB.S9S_MB_2U(SCH_1):GND

ISL69260IRAZT-ISL69260IRAZ-T,SA  I53  PU18
  23 PVCCD_HV_CPU1_ACSP1    CS7 @S9S_MB_2U_LIB.S9S_MB_2U(SCH_1):PVCCD_HV_CPU1_ACSP1
  39 PVCCD_HV_CPU1_VCC    VCC @S9S_MB_2U_LIB.S9S_MB_2U(SCH_1):PVCCD_HV_CPU1_VCC
  20    GND    EN1 @S9S_MB_2U_LIB.S9S_MB_2U(SCH_1):GND
  10 SMB_CLK_PVCCD_HV_CPU1  PMSCL @S9S_MB_2U_LIB.S9S_MB_2U(SCH_1):SMB_CLK_PVCCD_HV_CPU1
  18 SVID_DIO_PVCCD_HV_CPU1_R SVDATA @S9S_MB_2U_LIB.S9S_MB_2U(SCH_1):SVID_DIO_PVCCD_HV_CPU1_R
  24 NC_PVCCD_HV_CPU1_ACSP2    CS6 @S9S_MB_2U_LIB.S9S_MB_2U(SCH_1):NC_PVCCD_HV_CPU1_ACSP2
  19 SVID_ALERT_PVCCD_HV_CPU1_R NSVALERT# @S9S_MB_2U_LIB.S9S_MB_2U(SCH_1):SVID_ALERT_PVCCD_HV_CPU1_R
  14 IRQ_PVCCD_CPU1_VRHOT_LVC3_R_N NVRHOT# @S9S_MB_2U_LIB.S9S_MB_2U(SCH_1):IRQ_PVCCD_CPU1_VRHOT_LVC3_R_N
  25 NC_PVCCD_HV_CPU1_ACSP3    CS5 @S9S_MB_2U_LIB.S9S_MB_2U(SCH_1):NC_PVCCD_HV_CPU1_ACSP3
  26 NC_PVCCD_HV_CPU1_ACSP4    CS4 @S9S_MB_2U_LIB.S9S_MB_2U(SCH_1):NC_PVCCD_HV_CPU1_ACSP4
  16 NC_PVCCD_HV_CPU1_BVR_RDY    PG1 @S9S_MB_2U_LIB.S9S_MB_2U(SCH_1):NC_PVCCD_HV_CPU1_BVR_RDY
  17 SVID_CLK_PVCCD_HV_CPU1_R  SVCLK @S9S_MB_2U_LIB.S9S_MB_2U(SCH_1):SVID_CLK_PVCCD_HV_CPU1_R
  11 NC_PVCCD_HV_CPU1_SMB_ALERT NPMALERT# @S9S_MB_2U_LIB.S9S_MB_2U(SCH_1):NC_PVCCD_HV_CPU1_SMB_ALERT
  13 PVCCD_HV_CPU1_EN_R    EN0 @S9S_MB_2U_LIB.S9S_MB_2U(SCH_1):PVCCD_HV_CPU1_EN_R
  22 VSENSE_PVCCD_HV_CPU1_DN  RGND0 @S9S_MB_2U_LIB.S9S_MB_2U(SCH_1):VSENSE_PVCCD_HV_CPU1_DN
   9 SMB_DIO_PVCCD_HV_CPU1  PMSDA @S9S_MB_2U_LIB.S9S_MB_2U(SCH_1):SMB_DIO_PVCCD_HV_CPU1
   5 NC_PVCCD_HV_CPU1_APWM4   PWM4 @S9S_MB_2U_LIB.S9S_MB_2U(SCH_1):NC_PVCCD_HV_CPU1_APWM4
   6 NC_PVCCD_HV_CPU1_APWM3   PWM5 @S9S_MB_2U_LIB.S9S_MB_2U(SCH_1):NC_PVCCD_HV_CPU1_APWM3
  21 SH_PVCCD_HV_CPU1_R  VSEN0 @S9S_MB_2U_LIB.S9S_MB_2U(SCH_1):SH_PVCCD_HV_CPU1_R
   2 NC_PVCCD_HV_CPU1_APWM7   PWM1 @S9S_MB_2U_LIB.S9S_MB_2U(SCH_1):NC_PVCCD_HV_CPU1_APWM7
  12 PWRGD_PVCCD_HV_CPU1_R    PG0 @S9S_MB_2U_LIB.S9S_MB_2U(SCH_1):PWRGD_PVCCD_HV_CPU1_R
   7 NC_PVCCD_HV_CPU1_APWM2   PWM6 @S9S_MB_2U_LIB.S9S_MB_2U(SCH_1):NC_PVCCD_HV_CPU1_APWM2
  40 PVCCD_HV_CPU1_VREF   VCCS @S9S_MB_2U_LIB.S9S_MB_2U(SCH_1):PVCCD_HV_CPU1_VREF
  37 PVCCD_HV_CPU1_ISENSE_P VMON||IINSEN||VSYS||ISYS @S9S_MB_2U_LIB.S9S_MB_2U(SCH_1):PVCCD_HV_CPU1_ISENSE_P
  38 PVCCD_HV_CPU1_ISENSE_N VINSEN||VSYS @S9S_MB_2U_LIB.S9S_MB_2U(SCH_1):PVCCD_HV_CPU1_ISENSE_N
  36 PVCCD_HV_CPU1_ISYS_R TEMP1||ISYS @S9S_MB_2U_LIB.S9S_MB_2U(SCH_1):PVCCD_HV_CPU1_ISYS_R
  15 PVCCD_HV_CPU1_PIN_ALT NPINALERT#||NPSYSCRIT# @S9S_MB_2U_LIB.S9S_MB_2U(SCH_1):PVCCD_HV_CPU1_PIN_ALT
  32    GND  VSEN1 @S9S_MB_2U_LIB.S9S_MB_2U(SCH_1):GND
  31    GND  RGND1 @S9S_MB_2U_LIB.S9S_MB_2U(SCH_1):GND
  29 NC_PVCCD_HV_CPU1_ACSP7    CS1 @S9S_MB_2U_LIB.S9S_MB_2U(SCH_1):NC_PVCCD_HV_CPU1_ACSP7
   8 PVCCD_HV_CPU1_APWM1   PWM7 @S9S_MB_2U_LIB.S9S_MB_2U(SCH_1):PVCCD_HV_CPU1_APWM1
   4 NC_PVCCD_HV_CPU1_APWM5   PWM3 @S9S_MB_2U_LIB.S9S_MB_2U(SCH_1):NC_PVCCD_HV_CPU1_APWM5
  27 NC_PVCCD_HV_CPU1_ACSP5    CS3 @S9S_MB_2U_LIB.S9S_MB_2U(SCH_1):NC_PVCCD_HV_CPU1_ACSP5
   3 NC_PVCCD_HV_CPU1_APWM6   PWM2 @S9S_MB_2U_LIB.S9S_MB_2U(SCH_1):NC_PVCCD_HV_CPU1_APWM6
  28 NC_PVCCD_HV_CPU1_ACSP6    CS2 @S9S_MB_2U_LIB.S9S_MB_2U(SCH_1):NC_PVCCD_HV_CPU1_ACSP6
  33 PVCCD_HV_CPU1_FAULT    CFP @S9S_MB_2U_LIB.S9S_MB_2U(SCH_1):PVCCD_HV_CPU1_FAULT
  TH    GND TH_GND @S9S_MB_2U_LIB.S9S_MB_2U(SCH_1):GND
  34 PVCCD_HV_CPU1_ADDR ADDR_CFG @S9S_MB_2U_LIB.S9S_MB_2U(SCH_1):PVCCD_HV_CPU1_ADDR
  35 PVCCD_HV_CPU1_ATSEN  TEMP0 @S9S_MB_2U_LIB.S9S_MB_2U(SCH_1):PVCCD_HV_CPU1_ATSEN
   1 NC_PVCCD_HV_CPU1_APWM8   PWM0 @S9S_MB_2U_LIB.S9S_MB_2U(SCH_1):NC_PVCCD_HV_CPU1_APWM8
  30 NC_PVCCD_HV_CPU1_ACSP8    CS0 @S9S_MB_2U_LIB.S9S_MB_2U(SCH_1):NC_PVCCD_HV_CPU1_ACSP8

Q_RES_0402LF-0,5%,1/16W,CHIP,CA  I58  R2557
   1 IRQ_PVCCD_CPU1_VRHOT_LVC3_R_N      A @S9S_MB_2U_LIB.S9S_MB_2U(SCH_1):IRQ_PVCCD_CPU1_VRHOT_LVC3_R_N
   2 IRQ_PVCCD_CPU1_VRHOT_LVC3_N      B @S9S_MB_2U_LIB.S9S_MB_2U(SCH_1):IRQ_PVCCD_CPU1_VRHOT_LVC3_N

Q_RES_0402LF-0,5%,1/16W,CHIP,CA  I60  PR1315
   1 PVCCD_HV_CPU1_ISYS_R      A @S9S_MB_2U_LIB.S9S_MB_2U(SCH_1):PVCCD_HV_CPU1_ISYS_R
   2    GND      B @S9S_MB_2U_LIB.S9S_MB_2U(SCH_1):GND

Q_RES_0402LF-0,5%,1/16W,EMPTY,A  I61  PR410
   1 PVCCD_HV_CPU1_ISYS_R      A @S9S_MB_2U_LIB.S9S_MB_2U(SCH_1):PVCCD_HV_CPU1_ISYS_R
   2 PVCCD_HV_CPU1_NVDIMM_ISENSE      B @S9S_MB_2U_LIB.S9S_MB_2U(SCH_1):PVCCD_HV_CPU1_NVDIMM_ISENSE

Q_RES_0402LF-0,5%,1/16W,CHIP,CA  I63  PR4256
   1 NC_PVCCD_HV_CPU1_ACSP7      A @S9S_MB_2U_LIB.S9S_MB_2U(SCH_1):NC_PVCCD_HV_CPU1_ACSP7
   2    GND      B @S9S_MB_2U_LIB.S9S_MB_2U(SCH_1):GND

Q_RES_0402LF-100,1%,1/16W,CHIPA  I36  PR559
   1 VSENSE_PVCCD_HV_CPU1_DP      A @S9S_MB_2U_LIB.S9S_MB_2U(SCH_1):VSENSE_PVCCD_HV_CPU1_DP
   2 PVCCD_HV_CPU1      B @S9S_MB_2U_LIB.S9S_MB_2U(SCH_1):PVCCD_HV_CPU1

Q_CAP_0402-1000PF,50V,5%,EMPTYA  I45  C2454
   1 PWRGD_PVCCD_HV_CPU1_R      A @S9S_MB_2U_LIB.S9S_MB_2U(SCH_1):PWRGD_PVCCD_HV_CPU1_R
   2    GND      B @S9S_MB_2U_LIB.S9S_MB_2U(SCH_1):GND

Q_RES_0402LF-10K,1%,1/16W,EMPTA  I81  PR705
   1 PVCCD_HV_CPU1_ATSEN      A @S9S_MB_2U_LIB.S9S_MB_2U(SCH_1):PVCCD_HV_CPU1_ATSEN
   2    GND      B @S9S_MB_2U_LIB.S9S_MB_2U(SCH_1):GND

Q_CAP_0402-0.1UF,25V,10%,X7R,CA  I13  PC386
   1 PVCCD_HV_CPU1_ISENSE_P      A @S9S_MB_2U_LIB.S9S_MB_2U(SCH_1):PVCCD_HV_CPU1_ISENSE_P
   2    GND      B @S9S_MB_2U_LIB.S9S_MB_2U(SCH_1):GND

Q_RES_0402LF-1K,1%,1/16W,CHIP,A  I18  PR215
   1 P3V3_AUX      A @S9S_MB_2U_LIB.S9S_MB_2U(SCH_1):P3V3_AUX
   2 PVCCD_HV_CPU1_PIN_ALT      B @S9S_MB_2U_LIB.S9S_MB_2U(SCH_1):PVCCD_HV_CPU1_PIN_ALT

Q_RES_0402LF-1K,1%,1/16W,CHIP,A  I20  PR217
   1 P3V3_AUX      A @S9S_MB_2U_LIB.S9S_MB_2U(SCH_1):P3V3_AUX
   2 PVCCD_HV_CPU1_FAULT      B @S9S_MB_2U_LIB.S9S_MB_2U(SCH_1):PVCCD_HV_CPU1_FAULT

Q_RES_0402LF-0,5%,1/16W,CHIP,CA  I21  PR216
   1 SH_PVCCD_HV_CPU1      A @S9S_MB_2U_LIB.S9S_MB_2U(SCH_1):SH_PVCCD_HV_CPU1
   2 SH_PVCCD_HV_CPU1_R      B @S9S_MB_2U_LIB.S9S_MB_2U(SCH_1):SH_PVCCD_HV_CPU1_R

Q_CAP_0402-0.1UF,25V,10%,X7R,CA  I28  C1337
   1 PVNN_TERM_CPU1      A @S9S_MB_2U_LIB.S9S_MB_2U(SCH_1):PVNN_TERM_CPU1
   2    GND      B @S9S_MB_2U_LIB.S9S_MB_2U(SCH_1):GND

Q_RES_0402LF-0,5%,1/16W,CHIP,CA  I39  R4595
   1 SMB_VR_3V3AUX_SCL_R      A @S9S_MB_2U_LIB.S9S_MB_2U(SCH_1):SMB_VR_3V3AUX_SCL_R
   2 SMB_CLK_PVCCD_HV_CPU1      B @S9S_MB_2U_LIB.S9S_MB_2U(SCH_1):SMB_CLK_PVCCD_HV_CPU1

Q_CAP_C0402-1UF,16V,10%,X6S,CHA  I51  PC814
   1 PVCCD_HV_CPU1_ISENSE_N      A @S9S_MB_2U_LIB.S9S_MB_2U(SCH_1):PVCCD_HV_CPU1_ISENSE_N
   2 PVCCD_HV_CPU1_ISENSE_P      B @S9S_MB_2U_LIB.S9S_MB_2U(SCH_1):PVCCD_HV_CPU1_ISENSE_P

Q_CAP_0402-470PF,50V,10%,X7R,TA  I57  PC393
   1 PVCCD_HV_CPU1_ATSEN      A @S9S_MB_2U_LIB.S9S_MB_2U(SCH_1):PVCCD_HV_CPU1_ATSEN
   2    GND      B @S9S_MB_2U_LIB.S9S_MB_2U(SCH_1):GND

Q_CAP_C0402-10UF,6.3V,20%,X6S,B  I68  PC392
   1 PVCCD_HV_CPU1_VREF      A @S9S_MB_2U_LIB.S9S_MB_2U(SCH_1):PVCCD_HV_CPU1_VREF
   2    GND      B @S9S_MB_2U_LIB.S9S_MB_2U(SCH_1):GND

Q_CAP_C0402-100NF,50V,10%,EMPTA  I69  PC391
   1 PVCCD_HV_CPU1_VCC      A @S9S_MB_2U_LIB.S9S_MB_2U(SCH_1):PVCCD_HV_CPU1_VCC
   2    GND      B @S9S_MB_2U_LIB.S9S_MB_2U(SCH_1):GND

Q_RES_0402LF-0,5%,1/16W,CHIP,CA  I70  PR4251
   1 NC_PVCCD_HV_CPU1_ACSP2      A @S9S_MB_2U_LIB.S9S_MB_2U(SCH_1):NC_PVCCD_HV_CPU1_ACSP2
   2    GND      B @S9S_MB_2U_LIB.S9S_MB_2U(SCH_1):GND

Q_CAP_C0402-1UF,16V,10%,X6S,CHA  I74  PC1289
   1 PVCCD_HV_CPU1_VREF      A @S9S_MB_2U_LIB.S9S_MB_2U(SCH_1):PVCCD_HV_CPU1_VREF
   2    GND      B @S9S_MB_2U_LIB.S9S_MB_2U(SCH_1):GND

Q_RES_0402LF-1K,1%,1/16W,CHIP,A  I85  R223
   1 P3V3_AUX      A @S9S_MB_2U_LIB.S9S_MB_2U(SCH_1):P3V3_AUX
   2 IRQ_PVCCD_CPU1_VRHOT_LVC3_N      B @S9S_MB_2U_LIB.S9S_MB_2U(SCH_1):IRQ_PVCCD_CPU1_VRHOT_LVC3_N

Q_RES_0402LF-28K,1%,1/16W,EMPTA  I8  PR202
   1 PVCCD_HV_CPU1_VREF      A @S9S_MB_2U_LIB.S9S_MB_2U(SCH_1):PVCCD_HV_CPU1_VREF
   2 PVCCD_HV_CPU1_ADDR      B @S9S_MB_2U_LIB.S9S_MB_2U(SCH_1):PVCCD_HV_CPU1_ADDR

Q_RES_0402LF-49.9,1%,1/16W,CHIA  I9  PR1400
   1 P12V_AUX_CPU1_DIMM_ISEN_P      A @S9S_MB_2U_LIB.S9S_MB_2U(SCH_1):P12V_AUX_CPU1_DIMM_ISEN_P
   2 PVCCD_HV_CPU1_ISENSE_P      B @S9S_MB_2U_LIB.S9S_MB_2U(SCH_1):PVCCD_HV_CPU1_ISENSE_P

Q_RES_0402LF-49.9,1%,1/16W,CHIA  I10  PR1410
   1 P12V_AUX_CPU1_DIMM_ISEN_N      A @S9S_MB_2U_LIB.S9S_MB_2U(SCH_1):P12V_AUX_CPU1_DIMM_ISEN_N
   2 PVCCD_HV_CPU1_ISENSE_N      B @S9S_MB_2U_LIB.S9S_MB_2U(SCH_1):PVCCD_HV_CPU1_ISENSE_N

Q_RES_0402LF-1K,1%,1/16W,EMPTYA  I11  PR214
   1 PVCCD_HV_CPU1_ISENSE_P      A @S9S_MB_2U_LIB.S9S_MB_2U(SCH_1):PVCCD_HV_CPU1_ISENSE_P
   2    GND      B @S9S_MB_2U_LIB.S9S_MB_2U(SCH_1):GND

Q_RES_0402LF-100,1%,1/16W,CHIPA  I15  PR558
   1 VSENSE_PVCCD_HV_CPU1_DN      A @S9S_MB_2U_LIB.S9S_MB_2U(SCH_1):VSENSE_PVCCD_HV_CPU1_DN
   2    GND      B @S9S_MB_2U_LIB.S9S_MB_2U(SCH_1):GND

Q_SHORT_SM-EMPTY,SHORT6  I16  PJ48
   1 VSENSE_PVCCD_HV_CPU1_DP      1 @S9S_MB_2U_LIB.S9S_MB_2U(SCH_1):VSENSE_PVCCD_HV_CPU1_DP
   2 SH_PVCCD_HV_CPU1      2 @S9S_MB_2U_LIB.S9S_MB_2U(SCH_1):SH_PVCCD_HV_CPU1

Q_CAP_0402-3300PF,50V,10%,X7R,A  I22  PC389
   1 SH_PVCCD_HV_CPU1_R      A @S9S_MB_2U_LIB.S9S_MB_2U(SCH_1):SH_PVCCD_HV_CPU1_R
   2 VSENSE_PVCCD_HV_CPU1_DN      B @S9S_MB_2U_LIB.S9S_MB_2U(SCH_1):VSENSE_PVCCD_HV_CPU1_DN

Q_CAP_C0402-10UF,6.3V,20%,X6S,B  I24  C1336
   1 PVNN_TERM_CPU1      A @S9S_MB_2U_LIB.S9S_MB_2U(SCH_1):PVNN_TERM_CPU1
   2    GND      B @S9S_MB_2U_LIB.S9S_MB_2U(SCH_1):GND

Q_RES_0402LF-0,5%,1/16W,CHIP,CA  I40  R2580
   1 SVID_ALERT1_CPU1_R_N      A @S9S_MB_2U_LIB.S9S_MB_2U(SCH_1):SVID_ALERT1_CPU1_R_N
   2 SVID_ALERT_PVCCD_HV_CPU1_R      B @S9S_MB_2U_LIB.S9S_MB_2U(SCH_1):SVID_ALERT_PVCCD_HV_CPU1_R

Q_RES_0402LF-0,5%,1/16W,CHIP,CA  I41  R2579
   1 SVID_DIO1_CPU1_R      A @S9S_MB_2U_LIB.S9S_MB_2U(SCH_1):SVID_DIO1_CPU1_R
   2 SVID_DIO_PVCCD_HV_CPU1_R      B @S9S_MB_2U_LIB.S9S_MB_2U(SCH_1):SVID_DIO_PVCCD_HV_CPU1_R

Q_RES_0402LF-150,1%,1/16W,CHIPA  I42  R2578
   1 SVID_CLK1_CPU1_R      A @S9S_MB_2U_LIB.S9S_MB_2U(SCH_1):SVID_CLK1_CPU1_R
   2 SVID_CLK_PVCCD_HV_CPU1_R      B @S9S_MB_2U_LIB.S9S_MB_2U(SCH_1):SVID_CLK_PVCCD_HV_CPU1_R

Q_RES_0402LF-0,5%,1/16W,CHIP,CA  I43  R2577
   1 FM_PVCCD_HV_CPU1_EN      A @S9S_MB_2U_LIB.S9S_MB_2U(SCH_1):FM_PVCCD_HV_CPU1_EN
   2 PVCCD_HV_CPU1_EN_R      B @S9S_MB_2U_LIB.S9S_MB_2U(SCH_1):PVCCD_HV_CPU1_EN_R

Q_RES_0402LF-0,5%,1/16W,CHIP,CA  I44  R2576
   1 PWRGD_PVCCD_HV_CPU1      A @S9S_MB_2U_LIB.S9S_MB_2U(SCH_1):PWRGD_PVCCD_HV_CPU1
   2 PWRGD_PVCCD_HV_CPU1_R      B @S9S_MB_2U_LIB.S9S_MB_2U(SCH_1):PWRGD_PVCCD_HV_CPU1_R

Q_RES_0402LF-0,5%,1/16W,CHIP,CA  I59  PR4257
   1 NC_PVCCD_HV_CPU1_ACSP8      A @S9S_MB_2U_LIB.S9S_MB_2U(SCH_1):NC_PVCCD_HV_CPU1_ACSP8
   2    GND      B @S9S_MB_2U_LIB.S9S_MB_2U(SCH_1):GND

Q_RES_0402LF-0,5%,1/16W,CHIP,CA  I62  PR4255
   1 NC_PVCCD_HV_CPU1_ACSP6      A @S9S_MB_2U_LIB.S9S_MB_2U(SCH_1):NC_PVCCD_HV_CPU1_ACSP6
   2    GND      B @S9S_MB_2U_LIB.S9S_MB_2U(SCH_1):GND

Q_RES_0402LF-0,5%,1/16W,CHIP,CA  I64  PR4252
   1 NC_PVCCD_HV_CPU1_ACSP3      A @S9S_MB_2U_LIB.S9S_MB_2U(SCH_1):NC_PVCCD_HV_CPU1_ACSP3
   2    GND      B @S9S_MB_2U_LIB.S9S_MB_2U(SCH_1):GND

Q_RES_0402LF-0,5%,1/16W,CHIP,CA  I65  PR4253
   1 NC_PVCCD_HV_CPU1_ACSP4      A @S9S_MB_2U_LIB.S9S_MB_2U(SCH_1):NC_PVCCD_HV_CPU1_ACSP4
   2    GND      B @S9S_MB_2U_LIB.S9S_MB_2U(SCH_1):GND

Q_RES_0402LF-0,5%,1/16W,CHIP,CA  I66  PR4254
   1 NC_PVCCD_HV_CPU1_ACSP5      A @S9S_MB_2U_LIB.S9S_MB_2U(SCH_1):NC_PVCCD_HV_CPU1_ACSP5
   2    GND      B @S9S_MB_2U_LIB.S9S_MB_2U(SCH_1):GND

Q_CAP_C0402-1UF,16V,10%,X6S,CHA  I77  PC394
   1 PVCCD_HV_CPU1_VCC      A @S9S_MB_2U_LIB.S9S_MB_2U(SCH_1):PVCCD_HV_CPU1_VCC
   2    GND      B @S9S_MB_2U_LIB.S9S_MB_2U(SCH_1):GND

Q_RES_0402LF-1,1%,1/16W,CHIP,CA  I78  PR220
   1 PVCCD_HV_CPU1_VCC      A @S9S_MB_2U_LIB.S9S_MB_2U(SCH_1):PVCCD_HV_CPU1_VCC
   2 P3V3_AUX      B @S9S_MB_2U_LIB.S9S_MB_2U(SCH_1):P3V3_AUX

Q_RES_0402LF-24.3K,1%,1/16W,CHA  I95  PR203
   1    GND      A @S9S_MB_2U_LIB.S9S_MB_2U(SCH_1):GND
   2 PVCCD_HV_CPU1_ADDR      B @S9S_MB_2U_LIB.S9S_MB_2U(SCH_1):PVCCD_HV_CPU1_ADDR

Q_CAP_0402-0.1UF,25V,10%,EMPTYA  I96  PC2368
   1 PVCCD_HV_CPU1_VCC      A @S9S_MB_2U_LIB.S9S_MB_2U(SCH_1):PVCCD_HV_CPU1_VCC
   2    GND      B @S9S_MB_2U_LIB.S9S_MB_2U(SCH_1):GND


DRAWING: @S9S_MB_2U_LIB.S9S_MB_2U(SCH_1):PAGE286 

Q_CAP_0402-1000PF,50V,5%,EMPTYA  I6  C1308
   1 FM_PVNN_MAIN_CPU1_EN      A @S9S_MB_2U_LIB.S9S_MB_2U(SCH_1):FM_PVNN_MAIN_CPU1_EN
   2    GND      B @S9S_MB_2U_LIB.S9S_MB_2U(SCH_1):GND

Q_RES_0402LF-12.4K,0.1%,1/16W,A  I26  PR51
   1 PVNN_MAIN_CPU1_FB      A @S9S_MB_2U_LIB.S9S_MB_2U(SCH_1):PVNN_MAIN_CPU1_FB
   2    GND      B @S9S_MB_2U_LIB.S9S_MB_2U(SCH_1):GND

Q_INDUCTOR_SMLF-4.7UH,IND,CV-4B  I27  PL121
   2 PVNN_MAIN_CPU1      2 @S9S_MB_2U_LIB.S9S_MB_2U(SCH_1):PVNN_MAIN_CPU1
   1 SW_PVNN_MAIN_CPU1_SW      1 @S9S_MB_2U_LIB.S9S_MB_2U(SCH_1):SW_PVNN_MAIN_CPU1_SW

Q_RES_0402LF-0,5%,1/16W,CHIP,CA  I29  R2387
   1 PWRGD_PVNN_MAIN_CPU1_R      A @S9S_MB_2U_LIB.S9S_MB_2U(SCH_1):PWRGD_PVNN_MAIN_CPU1_R
   2 PWRGD_PVNN_MAIN_CPU1      B @S9S_MB_2U_LIB.S9S_MB_2U(SCH_1):PWRGD_PVNN_MAIN_CPU1

Q_RES_0402LF-10K,1%,1/16W,CHIPA  I31  R2584
   1 P3V3_AUX      A @S9S_MB_2U_LIB.S9S_MB_2U(SCH_1):P3V3_AUX
   2 PWRGD_PVNN_MAIN_CPU1_R      B @S9S_MB_2U_LIB.S9S_MB_2U(SCH_1):PWRGD_PVNN_MAIN_CPU1_R

Q_CAP_C0402-1UF,16V,10%,X6S,CHA  I16  PC1282
   1 SW_P12V_PVCCINFAON_CPU1_FLT      A @S9S_MB_2U_LIB.S9S_MB_2U(SCH_1):SW_P12V_PVCCINFAON_CPU1_FLT
   2    GND      B @S9S_MB_2U_LIB.S9S_MB_2U(SCH_1):GND

Q_CAP_0402-3300PF,50V,10%,X7R,A  I23  PC28
   1 PVNN_MAIN_CPU1_REF      A @S9S_MB_2U_LIB.S9S_MB_2U(SCH_1):PVNN_MAIN_CPU1_REF
   2    GND      B @S9S_MB_2U_LIB.S9S_MB_2U(SCH_1):GND

Q_RES_0402LF-0,5%,1/16W,EMPTY,A  I42  PR4700
   1 PVNN_MAIN_CPU1_FB_RC      A @S9S_MB_2U_LIB.S9S_MB_2U(SCH_1):PVNN_MAIN_CPU1_FB_RC
   2 PVNN_MAIN_CPU1      B @S9S_MB_2U_LIB.S9S_MB_2U(SCH_1):PVNN_MAIN_CPU1

Q_CAP_C0805-22UF,4V,20%,X6S,CHA  I44  PC1287
   1 PVNN_MAIN_CPU1      A @S9S_MB_2U_LIB.S9S_MB_2U(SCH_1):PVNN_MAIN_CPU1
   2    GND      B @S9S_MB_2U_LIB.S9S_MB_2U(SCH_1):GND

Q_CAP_C0805-22UF,16V,20%,X6S,CA  I9  PC1280
   1 SW_P12V_PVCCINFAON_CPU1_FLT      A @S9S_MB_2U_LIB.S9S_MB_2U(SCH_1):SW_P12V_PVCCINFAON_CPU1_FLT
   2    GND      B @S9S_MB_2U_LIB.S9S_MB_2U(SCH_1):GND

Q_RES_0402LF-0,5%,1/16W,CHIP,CA  I13  PR3338
   1 P3V3_AUX      A @S9S_MB_2U_LIB.S9S_MB_2U(SCH_1):P3V3_AUX
   2 PVNN_MAIN_CPU1_VCC      B @S9S_MB_2U_LIB.S9S_MB_2U(SCH_1):PVNN_MAIN_CPU1_VCC

RS53317LR-RS53317LR,SMLF,IC,ALA  I20  PU82
   3 SW_P12V_PVCCINFAON_CPU1_FLT    VIN @S9S_MB_2U_LIB.S9S_MB_2U(SCH_1):SW_P12V_PVCCINFAON_CPU1_FLT
   9 PWRGD_PVNN_MAIN_CPU1_R  PGOOD @S9S_MB_2U_LIB.S9S_MB_2U(SCH_1):PWRGD_PVNN_MAIN_CPU1_R
  14    GND  PGND2 @S9S_MB_2U_LIB.S9S_MB_2U(SCH_1):GND
   5 FM_PVNN_MAIN_CPU1_EN     EN @S9S_MB_2U_LIB.S9S_MB_2U(SCH_1):FM_PVNN_MAIN_CPU1_EN
  10 SW_PVNN_MAIN_CPU1_BST    BST @S9S_MB_2U_LIB.S9S_MB_2U(SCH_1):SW_PVNN_MAIN_CPU1_BST
   6 PVNN_MAIN_CPU1_FB     FB @S9S_MB_2U_LIB.S9S_MB_2U(SCH_1):PVNN_MAIN_CPU1_FB
   7    GND   AGND @S9S_MB_2U_LIB.S9S_MB_2U(SCH_1):GND
  13 PVNN_MAIN_CPU1_VCC    VCC @S9S_MB_2U_LIB.S9S_MB_2U(SCH_1):PVNN_MAIN_CPU1_VCC
   1    GND  PGND1 @S9S_MB_2U_LIB.S9S_MB_2U(SCH_1):GND
  11 SW_PVNN_MAIN_CPU1_SW    SW2 @S9S_MB_2U_LIB.S9S_MB_2U(SCH_1):SW_PVNN_MAIN_CPU1_SW
   8 PVNN_MAIN_CPU1_REF    REF @S9S_MB_2U_LIB.S9S_MB_2U(SCH_1):PVNN_MAIN_CPU1_REF
  12 PVNN_MAIN_CPU1_MODE   MODE @S9S_MB_2U_LIB.S9S_MB_2U(SCH_1):PVNN_MAIN_CPU1_MODE
   4 PVNN_MAIN_CPU1_CS     CS @S9S_MB_2U_LIB.S9S_MB_2U(SCH_1):PVNN_MAIN_CPU1_CS
   2 SW_PVNN_MAIN_CPU1_SW    SW1 @S9S_MB_2U_LIB.S9S_MB_2U(SCH_1):SW_PVNN_MAIN_CPU1_SW

Q_RES_0402LF-8.25K,0.1%,1/16W,A  I34  PR502
   1 PVNN_MAIN_CPU1_FB      A @S9S_MB_2U_LIB.S9S_MB_2U(SCH_1):PVNN_MAIN_CPU1_FB
   2 PVNN_MAIN_CPU1_FB_RC      B @S9S_MB_2U_LIB.S9S_MB_2U(SCH_1):PVNN_MAIN_CPU1_FB_RC

Q_CAP_C0805-22UF,4V,20%,X6S,CHA  I36  PC1285
   1 PVNN_MAIN_CPU1      A @S9S_MB_2U_LIB.S9S_MB_2U(SCH_1):PVNN_MAIN_CPU1
   2    GND      B @S9S_MB_2U_LIB.S9S_MB_2U(SCH_1):GND

Q_RES_0402LF-0,5%,1/16W,CHIP,CA  I22  PR2
   1    GND      A @S9S_MB_2U_LIB.S9S_MB_2U(SCH_1):GND
   2    GND      B @S9S_MB_2U_LIB.S9S_MB_2U(SCH_1):GND

Q_RES_0402LF-0,5%,1/16W,CHIP,CA  I25  PR4272
   1 SW_PVNN_MAIN_CPU1_BST      A @S9S_MB_2U_LIB.S9S_MB_2U(SCH_1):SW_PVNN_MAIN_CPU1_BST
   2 SW_PVNN_MAIN_CPU1_BST_R      B @S9S_MB_2U_LIB.S9S_MB_2U(SCH_1):SW_PVNN_MAIN_CPU1_BST_R

Q_CAP_0402-680PF,50V,10%,X7R,TA  I33  PC238
   1 PVNN_MAIN_CPU1_FB      A @S9S_MB_2U_LIB.S9S_MB_2U(SCH_1):PVNN_MAIN_CPU1_FB
   2 PVNN_MAIN_CPU1_FB_RC      B @S9S_MB_2U_LIB.S9S_MB_2U(SCH_1):PVNN_MAIN_CPU1_FB_RC

Q_CAP_C0805-22UF,4V,20%,X6S,CHA  I38  PC1286
   1 PVNN_MAIN_CPU1      A @S9S_MB_2U_LIB.S9S_MB_2U(SCH_1):PVNN_MAIN_CPU1
   2    GND      B @S9S_MB_2U_LIB.S9S_MB_2U(SCH_1):GND

Q_RES_0402LF-0,5%,1/16W,CHIP,CA  I43  PR4699
   1 PVNN_MAIN_CPU1_FB_RC      A @S9S_MB_2U_LIB.S9S_MB_2U(SCH_1):PVNN_MAIN_CPU1_FB_RC
   2 PVNN_MAIN_CPU1      B @S9S_MB_2U_LIB.S9S_MB_2U(SCH_1):PVNN_MAIN_CPU1

Q_RES_0402LF-10K,1%,1/16W,EMPTA  I5  R2384
   1 P3V3_AUX      A @S9S_MB_2U_LIB.S9S_MB_2U(SCH_1):P3V3_AUX
   2 FM_PVNN_MAIN_CPU1_EN      B @S9S_MB_2U_LIB.S9S_MB_2U(SCH_1):FM_PVNN_MAIN_CPU1_EN

Q_RES_0402LF-2K,1%,1/16W,CHIP,A  I7  R2385
   1 FM_PVNN_MAIN_CPU1_EN      A @S9S_MB_2U_LIB.S9S_MB_2U(SCH_1):FM_PVNN_MAIN_CPU1_EN
   2    GND      B @S9S_MB_2U_LIB.S9S_MB_2U(SCH_1):GND

Q_CAP_C0402-1UF,25V,10%,X6S,CHA  I10  PC2222
   1 PVNN_MAIN_CPU1_VCC      A @S9S_MB_2U_LIB.S9S_MB_2U(SCH_1):PVNN_MAIN_CPU1_VCC
   2    GND      B @S9S_MB_2U_LIB.S9S_MB_2U(SCH_1):GND

Q_RES_0402LF-60.4K,1%,1/16W,CHA  I12  PR2220
   1 PVNN_MAIN_CPU1_MODE      A @S9S_MB_2U_LIB.S9S_MB_2U(SCH_1):PVNN_MAIN_CPU1_MODE
   2    GND      B @S9S_MB_2U_LIB.S9S_MB_2U(SCH_1):GND

Q_CAP_C0805-22UF,16V,20%,X6S,CA  I14  PC1281
   1 SW_P12V_PVCCINFAON_CPU1_FLT      A @S9S_MB_2U_LIB.S9S_MB_2U(SCH_1):SW_P12V_PVCCINFAON_CPU1_FLT
   2    GND      B @S9S_MB_2U_LIB.S9S_MB_2U(SCH_1):GND

Q_RES_0402LF-34.8K,1%,1/16W,CHA  I19  PR2222
   1 PVNN_MAIN_CPU1_CS      A @S9S_MB_2U_LIB.S9S_MB_2U(SCH_1):PVNN_MAIN_CPU1_CS
   2    GND      B @S9S_MB_2U_LIB.S9S_MB_2U(SCH_1):GND

Q_CAP_C0402-0.22UF,25V,10%,X7RA  I24  PC1283
   1 SW_PVNN_MAIN_CPU1_BST_R      A @S9S_MB_2U_LIB.S9S_MB_2U(SCH_1):SW_PVNN_MAIN_CPU1_BST_R
   2 SW_PVNN_MAIN_CPU1_SW      B @S9S_MB_2U_LIB.S9S_MB_2U(SCH_1):SW_PVNN_MAIN_CPU1_SW

Q_CAP_C0402-100NF,50V,10%,X7R,A  I28  PC1284
   1 PVNN_MAIN_CPU1      A @S9S_MB_2U_LIB.S9S_MB_2U(SCH_1):PVNN_MAIN_CPU1
   2    GND      B @S9S_MB_2U_LIB.S9S_MB_2U(SCH_1):GND

Q_CAP_0402-1000PF,50V,5%,X7R,TA  I37  C1297
   1 PWRGD_PVNN_MAIN_CPU1      A @S9S_MB_2U_LIB.S9S_MB_2U(SCH_1):PWRGD_PVNN_MAIN_CPU1
   2    GND      B @S9S_MB_2U_LIB.S9S_MB_2U(SCH_1):GND

Q_CAP_0402-0.01UF,25V,10%,X7R,A  I40  PC2277
   1 PVNN_MAIN_CPU1_FB_RC      A @S9S_MB_2U_LIB.S9S_MB_2U(SCH_1):PVNN_MAIN_CPU1_FB_RC
   2    GND      B @S9S_MB_2U_LIB.S9S_MB_2U(SCH_1):GND

Q_CAP_C0805-22UF,4V,20%,X6S,CHA  I45  PC1207
   1 PVNN_MAIN_CPU1      A @S9S_MB_2U_LIB.S9S_MB_2U(SCH_1):PVNN_MAIN_CPU1
   2    GND      B @S9S_MB_2U_LIB.S9S_MB_2U(SCH_1):GND


DRAWING: @S9S_MB_2U_LIB.S9S_MB_2U(SCH_1):PAGE143 

Q_CAP_0402-1000PF,50V,5%,EMPTYA  I2  C2264
   1 GPU_3V3IO_RSVD0_FFU_ISO      A @S9S_MB_2U_LIB.S9S_MB_2U(SCH_1):GPU_3V3IO_RSVD0_FFU_ISO
   2    GND      B @S9S_MB_2U_LIB.S9S_MB_2U(SCH_1):GND

Q_RES_0402LF-4.7K,5%,1/16W,CHIA  I5  R4128
   1 P3V3_AUX      A @S9S_MB_2U_LIB.S9S_MB_2U(SCH_1):P3V3_AUX
   2 GPU_3V3IO_RSVD0_FFU_ISO      B @S9S_MB_2U_LIB.S9S_MB_2U(SCH_1):GPU_3V3IO_RSVD0_FFU_ISO

MOSFET_NCH_DUAL-PJT138K,SMLF,IA  I6  Q128
   3 GPU_3V3IO_RSVD0_FFU_ISO     D2 @S9S_MB_2U_LIB.S9S_MB_2U(SCH_1):GPU_3V3IO_RSVD0_FFU_ISO
   5 GPU_3V3IO_RSVD0_FFU_N     G2 @S9S_MB_2U_LIB.S9S_MB_2U(SCH_1):GPU_3V3IO_RSVD0_FFU_N
   4    GND     S2 @S9S_MB_2U_LIB.S9S_MB_2U(SCH_1):GND

Q_RES_0402LF-4.7K,5%,1/16W,CHIA  I9  R4125
   1 P3V3_AUX      A @S9S_MB_2U_LIB.S9S_MB_2U(SCH_1):P3V3_AUX
   2 GPU_3V3IO_RSVD0_FFU_N      B @S9S_MB_2U_LIB.S9S_MB_2U(SCH_1):GPU_3V3IO_RSVD0_FFU_N

MOSFET_NCH_DUAL-PJT138K,SMLF,IA  I11  Q128
   1    GND     S1 @S9S_MB_2U_LIB.S9S_MB_2U(SCH_1):GND
   2 GPU_3V3IO_RSVD0_FFU     G1 @S9S_MB_2U_LIB.S9S_MB_2U(SCH_1):GPU_3V3IO_RSVD0_FFU
   6 GPU_3V3IO_RSVD0_FFU_N     D1 @S9S_MB_2U_LIB.S9S_MB_2U(SCH_1):GPU_3V3IO_RSVD0_FFU_N

Q_RES_0402LF-54.9K,1%,1/16W,EMA  I13  R4119
   1 P3V3_AUX      A @S9S_MB_2U_LIB.S9S_MB_2U(SCH_1):P3V3_AUX
   2 GPU_3V3IO_RSVD0_FFU      B @S9S_MB_2U_LIB.S9S_MB_2U(SCH_1):GPU_3V3IO_RSVD0_FFU

Q_RES_0402LF-100K,1%,1/16W,EMPA  I14  R4120
   1 GPU_3V3IO_RSVD0_FFU      A @S9S_MB_2U_LIB.S9S_MB_2U(SCH_1):GPU_3V3IO_RSVD0_FFU
   2    GND      B @S9S_MB_2U_LIB.S9S_MB_2U(SCH_1):GND

MOSFET_NCH_DUAL-PJT138K,SMLF,IA  I19  Q131
   3 GPU_3V3IO_RSVD1_FFU_ISO     D2 @S9S_MB_2U_LIB.S9S_MB_2U(SCH_1):GPU_3V3IO_RSVD1_FFU_ISO
   5 GPU_3V3IO_RSVD1_FFU_N     G2 @S9S_MB_2U_LIB.S9S_MB_2U(SCH_1):GPU_3V3IO_RSVD1_FFU_N
   4    GND     S2 @S9S_MB_2U_LIB.S9S_MB_2U(SCH_1):GND

Q_RES_0402LF-4.7K,5%,1/16W,CHIA  I21  R4130
   1 P3V3_AUX      A @S9S_MB_2U_LIB.S9S_MB_2U(SCH_1):P3V3_AUX
   2 GPU_3V3IO_RSVD1_FFU_ISO      B @S9S_MB_2U_LIB.S9S_MB_2U(SCH_1):GPU_3V3IO_RSVD1_FFU_ISO

Q_CAP_0402-1000PF,50V,5%,EMPTYA  I23  C2266
   1 GPU_3V3IO_RSVD1_FFU_ISO      A @S9S_MB_2U_LIB.S9S_MB_2U(SCH_1):GPU_3V3IO_RSVD1_FFU_ISO
   2    GND      B @S9S_MB_2U_LIB.S9S_MB_2U(SCH_1):GND

Q_RES_0402LF-4.7K,5%,1/16W,CHIA  I27  R4127
   1 P3V3_AUX      A @S9S_MB_2U_LIB.S9S_MB_2U(SCH_1):P3V3_AUX
   2 GPU_3V3IO_RSVD1_FFU_N      B @S9S_MB_2U_LIB.S9S_MB_2U(SCH_1):GPU_3V3IO_RSVD1_FFU_N

MOSFET_NCH_DUAL-PJT138K,SMLF,IA  I29  Q131
   1    GND     S1 @S9S_MB_2U_LIB.S9S_MB_2U(SCH_1):GND
   2 GPU_3V3IO_RSVD1_FFU     G1 @S9S_MB_2U_LIB.S9S_MB_2U(SCH_1):GPU_3V3IO_RSVD1_FFU
   6 GPU_3V3IO_RSVD1_FFU_N     D1 @S9S_MB_2U_LIB.S9S_MB_2U(SCH_1):GPU_3V3IO_RSVD1_FFU_N

Q_RES_0402LF-54.9K,1%,1/16W,EMA  I31  R4123
   1 P3V3_AUX      A @S9S_MB_2U_LIB.S9S_MB_2U(SCH_1):P3V3_AUX
   2 GPU_3V3IO_RSVD1_FFU      B @S9S_MB_2U_LIB.S9S_MB_2U(SCH_1):GPU_3V3IO_RSVD1_FFU

Q_RES_0402LF-100K,1%,1/16W,EMPA  I32  R4124
   1 GPU_3V3IO_RSVD1_FFU      A @S9S_MB_2U_LIB.S9S_MB_2U(SCH_1):GPU_3V3IO_RSVD1_FFU
   2    GND      B @S9S_MB_2U_LIB.S9S_MB_2U(SCH_1):GND

MOSFET_NCH_DUAL-PJT138K,SMLF,IA  I35  Q132
   3 PRSNT_CABLE_GPU_B3_ISO_N     D2 @S9S_MB_2U_LIB.S9S_MB_2U(SCH_1):PRSNT_CABLE_GPU_B3_ISO_N
   5 PRSNT_CABLE_GPU_B3     G2 @S9S_MB_2U_LIB.S9S_MB_2U(SCH_1):PRSNT_CABLE_GPU_B3
   4    GND     S2 @S9S_MB_2U_LIB.S9S_MB_2U(SCH_1):GND

Q_RES_0402LF-4.7K,5%,1/16W,CHIA  I36  R4129
   1 P3V3_AUX      A @S9S_MB_2U_LIB.S9S_MB_2U(SCH_1):P3V3_AUX
   2 PRSNT_CABLE_GPU_B3_ISO_N      B @S9S_MB_2U_LIB.S9S_MB_2U(SCH_1):PRSNT_CABLE_GPU_B3_ISO_N

Q_CAP_0402-1000PF,50V,5%,EMPTYA  I40  C2265
   1 PRSNT_CABLE_GPU_B3_ISO_N      A @S9S_MB_2U_LIB.S9S_MB_2U(SCH_1):PRSNT_CABLE_GPU_B3_ISO_N
   2    GND      B @S9S_MB_2U_LIB.S9S_MB_2U(SCH_1):GND

Q_RES_0402LF-4.7K,5%,1/16W,CHIA  I43  R4126
   1 P3V3_AUX      A @S9S_MB_2U_LIB.S9S_MB_2U(SCH_1):P3V3_AUX
   2 PRSNT_CABLE_GPU_B3      B @S9S_MB_2U_LIB.S9S_MB_2U(SCH_1):PRSNT_CABLE_GPU_B3

MOSFET_NCH_DUAL-PJT138K,SMLF,IA  I44  Q132
   1    GND     S1 @S9S_MB_2U_LIB.S9S_MB_2U(SCH_1):GND
   2 PRSNT_CABLE_GPU_B3_N     G1 @S9S_MB_2U_LIB.S9S_MB_2U(SCH_1):PRSNT_CABLE_GPU_B3_N
   6 PRSNT_CABLE_GPU_B3     D1 @S9S_MB_2U_LIB.S9S_MB_2U(SCH_1):PRSNT_CABLE_GPU_B3

Q_RES_0402LF-100K,1%,1/16W,EMPA  I49  R4122
   1 PRSNT_CABLE_GPU_B3_N      A @S9S_MB_2U_LIB.S9S_MB_2U(SCH_1):PRSNT_CABLE_GPU_B3_N
   2    GND      B @S9S_MB_2U_LIB.S9S_MB_2U(SCH_1):GND

Q_RES_0402LF-4.7K,5%,1/16W,CHIA  I52  R4140
   1 P3V3_AUX      A @S9S_MB_2U_LIB.S9S_MB_2U(SCH_1):P3V3_AUX
   2 GPU_3V3IO_RSVD3_FFU_ISO      B @S9S_MB_2U_LIB.S9S_MB_2U(SCH_1):GPU_3V3IO_RSVD3_FFU_ISO

Q_CAP_0402-1000PF,50V,5%,EMPTYA  I55  C2267
   1 GPU_3V3IO_RSVD3_FFU_ISO      A @S9S_MB_2U_LIB.S9S_MB_2U(SCH_1):GPU_3V3IO_RSVD3_FFU_ISO
   2    GND      B @S9S_MB_2U_LIB.S9S_MB_2U(SCH_1):GND

Q_CAP_0402-1000PF,50V,5%,EMPTYA  I57  C2269
   1 PRSNT_CABLE_GPU_A2_ISO_N      A @S9S_MB_2U_LIB.S9S_MB_2U(SCH_1):PRSNT_CABLE_GPU_A2_ISO_N
   2    GND      B @S9S_MB_2U_LIB.S9S_MB_2U(SCH_1):GND

Q_RES_0402LF-4.7K,5%,1/16W,CHIA  I60  R4142
   1 P3V3_AUX      A @S9S_MB_2U_LIB.S9S_MB_2U(SCH_1):P3V3_AUX
   2 PRSNT_CABLE_GPU_A2_ISO_N      B @S9S_MB_2U_LIB.S9S_MB_2U(SCH_1):PRSNT_CABLE_GPU_A2_ISO_N

Q_RES_0402LF-4.7K,5%,1/16W,CHIA  I64  R4141
   1 P3V3_AUX      A @S9S_MB_2U_LIB.S9S_MB_2U(SCH_1):P3V3_AUX
   2 GPU_3V3IO_RSVD5_FFU_ISO      B @S9S_MB_2U_LIB.S9S_MB_2U(SCH_1):GPU_3V3IO_RSVD5_FFU_ISO

Q_CAP_0402-1000PF,50V,5%,EMPTYA  I66  C2268
   1 GPU_3V3IO_RSVD5_FFU_ISO      A @S9S_MB_2U_LIB.S9S_MB_2U(SCH_1):GPU_3V3IO_RSVD5_FFU_ISO
   2    GND      B @S9S_MB_2U_LIB.S9S_MB_2U(SCH_1):GND

MOSFET_NCH_DUAL-PJT138K,SMLF,IA  I70  Q130
   3 GPU_3V3IO_RSVD3_FFU_ISO     D2 @S9S_MB_2U_LIB.S9S_MB_2U(SCH_1):GPU_3V3IO_RSVD3_FFU_ISO
   5 GPU_3V3IO_RSVD3_FFU_N     G2 @S9S_MB_2U_LIB.S9S_MB_2U(SCH_1):GPU_3V3IO_RSVD3_FFU_N
   4    GND     S2 @S9S_MB_2U_LIB.S9S_MB_2U(SCH_1):GND

MOSFET_NCH_DUAL-PJT138K,SMLF,IA  I71  Q133
   3 PRSNT_CABLE_GPU_A2_ISO_N     D2 @S9S_MB_2U_LIB.S9S_MB_2U(SCH_1):PRSNT_CABLE_GPU_A2_ISO_N
   5 PRSNT_CABLE_GPU_A2     G2 @S9S_MB_2U_LIB.S9S_MB_2U(SCH_1):PRSNT_CABLE_GPU_A2
   4    GND     S2 @S9S_MB_2U_LIB.S9S_MB_2U(SCH_1):GND

Q_RES_0402LF-4.7K,5%,1/16W,CHIA  I72  R4137
   1 P3V3_AUX      A @S9S_MB_2U_LIB.S9S_MB_2U(SCH_1):P3V3_AUX
   2 GPU_3V3IO_RSVD3_FFU_N      B @S9S_MB_2U_LIB.S9S_MB_2U(SCH_1):GPU_3V3IO_RSVD3_FFU_N

MOSFET_NCH_DUAL-PJT138K,SMLF,IA  I74  Q130
   1    GND     S1 @S9S_MB_2U_LIB.S9S_MB_2U(SCH_1):GND
   2 GPU_3V3IO_RSVD3_FFU     G1 @S9S_MB_2U_LIB.S9S_MB_2U(SCH_1):GPU_3V3IO_RSVD3_FFU
   6 GPU_3V3IO_RSVD3_FFU_N     D1 @S9S_MB_2U_LIB.S9S_MB_2U(SCH_1):GPU_3V3IO_RSVD3_FFU_N

Q_RES_0402LF-4.7K,5%,1/16W,CHIA  I76  R4139
   1 P3V3_AUX      A @S9S_MB_2U_LIB.S9S_MB_2U(SCH_1):P3V3_AUX
   2 PRSNT_CABLE_GPU_A2      B @S9S_MB_2U_LIB.S9S_MB_2U(SCH_1):PRSNT_CABLE_GPU_A2

MOSFET_NCH_DUAL-PJT138K,SMLF,IA  I77  Q129
   3 GPU_3V3IO_RSVD5_FFU_ISO     D2 @S9S_MB_2U_LIB.S9S_MB_2U(SCH_1):GPU_3V3IO_RSVD5_FFU_ISO
   5 GPU_3V3IO_RSVD5_FFU_N     G2 @S9S_MB_2U_LIB.S9S_MB_2U(SCH_1):GPU_3V3IO_RSVD5_FFU_N
   4    GND     S2 @S9S_MB_2U_LIB.S9S_MB_2U(SCH_1):GND

MOSFET_NCH_DUAL-PJT138K,SMLF,IA  I78  Q133
   1    GND     S1 @S9S_MB_2U_LIB.S9S_MB_2U(SCH_1):GND
   2 PRSNT_CABLE_GPU_A2_N     G1 @S9S_MB_2U_LIB.S9S_MB_2U(SCH_1):PRSNT_CABLE_GPU_A2_N
   6 PRSNT_CABLE_GPU_A2     D1 @S9S_MB_2U_LIB.S9S_MB_2U(SCH_1):PRSNT_CABLE_GPU_A2

Q_RES_0402LF-4.7K,5%,1/16W,CHIA  I81  R4138
   1 P3V3_AUX      A @S9S_MB_2U_LIB.S9S_MB_2U(SCH_1):P3V3_AUX
   2 GPU_3V3IO_RSVD5_FFU_N      B @S9S_MB_2U_LIB.S9S_MB_2U(SCH_1):GPU_3V3IO_RSVD5_FFU_N

MOSFET_NCH_DUAL-PJT138K,SMLF,IA  I83  Q129
   1    GND     S1 @S9S_MB_2U_LIB.S9S_MB_2U(SCH_1):GND
   2 GPU_3V3IO_RSVD5_FFU     G1 @S9S_MB_2U_LIB.S9S_MB_2U(SCH_1):GPU_3V3IO_RSVD5_FFU
   6 GPU_3V3IO_RSVD5_FFU_N     D1 @S9S_MB_2U_LIB.S9S_MB_2U(SCH_1):GPU_3V3IO_RSVD5_FFU_N

Q_RES_0402LF-54.9K,1%,1/16W,EMA  I85  R4131
   1 P3V3_AUX      A @S9S_MB_2U_LIB.S9S_MB_2U(SCH_1):P3V3_AUX
   2 GPU_3V3IO_RSVD3_FFU      B @S9S_MB_2U_LIB.S9S_MB_2U(SCH_1):GPU_3V3IO_RSVD3_FFU

Q_RES_0402LF-100K,1%,1/16W,EMPA  I86  R4132
   1 GPU_3V3IO_RSVD3_FFU      A @S9S_MB_2U_LIB.S9S_MB_2U(SCH_1):GPU_3V3IO_RSVD3_FFU
   2    GND      B @S9S_MB_2U_LIB.S9S_MB_2U(SCH_1):GND

Q_RES_0402LF-100K,1%,1/16W,EMPA  I91  R4136
   1 PRSNT_CABLE_GPU_A2_N      A @S9S_MB_2U_LIB.S9S_MB_2U(SCH_1):PRSNT_CABLE_GPU_A2_N
   2    GND      B @S9S_MB_2U_LIB.S9S_MB_2U(SCH_1):GND

Q_RES_0402LF-54.9K,1%,1/16W,EMA  I95  R4133
   1 P3V3_AUX      A @S9S_MB_2U_LIB.S9S_MB_2U(SCH_1):P3V3_AUX
   2 GPU_3V3IO_RSVD5_FFU      B @S9S_MB_2U_LIB.S9S_MB_2U(SCH_1):GPU_3V3IO_RSVD5_FFU

Q_RES_0402LF-100K,1%,1/16W,EMPA  I96  R4134
   1 GPU_3V3IO_RSVD5_FFU      A @S9S_MB_2U_LIB.S9S_MB_2U(SCH_1):GPU_3V3IO_RSVD5_FFU
   2    GND      B @S9S_MB_2U_LIB.S9S_MB_2U(SCH_1):GND

MOSFET_NCH_DUAL-PJT138K,SMLF,IA  I99  Q134
   1    GND     S1 @S9S_MB_2U_LIB.S9S_MB_2U(SCH_1):GND
   2 PRSNT_CABLE_GPU_A1_N     G1 @S9S_MB_2U_LIB.S9S_MB_2U(SCH_1):PRSNT_CABLE_GPU_A1_N
   6 PRSNT_CABLE_GPU_A1     D1 @S9S_MB_2U_LIB.S9S_MB_2U(SCH_1):PRSNT_CABLE_GPU_A1

Q_RES_0402LF-4.7K,5%,1/16W,CHIA  I100  R4155
   1 P3V3_AUX      A @S9S_MB_2U_LIB.S9S_MB_2U(SCH_1):P3V3_AUX
   2 PRSNT_CABLE_GPU_A1      B @S9S_MB_2U_LIB.S9S_MB_2U(SCH_1):PRSNT_CABLE_GPU_A1

Q_RES_0402LF-4.7K,5%,1/16W,CHIA  I101  R4156
   1 P3V3_AUX      A @S9S_MB_2U_LIB.S9S_MB_2U(SCH_1):P3V3_AUX
   2 PRSNT_CABLE_GPU_A1_ISO_N      B @S9S_MB_2U_LIB.S9S_MB_2U(SCH_1):PRSNT_CABLE_GPU_A1_ISO_N

Q_CAP_0402-1000PF,50V,5%,EMPTYA  I105  C2270
   1 PRSNT_CABLE_GPU_A1_ISO_N      A @S9S_MB_2U_LIB.S9S_MB_2U(SCH_1):PRSNT_CABLE_GPU_A1_ISO_N
   2    GND      B @S9S_MB_2U_LIB.S9S_MB_2U(SCH_1):GND

MOSFET_NCH_DUAL-PJT138K,SMLF,IA  I107  Q134
   3 PRSNT_CABLE_GPU_A1_ISO_N     D2 @S9S_MB_2U_LIB.S9S_MB_2U(SCH_1):PRSNT_CABLE_GPU_A1_ISO_N
   5 PRSNT_CABLE_GPU_A1     G2 @S9S_MB_2U_LIB.S9S_MB_2U(SCH_1):PRSNT_CABLE_GPU_A1
   4    GND     S2 @S9S_MB_2U_LIB.S9S_MB_2U(SCH_1):GND

Q_RES_0402LF-100K,1%,1/16W,EMPA  I113  R4154
   1 PRSNT_CABLE_GPU_A1_N      A @S9S_MB_2U_LIB.S9S_MB_2U(SCH_1):PRSNT_CABLE_GPU_A1_N
   2    GND      B @S9S_MB_2U_LIB.S9S_MB_2U(SCH_1):GND

Q_RES_0402LF-4.7K,5%,1/16W,CHIA  I116  R4561
   1 P3V3_AUX      A @S9S_MB_2U_LIB.S9S_MB_2U(SCH_1):P3V3_AUX
   2 SWB_HSC_PWRGD_ISO      B @S9S_MB_2U_LIB.S9S_MB_2U(SCH_1):SWB_HSC_PWRGD_ISO

Q_CAP_0402-1000PF,50V,5%,EMPTYA  I118  C2343
   1 SWB_HSC_PWRGD_ISO      A @S9S_MB_2U_LIB.S9S_MB_2U(SCH_1):SWB_HSC_PWRGD_ISO
   2    GND      B @S9S_MB_2U_LIB.S9S_MB_2U(SCH_1):GND

MOSFET_NCH_DUAL-PJT138K,SMLF,IA  I121  Q146
   3 SWB_HSC_PWRGD_ISO     D2 @S9S_MB_2U_LIB.S9S_MB_2U(SCH_1):SWB_HSC_PWRGD_ISO
   5 SWB_HSC_PWRGD_N     G2 @S9S_MB_2U_LIB.S9S_MB_2U(SCH_1):SWB_HSC_PWRGD_N
   4    GND     S2 @S9S_MB_2U_LIB.S9S_MB_2U(SCH_1):GND

Q_RES_0402LF-4.7K,5%,1/16W,CHIA  I124  R4560
   1 P3V3_AUX      A @S9S_MB_2U_LIB.S9S_MB_2U(SCH_1):P3V3_AUX
   2 SWB_HSC_PWRGD_N      B @S9S_MB_2U_LIB.S9S_MB_2U(SCH_1):SWB_HSC_PWRGD_N

MOSFET_NCH_DUAL-PJT138K,SMLF,IA  I126  Q146
   1    GND     S1 @S9S_MB_2U_LIB.S9S_MB_2U(SCH_1):GND
   2 SWB_HSC_PWRGD     G1 @S9S_MB_2U_LIB.S9S_MB_2U(SCH_1):SWB_HSC_PWRGD
   6 SWB_HSC_PWRGD_N     D1 @S9S_MB_2U_LIB.S9S_MB_2U(SCH_1):SWB_HSC_PWRGD_N

Q_RES_0402LF-100K,1%,1/16W,CHIA  I129  R4559
   1 SWB_HSC_PWRGD      A @S9S_MB_2U_LIB.S9S_MB_2U(SCH_1):SWB_HSC_PWRGD
   2    GND      B @S9S_MB_2U_LIB.S9S_MB_2U(SCH_1):GND

Q_RES_0402LF-100K,1%,1/16W,EMPA  I132  R4562
   1 P3V3_AUX      A @S9S_MB_2U_LIB.S9S_MB_2U(SCH_1):P3V3_AUX
   2 SWB_HSC_PWRGD      B @S9S_MB_2U_LIB.S9S_MB_2U(SCH_1):SWB_HSC_PWRGD

Q_RES_0402LF-0,5%,1/16W,EMPTY,A  I136  R4574
   1 PRSNT_CABLE_GPU_A1_N      A @S9S_MB_2U_LIB.S9S_MB_2U(SCH_1):PRSNT_CABLE_GPU_A1_N
   2 PRSNT_CABLE_GPU_A1_ISO_N      B @S9S_MB_2U_LIB.S9S_MB_2U(SCH_1):PRSNT_CABLE_GPU_A1_ISO_N

Q_RES_0402LF-0,5%,1/16W,EMPTY,A  I137  R4577
   1 GPU_3V3IO_RSVD3_FFU      A @S9S_MB_2U_LIB.S9S_MB_2U(SCH_1):GPU_3V3IO_RSVD3_FFU
   2 GPU_3V3IO_RSVD3_FFU_ISO      B @S9S_MB_2U_LIB.S9S_MB_2U(SCH_1):GPU_3V3IO_RSVD3_FFU_ISO

Q_RES_0402LF-0,5%,1/16W,EMPTY,A  I138  R4578
   1 PRSNT_CABLE_GPU_A2_N      A @S9S_MB_2U_LIB.S9S_MB_2U(SCH_1):PRSNT_CABLE_GPU_A2_N
   2 PRSNT_CABLE_GPU_A2_ISO_N      B @S9S_MB_2U_LIB.S9S_MB_2U(SCH_1):PRSNT_CABLE_GPU_A2_ISO_N

Q_RES_0402LF-0,5%,1/16W,EMPTY,A  I139  R4576
   1 GPU_3V3IO_RSVD5_FFU      A @S9S_MB_2U_LIB.S9S_MB_2U(SCH_1):GPU_3V3IO_RSVD5_FFU
   2 GPU_3V3IO_RSVD5_FFU_ISO      B @S9S_MB_2U_LIB.S9S_MB_2U(SCH_1):GPU_3V3IO_RSVD5_FFU_ISO

Q_RES_0402LF-0,5%,1/16W,EMPTY,A  I140  R4573
   1 PRSNT_CABLE_GPU_B3_N      A @S9S_MB_2U_LIB.S9S_MB_2U(SCH_1):PRSNT_CABLE_GPU_B3_N
   2 PRSNT_CABLE_GPU_B3_ISO_N      B @S9S_MB_2U_LIB.S9S_MB_2U(SCH_1):PRSNT_CABLE_GPU_B3_ISO_N

Q_RES_0402LF-0,5%,1/16W,EMPTY,A  I141  R4572
   1 GPU_3V3IO_RSVD1_FFU      A @S9S_MB_2U_LIB.S9S_MB_2U(SCH_1):GPU_3V3IO_RSVD1_FFU
   2 GPU_3V3IO_RSVD1_FFU_ISO      B @S9S_MB_2U_LIB.S9S_MB_2U(SCH_1):GPU_3V3IO_RSVD1_FFU_ISO

Q_RES_0402LF-0,5%,1/16W,EMPTY,A  I142  R4575
   1 GPU_3V3IO_RSVD0_FFU      A @S9S_MB_2U_LIB.S9S_MB_2U(SCH_1):GPU_3V3IO_RSVD0_FFU
   2 GPU_3V3IO_RSVD0_FFU_ISO      B @S9S_MB_2U_LIB.S9S_MB_2U(SCH_1):GPU_3V3IO_RSVD0_FFU_ISO

Q_RES_0402LF-10K,1%,1/16W,CHIPA  I143  R4121
   1 P3V3_AUX      A @S9S_MB_2U_LIB.S9S_MB_2U(SCH_1):P3V3_AUX
   2 PRSNT_CABLE_GPU_B3_N      B @S9S_MB_2U_LIB.S9S_MB_2U(SCH_1):PRSNT_CABLE_GPU_B3_N

Q_RES_0402LF-10K,1%,1/16W,CHIPA  I144  R4135
   1 P3V3_AUX      A @S9S_MB_2U_LIB.S9S_MB_2U(SCH_1):P3V3_AUX
   2 PRSNT_CABLE_GPU_A2_N      B @S9S_MB_2U_LIB.S9S_MB_2U(SCH_1):PRSNT_CABLE_GPU_A2_N

Q_RES_0402LF-10K,1%,1/16W,CHIPA  I145  R4153
   1 P3V3_AUX      A @S9S_MB_2U_LIB.S9S_MB_2U(SCH_1):P3V3_AUX
   2 PRSNT_CABLE_GPU_A1_N      B @S9S_MB_2U_LIB.S9S_MB_2U(SCH_1):PRSNT_CABLE_GPU_A1_N


DRAWING: @S9S_MB_2U_LIB.S9S_MB_2U(SCH_1):PAGE139 

Q_RES_0402LF-100K,1%,1/16W,EMPA  I2  R4161
   1 GPU_3V3IO_RSVD4      A @S9S_MB_2U_LIB.S9S_MB_2U(SCH_1):GPU_3V3IO_RSVD4
   2    GND      B @S9S_MB_2U_LIB.S9S_MB_2U(SCH_1):GND

Q_RES_0402LF-54.9K,1%,1/16W,EMA  I4  R4160
   1 P3V3_AUX      A @S9S_MB_2U_LIB.S9S_MB_2U(SCH_1):P3V3_AUX
   2 GPU_3V3IO_RSVD4      B @S9S_MB_2U_LIB.S9S_MB_2U(SCH_1):GPU_3V3IO_RSVD4

Q_RES_0402LF-100K,1%,1/16W,EMPA  I8  R4163
   1 GPU_3V3IO_RSVD3      A @S9S_MB_2U_LIB.S9S_MB_2U(SCH_1):GPU_3V3IO_RSVD3
   2    GND      B @S9S_MB_2U_LIB.S9S_MB_2U(SCH_1):GND

Q_RES_0402LF-54.9K,1%,1/16W,EMA  I9  R4162
   1 P3V3_AUX      A @S9S_MB_2U_LIB.S9S_MB_2U(SCH_1):P3V3_AUX
   2 GPU_3V3IO_RSVD3      B @S9S_MB_2U_LIB.S9S_MB_2U(SCH_1):GPU_3V3IO_RSVD3

Q_RES_0402LF-100K,1%,1/16W,EMPA  I13  R4159
   1 GPU_3V3IO_RSVD1      A @S9S_MB_2U_LIB.S9S_MB_2U(SCH_1):GPU_3V3IO_RSVD1
   2    GND      B @S9S_MB_2U_LIB.S9S_MB_2U(SCH_1):GND

Q_RES_0402LF-54.9K,1%,1/16W,EMA  I14  R4158
   1 P3V3_AUX      A @S9S_MB_2U_LIB.S9S_MB_2U(SCH_1):P3V3_AUX
   2 GPU_3V3IO_RSVD1      B @S9S_MB_2U_LIB.S9S_MB_2U(SCH_1):GPU_3V3IO_RSVD1

MOSFET_NCH_DUAL-PJT138K,SMLF,IA  I17  Q136
   1    GND     S1 @S9S_MB_2U_LIB.S9S_MB_2U(SCH_1):GND
   2 GPU_3V3IO_RSVD4     G1 @S9S_MB_2U_LIB.S9S_MB_2U(SCH_1):GPU_3V3IO_RSVD4
   6 GPU_3V3IO_RSVD4_N     D1 @S9S_MB_2U_LIB.S9S_MB_2U(SCH_1):GPU_3V3IO_RSVD4_N

Q_RES_0402LF-4.7K,5%,1/16W,CHIA  I18  R4165
   1 P3V3_AUX      A @S9S_MB_2U_LIB.S9S_MB_2U(SCH_1):P3V3_AUX
   2 GPU_3V3IO_RSVD4_N      B @S9S_MB_2U_LIB.S9S_MB_2U(SCH_1):GPU_3V3IO_RSVD4_N

MOSFET_NCH_DUAL-PJT138K,SMLF,IA  I21  Q137
   1    GND     S1 @S9S_MB_2U_LIB.S9S_MB_2U(SCH_1):GND
   2 GPU_3V3IO_RSVD3     G1 @S9S_MB_2U_LIB.S9S_MB_2U(SCH_1):GPU_3V3IO_RSVD3
   6 GPU_3V3IO_RSVD3_N     D1 @S9S_MB_2U_LIB.S9S_MB_2U(SCH_1):GPU_3V3IO_RSVD3_N

MOSFET_NCH_DUAL-PJT138K,SMLF,IA  I22  Q136
   3 GPU_3V3IO_RSVD4_ISO     D2 @S9S_MB_2U_LIB.S9S_MB_2U(SCH_1):GPU_3V3IO_RSVD4_ISO
   5 GPU_3V3IO_RSVD4_N     G2 @S9S_MB_2U_LIB.S9S_MB_2U(SCH_1):GPU_3V3IO_RSVD4_N
   4    GND     S2 @S9S_MB_2U_LIB.S9S_MB_2U(SCH_1):GND

Q_RES_0402LF-4.7K,5%,1/16W,CHIA  I23  R4166
   1 P3V3_AUX      A @S9S_MB_2U_LIB.S9S_MB_2U(SCH_1):P3V3_AUX
   2 GPU_3V3IO_RSVD3_N      B @S9S_MB_2U_LIB.S9S_MB_2U(SCH_1):GPU_3V3IO_RSVD3_N

MOSFET_NCH_DUAL-PJT138K,SMLF,IA  I25  Q135
   1    GND     S1 @S9S_MB_2U_LIB.S9S_MB_2U(SCH_1):GND
   2 GPU_3V3IO_RSVD1     G1 @S9S_MB_2U_LIB.S9S_MB_2U(SCH_1):GPU_3V3IO_RSVD1
   6 GPU_3V3IO_RSVD1_N     D1 @S9S_MB_2U_LIB.S9S_MB_2U(SCH_1):GPU_3V3IO_RSVD1_N

Q_RES_0402LF-4.7K,5%,1/16W,CHIA  I27  R4164
   1 P3V3_AUX      A @S9S_MB_2U_LIB.S9S_MB_2U(SCH_1):P3V3_AUX
   2 GPU_3V3IO_RSVD1_N      B @S9S_MB_2U_LIB.S9S_MB_2U(SCH_1):GPU_3V3IO_RSVD1_N

MOSFET_NCH_DUAL-PJT138K,SMLF,IA  I28  Q137
   3 GPU_3V3IO_RSVD3_ISO     D2 @S9S_MB_2U_LIB.S9S_MB_2U(SCH_1):GPU_3V3IO_RSVD3_ISO
   5 GPU_3V3IO_RSVD3_N     G2 @S9S_MB_2U_LIB.S9S_MB_2U(SCH_1):GPU_3V3IO_RSVD3_N
   4    GND     S2 @S9S_MB_2U_LIB.S9S_MB_2U(SCH_1):GND

MOSFET_NCH_DUAL-PJT138K,SMLF,IA  I29  Q135
   3 GPU_3V3IO_RSVD1_ISO     D2 @S9S_MB_2U_LIB.S9S_MB_2U(SCH_1):GPU_3V3IO_RSVD1_ISO
   5 GPU_3V3IO_RSVD1_N     G2 @S9S_MB_2U_LIB.S9S_MB_2U(SCH_1):GPU_3V3IO_RSVD1_N
   4    GND     S2 @S9S_MB_2U_LIB.S9S_MB_2U(SCH_1):GND

Q_CAP_0402-1000PF,50V,5%,EMPTYA  I33  C2272
   1 GPU_3V3IO_RSVD4_ISO      A @S9S_MB_2U_LIB.S9S_MB_2U(SCH_1):GPU_3V3IO_RSVD4_ISO
   2    GND      B @S9S_MB_2U_LIB.S9S_MB_2U(SCH_1):GND

Q_RES_0402LF-4.7K,5%,1/16W,CHIA  I35  R4168
   1 P3V3_AUX      A @S9S_MB_2U_LIB.S9S_MB_2U(SCH_1):P3V3_AUX
   2 GPU_3V3IO_RSVD4_ISO      B @S9S_MB_2U_LIB.S9S_MB_2U(SCH_1):GPU_3V3IO_RSVD4_ISO

Q_RES_0402LF-4.7K,5%,1/16W,CHIA  I39  R4169
   1 P3V3_AUX      A @S9S_MB_2U_LIB.S9S_MB_2U(SCH_1):P3V3_AUX
   2 GPU_3V3IO_RSVD3_ISO      B @S9S_MB_2U_LIB.S9S_MB_2U(SCH_1):GPU_3V3IO_RSVD3_ISO

Q_CAP_0402-1000PF,50V,5%,EMPTYA  I42  C2273
   1 GPU_3V3IO_RSVD3_ISO      A @S9S_MB_2U_LIB.S9S_MB_2U(SCH_1):GPU_3V3IO_RSVD3_ISO
   2    GND      B @S9S_MB_2U_LIB.S9S_MB_2U(SCH_1):GND

Q_CAP_0402-1000PF,50V,5%,EMPTYA  I44  C2271
   1 GPU_3V3IO_RSVD1_ISO      A @S9S_MB_2U_LIB.S9S_MB_2U(SCH_1):GPU_3V3IO_RSVD1_ISO
   2    GND      B @S9S_MB_2U_LIB.S9S_MB_2U(SCH_1):GND

Q_RES_0402LF-4.7K,5%,1/16W,CHIA  I47  R4167
   1 P3V3_AUX      A @S9S_MB_2U_LIB.S9S_MB_2U(SCH_1):P3V3_AUX
   2 GPU_3V3IO_RSVD1_ISO      B @S9S_MB_2U_LIB.S9S_MB_2U(SCH_1):GPU_3V3IO_RSVD1_ISO

Q_RES_0402LF-4.7K,5%,1/16W,EMPA  I50  R4546
   1 P3V3_AUX      A @S9S_MB_2U_LIB.S9S_MB_2U(SCH_1):P3V3_AUX
   2 HGX_DETECT_N_ISO      B @S9S_MB_2U_LIB.S9S_MB_2U(SCH_1):HGX_DETECT_N_ISO

Q_CAP_0402-1000PF,50V,5%,EMPTYA  I52  C2340
   1 HGX_DETECT_N_ISO      A @S9S_MB_2U_LIB.S9S_MB_2U(SCH_1):HGX_DETECT_N_ISO
   2    GND      B @S9S_MB_2U_LIB.S9S_MB_2U(SCH_1):GND

MOSFET_NCH_DUAL-PJT138K,SMLF,IA  I55  Q148
   3 HGX_DETECT_N_ISO     D2 @S9S_MB_2U_LIB.S9S_MB_2U(SCH_1):HGX_DETECT_N_ISO
   5 HGX_DETECT     G2 @S9S_MB_2U_LIB.S9S_MB_2U(SCH_1):HGX_DETECT
   4    GND     S2 @S9S_MB_2U_LIB.S9S_MB_2U(SCH_1):GND

Q_RES_0402LF-4.7K,5%,1/16W,CHIA  I57  R4545
   1 P3V3_AUX      A @S9S_MB_2U_LIB.S9S_MB_2U(SCH_1):P3V3_AUX
   2 HGX_DETECT      B @S9S_MB_2U_LIB.S9S_MB_2U(SCH_1):HGX_DETECT

MOSFET_NCH_DUAL-PJT138K,SMLF,IA  I61  Q148
   1    GND     S1 @S9S_MB_2U_LIB.S9S_MB_2U(SCH_1):GND
   2 HGX_DETECT_N     G1 @S9S_MB_2U_LIB.S9S_MB_2U(SCH_1):HGX_DETECT_N
   6 HGX_DETECT     D1 @S9S_MB_2U_LIB.S9S_MB_2U(SCH_1):HGX_DETECT

Q_RES_0402LF-100K,1%,1/16W,EMPA  I62  R4544
   1 HGX_DETECT_N      A @S9S_MB_2U_LIB.S9S_MB_2U(SCH_1):HGX_DETECT_N
   2    GND      B @S9S_MB_2U_LIB.S9S_MB_2U(SCH_1):GND

Q_RES_0402LF-4.7K,5%,1/16W,CHIA  I85  R4543
   1 P3V3_AUX      A @S9S_MB_2U_LIB.S9S_MB_2U(SCH_1):P3V3_AUX
   2 HGX_DETECT_N      B @S9S_MB_2U_LIB.S9S_MB_2U(SCH_1):HGX_DETECT_N

74LVC2G17GW-74LVC2G17GW,SMLF,IA  I86  U316
   5 P3V3_AUX    VCC @S9S_MB_2U_LIB.S9S_MB_2U(SCH_1):P3V3_AUX
   4 NC_U316_2Y     B1 @S9S_MB_2U_LIB.S9S_MB_2U(SCH_1):NC_U316_2Y
   2    GND    GND @S9S_MB_2U_LIB.S9S_MB_2U(SCH_1):GND
   1 SWB_HSC_EN     A0 @S9S_MB_2U_LIB.S9S_MB_2U(SCH_1):SWB_HSC_EN
   3    GND     A1 @S9S_MB_2U_LIB.S9S_MB_2U(SCH_1):GND
   6 SWB_HSC_EN_BUF_R     B0 @S9S_MB_2U_LIB.S9S_MB_2U(SCH_1):SWB_HSC_EN_BUF_R

Q_RES_0402LF-100K,1%,1/16W,CHIA  I87  R4548
   1 SWB_HSC_EN      A @S9S_MB_2U_LIB.S9S_MB_2U(SCH_1):SWB_HSC_EN
   2    GND      B @S9S_MB_2U_LIB.S9S_MB_2U(SCH_1):GND

Q_RES_0402LF-100K,1%,1/16W,EMPA  I89  R4547
   1 P3V3_AUX      A @S9S_MB_2U_LIB.S9S_MB_2U(SCH_1):P3V3_AUX
   2 SWB_HSC_EN      B @S9S_MB_2U_LIB.S9S_MB_2U(SCH_1):SWB_HSC_EN

Q_CAP_0402-0.1UF,25V,10%,X7R,CA  I93  C2341
   1 P3V3_AUX      A @S9S_MB_2U_LIB.S9S_MB_2U(SCH_1):P3V3_AUX
   2    GND      B @S9S_MB_2U_LIB.S9S_MB_2U(SCH_1):GND

Q_RES_0402LF-4.7K,5%,1/16W,EMPA  I98  R4549
   1 P3V3_AUX      A @S9S_MB_2U_LIB.S9S_MB_2U(SCH_1):P3V3_AUX
   2 SWB_HSC_EN_BUF_R      B @S9S_MB_2U_LIB.S9S_MB_2U(SCH_1):SWB_HSC_EN_BUF_R

Q_RES_0402LF-4.7K,5%,1/16W,EMPA  I99  R4555
   1 SWB_HSC_EN_BUF_R      A @S9S_MB_2U_LIB.S9S_MB_2U(SCH_1):SWB_HSC_EN_BUF_R
   2    GND      B @S9S_MB_2U_LIB.S9S_MB_2U(SCH_1):GND

Q_RES_0402LF-0,5%,1/16W,EMPTY,A  I107  R4569
   1 GPU_3V3IO_RSVD1      A @S9S_MB_2U_LIB.S9S_MB_2U(SCH_1):GPU_3V3IO_RSVD1
   2 GPU_3V3IO_RSVD1_ISO      B @S9S_MB_2U_LIB.S9S_MB_2U(SCH_1):GPU_3V3IO_RSVD1_ISO

Q_RES_0402LF-0,5%,1/16W,EMPTY,A  I108  R4571
   1 GPU_3V3IO_RSVD4      A @S9S_MB_2U_LIB.S9S_MB_2U(SCH_1):GPU_3V3IO_RSVD4
   2 GPU_3V3IO_RSVD4_ISO      B @S9S_MB_2U_LIB.S9S_MB_2U(SCH_1):GPU_3V3IO_RSVD4_ISO

Q_RES_0402LF-0,5%,1/16W,EMPTY,A  I109  R4570
   1 GPU_3V3IO_RSVD3      A @S9S_MB_2U_LIB.S9S_MB_2U(SCH_1):GPU_3V3IO_RSVD3
   2 GPU_3V3IO_RSVD3_ISO      B @S9S_MB_2U_LIB.S9S_MB_2U(SCH_1):GPU_3V3IO_RSVD3_ISO

Q_RES_0402LF-49.9,1%,1/16W,CHIA  I110  R4550
   1 SWB_HSC_EN_BUF_R      A @S9S_MB_2U_LIB.S9S_MB_2U(SCH_1):SWB_HSC_EN_BUF_R
   2 SWB_HSC_EN_BUF      B @S9S_MB_2U_LIB.S9S_MB_2U(SCH_1):SWB_HSC_EN_BUF


DRAWING: @S9S_MB_2U_LIB.S9S_MB_2U(SCH_1):PAGE162 

Q_RES_0402LF-1K,1%,1/16W,EMPTYA  I7  R4281
   1 P3V3_AUX      A @S9S_MB_2U_LIB.S9S_MB_2U(SCH_1):P3V3_AUX
   2 FM_USB3_1_EQB      B @S9S_MB_2U_LIB.S9S_MB_2U(SCH_1):FM_USB3_1_EQB

Q_RES_0402LF-1K,1%,1/16W,EMPTYA  I11  R4274
   1 FM_USB3_1_FGB      A @S9S_MB_2U_LIB.S9S_MB_2U(SCH_1):FM_USB3_1_FGB
   2    GND      B @S9S_MB_2U_LIB.S9S_MB_2U(SCH_1):GND

Q_RES_0402LF-1K,1%,1/16W,EMPTYA  I17  R4280
   1 FM_USB3_1_FGA      A @S9S_MB_2U_LIB.S9S_MB_2U(SCH_1):FM_USB3_1_FGA
   2    GND      B @S9S_MB_2U_LIB.S9S_MB_2U(SCH_1):GND

Q_RES_0402LF-200K,1%,1/16W,CHIA  I24  R4637
   1 USB3_PCH_RX_DN<4>      A @S9S_MB_2U_LIB.S9S_MB_2U(SCH_1):USB3_PCH_RX_DN(4)
   2    GND      B @S9S_MB_2U_LIB.S9S_MB_2U(SCH_1):GND

Q_RES_0402LF-1K,1%,1/16W,EMPTYA  I41  R4284
   1 P3V3_AUX      A @S9S_MB_2U_LIB.S9S_MB_2U(SCH_1):P3V3_AUX
   2 FM_USB3_1_SWB      B @S9S_MB_2U_LIB.S9S_MB_2U(SCH_1):FM_USB3_1_SWB

Q_RES_0402LF-4.7K,1%,1/16W,EMPA  I63  R4292
   1 FM_USB3_1_EN_N      A @S9S_MB_2U_LIB.S9S_MB_2U(SCH_1):FM_USB3_1_EN_N
   2    GND      B @S9S_MB_2U_LIB.S9S_MB_2U(SCH_1):GND

Q_RES_0402LF-4.7K,1%,1/16W,EMPA  I68  R4290
   1 FM_USB3_1_RXDET_EN      A @S9S_MB_2U_LIB.S9S_MB_2U(SCH_1):FM_USB3_1_RXDET_EN
   2    GND      B @S9S_MB_2U_LIB.S9S_MB_2U(SCH_1):GND

Q_RES_0402LF-68K,1%,1/16W,CHIPA  I2  R4276
   1 FM_USB3_1_EQA      A @S9S_MB_2U_LIB.S9S_MB_2U(SCH_1):FM_USB3_1_EQA
   2    GND      B @S9S_MB_2U_LIB.S9S_MB_2U(SCH_1):GND

Q_RES_0402LF-1K,1%,1/16W,EMPTYA  I3  R4275
   1 P3V3_AUX      A @S9S_MB_2U_LIB.S9S_MB_2U(SCH_1):P3V3_AUX
   2 FM_USB3_1_EQA      B @S9S_MB_2U_LIB.S9S_MB_2U(SCH_1):FM_USB3_1_EQA

Q_RES_0402LF-68K,1%,1/16W,CHIPA  I6  R4282
   1 FM_USB3_1_EQB      A @S9S_MB_2U_LIB.S9S_MB_2U(SCH_1):FM_USB3_1_EQB
   2    GND      B @S9S_MB_2U_LIB.S9S_MB_2U(SCH_1):GND

Q_RES_0402LF-1K,1%,1/16W,EMPTYA  I12  R4273
   1 P3V3_AUX      A @S9S_MB_2U_LIB.S9S_MB_2U(SCH_1):P3V3_AUX
   2 FM_USB3_1_FGB      B @S9S_MB_2U_LIB.S9S_MB_2U(SCH_1):FM_USB3_1_FGB

Q_RES_0402LF-1K,1%,1/16W,EMPTYA  I18  R4279
   1 P3V3_AUX      A @S9S_MB_2U_LIB.S9S_MB_2U(SCH_1):P3V3_AUX
   2 FM_USB3_1_FGA      B @S9S_MB_2U_LIB.S9S_MB_2U(SCH_1):FM_USB3_1_FGA

Q_RES_0402LF-200K,1%,1/16W,CHIA  I23  R4636
   1 USB3_PCH_RX_DP<4>      A @S9S_MB_2U_LIB.S9S_MB_2U(SCH_1):USB3_PCH_RX_DP(4)
   2    GND      B @S9S_MB_2U_LIB.S9S_MB_2U(SCH_1):GND

Q_CAP_DIFFBUS_C0402-DIFF BUS_0A  I25  C2350
   1 USB3_PCH_RX_DN<4>      1 @S9S_MB_2U_LIB.S9S_MB_2U(SCH_1):USB3_PCH_RX_DN(4)
   2 USB3_PCH_RX_C_DN<4>      2 @S9S_MB_2U_LIB.S9S_MB_2U(SCH_1):USB3_PCH_RX_C_DN(4)

Q_CAP_DIFFBUS_C0402-DIFF BUS_0A  I26  C2349
   1 USB3_PCH_RX_DP<4>      1 @S9S_MB_2U_LIB.S9S_MB_2U(SCH_1):USB3_PCH_RX_DP(4)
   2 USB3_PCH_RX_C_DP<4>      2 @S9S_MB_2U_LIB.S9S_MB_2U(SCH_1):USB3_PCH_RX_C_DP(4)

Q_INDUCTOR_SMLF-BLM15PX121SN1DB  I35  L18
   2 P3V3_AUX_USB_BUF      2 @S9S_MB_2U_LIB.S9S_MB_2U(SCH_1):P3V3_AUX_USB_BUF
   1 P3V3_AUX      1 @S9S_MB_2U_LIB.S9S_MB_2U(SCH_1):P3V3_AUX

Q_CAP_C0805-22UF,16V,20%,X6S,CB  I37  C2284
   1 P3V3_AUX_USB_BUF      A @S9S_MB_2U_LIB.S9S_MB_2U(SCH_1):P3V3_AUX_USB_BUF
   2    GND      B @S9S_MB_2U_LIB.S9S_MB_2U(SCH_1):GND

Q_RES_0402LF-1K,1%,1/16W,EMPTYA  I40  R4285
   1 FM_USB3_1_SWB      A @S9S_MB_2U_LIB.S9S_MB_2U(SCH_1):FM_USB3_1_SWB
   2    GND      B @S9S_MB_2U_LIB.S9S_MB_2U(SCH_1):GND

PI3EQX1002EZREX-PI3EQX1002EZREA  I43  U309
   9    GND  GND_2 @S9S_MB_2U_LIB.S9S_MB_2U(SCH_1):GND
  17 P3V3_AUX_USB_BUF  VDD_2 @S9S_MB_2U_LIB.S9S_MB_2U(SCH_1):P3V3_AUX_USB_BUF
   4 FM_USB3_1_EN_N     EN @S9S_MB_2U_LIB.S9S_MB_2U(SCH_1):FM_USB3_1_EN_N
   5 P3V3_AUX_USB_BUF  VDD_1 @S9S_MB_2U_LIB.S9S_MB_2U(SCH_1):P3V3_AUX_USB_BUF
  23 USB3_PCH_TX_BUF_DN<4>    AON @S9S_MB_2U_LIB.S9S_MB_2U(SCH_1):USB3_PCH_TX_BUF_DN(4)
  24 USB3_PCH_TX_BUF_DP<4>    AOP @S9S_MB_2U_LIB.S9S_MB_2U(SCH_1):USB3_PCH_TX_BUF_DP(4)
  22    GND  GND_6 @S9S_MB_2U_LIB.S9S_MB_2U(SCH_1):GND
   7 USB3_PCH_TX_C_DN<4>    AIN @S9S_MB_2U_LIB.S9S_MB_2U(SCH_1):USB3_PCH_TX_C_DN(4)
   1 FM_USB3_1_EQA    EQA @S9S_MB_2U_LIB.S9S_MB_2U(SCH_1):FM_USB3_1_EQA
   2 FM_USB3_1_FGA    FGA @S9S_MB_2U_LIB.S9S_MB_2U(SCH_1):FM_USB3_1_FGA
  13 FM_USB3_1_RXDET_EN RXDET_EN @S9S_MB_2U_LIB.S9S_MB_2U(SCH_1):FM_USB3_1_RXDET_EN
   6 USB3_PCH_TX_C_DP<4>    AIP @S9S_MB_2U_LIB.S9S_MB_2U(SCH_1):USB3_PCH_TX_C_DP(4)
  TH    GND TH_GND @S9S_MB_2U_LIB.S9S_MB_2U(SCH_1):GND
  15 FM_USB3_1_FGB    FGB @S9S_MB_2U_LIB.S9S_MB_2U(SCH_1):FM_USB3_1_FGB
  19 USB3_PCH_RX_C_DN<4>    BIN @S9S_MB_2U_LIB.S9S_MB_2U(SCH_1):USB3_PCH_RX_C_DN(4)
  14 FM_USB3_1_SWB    SWB @S9S_MB_2U_LIB.S9S_MB_2U(SCH_1):FM_USB3_1_SWB
  18 USB3_PCH_RX_C_DP<4>    BIP @S9S_MB_2U_LIB.S9S_MB_2U(SCH_1):USB3_PCH_RX_C_DP(4)
   3 FM_USB3_1_SWA    SWA @S9S_MB_2U_LIB.S9S_MB_2U(SCH_1):FM_USB3_1_SWA
   8    GND  GND_1 @S9S_MB_2U_LIB.S9S_MB_2U(SCH_1):GND
  16 FM_USB3_1_EQB    EQB @S9S_MB_2U_LIB.S9S_MB_2U(SCH_1):FM_USB3_1_EQB
  10    GND  GND_3 @S9S_MB_2U_LIB.S9S_MB_2U(SCH_1):GND
  21    GND  GND_5 @S9S_MB_2U_LIB.S9S_MB_2U(SCH_1):GND
  11 USB3_PCH_RX_BUF_C_DN<4>    BON @S9S_MB_2U_LIB.S9S_MB_2U(SCH_1):USB3_PCH_RX_BUF_C_DN(4)
  12 USB3_PCH_RX_BUF_C_DP<4>    BOP @S9S_MB_2U_LIB.S9S_MB_2U(SCH_1):USB3_PCH_RX_BUF_C_DP(4)
  20    GND  GND_4 @S9S_MB_2U_LIB.S9S_MB_2U(SCH_1):GND

Q_CAP_0402-0.1UF,25V,10%,X7R,CA  I44  C2285
   1 P3V3_AUX_USB_BUF      A @S9S_MB_2U_LIB.S9S_MB_2U(SCH_1):P3V3_AUX_USB_BUF
   2    GND      B @S9S_MB_2U_LIB.S9S_MB_2U(SCH_1):GND

Q_CAP_0402-0.1UF,25V,10%,X7R,CA  I45  C2286
   1 P3V3_AUX_USB_BUF      A @S9S_MB_2U_LIB.S9S_MB_2U(SCH_1):P3V3_AUX_USB_BUF
   2    GND      B @S9S_MB_2U_LIB.S9S_MB_2U(SCH_1):GND

Q_RES_0402LF-1K,1%,1/16W,EMPTYA  I48  R4288
   1 FM_USB3_1_SWA      A @S9S_MB_2U_LIB.S9S_MB_2U(SCH_1):FM_USB3_1_SWA
   2    GND      B @S9S_MB_2U_LIB.S9S_MB_2U(SCH_1):GND

Q_RES_0402LF-1K,1%,1/16W,EMPTYA  I49  R4287
   1 P3V3_AUX      A @S9S_MB_2U_LIB.S9S_MB_2U(SCH_1):P3V3_AUX
   2 FM_USB3_1_SWA      B @S9S_MB_2U_LIB.S9S_MB_2U(SCH_1):FM_USB3_1_SWA

Q_CAP_C0201-0.1UF,6.3V,10%,X6SA  I54  C2292
   1 USB3_PCH_RX_BUF_C_DN<4>      A @S9S_MB_2U_LIB.S9S_MB_2U(SCH_1):USB3_PCH_RX_BUF_C_DN(4)
   2 USB3_PCH_RX_BUF_DN<4>      B @S9S_MB_2U_LIB.S9S_MB_2U(SCH_1):USB3_PCH_RX_BUF_DN(4)

Q_CAP_C0201-0.1UF,6.3V,10%,X6SA  I55  C2291
   1 USB3_PCH_RX_BUF_C_DP<4>      A @S9S_MB_2U_LIB.S9S_MB_2U(SCH_1):USB3_PCH_RX_BUF_C_DP(4)
   2 USB3_PCH_RX_BUF_DP<4>      B @S9S_MB_2U_LIB.S9S_MB_2U(SCH_1):USB3_PCH_RX_BUF_DP(4)

Q_CAP_C0201-0.1UF,6.3V,10%,X6SA  I56  C2290
   1 USB3_PCH_TX_BUF_DN<4>      A @S9S_MB_2U_LIB.S9S_MB_2U(SCH_1):USB3_PCH_TX_BUF_DN(4)
   2 USB3_PCH_TX_BUF_C_DN<4>      B @S9S_MB_2U_LIB.S9S_MB_2U(SCH_1):USB3_PCH_TX_BUF_C_DN(4)

Q_CAP_C0201-0.1UF,6.3V,10%,X6SA  I57  C2289
   1 USB3_PCH_TX_BUF_DP<4>      A @S9S_MB_2U_LIB.S9S_MB_2U(SCH_1):USB3_PCH_TX_BUF_DP(4)
   2 USB3_PCH_TX_BUF_C_DP<4>      B @S9S_MB_2U_LIB.S9S_MB_2U(SCH_1):USB3_PCH_TX_BUF_C_DP(4)

Q_RES_0402LF-4.7K,1%,1/16W,EMPA  I65  R4291
   1 P3V3_AUX      A @S9S_MB_2U_LIB.S9S_MB_2U(SCH_1):P3V3_AUX
   2 FM_USB3_1_EN_N      B @S9S_MB_2U_LIB.S9S_MB_2U(SCH_1):FM_USB3_1_EN_N

Q_RES_0402LF-4.7K,1%,1/16W,EMPA  I69  R4289
   1 P3V3_AUX      A @S9S_MB_2U_LIB.S9S_MB_2U(SCH_1):P3V3_AUX
   2 FM_USB3_1_RXDET_EN      B @S9S_MB_2U_LIB.S9S_MB_2U(SCH_1):FM_USB3_1_RXDET_EN


DRAWING: @S9S_MB_2U_LIB.S9S_MB_2U(SCH_1):PAGE237 

Q_RES_0402LF-71.5K,1%,1/16W,EMA  I43  PR3855
   1 P3V3_OCP_MODE_2      A @S9S_MB_2U_LIB.S9S_MB_2U(SCH_1):P3V3_OCP_MODE_2
   2    GND      B @S9S_MB_2U_LIB.S9S_MB_2U(SCH_1):GND

Q_CAP_C0402-1UF,25V,10%,EMPTY,A  I48  PC2169
   1 P3V3_AUX      A @S9S_MB_2U_LIB.S9S_MB_2U(SCH_1):P3V3_AUX
   2    GND      B @S9S_MB_2U_LIB.S9S_MB_2U(SCH_1):GND

Q_CAP_0402-100PF,50V,5%,EMPTY,A  I54  PC1322
   1 P3V3_OCP_GATE_PU207_2      A @S9S_MB_2U_LIB.S9S_MB_2U(SCH_1):P3V3_OCP_GATE_PU207_2
   2    GND      B @S9S_MB_2U_LIB.S9S_MB_2U(SCH_1):GND

Q_CAP_C0402-39PF,50V,5%,EMPTY,A  I35  PC2168
   1 P3V3_OCP_MODE_2      A @S9S_MB_2U_LIB.S9S_MB_2U(SCH_1):P3V3_OCP_MODE_2
   2    GND      B @S9S_MB_2U_LIB.S9S_MB_2U(SCH_1):GND

Q_RES_0402LF-0,5%,1/16W,EMPTY,A  I44  R3631
   1 HP_LVC3_OCP_V3_2_EN      A @S9S_MB_2U_LIB.S9S_MB_2U(SCH_1):HP_LVC3_OCP_V3_2_EN
   2 P3V3_OCP_EN_2      B @S9S_MB_2U_LIB.S9S_MB_2U(SCH_1):P3V3_OCP_EN_2

Q_RES_0402LF-1.33K,1%,1/16W,EMA  I46  PR3856
   1    GND      A @S9S_MB_2U_LIB.S9S_MB_2U(SCH_1):GND
   2 P3V3_OCP_ILIMIT_2      B @S9S_MB_2U_LIB.S9S_MB_2U(SCH_1):P3V3_OCP_ILIMIT_2

Q_CAP_0402-0.068UF,16V,10%,EMPA  I50  PC1321
   1 P3V3_OCP_DVDT_2      A @S9S_MB_2U_LIB.S9S_MB_2U(SCH_1):P3V3_OCP_DVDT_2
   2    GND      B @S9S_MB_2U_LIB.S9S_MB_2U(SCH_1):GND

MP5016GQHLZ-MP5016GQH-L-Z,SMLFA  I51  PU207
   9 P3V3_OCP_EN_2     EN @S9S_MB_2U_LIB.S9S_MB_2U(SCH_1):P3V3_OCP_EN_2
   5 P3V3_OCP_MODE_2   MODE @S9S_MB_2U_LIB.S9S_MB_2U(SCH_1):P3V3_OCP_MODE_2
   4 P3V3_OCP_ILIMIT_2 ILIMIT @S9S_MB_2U_LIB.S9S_MB_2U(SCH_1):P3V3_OCP_ILIMIT_2
   3    GND    GND @S9S_MB_2U_LIB.S9S_MB_2U(SCH_1):GND
 1_2 P3V3_AUX    VCC @S9S_MB_2U_LIB.S9S_MB_2U(SCH_1):P3V3_AUX
  10 P3V3_OCP_DVDT_2  DV_DT @S9S_MB_2U_LIB.S9S_MB_2U(SCH_1):P3V3_OCP_DVDT_2
   8 P3V3_OCP_GATE_PU207_2   GATE @S9S_MB_2U_LIB.S9S_MB_2U(SCH_1):P3V3_OCP_GATE_PU207_2
 6_7 P3V3_OCP_V3_2_R SOURCE @S9S_MB_2U_LIB.S9S_MB_2U(SCH_1):P3V3_OCP_V3_2_R

Q_CAP_C0805-10UF,16V,10%,EMPTYB  I56  PC2173
   1 P3V3_OCP_V3_2_R      A @S9S_MB_2U_LIB.S9S_MB_2U(SCH_1):P3V3_OCP_V3_2_R
   2    GND      B @S9S_MB_2U_LIB.S9S_MB_2U(SCH_1):GND

Q_RES_0402LF-14.3K,1%,1/16W,CHA  I61  PR3847
   1 P12V_OCP_ISET_2      A @S9S_MB_2U_LIB.S9S_MB_2U(SCH_1):P12V_OCP_ISET_2
   2    GND      B @S9S_MB_2U_LIB.S9S_MB_2U(SCH_1):GND

Q_CAP_0402-0.22UF,16V,10%,X7R,A  I62  PC2164
   1 P12V_OCP_TIMER_2      A @S9S_MB_2U_LIB.S9S_MB_2U(SCH_1):P12V_OCP_TIMER_2
   2    GND      B @S9S_MB_2U_LIB.S9S_MB_2U(SCH_1):GND

Q_CAP_C0402-0.047UF,25V,10%,X7A  I65  PC2166
   1 P12V_OCP_SS_2      A @S9S_MB_2U_LIB.S9S_MB_2U(SCH_1):P12V_OCP_SS_2
   2    GND      B @S9S_MB_2U_LIB.S9S_MB_2U(SCH_1):GND

Q_RES_0402LF-0,5%,1/16W,CHIP,CA  I66  R3630
   1 HP_LVC3_OCP_V3_2_EN      A @S9S_MB_2U_LIB.S9S_MB_2U(SCH_1):HP_LVC3_OCP_V3_2_EN
   2 P12V_OCP_V3_2_EN_2_R3      B @S9S_MB_2U_LIB.S9S_MB_2U(SCH_1):P12V_OCP_V3_2_EN_2_R3

Q_CAP_C0402-1UF,25V,10%,X6S,CHA  I68  PC2165
   1 P12V_AUX      A @S9S_MB_2U_LIB.S9S_MB_2U(SCH_1):P12V_AUX
   2    GND      B @S9S_MB_2U_LIB.S9S_MB_2U(SCH_1):GND

RS31312R-RS31312R,SMLF,IC,AL03A  I70  PU206
  20 P12V_OCP_V3_2 VOUT_20 @S9S_MB_2U_LIB.S9S_MB_2U(SCH_1):P12V_OCP_V3_2
21_22 P12V_AUX VIN_21_22 @S9S_MB_2U_LIB.S9S_MB_2U(SCH_1):P12V_AUX
  19 P12V_OCP_V3_2 VOUT_19 @S9S_MB_2U_LIB.S9S_MB_2U(SCH_1):P12V_OCP_V3_2
  18 P12V_OCP_V3_2 VOUT_18 @S9S_MB_2U_LIB.S9S_MB_2U(SCH_1):P12V_OCP_V3_2
  17 P12V_OCP_V3_2 VOUT_17 @S9S_MB_2U_LIB.S9S_MB_2U(SCH_1):P12V_OCP_V3_2
  16 P12V_OCP_V3_2 VOUT_16 @S9S_MB_2U_LIB.S9S_MB_2U(SCH_1):P12V_OCP_V3_2
  15 P12V_OCP_V3_2 VOUT_15 @S9S_MB_2U_LIB.S9S_MB_2U(SCH_1):P12V_OCP_V3_2
  14 P12V_OCP_V3_2 VOUT_14 @S9S_MB_2U_LIB.S9S_MB_2U(SCH_1):P12V_OCP_V3_2
  12 P12V_OCP_AVIN_PD_2   AVIN @S9S_MB_2U_LIB.S9S_MB_2U(SCH_1):P12V_OCP_AVIN_PD_2
  13 P12V_OCP_V3_2 VOUT_13 @S9S_MB_2U_LIB.S9S_MB_2U(SCH_1):P12V_OCP_V3_2
  11 P12V_OCP_OV_FB_2     OV @S9S_MB_2U_LIB.S9S_MB_2U(SCH_1):P12V_OCP_OV_FB_2
  10 HP_LVC3_OCP_V3_2_P12V_PWRGD     PG @S9S_MB_2U_LIB.S9S_MB_2U(SCH_1):HP_LVC3_OCP_V3_2_P12V_PWRGD
   9 P12V_OCP_FLTB_2   FLTB @S9S_MB_2U_LIB.S9S_MB_2U(SCH_1):P12V_OCP_FLTB_2
   8 P12V_OCP_IMON_2   IMON @S9S_MB_2U_LIB.S9S_MB_2U(SCH_1):P12V_OCP_IMON_2
  23 P12V_AUX VIN_23 @S9S_MB_2U_LIB.S9S_MB_2U(SCH_1):P12V_AUX
  24 P12V_AUX VIN_24 @S9S_MB_2U_LIB.S9S_MB_2U(SCH_1):P12V_AUX
  25 P12V_AUX VIN_25 @S9S_MB_2U_LIB.S9S_MB_2U(SCH_1):P12V_AUX
  26 P12V_AUX VIN_26 @S9S_MB_2U_LIB.S9S_MB_2U(SCH_1):P12V_AUX
   1 P12V_OCP_V3_2_EN_2_R3     EN @S9S_MB_2U_LIB.S9S_MB_2U(SCH_1):P12V_OCP_V3_2_EN_2_R3
   2    GND LOADEN @S9S_MB_2U_LIB.S9S_MB_2U(SCH_1):GND
   3    GND   ENTM @S9S_MB_2U_LIB.S9S_MB_2U(SCH_1):GND
   4 P12V_OCP_TIMER_2  TIMER @S9S_MB_2U_LIB.S9S_MB_2U(SCH_1):P12V_OCP_TIMER_2
   5 P12V_OCP_ISET_2   ISET @S9S_MB_2U_LIB.S9S_MB_2U(SCH_1):P12V_OCP_ISET_2
   6 P12V_OCP_SS_2     SS @S9S_MB_2U_LIB.S9S_MB_2U(SCH_1):P12V_OCP_SS_2
   7    GND    GND @S9S_MB_2U_LIB.S9S_MB_2U(SCH_1):GND

Q_RES_0402LF-17.4K,1%,1/16W,CHA  I72  PR3849
   1 P12V_OCP_IMON_2      A @S9S_MB_2U_LIB.S9S_MB_2U(SCH_1):P12V_OCP_IMON_2
   2    GND      B @S9S_MB_2U_LIB.S9S_MB_2U(SCH_1):GND

Q_CAP_0402-100PF,50V,5%,X7R,CHA  I73  PC2167
   1 P12V_OCP_IMON_2      A @S9S_MB_2U_LIB.S9S_MB_2U(SCH_1):P12V_OCP_IMON_2
   2    GND      B @S9S_MB_2U_LIB.S9S_MB_2U(SCH_1):GND

Q_RES_0402LF-10K,1%,1/16W,CHIPA  I74  PR3851
   1 P12V_OCP_FLTB_2      A @S9S_MB_2U_LIB.S9S_MB_2U(SCH_1):P12V_OCP_FLTB_2
   2 P3V3_AUX      B @S9S_MB_2U_LIB.S9S_MB_2U(SCH_1):P3V3_AUX

Q_RES_0402LF-10K,1%,1/16W,CHIPA  I75  R3848
   1 P3V3_AUX      A @S9S_MB_2U_LIB.S9S_MB_2U(SCH_1):P3V3_AUX
   2 HP_LVC3_OCP_V3_2_P12V_PWRGD      B @S9S_MB_2U_LIB.S9S_MB_2U(SCH_1):HP_LVC3_OCP_V3_2_P12V_PWRGD

Q_RES_0402LF-100,1%,1/16W,EMPTA  I77  PR3850
   1 P12V_OCP_V3_2      A @S9S_MB_2U_LIB.S9S_MB_2U(SCH_1):P12V_OCP_V3_2
   2 P12V_OCP_AVIN_PD_2      B @S9S_MB_2U_LIB.S9S_MB_2U(SCH_1):P12V_OCP_AVIN_PD_2

Q_RES_0402LF-0,5%,1/16W,CHIP,CA  I80  R3874
   1 P12V_OCP_IMON_2      A @S9S_MB_2U_LIB.S9S_MB_2U(SCH_1):P12V_OCP_IMON_2
   2 P12V_OCP_V3_2_ISENSE_MPS_TIC      B @S9S_MB_2U_LIB.S9S_MB_2U(SCH_1):P12V_OCP_V3_2_ISENSE_MPS_TIC

Q_RES_0402LF-0,5%,1/16W,EMPTY,A  I81  R3873
   1 P12V_OCP_IMON_2      A @S9S_MB_2U_LIB.S9S_MB_2U(SCH_1):P12V_OCP_IMON_2
   2 P12V_OCP_V3_2_ISENSE_MPS_MAM      B @S9S_MB_2U_LIB.S9S_MB_2U(SCH_1):P12V_OCP_V3_2_ISENSE_MPS_MAM

Q_RES_0402LF-10K,1%,1/16W,CHIPA  I83  PR3854
   1 P12V_OCP_OV_FB_2      A @S9S_MB_2U_LIB.S9S_MB_2U(SCH_1):P12V_OCP_OV_FB_2
   2    GND      B @S9S_MB_2U_LIB.S9S_MB_2U(SCH_1):GND

Q_RES_0402LF-120K,1%,1/16W,CHIA  I84  PR3853
   1 P12V_AUX      A @S9S_MB_2U_LIB.S9S_MB_2U(SCH_1):P12V_AUX
   2 P12V_OCP_OV_FB_2      B @S9S_MB_2U_LIB.S9S_MB_2U(SCH_1):P12V_OCP_OV_FB_2

Q_RES_0402LF-71.5K,1%,1/16W,EMA  I85  PR3852
   1 P12V_OCP_V3_2      A @S9S_MB_2U_LIB.S9S_MB_2U(SCH_1):P12V_OCP_V3_2
   2 P12V_OCP_OV_FB_2      B @S9S_MB_2U_LIB.S9S_MB_2U(SCH_1):P12V_OCP_OV_FB_2

Q_RES_0603LF-49.9,1%,1/10W,CHIA  I87  PR3857
   1 P12V_AUX      A @S9S_MB_2U_LIB.S9S_MB_2U(SCH_1):P12V_AUX
   2 P12V_OCP_AVIN_PD_2      B @S9S_MB_2U_LIB.S9S_MB_2U(SCH_1):P12V_OCP_AVIN_PD_2

Q_CAP_0402-0.1UF,25V,10%,X7R,CA  I91  PC2174
   1 P12V_OCP_V3_2      A @S9S_MB_2U_LIB.S9S_MB_2U(SCH_1):P12V_OCP_V3_2
   2    GND      B @S9S_MB_2U_LIB.S9S_MB_2U(SCH_1):GND

Q_CAP_C0603-2.2UF,16V,20%,X7R,A  I95  PC1320
   1 P12V_OCP_AVIN_PD_2      A @S9S_MB_2U_LIB.S9S_MB_2U(SCH_1):P12V_OCP_AVIN_PD_2
   2    GND      B @S9S_MB_2U_LIB.S9S_MB_2U(SCH_1):GND


DRAWING: @S9S_MB_2U_LIB.S9S_MB_2U(SCH_1):PAGE194 

Q_CAP_0402-0.1UF,25V,10%,EMPTYA  I2  C2321
   1 PD_USB_HUB_2_RSTN      A @S9S_MB_2U_LIB.S9S_MB_2U(SCH_1):PD_USB_HUB_2_RSTN
   2    GND      B @S9S_MB_2U_LIB.S9S_MB_2U(SCH_1):GND

Q_RES_0402LF-3.9K,5%,1/16W,EMPA  I4  R4465
   1 PD_USB_HUB_2_EQ      A @S9S_MB_2U_LIB.S9S_MB_2U(SCH_1):PD_USB_HUB_2_EQ
   2    GND      B @S9S_MB_2U_LIB.S9S_MB_2U(SCH_1):GND

Q_RES_0402LF-10K,1%,1/16W,EMPTA  I8  R4449
   1 USB_HUB_2_PSELF      A @S9S_MB_2U_LIB.S9S_MB_2U(SCH_1):USB_HUB_2_PSELF
   2    GND      B @S9S_MB_2U_LIB.S9S_MB_2U(SCH_1):GND

Q_RES_0402LF-10K,1%,1/16W,EMPTA  I9  R4448
   1 P3V3_AUX      A @S9S_MB_2U_LIB.S9S_MB_2U(SCH_1):P3V3_AUX
   2 USB_HUB_2_PSELF      B @S9S_MB_2U_LIB.S9S_MB_2U(SCH_1):USB_HUB_2_PSELF

Q_RES_0402LF-33.2,1%,1/16W,EMPA  I13  R4451
   1 RST_USB_HUB_N      A @S9S_MB_2U_LIB.S9S_MB_2U(SCH_1):RST_USB_HUB_N
   2 RST_USB_HUB_2_R_N      B @S9S_MB_2U_LIB.S9S_MB_2U(SCH_1):RST_USB_HUB_2_R_N

Q_CAP_C0402-1UF,25V,10%,EMPTY,A  I15  C2317
   1 RST_USB_HUB_2_R_N      A @S9S_MB_2U_LIB.S9S_MB_2U(SCH_1):RST_USB_HUB_2_R_N
   2    GND      B @S9S_MB_2U_LIB.S9S_MB_2U(SCH_1):GND

Q_RES_0402LF-0,5%,1/16W,EMPTY,A  I16  R4455
   1 USB2_HUB_2_EXT_DN      A @S9S_MB_2U_LIB.S9S_MB_2U(SCH_1):USB2_HUB_2_EXT_DN
   2 USB2_HUB_2_BUF_EXT_R_DN      B @S9S_MB_2U_LIB.S9S_MB_2U(SCH_1):USB2_HUB_2_BUF_EXT_R_DN

Q_RES_0402LF-0,5%,1/16W,EMPTY,A  I17  R4454
   1 USB2_HUB_2_EXT_DP      A @S9S_MB_2U_LIB.S9S_MB_2U(SCH_1):USB2_HUB_2_EXT_DP
   2 USB2_HUB_2_BUF_EXT_R_DP      B @S9S_MB_2U_LIB.S9S_MB_2U(SCH_1):USB2_HUB_2_BUF_EXT_R_DP

Q_RES_0402LF-0,5%,1/16W,CHIP,CA  I18  R4460
   1 USB2_HOST_PCH_0_DP      A @S9S_MB_2U_LIB.S9S_MB_2U(SCH_1):USB2_HOST_PCH_0_DP
   2 USB2_HUB_2_BUF_EXT_R_DP      B @S9S_MB_2U_LIB.S9S_MB_2U(SCH_1):USB2_HUB_2_BUF_EXT_R_DP

Q_RES_0402LF-0,5%,1/16W,CHIP,CA  I19  R4461
   1 USB2_HOST_PCH_0_DN      A @S9S_MB_2U_LIB.S9S_MB_2U(SCH_1):USB2_HOST_PCH_0_DN
   2 USB2_HUB_2_BUF_EXT_R_DN      B @S9S_MB_2U_LIB.S9S_MB_2U(SCH_1):USB2_HUB_2_BUF_EXT_R_DN

TUSB211IRWBR-TUSB211IRWBR,SMLFA  I20  U312
   5 PD_USB_HUB_2_RSTN   RSTN @S9S_MB_2U_LIB.S9S_MB_2U(SCH_1):PD_USB_HUB_2_RSTN
   8 USB2_HUB_2_BUF_EXT_R_DN    D2M @S9S_MB_2U_LIB.S9S_MB_2U(SCH_1):USB2_HUB_2_BUF_EXT_R_DN
  11 PD_USB_HUB_2_VREG   VREG @S9S_MB_2U_LIB.S9S_MB_2U(SCH_1):PD_USB_HUB_2_VREG
   3 TP_USB_HUB_2_TEST   TEST @S9S_MB_2U_LIB.S9S_MB_2U(SCH_1):TP_USB_HUB_2_TEST
  12 P3V3_AUX    VCC @S9S_MB_2U_LIB.S9S_MB_2U(SCH_1):P3V3_AUX
   9 TP_USB_HUB_2_ENA_HS ENA_HS @S9S_MB_2U_LIB.S9S_MB_2U(SCH_1):TP_USB_HUB_2_ENA_HS
   4 TP_USB_HUB_2_CD     CD @S9S_MB_2U_LIB.S9S_MB_2U(SCH_1):TP_USB_HUB_2_CD
   1 USB2_HUB_2_BUF_EXT_R_DN    D1M @S9S_MB_2U_LIB.S9S_MB_2U(SCH_1):USB2_HUB_2_BUF_EXT_R_DN
   2 USB2_HUB_2_BUF_EXT_R_DP    D1P @S9S_MB_2U_LIB.S9S_MB_2U(SCH_1):USB2_HUB_2_BUF_EXT_R_DP
   7 USB2_HUB_2_BUF_EXT_R_DP    D2P @S9S_MB_2U_LIB.S9S_MB_2U(SCH_1):USB2_HUB_2_BUF_EXT_R_DP
   6 PD_USB_HUB_2_EQ     EQ @S9S_MB_2U_LIB.S9S_MB_2U(SCH_1):PD_USB_HUB_2_EQ
  10    GND    GND @S9S_MB_2U_LIB.S9S_MB_2U(SCH_1):GND

Q_RES_0402LF-10K,1%,1/16W,EMPTA  I22  R4459
   1 P3V3_AUX      A @S9S_MB_2U_LIB.S9S_MB_2U(SCH_1):P3V3_AUX
   2 USB_HUB_2_OVCUR4      B @S9S_MB_2U_LIB.S9S_MB_2U(SCH_1):USB_HUB_2_OVCUR4

Q_RES_0402LF-10K,1%,1/16W,EMPTA  I23  R4458
   1 P3V3_AUX      A @S9S_MB_2U_LIB.S9S_MB_2U(SCH_1):P3V3_AUX
   2 USB_HUB_2_OVCUR3      B @S9S_MB_2U_LIB.S9S_MB_2U(SCH_1):USB_HUB_2_OVCUR3

Q_RES_0402LF-10K,1%,1/16W,EMPTA  I24  R4457
   1 P3V3_AUX      A @S9S_MB_2U_LIB.S9S_MB_2U(SCH_1):P3V3_AUX
   2 USB_HUB_2_OVCUR2      B @S9S_MB_2U_LIB.S9S_MB_2U(SCH_1):USB_HUB_2_OVCUR2

Q_RES_0402LF-10K,1%,1/16W,EMPTA  I25  R4456
   1 P3V3_AUX      A @S9S_MB_2U_LIB.S9S_MB_2U(SCH_1):P3V3_AUX
   2 USB_HUB_2_OVCUR1      B @S9S_MB_2U_LIB.S9S_MB_2U(SCH_1):USB_HUB_2_OVCUR1

Q_RES_0402LF-47K,0.1%,1/16W,EMA  I26  R4453
   1    GND      A @S9S_MB_2U_LIB.S9S_MB_2U(SCH_1):GND
   2 RST_USB_HUB_2_R_N      B @S9S_MB_2U_LIB.S9S_MB_2U(SCH_1):RST_USB_HUB_2_R_N

Q_RES_0402LF-10K,1%,1/16W,EMPTA  I27  R4452
   1 P3V3_AUX      A @S9S_MB_2U_LIB.S9S_MB_2U(SCH_1):P3V3_AUX
   2 RST_USB_HUB_2_R_N      B @S9S_MB_2U_LIB.S9S_MB_2U(SCH_1):RST_USB_HUB_2_R_N

Q_RES_0402LF-680,1%,1/16W,EMPTA  I37  R4463
   1 USB_HUB_2_RREF      A @S9S_MB_2U_LIB.S9S_MB_2U(SCH_1):USB_HUB_2_RREF
   2    GND      B @S9S_MB_2U_LIB.S9S_MB_2U(SCH_1):GND

Q_RES_0402LF-100K,1%,1/16W,EMPA  I38  R4464
   1 USB_HUB_2_PGANG      A @S9S_MB_2U_LIB.S9S_MB_2U(SCH_1):USB_HUB_2_PGANG
   2    GND      B @S9S_MB_2U_LIB.S9S_MB_2U(SCH_1):GND

GL852GOHY60-GL852G-OHY60,SMLF,B  I40  U313
  10 USB_HUB_2_XTAL_IN     X1 @S9S_MB_2U_LIB.S9S_MB_2U(SCH_1):USB_HUB_2_XTAL_IN
  11 USB_HUB_2_XTAL_OUT     X2 @S9S_MB_2U_LIB.S9S_MB_2U(SCH_1):USB_HUB_2_XTAL_OUT
  18 USB_HUB_2_TEST TEST||SCL @S9S_MB_2U_LIB.S9S_MB_2U(SCH_1):USB_HUB_2_TEST
  26 NC_USB_HUB_2_SDA    SDA @S9S_MB_2U_LIB.S9S_MB_2U(SCH_1):NC_USB_HUB_2_SDA
  27 P3V3_AUX_USB_HUB_2     V5 @S9S_MB_2U_LIB.S9S_MB_2U(SCH_1):P3V3_AUX_USB_HUB_2
  28 P3V3_AUX_USB_HUB_2    V33 @S9S_MB_2U_LIB.S9S_MB_2U(SCH_1):P3V3_AUX_USB_HUB_2
   5 P3V3_AUX_USB_HUB_2 AVDD<0> @S9S_MB_2U_LIB.S9S_MB_2U(SCH_1):P3V3_AUX_USB_HUB_2
   9 P3V3_AUX_USB_HUB_2 AVDD<1> @S9S_MB_2U_LIB.S9S_MB_2U(SCH_1):P3V3_AUX_USB_HUB_2
  14 P3V3_AUX_USB_HUB_2 AVDD<2> @S9S_MB_2U_LIB.S9S_MB_2U(SCH_1):P3V3_AUX_USB_HUB_2
  21 USB_HUB_2_DVDD   DVDD @S9S_MB_2U_LIB.S9S_MB_2U(SCH_1):USB_HUB_2_DVDD
  TH    GND     TH @S9S_MB_2U_LIB.S9S_MB_2U(SCH_1):GND
  25 USB_HUB_2_OVCUR1 OVCUR1#||SMC @S9S_MB_2U_LIB.S9S_MB_2U(SCH_1):USB_HUB_2_OVCUR1
  24 USB_HUB_2_OVCUR2 OVCUR2#||SMD @S9S_MB_2U_LIB.S9S_MB_2U(SCH_1):USB_HUB_2_OVCUR2
  20 USB_HUB_2_OVCUR3 OVCUR3# @S9S_MB_2U_LIB.S9S_MB_2U(SCH_1):USB_HUB_2_OVCUR3
  19 USB_HUB_2_OVCUR4 OVCUR4# @S9S_MB_2U_LIB.S9S_MB_2U(SCH_1):USB_HUB_2_OVCUR4
  17 RST_USB_HUB_2_R_N RESET# @S9S_MB_2U_LIB.S9S_MB_2U(SCH_1):RST_USB_HUB_2_R_N
  23 USB_HUB_2_PGANG  PGANG @S9S_MB_2U_LIB.S9S_MB_2U(SCH_1):USB_HUB_2_PGANG
  22 USB_HUB_2_PSELF  PSELF @S9S_MB_2U_LIB.S9S_MB_2U(SCH_1):USB_HUB_2_PSELF
   8 USB_HUB_2_RREF   RREF @S9S_MB_2U_LIB.S9S_MB_2U(SCH_1):USB_HUB_2_RREF
   2 USB2_PCH_0_R_DP    DP0 @S9S_MB_2U_LIB.S9S_MB_2U(SCH_1):USB2_PCH_0_R_DP
   1 USB2_PCH_0_R_DN    DM0 @S9S_MB_2U_LIB.S9S_MB_2U(SCH_1):USB2_PCH_0_R_DN
   4 USB2_HUB_2_EXT_DP    DP1 @S9S_MB_2U_LIB.S9S_MB_2U(SCH_1):USB2_HUB_2_EXT_DP
   3 USB2_HUB_2_EXT_DN    DM1 @S9S_MB_2U_LIB.S9S_MB_2U(SCH_1):USB2_HUB_2_EXT_DN
   7 NC_USB_HUB_2_DP2    DP2 @S9S_MB_2U_LIB.S9S_MB_2U(SCH_1):NC_USB_HUB_2_DP2
   6 NC_USB_HUB_2_DM2    DM2 @S9S_MB_2U_LIB.S9S_MB_2U(SCH_1):NC_USB_HUB_2_DM2
  13 NC_USB_HUB_2_DP3    DP3 @S9S_MB_2U_LIB.S9S_MB_2U(SCH_1):NC_USB_HUB_2_DP3
  12 NC_USB_HUB_2_DM3    DM3 @S9S_MB_2U_LIB.S9S_MB_2U(SCH_1):NC_USB_HUB_2_DM3
  16 NC_USB_HUB_2_DP4    DP4 @S9S_MB_2U_LIB.S9S_MB_2U(SCH_1):NC_USB_HUB_2_DP4
  15 NC_USB_HUB_2_DM4    DM4 @S9S_MB_2U_LIB.S9S_MB_2U(SCH_1):NC_USB_HUB_2_DM4

Q_RES_0402LF-0,5%,1/16W,EMPTY,A  I41  R4450
   1 P3V3_AUX      A @S9S_MB_2U_LIB.S9S_MB_2U(SCH_1):P3V3_AUX
   2 P3V3_AUX_USB_HUB_2      B @S9S_MB_2U_LIB.S9S_MB_2U(SCH_1):P3V3_AUX_USB_HUB_2

Q_CAP_C0402-10UF,6.3V,20%,EMPTA  I43  C2313
   1 P3V3_AUX_USB_HUB_2      A @S9S_MB_2U_LIB.S9S_MB_2U(SCH_1):P3V3_AUX_USB_HUB_2
   2    GND      B @S9S_MB_2U_LIB.S9S_MB_2U(SCH_1):GND

Q_CAP_0402-0.1UF,25V,10%,EMPTYA  I45  C2314
   1 P3V3_AUX_USB_HUB_2      A @S9S_MB_2U_LIB.S9S_MB_2U(SCH_1):P3V3_AUX_USB_HUB_2
   2    GND      B @S9S_MB_2U_LIB.S9S_MB_2U(SCH_1):GND

Q_CAP_0402-0.1UF,25V,10%,EMPTYA  I46  C2315
   1 P3V3_AUX_USB_HUB_2      A @S9S_MB_2U_LIB.S9S_MB_2U(SCH_1):P3V3_AUX_USB_HUB_2
   2    GND      B @S9S_MB_2U_LIB.S9S_MB_2U(SCH_1):GND

Q_CAP_C0402-1UF,25V,10%,EMPTY,A  I47  C2316
   1 P3V3_AUX_USB_HUB_2      A @S9S_MB_2U_LIB.S9S_MB_2U(SCH_1):P3V3_AUX_USB_HUB_2
   2    GND      B @S9S_MB_2U_LIB.S9S_MB_2U(SCH_1):GND

Q_CAP_0402-0.1UF,25V,10%,EMPTYA  I49  C2318
   1 P3V3_AUX_USB_HUB_2      A @S9S_MB_2U_LIB.S9S_MB_2U(SCH_1):P3V3_AUX_USB_HUB_2
   2    GND      B @S9S_MB_2U_LIB.S9S_MB_2U(SCH_1):GND

Q_RES_0402LF-0,5%,1/16W,EMPTY,A  I50  R4462
   1 P3V3_AUX_USB_HUB_2      A @S9S_MB_2U_LIB.S9S_MB_2U(SCH_1):P3V3_AUX_USB_HUB_2
   2 USB_HUB_2_DVDD      B @S9S_MB_2U_LIB.S9S_MB_2U(SCH_1):USB_HUB_2_DVDD

Q_CAP_0402-0.1UF,25V,10%,EMPTYA  I51  C2319
   1 P3V3_AUX_USB_HUB_2      A @S9S_MB_2U_LIB.S9S_MB_2U(SCH_1):P3V3_AUX_USB_HUB_2
   2    GND      B @S9S_MB_2U_LIB.S9S_MB_2U(SCH_1):GND

Q_CAP_0402-0.1UF,25V,10%,EMPTYA  I52  C2320
   1 P3V3_AUX_USB_HUB_2      A @S9S_MB_2U_LIB.S9S_MB_2U(SCH_1):P3V3_AUX_USB_HUB_2
   2    GND      B @S9S_MB_2U_LIB.S9S_MB_2U(SCH_1):GND

Q_CAP_C0402-1UF,25V,10%,EMPTY,A  I53  C2322
   1 P3V3_AUX_USB_HUB_2      A @S9S_MB_2U_LIB.S9S_MB_2U(SCH_1):P3V3_AUX_USB_HUB_2
   2    GND      B @S9S_MB_2U_LIB.S9S_MB_2U(SCH_1):GND

Q_CAP_0402-0.1UF,25V,10%,EMPTYA  I55  C2325
   1 PD_USB_HUB_2_VREG      A @S9S_MB_2U_LIB.S9S_MB_2U(SCH_1):PD_USB_HUB_2_VREG
   2    GND      B @S9S_MB_2U_LIB.S9S_MB_2U(SCH_1):GND

Q_CAP_C0402-1UF,25V,10%,EMPTY,A  I56  C2323
   1 P3V3_AUX      A @S9S_MB_2U_LIB.S9S_MB_2U(SCH_1):P3V3_AUX
   2    GND      B @S9S_MB_2U_LIB.S9S_MB_2U(SCH_1):GND

Q_CAP_0402-0.1UF,25V,10%,EMPTYA  I58  C2324
   1 P3V3_AUX      A @S9S_MB_2U_LIB.S9S_MB_2U(SCH_1):P3V3_AUX
   2    GND      B @S9S_MB_2U_LIB.S9S_MB_2U(SCH_1):GND

Q_RES_0402LF-0,5%,1/16W,CHIP,CA  I60  R4468
   1 USB2_HUB_2_BUF_EXT_R_DN      A @S9S_MB_2U_LIB.S9S_MB_2U(SCH_1):USB2_HUB_2_BUF_EXT_R_DN
   2 USB2_HUB_2_BUF_EXT_DN      B @S9S_MB_2U_LIB.S9S_MB_2U(SCH_1):USB2_HUB_2_BUF_EXT_DN

Q_RES_0402LF-0,5%,1/16W,CHIP,CA  I61  R4467
   1 USB2_HUB_2_BUF_EXT_R_DP      A @S9S_MB_2U_LIB.S9S_MB_2U(SCH_1):USB2_HUB_2_BUF_EXT_R_DP
   2 USB2_HUB_2_BUF_EXT_DP      B @S9S_MB_2U_LIB.S9S_MB_2U(SCH_1):USB2_HUB_2_BUF_EXT_DP

Q_RES_0402LF-0,5%,1/16W,CHIP,CA  I72  R4474
   1 USB2_0_DN      A @S9S_MB_2U_LIB.S9S_MB_2U(SCH_1):USB2_0_DN
   2 USB2_HOST_PCH_0_DN      B @S9S_MB_2U_LIB.S9S_MB_2U(SCH_1):USB2_HOST_PCH_0_DN

Q_RES_0402LF-0,5%,1/16W,CHIP,CA  I73  R4473
   1 USB2_0_DP      A @S9S_MB_2U_LIB.S9S_MB_2U(SCH_1):USB2_0_DP
   2 USB2_HOST_PCH_0_DP      B @S9S_MB_2U_LIB.S9S_MB_2U(SCH_1):USB2_HOST_PCH_0_DP

Q_RES_0402LF-0,5%,1/16W,EMPTY,A  I75  R4466
   1 USB_HUB_2_TEST      A @S9S_MB_2U_LIB.S9S_MB_2U(SCH_1):USB_HUB_2_TEST
   2    GND      B @S9S_MB_2U_LIB.S9S_MB_2U(SCH_1):GND

Q_RES_0402LF-0,5%,1/16W,EMPTY,A  I77  R4471
   1 USB2_PCH_0_R_DP      A @S9S_MB_2U_LIB.S9S_MB_2U(SCH_1):USB2_PCH_0_R_DP
   2 USB2_0_DP      B @S9S_MB_2U_LIB.S9S_MB_2U(SCH_1):USB2_0_DP

Q_RES_0402LF-0,5%,1/16W,EMPTY,A  I78  R4472
   1 USB2_PCH_0_R_DN      A @S9S_MB_2U_LIB.S9S_MB_2U(SCH_1):USB2_PCH_0_R_DN
   2 USB2_0_DN      B @S9S_MB_2U_LIB.S9S_MB_2U(SCH_1):USB2_0_DN

Q_CAP_C0402-12PF,50V,5%,EMPTY,A  I81  C2326
   1 USB_HUB_2_XTAL_IN      A @S9S_MB_2U_LIB.S9S_MB_2U(SCH_1):USB_HUB_2_XTAL_IN
   2    GND      B @S9S_MB_2U_LIB.S9S_MB_2U(SCH_1):GND

Q_XTAL_4P_13BI_24GND-12MHZ,SMLB  I83  Y9
   1 USB_HUB_2_XTAL_IN     X1 @S9S_MB_2U_LIB.S9S_MB_2U(SCH_1):USB_HUB_2_XTAL_IN
   2    GND     G1 @S9S_MB_2U_LIB.S9S_MB_2U(SCH_1):GND
   4    GND     G2 @S9S_MB_2U_LIB.S9S_MB_2U(SCH_1):GND
   3 USB_HUB_2_XTAL_OUT     X2 @S9S_MB_2U_LIB.S9S_MB_2U(SCH_1):USB_HUB_2_XTAL_OUT

Q_CAP_C0402-12PF,50V,5%,EMPTY,A  I85  C2327
   1 USB_HUB_2_XTAL_OUT      A @S9S_MB_2U_LIB.S9S_MB_2U(SCH_1):USB_HUB_2_XTAL_OUT
   2    GND      B @S9S_MB_2U_LIB.S9S_MB_2U(SCH_1):GND

Q_RES_0402LF-49.9,1%,1/16W,EMPA  I90  R4486
   1 USB2_HOST_PCH_0_DP      A @S9S_MB_2U_LIB.S9S_MB_2U(SCH_1):USB2_HOST_PCH_0_DP
   2    GND      B @S9S_MB_2U_LIB.S9S_MB_2U(SCH_1):GND

Q_RES_0402LF-49.9,1%,1/16W,EMPA  I88  R4487
   1 USB2_HOST_PCH_0_DN      A @S9S_MB_2U_LIB.S9S_MB_2U(SCH_1):USB2_HOST_PCH_0_DN
   2    GND      B @S9S_MB_2U_LIB.S9S_MB_2U(SCH_1):GND


DRAWING: @S9S_MB_2U_LIB.S9S_MB_2U(SCH_1):PAGE303 

Q_RES_0402LF-33K,1%,1/16W,CHIPA  I4  R3907
   1 PDB_PRSNT_N      A @S9S_MB_2U_LIB.S9S_MB_2U(SCH_1):PDB_PRSNT_N
   2    GND      B @S9S_MB_2U_LIB.S9S_MB_2U(SCH_1):GND

MOSFET_NCH_GDS_ESD_PROTECTED-2A  I5  U290
   D HSC_EN      D @S9S_MB_2U_LIB.S9S_MB_2U(SCH_1):HSC_EN
   G PDB_PRSNT_N      G @S9S_MB_2U_LIB.S9S_MB_2U(SCH_1):PDB_PRSNT_N
   S    GND      S @S9S_MB_2U_LIB.S9S_MB_2U(SCH_1):GND

Q_RES_0402LF-63.4K,1%,1/16W,CHA  I10  R3923
   1 P12V_PSU_FUSE      A @S9S_MB_2U_LIB.S9S_MB_2U(SCH_1):P12V_PSU_FUSE
   2 PDB_PRSNT_N      B @S9S_MB_2U_LIB.S9S_MB_2U(SCH_1):PDB_PRSNT_N

Q_RES_0402LF-75K,0.1%,1/16W,CHA  I52  PR3926
   1 P12V_PSU      A @S9S_MB_2U_LIB.S9S_MB_2U(SCH_1):P12V_PSU
   2 HSC_VSENSE      B @S9S_MB_2U_LIB.S9S_MB_2U(SCH_1):HSC_VSENSE

MP5990GMA1111Z-MP5990GMA-1111-A  I56  PU289
  29 P12V_AUX  VOUT3 @S9S_MB_2U_LIB.S9S_MB_2U(SCH_1):P12V_AUX
  28 P12V_AUX  VOUT2 @S9S_MB_2U_LIB.S9S_MB_2U(SCH_1):P12V_AUX
  27 P12V_AUX  VOUT1 @S9S_MB_2U_LIB.S9S_MB_2U(SCH_1):P12V_AUX
   2 P12V_PSU   VIN2 @S9S_MB_2U_LIB.S9S_MB_2U(SCH_1):P12V_PSU
  26 HSC_EN_R     EN @S9S_MB_2U_LIB.S9S_MB_2U(SCH_1):HSC_EN_R
   3 P12V_PSU   VIN3 @S9S_MB_2U_LIB.S9S_MB_2U(SCH_1):P12V_PSU
   4 P12V_PSU   VIN4 @S9S_MB_2U_LIB.S9S_MB_2U(SCH_1):P12V_PSU
  18 AGND_HSC   GND1 @S9S_MB_2U_LIB.S9S_MB_2U(SCH_1):AGND_HSC
  12 SMB_SML1_PMBUS_HSC_R_SDA    SDA @S9S_MB_2U_LIB.S9S_MB_2U(SCH_1):SMB_SML1_PMBUS_HSC_R_SDA
  14 HSC_VIN_UVW_N VIN_UVW# @S9S_MB_2U_LIB.S9S_MB_2U(SCH_1):HSC_VIN_UVW_N
  11 SMB_SML1_PMBUS_HSC_L_SCL    SCL @S9S_MB_2U_LIB.S9S_MB_2U(SCH_1):SMB_SML1_PMBUS_HSC_L_SCL
  37 HSC_D_OC_R   D_OC @S9S_MB_2U_LIB.S9S_MB_2U(SCH_1):HSC_D_OC_R
  31 P12V_AUX  VOUT5 @S9S_MB_2U_LIB.S9S_MB_2U(SCH_1):P12V_AUX
  35 P12V_AUX  VOUT9 @S9S_MB_2U_LIB.S9S_MB_2U(SCH_1):P12V_AUX
  10 IRQ_SML1_PMBUS_ALERT   ALT# @S9S_MB_2U_LIB.S9S_MB_2U(SCH_1):IRQ_SML1_PMBUS_ALERT
  39 HSC_FAULT    GOK @S9S_MB_2U_LIB.S9S_MB_2U(SCH_1):HSC_FAULT
   7 P12V_PSU   VIN7 @S9S_MB_2U_LIB.S9S_MB_2U(SCH_1):P12V_PSU
  33 P12V_AUX  VOUT7 @S9S_MB_2U_LIB.S9S_MB_2U(SCH_1):P12V_AUX
  41 HSC_MODE   MODE @S9S_MB_2U_LIB.S9S_MB_2U(SCH_1):HSC_MODE
   8 P12V_PSU   VIN8 @S9S_MB_2U_LIB.S9S_MB_2U(SCH_1):P12V_PSU
  13 MB0_P12V_STBY_PWRGD PG||OCW# @S9S_MB_2U_LIB.S9S_MB_2U(SCH_1):MB0_P12V_STBY_PWRGD
  34 P12V_AUX  VOUT8 @S9S_MB_2U_LIB.S9S_MB_2U(SCH_1):P12V_AUX
  38 HSC_ON_R     ON @S9S_MB_2U_LIB.S9S_MB_2U(SCH_1):HSC_ON_R
   5 P12V_PSU   VIN5 @S9S_MB_2U_LIB.S9S_MB_2U(SCH_1):P12V_PSU
   6 P12V_PSU   VIN6 @S9S_MB_2U_LIB.S9S_MB_2U(SCH_1):P12V_PSU
  15 HSC_VTEMP  VTEMP @S9S_MB_2U_LIB.S9S_MB_2U(SCH_1):HSC_VTEMP
  22 HSC_OCREF  OCREF @S9S_MB_2U_LIB.S9S_MB_2U(SCH_1):HSC_OCREF
  25 HSC_SCREF SCREF_OCWREF @S9S_MB_2U_LIB.S9S_MB_2U(SCH_1):HSC_SCREF
  16 HSC_SS     SS @S9S_MB_2U_LIB.S9S_MB_2U(SCH_1):HSC_SS
  32 P12V_AUX  VOUT6 @S9S_MB_2U_LIB.S9S_MB_2U(SCH_1):P12V_AUX
  21 HSC_IMON   IMON @S9S_MB_2U_LIB.S9S_MB_2U(SCH_1):HSC_IMON
  20 HSC_CS     CS @S9S_MB_2U_LIB.S9S_MB_2U(SCH_1):HSC_CS
  42 P12V_PSU   VIN9 @S9S_MB_2U_LIB.S9S_MB_2U(SCH_1):P12V_PSU
  36 P12V_AUX VOUT10 @S9S_MB_2U_LIB.S9S_MB_2U(SCH_1):P12V_AUX
  24 HSC_VOSEN  VOSEN @S9S_MB_2U_LIB.S9S_MB_2U(SCH_1):HSC_VOSEN
  30 P12V_AUX  VOUT4 @S9S_MB_2U_LIB.S9S_MB_2U(SCH_1):P12V_AUX
   1 P12V_PSU   VIN1 @S9S_MB_2U_LIB.S9S_MB_2U(SCH_1):P12V_PSU
  44 AGND_HSC   GND2 @S9S_MB_2U_LIB.S9S_MB_2U(SCH_1):AGND_HSC
  40 HSC_FLT_TYPE FLT_TYPE @S9S_MB_2U_LIB.S9S_MB_2U(SCH_1):HSC_FLT_TYPE
  43 P12V_PSU  VIN10 @S9S_MB_2U_LIB.S9S_MB_2U(SCH_1):P12V_PSU
   9 HSC_VSENSE VINSEN @S9S_MB_2U_LIB.S9S_MB_2U(SCH_1):HSC_VSENSE
  17 HSC_VDD_R VDD33_1 @S9S_MB_2U_LIB.S9S_MB_2U(SCH_1):HSC_VDD_R
  45 HSC_VDD_R VDD33_2 @S9S_MB_2U_LIB.S9S_MB_2U(SCH_1):HSC_VDD_R
  19 HSC_VDD18  VDD18 @S9S_MB_2U_LIB.S9S_MB_2U(SCH_1):HSC_VDD18
  23 HSC_ADDR   ADDR @S9S_MB_2U_LIB.S9S_MB_2U(SCH_1):HSC_ADDR

Q_RES_0402LF-4.99K,0.1%,1/16W,A  I59  PR3932
   1 HSC_VOSEN      A @S9S_MB_2U_LIB.S9S_MB_2U(SCH_1):HSC_VOSEN
   2 AGND_HSC      B @S9S_MB_2U_LIB.S9S_MB_2U(SCH_1):AGND_HSC

Q_RES_0402LF-4.7K,1%,1/16W,CHIA  I85  R3936
   1 HSC_VDD      A @S9S_MB_2U_LIB.S9S_MB_2U(SCH_1):HSC_VDD
   2 HSC_D_OC      B @S9S_MB_2U_LIB.S9S_MB_2U(SCH_1):HSC_D_OC

Q_RES_0402LF-75K,0.1%,1/16W,CHA  I86  PR3931
   1 P12V_AUX      A @S9S_MB_2U_LIB.S9S_MB_2U(SCH_1):P12V_AUX
   2 HSC_VOSEN      B @S9S_MB_2U_LIB.S9S_MB_2U(SCH_1):HSC_VOSEN

Q_RES_0402LF-0,5%,1/16W,CHIP,CA  I24  PR2149
   1 HSC_VDD_R      A @S9S_MB_2U_LIB.S9S_MB_2U(SCH_1):HSC_VDD_R
   2 HSC_VDD      B @S9S_MB_2U_LIB.S9S_MB_2U(SCH_1):HSC_VDD

Q_RES_0402LF-10K,1%,1/16W,CHIPA  I43  PR2106
   1 HSC_VDD      A @S9S_MB_2U_LIB.S9S_MB_2U(SCH_1):HSC_VDD
   2 HSC_VIN_UVW_N      B @S9S_MB_2U_LIB.S9S_MB_2U(SCH_1):HSC_VIN_UVW_N

Q_CAP_C0402-1UF,25V,10%,X6S,CHA  I51  PC2188
   1 P12V_PSU      A @S9S_MB_2U_LIB.S9S_MB_2U(SCH_1):P12V_PSU
   2    GND      B @S9S_MB_2U_LIB.S9S_MB_2U(SCH_1):GND

Q_CAP_C0402-0.01UF,50V,10%,X7RA  I75  PC2190
   1 HSC_VOSEN      A @S9S_MB_2U_LIB.S9S_MB_2U(SCH_1):HSC_VOSEN
   2 AGND_HSC      B @S9S_MB_2U_LIB.S9S_MB_2U(SCH_1):AGND_HSC

Q_RES_0402LF-22,1%,1/16W,CHIP,A  I81  R2588
   1 HSC_FAULT      A @S9S_MB_2U_LIB.S9S_MB_2U(SCH_1):HSC_FAULT
   2 IRQ_HSC_FAULT_N      B @S9S_MB_2U_LIB.S9S_MB_2U(SCH_1):IRQ_HSC_FAULT_N

Q_RES_0402LF-31.6K,1%,1/16W,CHA  I7  R2585
   1 HSC_EN      A @S9S_MB_2U_LIB.S9S_MB_2U(SCH_1):HSC_EN
   2    GND      B @S9S_MB_2U_LIB.S9S_MB_2U(SCH_1):GND

Q_RES_0402LF-0,5%,1/16W,CHIP,CA  I17  R3924
   1 IRQ_SML1_PMBUS_ALERT_N      A @S9S_MB_2U_LIB.S9S_MB_2U(SCH_1):IRQ_SML1_PMBUS_ALERT_N
   2 IRQ_SML1_PMBUS_ALERT      B @S9S_MB_2U_LIB.S9S_MB_2U(SCH_1):IRQ_SML1_PMBUS_ALERT

Q_RES_0402LF-1K,1%,1/16W,CHIP,A  I33  R3925
   1 IRQ_SML1_PMBUS_ALERT      A @S9S_MB_2U_LIB.S9S_MB_2U(SCH_1):IRQ_SML1_PMBUS_ALERT
   2 P3V3_AUX      B @S9S_MB_2U_LIB.S9S_MB_2U(SCH_1):P3V3_AUX

Q_RES_0402LF-33.2,1%,1/16W,CHIA  I38  R3909
   1 SMB_SML1_PMBUS_HSC_SCL      A @S9S_MB_2U_LIB.S9S_MB_2U(SCH_1):SMB_SML1_PMBUS_HSC_SCL
   2 SMB_SML1_PMBUS_HSC_L_SCL      B @S9S_MB_2U_LIB.S9S_MB_2U(SCH_1):SMB_SML1_PMBUS_HSC_L_SCL

Q_RES_0402LF-4.99K,0.1%,1/16W,A  I40  PR3927
   1 HSC_VSENSE      A @S9S_MB_2U_LIB.S9S_MB_2U(SCH_1):HSC_VSENSE
   2 AGND_HSC      B @S9S_MB_2U_LIB.S9S_MB_2U(SCH_1):AGND_HSC

Q_RES_0402LF-0,5%,1/16W,CHIP,CA  I41  PR3928
   1 HSC_ON      A @S9S_MB_2U_LIB.S9S_MB_2U(SCH_1):HSC_ON
   2 HSC_ON_R      B @S9S_MB_2U_LIB.S9S_MB_2U(SCH_1):HSC_ON_R

Q_CAP_C0402-0.01UF,50V,10%,X7RA  I45  PC2189
   1 HSC_VSENSE      A @S9S_MB_2U_LIB.S9S_MB_2U(SCH_1):HSC_VSENSE
   2 AGND_HSC      B @S9S_MB_2U_LIB.S9S_MB_2U(SCH_1):AGND_HSC

Q_RES_0402LF-6.19K,1%,1/16W,CHA  I61  R1117
   1 MB0_P12V_STBY_PWRGD      A @S9S_MB_2U_LIB.S9S_MB_2U(SCH_1):MB0_P12V_STBY_PWRGD
   2 AGND_HSC      B @S9S_MB_2U_LIB.S9S_MB_2U(SCH_1):AGND_HSC

Q_CAP_0402-0.068UF,16V,10%,X7RA  I69  PC2191
   1 HSC_SS      A @S9S_MB_2U_LIB.S9S_MB_2U(SCH_1):HSC_SS
   2 AGND_HSC      B @S9S_MB_2U_LIB.S9S_MB_2U(SCH_1):AGND_HSC

Q_CAP_C0402-0.001UF,50V,10%,X7A  I77  PC2192
   1 HSC_VTEMP      A @S9S_MB_2U_LIB.S9S_MB_2U(SCH_1):HSC_VTEMP
   2 AGND_HSC      B @S9S_MB_2U_LIB.S9S_MB_2U(SCH_1):AGND_HSC

Q_CAP_0402-0.1UF,25V,10%,X7R,CA  I3  C1797
   1 PDB_PRSNT_N      A @S9S_MB_2U_LIB.S9S_MB_2U(SCH_1):PDB_PRSNT_N
   2    GND      B @S9S_MB_2U_LIB.S9S_MB_2U(SCH_1):GND

CONN3_210HP1030BR1-CONN3_210-HB  I12  JP4003
   3    GND      3 @S9S_MB_2U_LIB.S9S_MB_2U(SCH_1):GND
   2 PDB_PRSNT_N      2 @S9S_MB_2U_LIB.S9S_MB_2U(SCH_1):PDB_PRSNT_N
   1     NC      1     NC

Q_CAP_C0402-1UF,25V,10%,X6S,CHA  I14  PC2186
   1 HSC_VDD_R      A @S9S_MB_2U_LIB.S9S_MB_2U(SCH_1):HSC_VDD_R
   2 AGND_HSC      B @S9S_MB_2U_LIB.S9S_MB_2U(SCH_1):AGND_HSC

Q_CAP_C0402-1UF,25V,10%,X6S,CHA  I23  PC2187
   1 HSC_VDD_R      A @S9S_MB_2U_LIB.S9S_MB_2U(SCH_1):HSC_VDD_R
   2 AGND_HSC      B @S9S_MB_2U_LIB.S9S_MB_2U(SCH_1):AGND_HSC

Q_RES_0402LF-82K,1%,1/16W,CHIPA  I26  R4901
   1 P12V_PSU_FUSE      A @S9S_MB_2U_LIB.S9S_MB_2U(SCH_1):P12V_PSU_FUSE
   2 HSC_EN      B @S9S_MB_2U_LIB.S9S_MB_2U(SCH_1):HSC_EN

Q_CAP_C0402-100NF,50V,10%,X7R,A  I29  C2179
   1 HSC_EN      A @S9S_MB_2U_LIB.S9S_MB_2U(SCH_1):HSC_EN
   2 AGND_HSC      B @S9S_MB_2U_LIB.S9S_MB_2U(SCH_1):AGND_HSC

Q_RES_0402LF-0,5%,1/16W,CHIP,CA  I32  PR3930
   1 AGND_HSC      A @S9S_MB_2U_LIB.S9S_MB_2U(SCH_1):AGND_HSC
   2 HSC_ADDR      B @S9S_MB_2U_LIB.S9S_MB_2U(SCH_1):HSC_ADDR

Q_CAP_C0402-1UF,25V,10%,X6S,CHA  I35  PC2103
   1 HSC_VDD18      A @S9S_MB_2U_LIB.S9S_MB_2U(SCH_1):HSC_VDD18
   2 AGND_HSC      B @S9S_MB_2U_LIB.S9S_MB_2U(SCH_1):AGND_HSC

Q_RES_0402LF-0,5%,1/16W,CHIP,CA  I37  R1714
   1 SMB_SML1_PMBUS_HSC_SDA      A @S9S_MB_2U_LIB.S9S_MB_2U(SCH_1):SMB_SML1_PMBUS_HSC_SDA
   2 SMB_SML1_PMBUS_HSC_R_SDA      B @S9S_MB_2U_LIB.S9S_MB_2U(SCH_1):SMB_SML1_PMBUS_HSC_R_SDA

Q_RES_0402LF-1K,1%,1/16W,EMPTYA  I42  PR3929
   1 HSC_ADDR      A @S9S_MB_2U_LIB.S9S_MB_2U(SCH_1):HSC_ADDR
   2 HSC_VDD18      B @S9S_MB_2U_LIB.S9S_MB_2U(SCH_1):HSC_VDD18

Q_RES_0402LF-0,5%,1/16W,CHIP,CA  I44  R2586
   1 HSC_EN      A @S9S_MB_2U_LIB.S9S_MB_2U(SCH_1):HSC_EN
   2 HSC_EN_R      B @S9S_MB_2U_LIB.S9S_MB_2U(SCH_1):HSC_EN_R

Q_RES_0402LF-0,5%,1/16W,CHIP,CA  I54  PR3002
   1    GND      A @S9S_MB_2U_LIB.S9S_MB_2U(SCH_1):GND
   2 AGND_HSC      B @S9S_MB_2U_LIB.S9S_MB_2U(SCH_1):AGND_HSC

Q_RES_0402LF-2K,0.1%,1/16W,CHIA  I58  PR1131
   1 HSC_CS      A @S9S_MB_2U_LIB.S9S_MB_2U(SCH_1):HSC_CS
   2 AGND_HSC      B @S9S_MB_2U_LIB.S9S_MB_2U(SCH_1):AGND_HSC

Q_RES_0402LF-16.9K,1%,1/16W,CHA  I62  R3933
   1 P12V_AUX      A @S9S_MB_2U_LIB.S9S_MB_2U(SCH_1):P12V_AUX
   2 MB0_P12V_STBY_PWRGD      B @S9S_MB_2U_LIB.S9S_MB_2U(SCH_1):MB0_P12V_STBY_PWRGD

Q_RES_0402LF-10K,1%,1/16W,CHIPA  I79  PR3935
   1 HSC_VTEMP      A @S9S_MB_2U_LIB.S9S_MB_2U(SCH_1):HSC_VTEMP
   2 AGND_HSC      B @S9S_MB_2U_LIB.S9S_MB_2U(SCH_1):AGND_HSC

Q_RES_0402LF-22,1%,1/16W,CHIP,A  I82  R3934
   1 HSC_D_OC_R      A @S9S_MB_2U_LIB.S9S_MB_2U(SCH_1):HSC_D_OC_R
   2 HSC_D_OC      B @S9S_MB_2U_LIB.S9S_MB_2U(SCH_1):HSC_D_OC

Q_RES_0402LF-120K,1%,1/16W,CHIA  I84  PR3937
   1 HSC_MODE      A @S9S_MB_2U_LIB.S9S_MB_2U(SCH_1):HSC_MODE
   2 AGND_HSC      B @S9S_MB_2U_LIB.S9S_MB_2U(SCH_1):AGND_HSC

Q_CAP_C0402-0.047UF,25V,10%,X7A  I89  PC2193
   1 HSC_IMON      A @S9S_MB_2U_LIB.S9S_MB_2U(SCH_1):HSC_IMON
   2 AGND_HSC      B @S9S_MB_2U_LIB.S9S_MB_2U(SCH_1):AGND_HSC

Q_RES_0402LF-2K,0.1%,1/16W,CHIA  I91  PR1133
   1 HSC_IMON      A @S9S_MB_2U_LIB.S9S_MB_2U(SCH_1):HSC_IMON
   2 AGND_HSC      B @S9S_MB_2U_LIB.S9S_MB_2U(SCH_1):AGND_HSC

Q_RES_0402LF-4.7K,1%,1/16W,CHIA  I93  R2587
   1 HSC_VDD      A @S9S_MB_2U_LIB.S9S_MB_2U(SCH_1):HSC_VDD
   2 IRQ_HSC_FAULT_N      B @S9S_MB_2U_LIB.S9S_MB_2U(SCH_1):IRQ_HSC_FAULT_N


DRAWING: @S9S_MB_2U_LIB.S9S_MB_2U(SCH_1):PAGE225 

Q_CAP_0402-0.1UF,25V,10%,X7R,CA  I5  C2337
   1 P3V3_AUX      A @S9S_MB_2U_LIB.S9S_MB_2U(SCH_1):P3V3_AUX
   2    GND      B @S9S_MB_2U_LIB.S9S_MB_2U(SCH_1):GND

Q_CAP_0402-0.1UF,25V,10%,X7R,CA  I8  C2338
   1   P3V3      A @S9S_MB_2U_LIB.S9S_MB_2U(SCH_1):P3V3
   2    GND      B @S9S_MB_2U_LIB.S9S_MB_2U(SCH_1):GND

Q_RES_0402LF-4.7K,5%,1/16W,CHIA  I11  R4498
   1   P3V3      A @S9S_MB_2U_LIB.S9S_MB_2U(SCH_1):P3V3
   2 SMB_HOST_CLK_BUF_ISO_3V3AUX_S_1      B @S9S_MB_2U_LIB.S9S_MB_2U(SCH_1):SMB_HOST_CLK_BUF_ISO_3V3AUX_SCL_R

Q_RES_0402LF-4.7K,5%,1/16W,CHIA  I12  R4499
   1   P3V3      A @S9S_MB_2U_LIB.S9S_MB_2U(SCH_1):P3V3
   2 SMB_HOST_CLK_BUF_ISO_3V3AUX_S_2      B @S9S_MB_2U_LIB.S9S_MB_2U(SCH_1):SMB_HOST_CLK_BUF_ISO_3V3AUX_SDA_R

PCA9617ADP-PCA9617ADP,SMLF,IC,A  I17  U315
   5 PU_CLK_BUF_ISO_EN     EN @S9S_MB_2U_LIB.S9S_MB_2U(SCH_1):PU_CLK_BUF_ISO_EN
   1 P3V3_AUX   VCCA @S9S_MB_2U_LIB.S9S_MB_2U(SCH_1):P3V3_AUX
   8   P3V3   VCCB @S9S_MB_2U_LIB.S9S_MB_2U(SCH_1):P3V3
   2 SMB_HOST_CLK_BUF_3V3AUX_SCL   SCLA @S9S_MB_2U_LIB.S9S_MB_2U(SCH_1):SMB_HOST_CLK_BUF_3V3AUX_SCL
   3 SMB_HOST_CLK_BUF_3V3AUX_SDA   SDAA @S9S_MB_2U_LIB.S9S_MB_2U(SCH_1):SMB_HOST_CLK_BUF_3V3AUX_SDA
   6 SMB_HOST_CLK_BUF_ISO_3V3AUX_S_2   SDAB @S9S_MB_2U_LIB.S9S_MB_2U(SCH_1):SMB_HOST_CLK_BUF_ISO_3V3AUX_SDA_R
   7 SMB_HOST_CLK_BUF_ISO_3V3AUX_S_1   SCLB @S9S_MB_2U_LIB.S9S_MB_2U(SCH_1):SMB_HOST_CLK_BUF_ISO_3V3AUX_SCL_R
   4    GND    GND @S9S_MB_2U_LIB.S9S_MB_2U(SCH_1):GND

Q_RES_0402LF-33.2,1%,1/16W,CHIA  I24  R4480
   1 SMB_HOST_CLK_BUF_ISO_3V3AUX_SCL      A @S9S_MB_2U_LIB.S9S_MB_2U(SCH_1):SMB_HOST_CLK_BUF_ISO_3V3AUX_SCL
   2 SMB_HOST_9ZXL045_3V3AUX_SCL      B @S9S_MB_2U_LIB.S9S_MB_2U(SCH_1):SMB_HOST_9ZXL045_3V3AUX_SCL

Q_RES_0402LF-33.2,1%,1/16W,CHIA  I25  R4481
   1 SMB_HOST_CLK_BUF_ISO_3V3AUX_SDA      A @S9S_MB_2U_LIB.S9S_MB_2U(SCH_1):SMB_HOST_CLK_BUF_ISO_3V3AUX_SDA
   2 SMB_HOST_9ZXL045_3V3AUX_SDA      B @S9S_MB_2U_LIB.S9S_MB_2U(SCH_1):SMB_HOST_9ZXL045_3V3AUX_SDA

Q_RES_0402LF-33.2,1%,1/16W,CHIA  I26  R4497
   1 SMB_HOST_CLK_BUF_ISO_3V3AUX_SDA      A @S9S_MB_2U_LIB.S9S_MB_2U(SCH_1):SMB_HOST_CLK_BUF_ISO_3V3AUX_SDA
   2 SMB_HOST_DB2000_3V3AUX_SDA      B @S9S_MB_2U_LIB.S9S_MB_2U(SCH_1):SMB_HOST_DB2000_3V3AUX_SDA

Q_RES_0402LF-33.2,1%,1/16W,CHIA  I27  R4496
   1 SMB_HOST_CLK_BUF_ISO_3V3AUX_SCL      A @S9S_MB_2U_LIB.S9S_MB_2U(SCH_1):SMB_HOST_CLK_BUF_ISO_3V3AUX_SCL
   2 SMB_HOST_DB2000_3V3AUX_SCL      B @S9S_MB_2U_LIB.S9S_MB_2U(SCH_1):SMB_HOST_DB2000_3V3AUX_SCL

Q_RES_0402LF-10K,1%,1/16W,EMPTA  I32  R4500
   1   P3V3      A @S9S_MB_2U_LIB.S9S_MB_2U(SCH_1):P3V3
   2 PU_CLK_BUF_ISO_EN      B @S9S_MB_2U_LIB.S9S_MB_2U(SCH_1):PU_CLK_BUF_ISO_EN

Q_RES_0402LF-33.2,1%,1/16W,CHIA  I33  R4540
   1 SMB_HOST_CLK_BUF_ISO_3V3AUX_S_1      A @S9S_MB_2U_LIB.S9S_MB_2U(SCH_1):SMB_HOST_CLK_BUF_ISO_3V3AUX_SCL_R
   2 SMB_HOST_CLK_BUF_ISO_3V3AUX_SCL      B @S9S_MB_2U_LIB.S9S_MB_2U(SCH_1):SMB_HOST_CLK_BUF_ISO_3V3AUX_SCL

Q_RES_0402LF-33.2,1%,1/16W,CHIA  I34  R4541
   1 SMB_HOST_CLK_BUF_ISO_3V3AUX_S_2      A @S9S_MB_2U_LIB.S9S_MB_2U(SCH_1):SMB_HOST_CLK_BUF_ISO_3V3AUX_SDA_R
   2 SMB_HOST_CLK_BUF_ISO_3V3AUX_SDA      B @S9S_MB_2U_LIB.S9S_MB_2U(SCH_1):SMB_HOST_CLK_BUF_ISO_3V3AUX_SDA


DRAWING: @S9S_MB_2U_LIB.S9S_MB_2U(SCH_1):PAGE184 

Q_RES_0402LF-1K,1%,1/16W,CHIP,A  I1  R4581
   1 FM_BOARD_BMC_SKU_ID4      A @S9S_MB_2U_LIB.S9S_MB_2U(SCH_1):FM_BOARD_BMC_SKU_ID4
   2    GND      B @S9S_MB_2U_LIB.S9S_MB_2U(SCH_1):GND

Q_RES_0402LF-1K,1%,1/16W,CHIP,A  I18  R4583
   1 FM_BOARD_BMC_SKU_ID1      A @S9S_MB_2U_LIB.S9S_MB_2U(SCH_1):FM_BOARD_BMC_SKU_ID1
   2    GND      B @S9S_MB_2U_LIB.S9S_MB_2U(SCH_1):GND

Q_RES_0402LF-1K,1%,1/16W,CHIP,A  I20  R4585
   1 FM_BOARD_BMC_SKU_ID0      A @S9S_MB_2U_LIB.S9S_MB_2U(SCH_1):FM_BOARD_BMC_SKU_ID0
   2    GND      B @S9S_MB_2U_LIB.S9S_MB_2U(SCH_1):GND

Q_RES_0402LF-10K,1%,1/16W,EMPTA  I22  R4597
   1 P3V3_AUX      A @S9S_MB_2U_LIB.S9S_MB_2U(SCH_1):P3V3_AUX
   2 FM_BOARD_BMC_SKU_ID2      B @S9S_MB_2U_LIB.S9S_MB_2U(SCH_1):FM_BOARD_BMC_SKU_ID2

Q_RES_0402LF-1K,1%,1/16W,CHIP,A  I30  R2243
   1 FM_BOARD_SKU_ID0      A @S9S_MB_2U_LIB.S9S_MB_2U(SCH_1):FM_BOARD_SKU_ID0
   2    GND      B @S9S_MB_2U_LIB.S9S_MB_2U(SCH_1):GND

Q_RES_0402LF-10K,1%,1/16W,EMPTA  I50  R2242
   1 P1V05_PCH_AUX      A @S9S_MB_2U_LIB.S9S_MB_2U(SCH_1):P1V05_PCH_AUX
   2 FM_BOARD_SKU_ID0      B @S9S_MB_2U_LIB.S9S_MB_2U(SCH_1):FM_BOARD_SKU_ID0

Q_RES_0402LF-1K,1%,1/16W,EMPTYA  I58  R4588
   1 FAB_BMC_REV_ID2      A @S9S_MB_2U_LIB.S9S_MB_2U(SCH_1):FAB_BMC_REV_ID2
   2    GND      B @S9S_MB_2U_LIB.S9S_MB_2U(SCH_1):GND

Q_RES_0402LF-1K,1%,1/16W,EMPTYA  I59  R4590
   1 FAB_BMC_REV_ID1      A @S9S_MB_2U_LIB.S9S_MB_2U(SCH_1):FAB_BMC_REV_ID1
   2    GND      B @S9S_MB_2U_LIB.S9S_MB_2U(SCH_1):GND

Q_RES_0402LF-10K,1%,1/16W,CHIPA  I62  R4586
   1 P3V3_AUX      A @S9S_MB_2U_LIB.S9S_MB_2U(SCH_1):P3V3_AUX
   2 FAB_BMC_REV_ID2      B @S9S_MB_2U_LIB.S9S_MB_2U(SCH_1):FAB_BMC_REV_ID2

Q_RES_0402LF-1K,1%,1/16W,CHIP,A  I4  R4592
   1 FM_BOARD_BMC_SKU_ID3      A @S9S_MB_2U_LIB.S9S_MB_2U(SCH_1):FM_BOARD_BMC_SKU_ID3
   2    GND      B @S9S_MB_2U_LIB.S9S_MB_2U(SCH_1):GND

Q_RES_0402LF-10K,1%,1/16W,EMPTA  I5  R4580
   1 P3V3_AUX      A @S9S_MB_2U_LIB.S9S_MB_2U(SCH_1):P3V3_AUX
   2 FM_BOARD_BMC_SKU_ID4      B @S9S_MB_2U_LIB.S9S_MB_2U(SCH_1):FM_BOARD_BMC_SKU_ID4

Q_RES_0402LF-10K,1%,1/16W,EMPTA  I6  R4591
   1 P3V3_AUX      A @S9S_MB_2U_LIB.S9S_MB_2U(SCH_1):P3V3_AUX
   2 FM_BOARD_BMC_SKU_ID3      B @S9S_MB_2U_LIB.S9S_MB_2U(SCH_1):FM_BOARD_BMC_SKU_ID3

Q_RES_0402LF-1K,1%,1/16W,CHIP,A  I9  R2235
   1 FM_BOARD_SKU_ID4      A @S9S_MB_2U_LIB.S9S_MB_2U(SCH_1):FM_BOARD_SKU_ID4
   2    GND      B @S9S_MB_2U_LIB.S9S_MB_2U(SCH_1):GND

Q_RES_0402LF-1K,1%,1/16W,CHIP,A  I11  R2977
   1 FM_BOARD_SKU_ID3      A @S9S_MB_2U_LIB.S9S_MB_2U(SCH_1):FM_BOARD_SKU_ID3
   2    GND      B @S9S_MB_2U_LIB.S9S_MB_2U(SCH_1):GND

Q_RES_0402LF-10K,1%,1/16W,EMPTA  I12  R2234
   1 P1V05_PCH_AUX      A @S9S_MB_2U_LIB.S9S_MB_2U(SCH_1):P1V05_PCH_AUX
   2 FM_BOARD_SKU_ID4      B @S9S_MB_2U_LIB.S9S_MB_2U(SCH_1):FM_BOARD_SKU_ID4

Q_RES_0402LF-10K,1%,1/16W,EMPTA  I13  R2976
   1 P1V05_PCH_AUX      A @S9S_MB_2U_LIB.S9S_MB_2U(SCH_1):P1V05_PCH_AUX
   2 FM_BOARD_SKU_ID3      B @S9S_MB_2U_LIB.S9S_MB_2U(SCH_1):FM_BOARD_SKU_ID3

Q_RES_0402LF-1K,1%,1/16W,CHIP,A  I16  R4598
   1 FM_BOARD_BMC_SKU_ID2      A @S9S_MB_2U_LIB.S9S_MB_2U(SCH_1):FM_BOARD_BMC_SKU_ID2
   2    GND      B @S9S_MB_2U_LIB.S9S_MB_2U(SCH_1):GND

Q_RES_0402LF-10K,1%,1/16W,EMPTA  I23  R4582
   1 P3V3_AUX      A @S9S_MB_2U_LIB.S9S_MB_2U(SCH_1):P3V3_AUX
   2 FM_BOARD_BMC_SKU_ID1      B @S9S_MB_2U_LIB.S9S_MB_2U(SCH_1):FM_BOARD_BMC_SKU_ID1

Q_RES_0402LF-10K,1%,1/16W,EMPTA  I24  R4584
   1 P3V3_AUX      A @S9S_MB_2U_LIB.S9S_MB_2U(SCH_1):P3V3_AUX
   2 FM_BOARD_BMC_SKU_ID0      B @S9S_MB_2U_LIB.S9S_MB_2U(SCH_1):FM_BOARD_BMC_SKU_ID0

Q_RES_0402LF-1K,1%,1/16W,CHIP,A  I26  R2980
   1 FM_BOARD_SKU_ID2      A @S9S_MB_2U_LIB.S9S_MB_2U(SCH_1):FM_BOARD_SKU_ID2
   2    GND      B @S9S_MB_2U_LIB.S9S_MB_2U(SCH_1):GND

Q_RES_0402LF-1K,1%,1/16W,CHIP,A  I28  R2241
   1 FM_BOARD_SKU_ID1      A @S9S_MB_2U_LIB.S9S_MB_2U(SCH_1):FM_BOARD_SKU_ID1
   2    GND      B @S9S_MB_2U_LIB.S9S_MB_2U(SCH_1):GND

Q_RES_0402LF-10K,1%,1/16W,EMPTA  I48  R2979
   1 P1V05_PCH_AUX      A @S9S_MB_2U_LIB.S9S_MB_2U(SCH_1):P1V05_PCH_AUX
   2 FM_BOARD_SKU_ID2      B @S9S_MB_2U_LIB.S9S_MB_2U(SCH_1):FM_BOARD_SKU_ID2

Q_RES_0402LF-10K,1%,1/16W,EMPTA  I49  R2240
   1 P1V05_PCH_AUX      A @S9S_MB_2U_LIB.S9S_MB_2U(SCH_1):P1V05_PCH_AUX
   2 FM_BOARD_SKU_ID1      B @S9S_MB_2U_LIB.S9S_MB_2U(SCH_1):FM_BOARD_SKU_ID1

Q_RES_0402LF-1K,1%,1/16W,EMPTYA  I61  R4596
   1 FAB_BMC_REV_ID0      A @S9S_MB_2U_LIB.S9S_MB_2U(SCH_1):FAB_BMC_REV_ID0
   2    GND      B @S9S_MB_2U_LIB.S9S_MB_2U(SCH_1):GND

Q_RES_0402LF-10K,1%,1/16W,CHIPA  I63  R4589
   1 P3V3_AUX      A @S9S_MB_2U_LIB.S9S_MB_2U(SCH_1):P3V3_AUX
   2 FAB_BMC_REV_ID1      B @S9S_MB_2U_LIB.S9S_MB_2U(SCH_1):FAB_BMC_REV_ID1

Q_RES_0402LF-10K,1%,1/16W,CHIPA  I67  R4579
   1 P3V3_AUX      A @S9S_MB_2U_LIB.S9S_MB_2U(SCH_1):P3V3_AUX
   2 FAB_BMC_REV_ID0      B @S9S_MB_2U_LIB.S9S_MB_2U(SCH_1):FAB_BMC_REV_ID0

Q_RES_0402LF-1K,1%,1/16W,EMPTYA  I69  R2973
   1 FAB_REV_ID2      A @S9S_MB_2U_LIB.S9S_MB_2U(SCH_1):FAB_REV_ID2
   2    GND      B @S9S_MB_2U_LIB.S9S_MB_2U(SCH_1):GND

Q_RES_0402LF-1K,1%,1/16W,EMPTYA  I70  R2975
   1 FAB_REV_ID1      A @S9S_MB_2U_LIB.S9S_MB_2U(SCH_1):FAB_REV_ID1
   2    GND      B @S9S_MB_2U_LIB.S9S_MB_2U(SCH_1):GND

Q_RES_0402LF-10K,1%,1/16W,CHIPA  I71  R2972
   1 P1V05_PCH_AUX      A @S9S_MB_2U_LIB.S9S_MB_2U(SCH_1):P1V05_PCH_AUX
   2 FAB_REV_ID2      B @S9S_MB_2U_LIB.S9S_MB_2U(SCH_1):FAB_REV_ID2

Q_RES_0402LF-10K,1%,1/16W,CHIPA  I72  R2974
   1 P1V05_PCH_AUX      A @S9S_MB_2U_LIB.S9S_MB_2U(SCH_1):P1V05_PCH_AUX
   2 FAB_REV_ID1      B @S9S_MB_2U_LIB.S9S_MB_2U(SCH_1):FAB_REV_ID1

Q_RES_0402LF-1K,1%,1/16W,EMPTYA  I74  R2978
   1 FAB_REV_ID0      A @S9S_MB_2U_LIB.S9S_MB_2U(SCH_1):FAB_REV_ID0
   2    GND      B @S9S_MB_2U_LIB.S9S_MB_2U(SCH_1):GND

Q_RES_0402LF-10K,1%,1/16W,CHIPA  I75  R2232
   1 P1V05_PCH_AUX      A @S9S_MB_2U_LIB.S9S_MB_2U(SCH_1):P1V05_PCH_AUX
   2 FAB_REV_ID0      B @S9S_MB_2U_LIB.S9S_MB_2U(SCH_1):FAB_REV_ID0


DRAWING: @S9S_MB_2U_LIB.S9S_MB_2U(SCH_1):PAGE235 

Q_RES_0402LF-0,5%,1/16W,CHIP,CA  I16  R4628
   1 JTAG_BMC_TMS      A @S9S_MB_2U_LIB.S9S_MB_2U(SCH_1):JTAG_BMC_TMS
   2 JTAG_BMC_TMS_R      B @S9S_MB_2U_LIB.S9S_MB_2U(SCH_1):JTAG_BMC_TMS_R

Q_RES_0402LF-0,5%,1/16W,CHIP,CA  I25  R4631
   1 JTAG_BMC_SW_TDI_R      A @S9S_MB_2U_LIB.S9S_MB_2U(SCH_1):JTAG_BMC_SW_TDI_R
   2 JTAG_BMC_SW_TDI      B @S9S_MB_2U_LIB.S9S_MB_2U(SCH_1):JTAG_BMC_SW_TDI

Q_RES_0402LF-0,5%,1/16W,CHIP,CA  I27  R4630
   1 JTAG_BMC_SW_TDO_R      A @S9S_MB_2U_LIB.S9S_MB_2U(SCH_1):JTAG_BMC_SW_TDO_R
   2 JTAG_BMC_SW_TDO      B @S9S_MB_2U_LIB.S9S_MB_2U(SCH_1):JTAG_BMC_SW_TDO

Q_RES_0402LF-10K,1%,1/16W,CHIPA  I3  R4635
   1 JTAG_BMC_SW_OE      A @S9S_MB_2U_LIB.S9S_MB_2U(SCH_1):JTAG_BMC_SW_OE
   2    GND      B @S9S_MB_2U_LIB.S9S_MB_2U(SCH_1):GND

Q_RES_0402LF-1K,1%,1/16W,EMPTYA  I4  R4634
   1 P3V3_AUX      A @S9S_MB_2U_LIB.S9S_MB_2U(SCH_1):P3V3_AUX
   2 JTAG_BMC_SW_OE      B @S9S_MB_2U_LIB.S9S_MB_2U(SCH_1):JTAG_BMC_SW_OE

Q_RES_0402LF-1K,1%,1/16W,CHIP,A  I11  R4623
   1 P3V3_AUX      A @S9S_MB_2U_LIB.S9S_MB_2U(SCH_1):P3V3_AUX
   2 PU_JTAG_SW_PU      B @S9S_MB_2U_LIB.S9S_MB_2U(SCH_1):PU_JTAG_SW_PU

CONN3_210HP1030BR1-CONN3_210-HB  I13  JP16
   3    GND      3 @S9S_MB_2U_LIB.S9S_MB_2U(SCH_1):GND
   2 JTAG_BMC_SW_OE      2 @S9S_MB_2U_LIB.S9S_MB_2U(SCH_1):JTAG_BMC_SW_OE
   1 PU_JTAG_SW_PU      1 @S9S_MB_2U_LIB.S9S_MB_2U(SCH_1):PU_JTAG_SW_PU

Q_RES_0402LF-0,5%,1/16W,CHIP,CA  I14  R4624
   1 JTAG_BMC_SW_OE      A @S9S_MB_2U_LIB.S9S_MB_2U(SCH_1):JTAG_BMC_SW_OE
   2 JTAG_BMC_SW_R_OE      B @S9S_MB_2U_LIB.S9S_MB_2U(SCH_1):JTAG_BMC_SW_R_OE

Q_RES_0402LF-0,5%,1/16W,CHIP,CA  I15  R4629
   1 JTAG_BMC_TCK      A @S9S_MB_2U_LIB.S9S_MB_2U(SCH_1):JTAG_BMC_TCK
   2 JTAG_BMC_TCK_R      B @S9S_MB_2U_LIB.S9S_MB_2U(SCH_1):JTAG_BMC_TCK_R

Q_RES_0402LF-0,5%,1/16W,CHIP,CA  I17  R4627
   1 JTAG_BMC_TDI      A @S9S_MB_2U_LIB.S9S_MB_2U(SCH_1):JTAG_BMC_TDI
   2 JTAG_BMC_TDI_R      B @S9S_MB_2U_LIB.S9S_MB_2U(SCH_1):JTAG_BMC_TDI_R

Q_RES_0402LF-0,5%,1/16W,CHIP,CA  I18  R4626
   1 JTAG_BMC_TDO      A @S9S_MB_2U_LIB.S9S_MB_2U(SCH_1):JTAG_BMC_TDO
   2 JTAG_BMC_TDO_R      B @S9S_MB_2U_LIB.S9S_MB_2U(SCH_1):JTAG_BMC_TDO_R

74CBTLV3126PW-74CBTLV3126PW,SMA  I19  U327
   5 JTAG_BMC_TMS_R     2A @S9S_MB_2U_LIB.S9S_MB_2U(SCH_1):JTAG_BMC_TMS_R
   8 JTAG_BMC_SW_TDI_R     3B @S9S_MB_2U_LIB.S9S_MB_2U(SCH_1):JTAG_BMC_SW_TDI_R
   1 JTAG_BMC_SW_R_OE    1OE @S9S_MB_2U_LIB.S9S_MB_2U(SCH_1):JTAG_BMC_SW_R_OE
   4 JTAG_BMC_SW_R_OE    2OE @S9S_MB_2U_LIB.S9S_MB_2U(SCH_1):JTAG_BMC_SW_R_OE
   3 JTAG_BMC_SW_TCK_R     1B @S9S_MB_2U_LIB.S9S_MB_2U(SCH_1):JTAG_BMC_SW_TCK_R
   6 JTAG_BMC_SW_TMS_R     2B @S9S_MB_2U_LIB.S9S_MB_2U(SCH_1):JTAG_BMC_SW_TMS_R
   2 JTAG_BMC_TCK_R     1A @S9S_MB_2U_LIB.S9S_MB_2U(SCH_1):JTAG_BMC_TCK_R
   7    GND    GND @S9S_MB_2U_LIB.S9S_MB_2U(SCH_1):GND
   9 JTAG_BMC_TDI_R     3A @S9S_MB_2U_LIB.S9S_MB_2U(SCH_1):JTAG_BMC_TDI_R
  10 JTAG_BMC_SW_R_OE    3OE @S9S_MB_2U_LIB.S9S_MB_2U(SCH_1):JTAG_BMC_SW_R_OE
  11 JTAG_BMC_SW_TDO_R     4B @S9S_MB_2U_LIB.S9S_MB_2U(SCH_1):JTAG_BMC_SW_TDO_R
  12 JTAG_BMC_TDO_R     4A @S9S_MB_2U_LIB.S9S_MB_2U(SCH_1):JTAG_BMC_TDO_R
  13 JTAG_BMC_SW_R_OE    4OE @S9S_MB_2U_LIB.S9S_MB_2U(SCH_1):JTAG_BMC_SW_R_OE
  14 P3V3_AUX    VCC @S9S_MB_2U_LIB.S9S_MB_2U(SCH_1):P3V3_AUX

Q_CAP_0402-0.1UF,25V,10%,X7R,CA  I23  C2348
   1 P3V3_AUX      A @S9S_MB_2U_LIB.S9S_MB_2U(SCH_1):P3V3_AUX
   2    GND      B @S9S_MB_2U_LIB.S9S_MB_2U(SCH_1):GND

Q_RES_0402LF-0,5%,1/16W,CHIP,CA  I24  R4633
   1 JTAG_BMC_SW_TCK_R      A @S9S_MB_2U_LIB.S9S_MB_2U(SCH_1):JTAG_BMC_SW_TCK_R
   2 JTAG_BMC_SW_TCK      B @S9S_MB_2U_LIB.S9S_MB_2U(SCH_1):JTAG_BMC_SW_TCK

Q_RES_0402LF-0,5%,1/16W,CHIP,CA  I26  R4632
   1 JTAG_BMC_SW_TMS_R      A @S9S_MB_2U_LIB.S9S_MB_2U(SCH_1):JTAG_BMC_SW_TMS_R
   2 JTAG_BMC_SW_TMS      B @S9S_MB_2U_LIB.S9S_MB_2U(SCH_1):JTAG_BMC_SW_TMS


DRAWING: @S9S_MB_2U_LIB.S9S_MB_2U(SCH_1):PAGE328 

Q_RES_0402LF-10,1%,1/16W,EMPTYA  I16  PR2528
   1 P12V_HSC_GATE_G1      A @S9S_MB_2U_LIB.S9S_MB_2U(SCH_1):P12V_HSC_GATE_G1
   2 P12V_HSC_GATE2      B @S9S_MB_2U_LIB.S9S_MB_2U(SCH_1):P12V_HSC_GATE2

MOSFET_NCH_1D3S-PSMNR58-30YLH,B  I35  PPQ5
   3 P12V_AUX      3 @S9S_MB_2U_LIB.S9S_MB_2U(SCH_1):P12V_AUX
   5 P12V_MAIN_R      5 @S9S_MB_2U_LIB.S9S_MB_2U(SCH_1):P12V_MAIN_R
   2 P12V_AUX      2 @S9S_MB_2U_LIB.S9S_MB_2U(SCH_1):P12V_AUX
   4 P12V_HSC_GATE_G1      4 @S9S_MB_2U_LIB.S9S_MB_2U(SCH_1):P12V_HSC_GATE_G1
   1 P12V_AUX      1 @S9S_MB_2U_LIB.S9S_MB_2U(SCH_1):P12V_AUX

Q_RES_0402LF-10,1%,1/16W,EMPTYA  I38  PR2529
   1 P12V_HSC_GATE_G2      A @S9S_MB_2U_LIB.S9S_MB_2U(SCH_1):P12V_HSC_GATE_G2
   2 P12V_HSC_GATE2      B @S9S_MB_2U_LIB.S9S_MB_2U(SCH_1):P12V_HSC_GATE2

Q_RES_0402LF-10,1%,1/16W,EMPTYA  I39  PR2530
   1 P12V_HSC_GATE_G3      A @S9S_MB_2U_LIB.S9S_MB_2U(SCH_1):P12V_HSC_GATE_G3
   2 P12V_HSC_GATE2      B @S9S_MB_2U_LIB.S9S_MB_2U(SCH_1):P12V_HSC_GATE2

MOSFET_NCH_1D3S-PSMNR58-30YLH,B  I40  PPQ6
   3 P12V_AUX      3 @S9S_MB_2U_LIB.S9S_MB_2U(SCH_1):P12V_AUX
   5 P12V_MAIN_R      5 @S9S_MB_2U_LIB.S9S_MB_2U(SCH_1):P12V_MAIN_R
   2 P12V_AUX      2 @S9S_MB_2U_LIB.S9S_MB_2U(SCH_1):P12V_AUX
   4 P12V_HSC_GATE_G2      4 @S9S_MB_2U_LIB.S9S_MB_2U(SCH_1):P12V_HSC_GATE_G2
   1 P12V_AUX      1 @S9S_MB_2U_LIB.S9S_MB_2U(SCH_1):P12V_AUX

MOSFET_NCH_1D3S-PSMNR58-30YLH,B  I41  PPQ7
   3 P12V_AUX      3 @S9S_MB_2U_LIB.S9S_MB_2U(SCH_1):P12V_AUX
   5 P12V_MAIN_R      5 @S9S_MB_2U_LIB.S9S_MB_2U(SCH_1):P12V_MAIN_R
   2 P12V_AUX      2 @S9S_MB_2U_LIB.S9S_MB_2U(SCH_1):P12V_AUX
   4 P12V_HSC_GATE_G3      4 @S9S_MB_2U_LIB.S9S_MB_2U(SCH_1):P12V_HSC_GATE_G3
   1 P12V_AUX      1 @S9S_MB_2U_LIB.S9S_MB_2U(SCH_1):P12V_AUX

ZENER_AC-5.0SMDJ14A,SMLF,IC,BCA  I51  PD15
   A    GND      A @S9S_MB_2U_LIB.S9S_MB_2U(SCH_1):GND
   C P12V_PSU_FUSE      C @S9S_MB_2U_LIB.S9S_MB_2U(SCH_1):P12V_PSU_FUSE

ZENER_AC-5.0SMDJ14A,SMLF,IC,BCA  I53  PD16
   A    GND      A @S9S_MB_2U_LIB.S9S_MB_2U(SCH_1):GND
   C P12V_PSU_FUSE      C @S9S_MB_2U_LIB.S9S_MB_2U(SCH_1):P12V_PSU_FUSE

Q_FUSE_SMLF-20A/125V,IC,DKK00XA  I54  FS1
   1 P12V_PSU      1 @S9S_MB_2U_LIB.S9S_MB_2U(SCH_1):P12V_PSU
   2 P12V_PSU_FUSE      2 @S9S_MB_2U_LIB.S9S_MB_2U(SCH_1):P12V_PSU_FUSE

Q_RES_0402LF-10,1%,1/16W,EMPTYA  I59  PR2531
   1 P12V_HSC_GATE_G4      A @S9S_MB_2U_LIB.S9S_MB_2U(SCH_1):P12V_HSC_GATE_G4
   2 P12V_HSC_GATE2      B @S9S_MB_2U_LIB.S9S_MB_2U(SCH_1):P12V_HSC_GATE2

Q_RES_0402LF-10,1%,1/16W,EMPTYA  I60  PR2535
   1 P12V_HSC_GATE_G5      A @S9S_MB_2U_LIB.S9S_MB_2U(SCH_1):P12V_HSC_GATE_G5
   2 P12V_HSC_GATE2      B @S9S_MB_2U_LIB.S9S_MB_2U(SCH_1):P12V_HSC_GATE2

Q_RES_0402LF-10,1%,1/16W,EMPTYA  I61  PR2536
   1 P12V_HSC_GATE_G6      A @S9S_MB_2U_LIB.S9S_MB_2U(SCH_1):P12V_HSC_GATE_G6
   2 P12V_HSC_GATE2      B @S9S_MB_2U_LIB.S9S_MB_2U(SCH_1):P12V_HSC_GATE2

MOSFET_NCH_1D3S-PSMNR58-30YLH,B  I62  PPQ8
   3 P12V_AUX      3 @S9S_MB_2U_LIB.S9S_MB_2U(SCH_1):P12V_AUX
   5 P12V_MAIN_R      5 @S9S_MB_2U_LIB.S9S_MB_2U(SCH_1):P12V_MAIN_R
   2 P12V_AUX      2 @S9S_MB_2U_LIB.S9S_MB_2U(SCH_1):P12V_AUX
   4 P12V_HSC_GATE_G4      4 @S9S_MB_2U_LIB.S9S_MB_2U(SCH_1):P12V_HSC_GATE_G4
   1 P12V_AUX      1 @S9S_MB_2U_LIB.S9S_MB_2U(SCH_1):P12V_AUX

Q_SP_RES4P-0.0003,1%,4W,SMLF,EA  I63  PR2534
  2B P12V_HSC_SENSE2_R4_N     2B @S9S_MB_2U_LIB.S9S_MB_2U(SCH_1):P12V_HSC_SENSE2_R4_N
  1B P12V_HSC_SENSE2_R4_P     1B @S9S_MB_2U_LIB.S9S_MB_2U(SCH_1):P12V_HSC_SENSE2_R4_P
  2A P12V_MAIN_R     2A @S9S_MB_2U_LIB.S9S_MB_2U(SCH_1):P12V_MAIN_R
  1A P12V_PSU     1A @S9S_MB_2U_LIB.S9S_MB_2U(SCH_1):P12V_PSU

Q_SP_RES4P-0.0003,1%,4W,SMLF,EA  I64  PR2533
  2B P12V_HSC_SENSE2_R3_N     2B @S9S_MB_2U_LIB.S9S_MB_2U(SCH_1):P12V_HSC_SENSE2_R3_N
  1B P12V_HSC_SENSE2_R3_P     1B @S9S_MB_2U_LIB.S9S_MB_2U(SCH_1):P12V_HSC_SENSE2_R3_P
  2A P12V_MAIN_R     2A @S9S_MB_2U_LIB.S9S_MB_2U(SCH_1):P12V_MAIN_R
  1A P12V_PSU     1A @S9S_MB_2U_LIB.S9S_MB_2U(SCH_1):P12V_PSU

MOSFET_NCH_1D3S-PSMNR58-30YLH,B  I65  PPQ1
   3 P12V_AUX      3 @S9S_MB_2U_LIB.S9S_MB_2U(SCH_1):P12V_AUX
   5 P12V_MAIN_R      5 @S9S_MB_2U_LIB.S9S_MB_2U(SCH_1):P12V_MAIN_R
   2 P12V_AUX      2 @S9S_MB_2U_LIB.S9S_MB_2U(SCH_1):P12V_AUX
   4 P12V_HSC_GATE_G5      4 @S9S_MB_2U_LIB.S9S_MB_2U(SCH_1):P12V_HSC_GATE_G5
   1 P12V_AUX      1 @S9S_MB_2U_LIB.S9S_MB_2U(SCH_1):P12V_AUX

Q_CAP_C0402-33NF,25V,10%,EMPTYA  I68  PC1750
   1 P12V_AUX      A @S9S_MB_2U_LIB.S9S_MB_2U(SCH_1):P12V_AUX
   2 P12V_HSC_GATE2      B @S9S_MB_2U_LIB.S9S_MB_2U(SCH_1):P12V_HSC_GATE2

Q_CAP_0402-1NF,50V,10%,EMPTY,CA  I69  PC1751
   1 P12V_HSC_GATE_RC      A @S9S_MB_2U_LIB.S9S_MB_2U(SCH_1):P12V_HSC_GATE_RC
   2 P12V_HSC_GATE2      B @S9S_MB_2U_LIB.S9S_MB_2U(SCH_1):P12V_HSC_GATE2

Q_RES_0402LF-10,1%,1/16W,EMPTYA  I70  PR2537
   1 P12V_AUX      A @S9S_MB_2U_LIB.S9S_MB_2U(SCH_1):P12V_AUX
   2 P12V_HSC_GATE_RC      B @S9S_MB_2U_LIB.S9S_MB_2U(SCH_1):P12V_HSC_GATE_RC

SS15P3SM386A-SS15P3S-M3/86A,SMA  I72  PD17
   1    GND ANODE_1 @S9S_MB_2U_LIB.S9S_MB_2U(SCH_1):GND
   K P12V_AUX CATHODE @S9S_MB_2U_LIB.S9S_MB_2U(SCH_1):P12V_AUX
   2    GND ANODE_2 @S9S_MB_2U_LIB.S9S_MB_2U(SCH_1):GND

MOSFET_NCH_1D3S-PSMNR58-30YLH,B  I73  PPQ2
   3 P12V_AUX      3 @S9S_MB_2U_LIB.S9S_MB_2U(SCH_1):P12V_AUX
   5 P12V_MAIN_R      5 @S9S_MB_2U_LIB.S9S_MB_2U(SCH_1):P12V_MAIN_R
   2 P12V_AUX      2 @S9S_MB_2U_LIB.S9S_MB_2U(SCH_1):P12V_AUX
   4 P12V_HSC_GATE_G6      4 @S9S_MB_2U_LIB.S9S_MB_2U(SCH_1):P12V_HSC_GATE_G6
   1 P12V_AUX      1 @S9S_MB_2U_LIB.S9S_MB_2U(SCH_1):P12V_AUX

Q_RES_0402LF-10,1%,1/16W,EMPTYA  I76  PR2538
   1 MB0_CM_GATE_G0      A @S9S_MB_2U_LIB.S9S_MB_2U(SCH_1):MB0_CM_GATE_G0
   2 P12V_HSC_GATE1      B @S9S_MB_2U_LIB.S9S_MB_2U(SCH_1):P12V_HSC_GATE1

MOSFET_NCH_1D3S-PSMNR58-30YLH,B  I77  PPQ9
   3 P12V_AUX      3 @S9S_MB_2U_LIB.S9S_MB_2U(SCH_1):P12V_AUX
   5 P12V_MAIN_R_0      5 @S9S_MB_2U_LIB.S9S_MB_2U(SCH_1):P12V_MAIN_R_0
   2 P12V_AUX      2 @S9S_MB_2U_LIB.S9S_MB_2U(SCH_1):P12V_AUX
   4 MB0_CM_GATE_G0      4 @S9S_MB_2U_LIB.S9S_MB_2U(SCH_1):MB0_CM_GATE_G0
   1 P12V_AUX      1 @S9S_MB_2U_LIB.S9S_MB_2U(SCH_1):P12V_AUX

Q_SP_RES4P-0.0003,1%,4W,SMLF,EA  I78  PR2532
  2B P12V_HSC_SENSE2_R2_N     2B @S9S_MB_2U_LIB.S9S_MB_2U(SCH_1):P12V_HSC_SENSE2_R2_N
  1B P12V_HSC_SENSE2_R2_P     1B @S9S_MB_2U_LIB.S9S_MB_2U(SCH_1):P12V_HSC_SENSE2_R2_P
  2A P12V_MAIN_R     2A @S9S_MB_2U_LIB.S9S_MB_2U(SCH_1):P12V_MAIN_R
  1A P12V_PSU     1A @S9S_MB_2U_LIB.S9S_MB_2U(SCH_1):P12V_PSU

Q_SP_RES4P-0.0003,1%,4W,SMLF,EA  I79  PR4
  2B P12V_HSC_SENSE2_R1_N     2B @S9S_MB_2U_LIB.S9S_MB_2U(SCH_1):P12V_HSC_SENSE2_R1_N
  1B P12V_HSC_SENSE2_R1_P     1B @S9S_MB_2U_LIB.S9S_MB_2U(SCH_1):P12V_HSC_SENSE2_R1_P
  2A P12V_MAIN_R     2A @S9S_MB_2U_LIB.S9S_MB_2U(SCH_1):P12V_MAIN_R
  1A P12V_PSU     1A @S9S_MB_2U_LIB.S9S_MB_2U(SCH_1):P12V_PSU

Q_RES_0402LF-1,1%,1/16W,EMPTY,A  I86  PR2522
   1 P12V_HSC_SENSE2_P      A @S9S_MB_2U_LIB.S9S_MB_2U(SCH_1):P12V_HSC_SENSE2_P
   2 P12V_HSC_SENSE2_R3_P      B @S9S_MB_2U_LIB.S9S_MB_2U(SCH_1):P12V_HSC_SENSE2_R3_P

Q_RES_0402LF-1,1%,1/16W,EMPTY,A  I87  PR2523
   1 P12V_HSC_SENSE2_P      A @S9S_MB_2U_LIB.S9S_MB_2U(SCH_1):P12V_HSC_SENSE2_P
   2 P12V_HSC_SENSE2_R4_P      B @S9S_MB_2U_LIB.S9S_MB_2U(SCH_1):P12V_HSC_SENSE2_R4_P

Q_RES_0402LF-1,1%,1/16W,EMPTY,A  I88  PR2521
   1 P12V_HSC_SENSE2_P      A @S9S_MB_2U_LIB.S9S_MB_2U(SCH_1):P12V_HSC_SENSE2_P
   2 P12V_HSC_SENSE2_R2_P      B @S9S_MB_2U_LIB.S9S_MB_2U(SCH_1):P12V_HSC_SENSE2_R2_P

Q_RES_0402LF-1,1%,1/16W,EMPTY,A  I89  PR2520
   1 P12V_HSC_SENSE2_P      A @S9S_MB_2U_LIB.S9S_MB_2U(SCH_1):P12V_HSC_SENSE2_P
   2 P12V_HSC_SENSE2_R1_P      B @S9S_MB_2U_LIB.S9S_MB_2U(SCH_1):P12V_HSC_SENSE2_R1_P

Q_RES_0402LF-10,1%,1/16W,EMPTYA  I90  PR2517
   1 P12V_HSC_ADC_N      A @S9S_MB_2U_LIB.S9S_MB_2U(SCH_1):P12V_HSC_ADC_N
   2 P12V_HSC_SENSE2_R3_N      B @S9S_MB_2U_LIB.S9S_MB_2U(SCH_1):P12V_HSC_SENSE2_R3_N

Q_RES_0402LF-10,1%,1/16W,EMPTYA  I91  PR2518
   1 P12V_HSC_ADC_N      A @S9S_MB_2U_LIB.S9S_MB_2U(SCH_1):P12V_HSC_ADC_N
   2 P12V_HSC_SENSE2_R4_N      B @S9S_MB_2U_LIB.S9S_MB_2U(SCH_1):P12V_HSC_SENSE2_R4_N

Q_RES_0402LF-100,1%,1/16W,EMPTA  I92  PR2519
   1 P12V_HSC_ADC_N      A @S9S_MB_2U_LIB.S9S_MB_2U(SCH_1):P12V_HSC_ADC_N
   2 P12V_HSC_SENSE1_N      B @S9S_MB_2U_LIB.S9S_MB_2U(SCH_1):P12V_HSC_SENSE1_N

Q_RES_0402LF-10,1%,1/16W,EMPTYA  I93  PR2515
   1 P12V_HSC_ADC_N      A @S9S_MB_2U_LIB.S9S_MB_2U(SCH_1):P12V_HSC_ADC_N
   2 P12V_HSC_SENSE2_R1_N      B @S9S_MB_2U_LIB.S9S_MB_2U(SCH_1):P12V_HSC_SENSE2_R1_N

Q_RES_0402LF-10,1%,1/16W,EMPTYA  I94  PR2516
   1 P12V_HSC_ADC_N      A @S9S_MB_2U_LIB.S9S_MB_2U(SCH_1):P12V_HSC_ADC_N
   2 P12V_HSC_SENSE2_R2_N      B @S9S_MB_2U_LIB.S9S_MB_2U(SCH_1):P12V_HSC_SENSE2_R2_N

Q_RES_0402LF-1,1%,1/16W,EMPTY,A  I95  PR2513
   1 P12V_HSC_ADC_P      A @S9S_MB_2U_LIB.S9S_MB_2U(SCH_1):P12V_HSC_ADC_P
   2 P12V_HSC_SENSE2_R4_P      B @S9S_MB_2U_LIB.S9S_MB_2U(SCH_1):P12V_HSC_SENSE2_R4_P

Q_RES_0402LF-1,1%,1/16W,EMPTY,A  I96  PR2512
   1 P12V_HSC_ADC_P      A @S9S_MB_2U_LIB.S9S_MB_2U(SCH_1):P12V_HSC_ADC_P
   2 P12V_HSC_SENSE2_R3_P      B @S9S_MB_2U_LIB.S9S_MB_2U(SCH_1):P12V_HSC_SENSE2_R3_P

Q_RES_0402LF-10,1%,1/16W,EMPTYA  I97  PR2514
   1 P12V_HSC_ADC_P      A @S9S_MB_2U_LIB.S9S_MB_2U(SCH_1):P12V_HSC_ADC_P
   2 P12V_HSC_SENSE1_P      B @S9S_MB_2U_LIB.S9S_MB_2U(SCH_1):P12V_HSC_SENSE1_P

Q_RES_0402LF-1,1%,1/16W,EMPTY,A  I98  PR2510
   1 P12V_HSC_ADC_P      A @S9S_MB_2U_LIB.S9S_MB_2U(SCH_1):P12V_HSC_ADC_P
   2 P12V_HSC_SENSE2_R1_P      B @S9S_MB_2U_LIB.S9S_MB_2U(SCH_1):P12V_HSC_SENSE2_R1_P

Q_RES_0402LF-1,1%,1/16W,EMPTY,A  I99  PR2511
   1 P12V_HSC_ADC_P      A @S9S_MB_2U_LIB.S9S_MB_2U(SCH_1):P12V_HSC_ADC_P
   2 P12V_HSC_SENSE2_R2_P      B @S9S_MB_2U_LIB.S9S_MB_2U(SCH_1):P12V_HSC_SENSE2_R2_P

Q_RES_0402LF-10,1%,1/16W,EMPTYA  I117  PR2527
   1 P12V_HSC_SENSE2_N      A @S9S_MB_2U_LIB.S9S_MB_2U(SCH_1):P12V_HSC_SENSE2_N
   2 P12V_HSC_SENSE2_R4_N      B @S9S_MB_2U_LIB.S9S_MB_2U(SCH_1):P12V_HSC_SENSE2_R4_N

Q_RES_0402LF-10,1%,1/16W,EMPTYA  I118  PR2526
   1 P12V_HSC_SENSE2_N      A @S9S_MB_2U_LIB.S9S_MB_2U(SCH_1):P12V_HSC_SENSE2_N
   2 P12V_HSC_SENSE2_R3_N      B @S9S_MB_2U_LIB.S9S_MB_2U(SCH_1):P12V_HSC_SENSE2_R3_N

Q_RES_0402LF-10,1%,1/16W,EMPTYA  I119  PR2524
   1 P12V_HSC_SENSE2_N      A @S9S_MB_2U_LIB.S9S_MB_2U(SCH_1):P12V_HSC_SENSE2_N
   2 P12V_HSC_SENSE2_R1_N      B @S9S_MB_2U_LIB.S9S_MB_2U(SCH_1):P12V_HSC_SENSE2_R1_N

Q_RES_0402LF-10,1%,1/16W,EMPTYA  I120  PR2525
   1 P12V_HSC_SENSE2_N      A @S9S_MB_2U_LIB.S9S_MB_2U(SCH_1):P12V_HSC_SENSE2_N
   2 P12V_HSC_SENSE2_R2_N      B @S9S_MB_2U_LIB.S9S_MB_2U(SCH_1):P12V_HSC_SENSE2_R2_N

Q_RES_4P_12-0.003,1%,3W,SMLF,EA  I126  PR3
   1 P12V_PSU      1 @S9S_MB_2U_LIB.S9S_MB_2U(SCH_1):P12V_PSU
   2 P12V_MAIN_R_0      2 @S9S_MB_2U_LIB.S9S_MB_2U(SCH_1):P12V_MAIN_R_0
   3 P12V_HSC_SENSE1_P      3 @S9S_MB_2U_LIB.S9S_MB_2U(SCH_1):P12V_HSC_SENSE1_P
   4 P12V_HSC_SENSE1_N      4 @S9S_MB_2U_LIB.S9S_MB_2U(SCH_1):P12V_HSC_SENSE1_N


DRAWING: @S9S_MB_2U_LIB.S9S_MB_2U(SCH_1):PAGE327 

Q_RES_0402LF-49.9,1%,1/16W,EMPA  I4  R4893
   1 P12V_HSC_TEMP_E      A @S9S_MB_2U_LIB.S9S_MB_2U(SCH_1):P12V_HSC_TEMP_E
   2 P12V_HSC_TEMP_D-      B @S9S_MB_2U_LIB.S9S_MB_2U(SCH_1):P12V_HSC_TEMP_D-

Q_RES_0402LF-49.9,1%,1/16W,EMPA  I5  R4892
   1 P12V_HSC_TEMP_R      A @S9S_MB_2U_LIB.S9S_MB_2U(SCH_1):P12V_HSC_TEMP_R
   2 P12V_HSC_TEMP_D+      B @S9S_MB_2U_LIB.S9S_MB_2U(SCH_1):P12V_HSC_TEMP_D+

Q_CAP_0603-1000PF,50V,10%,EMPTA  I6  C2459
   1 P12V_HSC_TEMP_D+      A @S9S_MB_2U_LIB.S9S_MB_2U(SCH_1):P12V_HSC_TEMP_D+
   2 P12V_HSC_TEMP_D-      B @S9S_MB_2U_LIB.S9S_MB_2U(SCH_1):P12V_HSC_TEMP_D-

Q_CAP_0402-0.1UF,25V,10%,EMPTYA  I8  C2458
   1 P3V3_AUX      A @S9S_MB_2U_LIB.S9S_MB_2U(SCH_1):P3V3_AUX
   2    GND      B @S9S_MB_2U_LIB.S9S_MB_2U(SCH_1):GND

NCT7718W-NCT7718W,SMLF,EMPTY,AA  I10  U345
   1 P3V3_AUX    VDD @S9S_MB_2U_LIB.S9S_MB_2U(SCH_1):P3V3_AUX
   2 P12V_HSC_TEMP_D+     D+ @S9S_MB_2U_LIB.S9S_MB_2U(SCH_1):P12V_HSC_TEMP_D+
   3 P12V_HSC_TEMP_D-     D- @S9S_MB_2U_LIB.S9S_MB_2U(SCH_1):P12V_HSC_TEMP_D-
   4 P12V_HSC_T_CRIT_N T_CRIT# @S9S_MB_2U_LIB.S9S_MB_2U(SCH_1):P12V_HSC_T_CRIT_N
   5    GND    GND @S9S_MB_2U_LIB.S9S_MB_2U(SCH_1):GND
   6 P12V_HSC_TEMP_ALERT_N ALERT# @S9S_MB_2U_LIB.S9S_MB_2U(SCH_1):P12V_HSC_TEMP_ALERT_N
   7 P12V_HSC_TEMP_SDA    SDA @S9S_MB_2U_LIB.S9S_MB_2U(SCH_1):P12V_HSC_TEMP_SDA
   8 P12V_HSC_TEMP_SCL    SCL @S9S_MB_2U_LIB.S9S_MB_2U(SCH_1):P12V_HSC_TEMP_SCL

Q_RES_0402LF-0,5%,1/16W,EMPTY,A  I11  R4896
   1 P12V_HSC_T_CRIT_N      A @S9S_MB_2U_LIB.S9S_MB_2U(SCH_1):P12V_HSC_T_CRIT_N
   2 P12V_HSC_T_CRIT_R_N      B @S9S_MB_2U_LIB.S9S_MB_2U(SCH_1):P12V_HSC_T_CRIT_R_N

Q_RES_0402LF-0,5%,1/16W,EMPTY,A  I14  R4684
   1 P12V_HSC_TEMP_ALERT_N      A @S9S_MB_2U_LIB.S9S_MB_2U(SCH_1):P12V_HSC_TEMP_ALERT_N
   2 P12V_HSC_TEMP_ALERT_R_N      B @S9S_MB_2U_LIB.S9S_MB_2U(SCH_1):P12V_HSC_TEMP_ALERT_R_N

Q_RES_0402LF-0,5%,1/16W,EMPTY,A  I15  R4894
   1 P12V_HSC_TEMP_SCL      A @S9S_MB_2U_LIB.S9S_MB_2U(SCH_1):P12V_HSC_TEMP_SCL
   2 SMB_LM75_0_3V3AUX_SCL      B @S9S_MB_2U_LIB.S9S_MB_2U(SCH_1):SMB_LM75_0_3V3AUX_SCL

Q_RES_0402LF-0,5%,1/16W,EMPTY,A  I16  R4895
   1 P12V_HSC_TEMP_SDA      A @S9S_MB_2U_LIB.S9S_MB_2U(SCH_1):P12V_HSC_TEMP_SDA
   2 SMB_LM75_0_3V3AUX_SDA      B @S9S_MB_2U_LIB.S9S_MB_2U(SCH_1):SMB_LM75_0_3V3AUX_SDA

Q_RES_0402LF-10.5K,1%,1/16W,EMA  I17  R4686
   1 P3V3_AUX      A @S9S_MB_2U_LIB.S9S_MB_2U(SCH_1):P3V3_AUX
   2 P12V_HSC_T_CRIT_R_N      B @S9S_MB_2U_LIB.S9S_MB_2U(SCH_1):P12V_HSC_T_CRIT_R_N

Q_RES_0402LF-10.5K,1%,1/16W,EMA  I23  R4685
   1 P3V3_AUX      A @S9S_MB_2U_LIB.S9S_MB_2U(SCH_1):P3V3_AUX
   2 P12V_HSC_TEMP_ALERT_R_N      B @S9S_MB_2U_LIB.S9S_MB_2U(SCH_1):P12V_HSC_TEMP_ALERT_R_N

Q_RES_0402LF-0,5%,1/16W,CHIP,CA  I25  R4696
   1 SMB_SML1_PMBUS_HSC_SDA      A @S9S_MB_2U_LIB.S9S_MB_2U(SCH_1):SMB_SML1_PMBUS_HSC_SDA
   2 SMB_SML1_PMBUS_HSC_MODULE_SDA      B @S9S_MB_2U_LIB.S9S_MB_2U(SCH_1):SMB_SML1_PMBUS_HSC_MODULE_SDA

Q_RES_0402LF-0,5%,1/16W,CHIP,CA  I26  R4695
   1 SMB_SML1_PMBUS_HSC_SCL      A @S9S_MB_2U_LIB.S9S_MB_2U(SCH_1):SMB_SML1_PMBUS_HSC_SCL
   2 SMB_SML1_PMBUS_HSC_MODULE_SCL      B @S9S_MB_2U_LIB.S9S_MB_2U(SCH_1):SMB_SML1_PMBUS_HSC_MODULE_SCL

SCONN21_9193031121LF-SCONN21_9A  I34  PJ42
   1 P12V_PSU      1 @S9S_MB_2U_LIB.S9S_MB_2U(SCH_1):P12V_PSU
   3 P12V_HSC_SENSE1_N      3 @S9S_MB_2U_LIB.S9S_MB_2U(SCH_1):P12V_HSC_SENSE1_N
   4 P12V_HSC_SENSE2_P      4 @S9S_MB_2U_LIB.S9S_MB_2U(SCH_1):P12V_HSC_SENSE2_P
   5 P12V_HSC_SENSE2_N      5 @S9S_MB_2U_LIB.S9S_MB_2U(SCH_1):P12V_HSC_SENSE2_N
   2 P12V_HSC_SENSE1_P      2 @S9S_MB_2U_LIB.S9S_MB_2U(SCH_1):P12V_HSC_SENSE1_P
  G1    GND     G1 @S9S_MB_2U_LIB.S9S_MB_2U(SCH_1):GND
  G2    GND     G2 @S9S_MB_2U_LIB.S9S_MB_2U(SCH_1):GND
   6 P12V_HSC_ADC_N      6 @S9S_MB_2U_LIB.S9S_MB_2U(SCH_1):P12V_HSC_ADC_N
   7 P12V_HSC_ADC_P      7 @S9S_MB_2U_LIB.S9S_MB_2U(SCH_1):P12V_HSC_ADC_P
   8 P12V_HSC_GATE1      8 @S9S_MB_2U_LIB.S9S_MB_2U(SCH_1):P12V_HSC_GATE1
   9 P12V_HSC_GATE2      9 @S9S_MB_2U_LIB.S9S_MB_2U(SCH_1):P12V_HSC_GATE2
  10 P12V_AUX     10 @S9S_MB_2U_LIB.S9S_MB_2U(SCH_1):P12V_AUX
  11    GND     11 @S9S_MB_2U_LIB.S9S_MB_2U(SCH_1):GND
  12 P3V3_AUX     12 @S9S_MB_2U_LIB.S9S_MB_2U(SCH_1):P3V3_AUX
  13 IRQ_HSC_FAULT_N     13 @S9S_MB_2U_LIB.S9S_MB_2U(SCH_1):IRQ_HSC_FAULT_N
  14 HSC_EN     14 @S9S_MB_2U_LIB.S9S_MB_2U(SCH_1):HSC_EN
  15 MB0_P12V_STBY_PWRGD     15 @S9S_MB_2U_LIB.S9S_MB_2U(SCH_1):MB0_P12V_STBY_PWRGD
  16 HSC_CSOUT     16 @S9S_MB_2U_LIB.S9S_MB_2U(SCH_1):HSC_CSOUT
  17 HSC_TYPE_ADC     17 @S9S_MB_2U_LIB.S9S_MB_2U(SCH_1):HSC_TYPE_ADC
  18 SMB_SML1_PMBUS_HSC_MODULE_SCL     18 @S9S_MB_2U_LIB.S9S_MB_2U(SCH_1):SMB_SML1_PMBUS_HSC_MODULE_SCL
  19 SMB_SML1_PMBUS_HSC_MODULE_SDA     19 @S9S_MB_2U_LIB.S9S_MB_2U(SCH_1):SMB_SML1_PMBUS_HSC_MODULE_SDA
  20 IRQ_SML1_PMBUS_ALERT_N     20 @S9S_MB_2U_LIB.S9S_MB_2U(SCH_1):IRQ_SML1_PMBUS_ALERT_N
  21    GND     21 @S9S_MB_2U_LIB.S9S_MB_2U(SCH_1):GND

Q_CAP_0402-0.1UF,25V,10%,EMPTYA  I38  PC1789
   1 P12V_AUX      A @S9S_MB_2U_LIB.S9S_MB_2U(SCH_1):P12V_AUX
   2    GND      B @S9S_MB_2U_LIB.S9S_MB_2U(SCH_1):GND

MMBT3904_SMLF-MMBT3904    ,EMPA  I49  U365
   B P12V_HSC_TEMP_R      1 @S9S_MB_2U_LIB.S9S_MB_2U(SCH_1):P12V_HSC_TEMP_R
   E P12V_HSC_TEMP_E      2 @S9S_MB_2U_LIB.S9S_MB_2U(SCH_1):P12V_HSC_TEMP_E
   C P12V_HSC_TEMP_R      3 @S9S_MB_2U_LIB.S9S_MB_2U(SCH_1):P12V_HSC_TEMP_R

CONN3_210HP1030BR1-CONN3_210-HB  I51  JP10
   3    GND      3 @S9S_MB_2U_LIB.S9S_MB_2U(SCH_1):GND
   2 SMB_SML1_PMBUS_HSC_MODULE_SDA      2 @S9S_MB_2U_LIB.S9S_MB_2U(SCH_1):SMB_SML1_PMBUS_HSC_MODULE_SDA
   1 SMB_SML1_PMBUS_HSC_MODULE_SCL      1 @S9S_MB_2U_LIB.S9S_MB_2U(SCH_1):SMB_SML1_PMBUS_HSC_MODULE_SCL


DRAWING: @S9S_MB_2U_LIB.S9S_MB_2U(SCH_1):PAGE326 

Q_RES_0402LF-4.99K,1%,1/16W,EMA  I2  R2238
   1 A_HSC_INAP      A @S9S_MB_2U_LIB.S9S_MB_2U(SCH_1):A_HSC_INAP
   2    GND      B @S9S_MB_2U_LIB.S9S_MB_2U(SCH_1):GND

TPS3700DDCR-TPS3700DDCR,SMLF,EA  I5  U205
   5 U205_VDD    VDD @S9S_MB_2U_LIB.S9S_MB_2U(SCH_1):U205_VDD
   4 NC_U205_INB-   INB- @S9S_MB_2U_LIB.S9S_MB_2U(SCH_1):NC_U205_INB-
   2    GND    GND @S9S_MB_2U_LIB.S9S_MB_2U(SCH_1):GND
   1 PWRGD_DSW_PWROK_R4   OUTA @S9S_MB_2U_LIB.S9S_MB_2U(SCH_1):PWRGD_DSW_PWROK_R4
   3 A_HSC_INAP   INA+ @S9S_MB_2U_LIB.S9S_MB_2U(SCH_1):A_HSC_INAP
   6 NC_U205_OUTB   OUTB @S9S_MB_2U_LIB.S9S_MB_2U(SCH_1):NC_U205_OUTB

Q_RES_0402LF-100K,1%,1/16W,EMPA  I7  R2236
   1 P12V_AUX      A @S9S_MB_2U_LIB.S9S_MB_2U(SCH_1):P12V_AUX
   2 A_HSC_INAP      B @S9S_MB_2U_LIB.S9S_MB_2U(SCH_1):A_HSC_INAP

Q_RES_0402LF-10K,1%,1/16W,EMPTA  I13  R4668
   1 A_HSC_LOW      A @S9S_MB_2U_LIB.S9S_MB_2U(SCH_1):A_HSC_LOW
   2    GND      B @S9S_MB_2U_LIB.S9S_MB_2U(SCH_1):GND

Q_RES_0402LF-160K,1%,1/16W,EMPA  I14  R4667
   1 HSC_CSOUT      A @S9S_MB_2U_LIB.S9S_MB_2U(SCH_1):HSC_CSOUT
   2 A_HSC_LOW      B @S9S_MB_2U_LIB.S9S_MB_2U(SCH_1):A_HSC_LOW

Q_RES_0402LF-1K,1%,1/16W,CHIP,A  I17  R2222
   1 A_P12V_STBY_FP_TRIGGER      A @S9S_MB_2U_LIB.S9S_MB_2U(SCH_1):A_P12V_STBY_FP_TRIGGER
   2    GND      B @S9S_MB_2U_LIB.S9S_MB_2U(SCH_1):GND

Q_RES_0402LF-26.7K,1%,1/16W,CHA  I20  R2221
   1 P12V_AUX      A @S9S_MB_2U_LIB.S9S_MB_2U(SCH_1):P12V_AUX
   2 A_P12V_STBY_FP_TRIGGER      B @S9S_MB_2U_LIB.S9S_MB_2U(SCH_1):A_P12V_STBY_FP_TRIGGER

Q_RES_0402LF-10K,1%,1/16W,EMPTA  I24  R4670
   1 A_HSC_HIGH      A @S9S_MB_2U_LIB.S9S_MB_2U(SCH_1):A_HSC_HIGH
   2    GND      B @S9S_MB_2U_LIB.S9S_MB_2U(SCH_1):GND

Q_RES_0402LF-160K,1%,1/16W,EMPA  I25  R4669
   1 HSC_CSOUT      A @S9S_MB_2U_LIB.S9S_MB_2U(SCH_1):HSC_CSOUT
   2 A_HSC_HIGH      B @S9S_MB_2U_LIB.S9S_MB_2U(SCH_1):A_HSC_HIGH

Q_RES_0402LF-0,5%,1/16W,EMPTY,A  I29  R4693
   1 HSC_CSOUT      A @S9S_MB_2U_LIB.S9S_MB_2U(SCH_1):HSC_CSOUT
   2 HSC_D_OC      B @S9S_MB_2U_LIB.S9S_MB_2U(SCH_1):HSC_D_OC

TPS3700DDCR-TPS3700DDCR,SMLF,EA  I30  U369
   5 U369_VDD    VDD @S9S_MB_2U_LIB.S9S_MB_2U(SCH_1):U369_VDD
   4 A_HSC_HIGH   INB- @S9S_MB_2U_LIB.S9S_MB_2U(SCH_1):A_HSC_HIGH
   2    GND    GND @S9S_MB_2U_LIB.S9S_MB_2U(SCH_1):GND
   1 A_HSC_LOW_GATE   OUTA @S9S_MB_2U_LIB.S9S_MB_2U(SCH_1):A_HSC_LOW_GATE
   3 A_HSC_LOW   INA+ @S9S_MB_2U_LIB.S9S_MB_2U(SCH_1):A_HSC_LOW
   6 HSC_D_OC   OUTB @S9S_MB_2U_LIB.S9S_MB_2U(SCH_1):HSC_D_OC

Q_RES_0402LF-0,5%,1/16W,EMPTY,A  I33  R2330
   1 PWRGD_DSW_PWROK_R4      A @S9S_MB_2U_LIB.S9S_MB_2U(SCH_1):PWRGD_DSW_PWROK_R4
   2 PWRGD_DSW_PWROK      B @S9S_MB_2U_LIB.S9S_MB_2U(SCH_1):PWRGD_DSW_PWROK

MOSFET_N_SMLF-BSS138K,BSS138K,A  I38  U325
   G A_P12V_STBY_FPH_GATE   GATE @S9S_MB_2U_LIB.S9S_MB_2U(SCH_1):A_P12V_STBY_FPH_GATE
   D IRQ_UV_DETECT_N  DRAIN @S9S_MB_2U_LIB.S9S_MB_2U(SCH_1):IRQ_UV_DETECT_N
   S    GND SOURCE @S9S_MB_2U_LIB.S9S_MB_2U(SCH_1):GND

Q_RES_0402LF-10K,1%,1/16W,CHIPA  I39  R2230
   1 P3V3_AUX      A @S9S_MB_2U_LIB.S9S_MB_2U(SCH_1):P3V3_AUX
   2 A_P12V_STBY_FPH_GATE      B @S9S_MB_2U_LIB.S9S_MB_2U(SCH_1):A_P12V_STBY_FPH_GATE

Q_RES_0402LF-10K,1%,1/16W,CHIPA  I41  R2233
   1 P3V3_AUX      A @S9S_MB_2U_LIB.S9S_MB_2U(SCH_1):P3V3_AUX
   2 FM_UV_ADR_TRIGGER_N      B @S9S_MB_2U_LIB.S9S_MB_2U(SCH_1):FM_UV_ADR_TRIGGER_N

Q_RES_0402LF-0,5%,1/16W,EMPTY,A  I44  R4673
   1 A_HSC_LOW_GATE      A @S9S_MB_2U_LIB.S9S_MB_2U(SCH_1):A_HSC_LOW_GATE
   2    GND      B @S9S_MB_2U_LIB.S9S_MB_2U(SCH_1):GND

Q_RES_0402LF-4.7K,5%,1/16W,CHIA  I45  R4620
   1 P3V3_AUX      A @S9S_MB_2U_LIB.S9S_MB_2U(SCH_1):P3V3_AUX
   2 IRQ_UV_DETECT_N      B @S9S_MB_2U_LIB.S9S_MB_2U(SCH_1):IRQ_UV_DETECT_N

MOSFET_NCH_GDS_ESD_PROTECTED-2B  I46  U329
   D A_HSC_LOW_DRAIN      D @S9S_MB_2U_LIB.S9S_MB_2U(SCH_1):A_HSC_LOW_DRAIN
   G A_HSC_LOW_GATE      G @S9S_MB_2U_LIB.S9S_MB_2U(SCH_1):A_HSC_LOW_GATE
   S    GND      S @S9S_MB_2U_LIB.S9S_MB_2U(SCH_1):GND

Q_RES_0402LF-0,5%,1/16W,EMPTY,A  I48  R4652
   1 A_HSC_LOW_DRAIN      A @S9S_MB_2U_LIB.S9S_MB_2U(SCH_1):A_HSC_LOW_DRAIN
   2 HSC_D_OC      B @S9S_MB_2U_LIB.S9S_MB_2U(SCH_1):HSC_D_OC

Q_RES_0402LF-10K,1%,1/16W,EMPTA  I51  R4671
   1 P3V3_AUX      A @S9S_MB_2U_LIB.S9S_MB_2U(SCH_1):P3V3_AUX
   2 HSC_D_OC      B @S9S_MB_2U_LIB.S9S_MB_2U(SCH_1):HSC_D_OC

Q_RES_0402LF-10K,1%,1/16W,EMPTA  I53  R4672
   1 P3V3_AUX      A @S9S_MB_2U_LIB.S9S_MB_2U(SCH_1):P3V3_AUX
   2 A_HSC_LOW_GATE      B @S9S_MB_2U_LIB.S9S_MB_2U(SCH_1):A_HSC_LOW_GATE

LM4040AIM3X25NOPB-LM4040AIM3X-A  I56  U343
   1 OC_P2V5_COMP     1+ @S9S_MB_2U_LIB.S9S_MB_2U(SCH_1):OC_P2V5_COMP
   2    GND     2- @S9S_MB_2U_LIB.S9S_MB_2U(SCH_1):GND
   3     NC      3     NC

Q_RES_0402LF-10K,1%,1/16W,EMPTA  I57  R4792
   1 P3V3_AUX      A @S9S_MB_2U_LIB.S9S_MB_2U(SCH_1):P3V3_AUX
   2 OC_P2V5_COMP      B @S9S_MB_2U_LIB.S9S_MB_2U(SCH_1):OC_P2V5_COMP

Q_CAP_C0402-100NF,50V,10%,EMPTA  I64  C2388
   1 OC_P2V5_COMP      A @S9S_MB_2U_LIB.S9S_MB_2U(SCH_1):OC_P2V5_COMP
   2    GND      B @S9S_MB_2U_LIB.S9S_MB_2U(SCH_1):GND

AP331AWG7-AP331AWG-7,SMLF,EMPTA  I66  U344
   3 HSC_OC_VOL    IN+ @S9S_MB_2U_LIB.S9S_MB_2U(SCH_1):HSC_OC_VOL
   1 OC_P2V5_COMP    IN- @S9S_MB_2U_LIB.S9S_MB_2U(SCH_1):OC_P2V5_COMP
   4 HSC_D_OC_R2 OUTPUT @S9S_MB_2U_LIB.S9S_MB_2U(SCH_1):HSC_D_OC_R2
   5 P12V_AUX    VCC @S9S_MB_2U_LIB.S9S_MB_2U(SCH_1):P12V_AUX
   2    GND    GND @S9S_MB_2U_LIB.S9S_MB_2U(SCH_1):GND

Q_RES_0402LF-1M,1%,1/16W,EMPTYA  I68  R4793
   1 HSC_OC_VOL      A @S9S_MB_2U_LIB.S9S_MB_2U(SCH_1):HSC_OC_VOL
   2 HSC_D_OC_R2      B @S9S_MB_2U_LIB.S9S_MB_2U(SCH_1):HSC_D_OC_R2

Q_CAP_C0402-100NF,50V,10%,EMPTA  I71  C2390
   1 P12V_AUX      A @S9S_MB_2U_LIB.S9S_MB_2U(SCH_1):P12V_AUX
   2    GND      B @S9S_MB_2U_LIB.S9S_MB_2U(SCH_1):GND

Q_RES_0402LF-33.2,1%,1/16W,EMPA  I72  R4794
   1 HSC_D_OC_R2      A @S9S_MB_2U_LIB.S9S_MB_2U(SCH_1):HSC_D_OC_R2
   2 A_HSC_LOW_GATE      B @S9S_MB_2U_LIB.S9S_MB_2U(SCH_1):A_HSC_LOW_GATE

Q_CAP_C0402-100NF,50V,10%,EMPTA  I76  C2389
   1 HSC_OC_VOL      A @S9S_MB_2U_LIB.S9S_MB_2U(SCH_1):HSC_OC_VOL
   2    GND      B @S9S_MB_2U_LIB.S9S_MB_2U(SCH_1):GND

Q_RES_0402LF-10K,1%,1/16W,EMPTA  I77  R4796
   1 HSC_OC_VOL      A @S9S_MB_2U_LIB.S9S_MB_2U(SCH_1):HSC_OC_VOL
   2    GND      B @S9S_MB_2U_LIB.S9S_MB_2U(SCH_1):GND

Q_RES_0402LF-160K,1%,1/16W,EMPA  I78  R4795
   1 HSC_CSOUT      A @S9S_MB_2U_LIB.S9S_MB_2U(SCH_1):HSC_CSOUT
   2 HSC_OC_VOL      B @S9S_MB_2U_LIB.S9S_MB_2U(SCH_1):HSC_OC_VOL

Q_RES_0402LF-10K,1%,1/16W,EMPTA  I80  R4797
   1 P3V3_AUX      A @S9S_MB_2U_LIB.S9S_MB_2U(SCH_1):P3V3_AUX
   2 A_HSC_LOW_GATE      B @S9S_MB_2U_LIB.S9S_MB_2U(SCH_1):A_HSC_LOW_GATE

Q_CAP_C0402-1UF,25V,10%,EMPTY,A  I89  C1562
   1 U205_VDD      A @S9S_MB_2U_LIB.S9S_MB_2U(SCH_1):U205_VDD
   2    GND      B @S9S_MB_2U_LIB.S9S_MB_2U(SCH_1):GND

Q_CAP_C0402-1UF,25V,10%,X6S,CHA  I90  C1561
   1 U206_VDD      A @S9S_MB_2U_LIB.S9S_MB_2U(SCH_1):U206_VDD
   2    GND      B @S9S_MB_2U_LIB.S9S_MB_2U(SCH_1):GND

Q_CAP_C0402-1UF,25V,10%,EMPTY,A  I91  C4562
   1 U369_VDD      A @S9S_MB_2U_LIB.S9S_MB_2U(SCH_1):U369_VDD
   2    GND      B @S9S_MB_2U_LIB.S9S_MB_2U(SCH_1):GND

Q_CAP_0402-0.1UF,25V,10%,EMPTYA  I92  C2393
   1 U369_VDD      A @S9S_MB_2U_LIB.S9S_MB_2U(SCH_1):U369_VDD
   2    GND      B @S9S_MB_2U_LIB.S9S_MB_2U(SCH_1):GND

Q_CAP_0402-0.1UF,25V,10%,X7R,CA  I93  C2394
   1 U206_VDD      A @S9S_MB_2U_LIB.S9S_MB_2U(SCH_1):U206_VDD
   2    GND      B @S9S_MB_2U_LIB.S9S_MB_2U(SCH_1):GND

Q_CAP_0402-0.1UF,25V,10%,EMPTYA  I95  C2392
   1 U205_VDD      A @S9S_MB_2U_LIB.S9S_MB_2U(SCH_1):U205_VDD
   2    GND      B @S9S_MB_2U_LIB.S9S_MB_2U(SCH_1):GND

Q_RES_0402LF-1K,1%,1/16W,EMPTYA  I97  R4804
   1 P3V3_AUX      A @S9S_MB_2U_LIB.S9S_MB_2U(SCH_1):P3V3_AUX
   2 U205_VDD      B @S9S_MB_2U_LIB.S9S_MB_2U(SCH_1):U205_VDD

Q_RES_0402LF-1K,1%,1/16W,CHIP,A  I98  R4806
   1 P12V_AUX      A @S9S_MB_2U_LIB.S9S_MB_2U(SCH_1):P12V_AUX
   2 U206_VDD      B @S9S_MB_2U_LIB.S9S_MB_2U(SCH_1):U206_VDD

Q_RES_0402LF-1K,1%,1/16W,EMPTYA  I99  R4805
   1 P3V3_AUX      A @S9S_MB_2U_LIB.S9S_MB_2U(SCH_1):P3V3_AUX
   2 U369_VDD      B @S9S_MB_2U_LIB.S9S_MB_2U(SCH_1):U369_VDD

Q_RES_0402LF-26.7K,1%,1/16W,CHA  I100  R2219
   1 P12V_AUX      A @S9S_MB_2U_LIB.S9S_MB_2U(SCH_1):P12V_AUX
   2 A_P12V_STBY_ADR_TRIGGER      B @S9S_MB_2U_LIB.S9S_MB_2U(SCH_1):A_P12V_STBY_ADR_TRIGGER

Q_RES_0402LF-1K,1%,1/16W,CHIP,A  I101  R2227
   1 A_P12V_STBY_ADR_TRIGGER      A @S9S_MB_2U_LIB.S9S_MB_2U(SCH_1):A_P12V_STBY_ADR_TRIGGER
   2    GND      B @S9S_MB_2U_LIB.S9S_MB_2U(SCH_1):GND

LT6700CS61TRPBF-LT6700CS6-1#TRA  I102  U206
   5 U206_VDD     VS @S9S_MB_2U_LIB.S9S_MB_2U(SCH_1):U206_VDD
   4 A_P12V_STBY_FP_TRIGGER   INB- @S9S_MB_2U_LIB.S9S_MB_2U(SCH_1):A_P12V_STBY_FP_TRIGGER
   2    GND    GND @S9S_MB_2U_LIB.S9S_MB_2U(SCH_1):GND
   1 FM_UV_ADR_TRIGGER_N   OUTA @S9S_MB_2U_LIB.S9S_MB_2U(SCH_1):FM_UV_ADR_TRIGGER_N
   3 A_P12V_STBY_ADR_TRIGGER   INA+ @S9S_MB_2U_LIB.S9S_MB_2U(SCH_1):A_P12V_STBY_ADR_TRIGGER
   6 A_P12V_STBY_FPH_GATE   OUTB @S9S_MB_2U_LIB.S9S_MB_2U(SCH_1):A_P12V_STBY_FPH_GATE


DRAWING: @S9S_MB_2U_LIB.S9S_MB_2U(SCH_1):PAGE209 

Q_CAP_0402-100PF,50V,5%,NPO,CHA  I3  C1209
   1 PWRGD_SYS_PWROK_R      A @S9S_MB_2U_LIB.S9S_MB_2U(SCH_1):PWRGD_SYS_PWROK_R
   2    GND      B @S9S_MB_2U_LIB.S9S_MB_2U(SCH_1):GND

Q_CAP_0402-100PF,50V,5%,NPO,CHA  I4  C1211
   1 PWRGD_PCH_PWROK_R      A @S9S_MB_2U_LIB.S9S_MB_2U(SCH_1):PWRGD_PCH_PWROK_R
   2    GND      B @S9S_MB_2U_LIB.S9S_MB_2U(SCH_1):GND

Q_RES_0402LF-1K,1%,1/16W,EMPTYA  I11  R736
   1 FM_DIMM_12V_CPS_SX_N      A @S9S_MB_2U_LIB.S9S_MB_2U(SCH_1):FM_DIMM_12V_CPS_SX_N
   2    GND      B @S9S_MB_2U_LIB.S9S_MB_2U(SCH_1):GND

Q_RES_0402LF-10K,1%,1/16W,CHIPA  I13  R735
   1 P3V3_AUX      A @S9S_MB_2U_LIB.S9S_MB_2U(SCH_1):P3V3_AUX
   2 FM_DIMM_12V_CPS_SX_N      B @S9S_MB_2U_LIB.S9S_MB_2U(SCH_1):FM_DIMM_12V_CPS_SX_N

Q_RES_0402LF-10K,1%,1/16W,EMPTA  I14  R1660
   1 FM_SLP_SUS_RSM_RST_N      A @S9S_MB_2U_LIB.S9S_MB_2U(SCH_1):FM_SLP_SUS_RSM_RST_N
   2 P3V3_AUX      B @S9S_MB_2U_LIB.S9S_MB_2U(SCH_1):P3V3_AUX

Q_RES_0402LF-10K,1%,1/16W,EMPTA  I15  R1558
   1 FM_CPU_RMCA_CATERR_LVT3_R_N      A @S9S_MB_2U_LIB.S9S_MB_2U(SCH_1):FM_CPU_RMCA_CATERR_LVT3_R_N
   2 P3V3_AUX      B @S9S_MB_2U_LIB.S9S_MB_2U(SCH_1):P3V3_AUX

Q_RES_0402LF-10K,1%,1/16W,CHIPA  I16  R1401
   1 PU_MAIN_FPGA_CONFIG_DONE      A @S9S_MB_2U_LIB.S9S_MB_2U(SCH_1):PU_MAIN_FPGA_CONFIG_DONE
   2 P3V3_AUX      B @S9S_MB_2U_LIB.S9S_MB_2U(SCH_1):P3V3_AUX

Q_RES_0402LF-10K,1%,1/16W,CHIPA  I17  R1399
   1 FM_PFR_DSW_PWROK_N      A @S9S_MB_2U_LIB.S9S_MB_2U(SCH_1):FM_PFR_DSW_PWROK_N
   2 P3V3_AUX      B @S9S_MB_2U_LIB.S9S_MB_2U(SCH_1):P3V3_AUX

Q_RES_0402LF-1K,1%,1/16W,EMPTYA  I21  R1494
   1 FM_DIS_PS_PWROK_DLY      A @S9S_MB_2U_LIB.S9S_MB_2U(SCH_1):FM_DIS_PS_PWROK_DLY
   2    GND      B @S9S_MB_2U_LIB.S9S_MB_2U(SCH_1):GND

Q_RES_0402LF-10K,1%,1/16W,EMPTA  I22  R1312
   1 FM_RST_PERST_BIT2      A @S9S_MB_2U_LIB.S9S_MB_2U(SCH_1):FM_RST_PERST_BIT2
   2    GND      B @S9S_MB_2U_LIB.S9S_MB_2U(SCH_1):GND

Q_RES_0402LF-10K,1%,1/16W,EMPTA  I23  R1308
   1 FM_RST_PERST_BIT1      A @S9S_MB_2U_LIB.S9S_MB_2U(SCH_1):FM_RST_PERST_BIT1
   2    GND      B @S9S_MB_2U_LIB.S9S_MB_2U(SCH_1):GND

Q_RES_0402LF-10K,1%,1/16W,EMPTA  I24  R1742
   1 FM_RST_PERST_BIT0      A @S9S_MB_2U_LIB.S9S_MB_2U(SCH_1):FM_RST_PERST_BIT0
   2    GND      B @S9S_MB_2U_LIB.S9S_MB_2U(SCH_1):GND

Q_RES_0402LF-10K,1%,1/16W,CHIPA  I35  R1492
   1 FM_DIS_PS_PWROK_DLY      A @S9S_MB_2U_LIB.S9S_MB_2U(SCH_1):FM_DIS_PS_PWROK_DLY
   2 P3V3_AUX      B @S9S_MB_2U_LIB.S9S_MB_2U(SCH_1):P3V3_AUX

Q_RES_0402LF-1K,1%,1/16W,CHIP,A  I36  R1474
   1 FM_RST_PERST_BIT2      A @S9S_MB_2U_LIB.S9S_MB_2U(SCH_1):FM_RST_PERST_BIT2
   2 P3V3_AUX      B @S9S_MB_2U_LIB.S9S_MB_2U(SCH_1):P3V3_AUX

Q_RES_0402LF-1K,1%,1/16W,CHIP,A  I37  R1473
   1 FM_RST_PERST_BIT1      A @S9S_MB_2U_LIB.S9S_MB_2U(SCH_1):FM_RST_PERST_BIT1
   2 P3V3_AUX      B @S9S_MB_2U_LIB.S9S_MB_2U(SCH_1):P3V3_AUX

Q_RES_0402LF-1K,1%,1/16W,CHIP,A  I38  R1741
   1 FM_RST_PERST_BIT0      A @S9S_MB_2U_LIB.S9S_MB_2U(SCH_1):FM_RST_PERST_BIT0
   2 P3V3_AUX      B @S9S_MB_2U_LIB.S9S_MB_2U(SCH_1):P3V3_AUX

Q_RES_0402LF-10K,1%,1/16W,CHIPA  I39  R2244
   1 ROT_P1_RST_IND_N_R      A @S9S_MB_2U_LIB.S9S_MB_2U(SCH_1):ROT_P1_RST_IND_N_R
   2 P3V3_AUX      B @S9S_MB_2U_LIB.S9S_MB_2U(SCH_1):P3V3_AUX

Q_RES_0402LF-10K,1%,1/16W,EMPTA  I40  R139
   1 FM_BMC_PWRBTN_N      A @S9S_MB_2U_LIB.S9S_MB_2U(SCH_1):FM_BMC_PWRBTN_N
   2 P3V3_AUX      B @S9S_MB_2U_LIB.S9S_MB_2U(SCH_1):P3V3_AUX

Q_RES_0402LF-10K,1%,1/16W,EMPTA  I41  R1440
   1 JTAG_PLD_TDO_R      A @S9S_MB_2U_LIB.S9S_MB_2U(SCH_1):JTAG_PLD_TDO_R
   2 P3V3_AUX      B @S9S_MB_2U_LIB.S9S_MB_2U(SCH_1):P3V3_AUX

Q_RES_0402LF-10K,1%,1/16W,CHIPA  I42  R1437
   1 FM_PLD_HEARTBEAT_LVC3      A @S9S_MB_2U_LIB.S9S_MB_2U(SCH_1):FM_PLD_HEARTBEAT_LVC3
   2 P3V3_AUX      B @S9S_MB_2U_LIB.S9S_MB_2U(SCH_1):P3V3_AUX

Q_RES_0402LF-10K,1%,1/16W,CHIPA  I43  R1435
   1 FM_ADR_TRIGGER_N      A @S9S_MB_2U_LIB.S9S_MB_2U(SCH_1):FM_ADR_TRIGGER_N
   2 P3V3_AUX      B @S9S_MB_2U_LIB.S9S_MB_2U(SCH_1):P3V3_AUX

Q_RES_0402LF-10K,1%,1/16W,CHIPA  I44  R1434
   1 FM_SYS_THROTTLE_R_N      A @S9S_MB_2U_LIB.S9S_MB_2U(SCH_1):FM_SYS_THROTTLE_R_N
   2 P3V3_AUX      B @S9S_MB_2U_LIB.S9S_MB_2U(SCH_1):P3V3_AUX

Q_RES_0402LF-10K,1%,1/16W,CHIPA  I46  R4674
   1 FM_SLP_SUS_RSM_RST_N      A @S9S_MB_2U_LIB.S9S_MB_2U(SCH_1):FM_SLP_SUS_RSM_RST_N
   2    GND      B @S9S_MB_2U_LIB.S9S_MB_2U(SCH_1):GND


DRAWING: @S9S_MB_2U_LIB.S9S_MB_2U(SCH_1):PAGE173 

Q_RES_0402LF-100,1%,1/16W,CHIPA  I1  R495
   1 PCH_PCIEUP_RCOMPP      A @S9S_MB_2U_LIB.S9S_MB_2U(SCH_1):PCH_PCIEUP_RCOMPP
   2 PCH_PCIEUP_RCOMPN      B @S9S_MB_2U_LIB.S9S_MB_2U(SCH_1):PCH_PCIEUP_RCOMPN

Q_CAP_DIFFBUS_C0201-DIFF BUS_0A  I60  C1105
   1 P3E_PCH_M2_TX_DN<0>      1 @S9S_MB_2U_LIB.S9S_MB_2U(SCH_1):P3E_PCH_M2_TX_DN(0)
   2 P3E_PCH_M2_TX_C_DN<0>      2 @S9S_MB_2U_LIB.S9S_MB_2U(SCH_1):P3E_PCH_M2_TX_C_DN(0)

Q_CAP_DIFFBUS_C0201-DIFF BUS_0A  I61  C1104
   1 P3E_PCH_M2_TX_DP<0>      1 @S9S_MB_2U_LIB.S9S_MB_2U(SCH_1):P3E_PCH_M2_TX_DP(0)
   2 P3E_PCH_M2_TX_C_DP<0>      2 @S9S_MB_2U_LIB.S9S_MB_2U(SCH_1):P3E_PCH_M2_TX_C_DP(0)

Q_CAP_DIFFBUS_C0201-DIFF BUS_0A  I62  C1103
   1 P3E_PCH_M2_TX_DN<1>      1 @S9S_MB_2U_LIB.S9S_MB_2U(SCH_1):P3E_PCH_M2_TX_DN(1)
   2 P3E_PCH_M2_TX_C_DN<1>      2 @S9S_MB_2U_LIB.S9S_MB_2U(SCH_1):P3E_PCH_M2_TX_C_DN(1)

Q_CAP_DIFFBUS_C0201-DIFF BUS_0A  I63  C1102
   1 P3E_PCH_M2_TX_DP<1>      1 @S9S_MB_2U_LIB.S9S_MB_2U(SCH_1):P3E_PCH_M2_TX_DP(1)
   2 P3E_PCH_M2_TX_C_DP<1>      2 @S9S_MB_2U_LIB.S9S_MB_2U(SCH_1):P3E_PCH_M2_TX_C_DP(1)

Q_CAP_DIFFBUS_C0201-DIFF BUS_0A  I64  C1100
   1 P3E_PCH_M2_TX_DP<2>      1 @S9S_MB_2U_LIB.S9S_MB_2U(SCH_1):P3E_PCH_M2_TX_DP(2)
   2 P3E_PCH_M2_TX_C_DP<2>      2 @S9S_MB_2U_LIB.S9S_MB_2U(SCH_1):P3E_PCH_M2_TX_C_DP(2)

Q_CAP_DIFFBUS_C0201-DIFF BUS_0A  I65  C1101
   1 P3E_PCH_M2_TX_DN<2>      1 @S9S_MB_2U_LIB.S9S_MB_2U(SCH_1):P3E_PCH_M2_TX_DN(2)
   2 P3E_PCH_M2_TX_C_DN<2>      2 @S9S_MB_2U_LIB.S9S_MB_2U(SCH_1):P3E_PCH_M2_TX_C_DN(2)

Q_CAP_DIFFBUS_C0201-DIFF BUS_0A  I66  C1099
   1 P3E_PCH_M2_TX_DN<3>      1 @S9S_MB_2U_LIB.S9S_MB_2U(SCH_1):P3E_PCH_M2_TX_DN(3)
   2 P3E_PCH_M2_TX_C_DN<3>      2 @S9S_MB_2U_LIB.S9S_MB_2U(SCH_1):P3E_PCH_M2_TX_C_DN(3)

Q_CAP_DIFFBUS_C0201-DIFF BUS_0A  I67  C1098
   1 P3E_PCH_M2_TX_DP<3>      1 @S9S_MB_2U_LIB.S9S_MB_2U(SCH_1):P3E_PCH_M2_TX_DP(3)
   2 P3E_PCH_M2_TX_C_DP<3>      2 @S9S_MB_2U_LIB.S9S_MB_2U(SCH_1):P3E_PCH_M2_TX_C_DP(3)

Q_CAP_DIFFBUS_C0201-DIFF BUS_0A  I68  C1996
   1 P3E_PCH_E1S_TX_DN<0>      1 @S9S_MB_2U_LIB.S9S_MB_2U(SCH_1):P3E_PCH_E1S_TX_DN(0)
   2 P3E_PCH_E1S_TX_C_DN<0>      2 @S9S_MB_2U_LIB.S9S_MB_2U(SCH_1):P3E_PCH_E1S_TX_C_DN(0)

Q_CAP_DIFFBUS_C0201-DIFF BUS_0A  I69  C1995
   1 P3E_PCH_E1S_TX_DP<0>      1 @S9S_MB_2U_LIB.S9S_MB_2U(SCH_1):P3E_PCH_E1S_TX_DP(0)
   2 P3E_PCH_E1S_TX_C_DP<0>      2 @S9S_MB_2U_LIB.S9S_MB_2U(SCH_1):P3E_PCH_E1S_TX_C_DP(0)

Q_CAP_DIFFBUS_C0201-DIFF BUS_0A  I70  C1994
   1 P3E_PCH_E1S_TX_DN<1>      1 @S9S_MB_2U_LIB.S9S_MB_2U(SCH_1):P3E_PCH_E1S_TX_DN(1)
   2 P3E_PCH_E1S_TX_C_DN<1>      2 @S9S_MB_2U_LIB.S9S_MB_2U(SCH_1):P3E_PCH_E1S_TX_C_DN(1)

Q_CAP_DIFFBUS_C0201-DIFF BUS_0A  I71  C1993
   1 P3E_PCH_E1S_TX_DP<1>      1 @S9S_MB_2U_LIB.S9S_MB_2U(SCH_1):P3E_PCH_E1S_TX_DP(1)
   2 P3E_PCH_E1S_TX_C_DP<1>      2 @S9S_MB_2U_LIB.S9S_MB_2U(SCH_1):P3E_PCH_E1S_TX_C_DP(1)

Q_CAP_DIFFBUS_C0201-DIFF BUS_0A  I72  C1992
   1 P3E_PCH_E1S_TX_DN<2>      1 @S9S_MB_2U_LIB.S9S_MB_2U(SCH_1):P3E_PCH_E1S_TX_DN(2)
   2 P3E_PCH_E1S_TX_C_DN<2>      2 @S9S_MB_2U_LIB.S9S_MB_2U(SCH_1):P3E_PCH_E1S_TX_C_DN(2)

Q_CAP_DIFFBUS_C0201-DIFF BUS_0A  I73  C1991
   1 P3E_PCH_E1S_TX_DP<2>      1 @S9S_MB_2U_LIB.S9S_MB_2U(SCH_1):P3E_PCH_E1S_TX_DP(2)
   2 P3E_PCH_E1S_TX_C_DP<2>      2 @S9S_MB_2U_LIB.S9S_MB_2U(SCH_1):P3E_PCH_E1S_TX_C_DP(2)

Q_CAP_DIFFBUS_C0201-DIFF BUS_0A  I74  C1990
   1 P3E_PCH_E1S_TX_DN<3>      1 @S9S_MB_2U_LIB.S9S_MB_2U(SCH_1):P3E_PCH_E1S_TX_DN(3)
   2 P3E_PCH_E1S_TX_C_DN<3>      2 @S9S_MB_2U_LIB.S9S_MB_2U(SCH_1):P3E_PCH_E1S_TX_C_DN(3)

Q_CAP_DIFFBUS_C0201-DIFF BUS_0A  I75  C1989
   1 P3E_PCH_E1S_TX_DP<3>      1 @S9S_MB_2U_LIB.S9S_MB_2U(SCH_1):P3E_PCH_E1S_TX_DP(3)
   2 P3E_PCH_E1S_TX_C_DP<3>      2 @S9S_MB_2U_LIB.S9S_MB_2U(SCH_1):P3E_PCH_E1S_TX_C_DP(3)

Q_CAP_DIFFBUS_C0201-DIFF BUS_0A  I76  C2078
   1 P3E_PCH_BMC_TX_DN      1 @S9S_MB_2U_LIB.S9S_MB_2U(SCH_1):P3E_PCH_BMC_TX_DN
   2 P3E_PCH_BMC_TX_C_DN      2 @S9S_MB_2U_LIB.S9S_MB_2U(SCH_1):P3E_PCH_BMC_TX_C_DN

Q_CAP_DIFFBUS_C0201-DIFF BUS_0A  I77  C2077
   1 P3E_PCH_BMC_TX_DP      1 @S9S_MB_2U_LIB.S9S_MB_2U(SCH_1):P3E_PCH_BMC_TX_DP
   2 P3E_PCH_BMC_TX_C_DP      2 @S9S_MB_2U_LIB.S9S_MB_2U(SCH_1):P3E_PCH_BMC_TX_C_DP

Q_CAP_C0201-0.1UF,6.3V,10%,X6SA  I78  C1097
   1 USB3_PCH_TX_DN<4>      A @S9S_MB_2U_LIB.S9S_MB_2U(SCH_1):USB3_PCH_TX_DN(4)
   2 USB3_PCH_TX_C_DN<4>      B @S9S_MB_2U_LIB.S9S_MB_2U(SCH_1):USB3_PCH_TX_C_DN(4)

Q_CAP_DIFFBUS_C0201-DIFF BUS_0A  I79  C2076
   1 P3E_PCH_NVS_TX_DN<0>      1 @S9S_MB_2U_LIB.S9S_MB_2U(SCH_1):P3E_PCH_NVS_TX_DN(0)
   2 P3E_PCH_NVS_TX_C_DN<0>      2 @S9S_MB_2U_LIB.S9S_MB_2U(SCH_1):P3E_PCH_NVS_TX_C_DN(0)

Q_CAP_C0201-0.1UF,6.3V,10%,X6SA  I80  C1096
   1 USB3_PCH_TX_DP<4>      A @S9S_MB_2U_LIB.S9S_MB_2U(SCH_1):USB3_PCH_TX_DP(4)
   2 USB3_PCH_TX_C_DP<4>      B @S9S_MB_2U_LIB.S9S_MB_2U(SCH_1):USB3_PCH_TX_C_DP(4)

Q_CAP_DIFFBUS_C0201-DIFF BUS_0A  I81  C2075
   1 P3E_PCH_NVS_TX_DP<0>      1 @S9S_MB_2U_LIB.S9S_MB_2U(SCH_1):P3E_PCH_NVS_TX_DP(0)
   2 P3E_PCH_NVS_TX_C_DP<0>      2 @S9S_MB_2U_LIB.S9S_MB_2U(SCH_1):P3E_PCH_NVS_TX_C_DP(0)

Q_CAP_DIFFBUS_C0201-DIFF BUS_0A  I82  C2074
   1 P3E_PCH_NVS_TX_DN<1>      1 @S9S_MB_2U_LIB.S9S_MB_2U(SCH_1):P3E_PCH_NVS_TX_DN(1)
   2 P3E_PCH_NVS_TX_C_DN<1>      2 @S9S_MB_2U_LIB.S9S_MB_2U(SCH_1):P3E_PCH_NVS_TX_C_DN(1)

Q_CAP_DIFFBUS_C0201-DIFF BUS_0A  I83  C2073
   1 P3E_PCH_NVS_TX_DP<1>      1 @S9S_MB_2U_LIB.S9S_MB_2U(SCH_1):P3E_PCH_NVS_TX_DP(1)
   2 P3E_PCH_NVS_TX_C_DP<1>      2 @S9S_MB_2U_LIB.S9S_MB_2U(SCH_1):P3E_PCH_NVS_TX_C_DP(1)

EMMITSBURG_REV0P9-GFNOCPU04302A  I110  U4
 A30 DMI_CPU0_PCH_TX_C_DN<0> DMI_0_RXN @S9S_MB_2U_LIB.S9S_MB_2U(SCH_1):DMI_CPU0_PCH_TX_C_DN(0)
 C30 DMI_CPU0_PCH_TX_C_DP<0> DMI_0_RXP @S9S_MB_2U_LIB.S9S_MB_2U(SCH_1):DMI_CPU0_PCH_TX_C_DP(0)
 K28 DMI_CPU0_PCH_RX_DN<0> DMI_0_TXN @S9S_MB_2U_LIB.S9S_MB_2U(SCH_1):DMI_CPU0_PCH_RX_DN(0)
 H28 DMI_CPU0_PCH_RX_DP<0> DMI_0_TXP @S9S_MB_2U_LIB.S9S_MB_2U(SCH_1):DMI_CPU0_PCH_RX_DP(0)
 B31 DMI_CPU0_PCH_TX_C_DN<1> DMI_1_RXN @S9S_MB_2U_LIB.S9S_MB_2U(SCH_1):DMI_CPU0_PCH_TX_C_DN(1)
 D31 DMI_CPU0_PCH_TX_C_DP<1> DMI_1_RXP @S9S_MB_2U_LIB.S9S_MB_2U(SCH_1):DMI_CPU0_PCH_TX_C_DP(1)
 G29 DMI_CPU0_PCH_RX_DN<1> DMI_1_TXN @S9S_MB_2U_LIB.S9S_MB_2U(SCH_1):DMI_CPU0_PCH_RX_DN(1)
 F28 DMI_CPU0_PCH_RX_DP<1> DMI_1_TXP @S9S_MB_2U_LIB.S9S_MB_2U(SCH_1):DMI_CPU0_PCH_RX_DP(1)
 A32 DMI_CPU0_PCH_TX_C_DN<2> DMI_2_RXN @S9S_MB_2U_LIB.S9S_MB_2U(SCH_1):DMI_CPU0_PCH_TX_C_DN(2)
 C32 DMI_CPU0_PCH_TX_C_DP<2> DMI_2_RXP @S9S_MB_2U_LIB.S9S_MB_2U(SCH_1):DMI_CPU0_PCH_TX_C_DP(2)
 J29 DMI_CPU0_PCH_RX_DN<2> DMI_2_TXN @S9S_MB_2U_LIB.S9S_MB_2U(SCH_1):DMI_CPU0_PCH_RX_DN(2)
 H31 DMI_CPU0_PCH_RX_DP<2> DMI_2_TXP @S9S_MB_2U_LIB.S9S_MB_2U(SCH_1):DMI_CPU0_PCH_RX_DP(2)
 B33 DMI_CPU0_PCH_TX_C_DN<3> DMI_3_RXN @S9S_MB_2U_LIB.S9S_MB_2U(SCH_1):DMI_CPU0_PCH_TX_C_DN(3)
 D33 DMI_CPU0_PCH_TX_C_DP<3> DMI_3_RXP @S9S_MB_2U_LIB.S9S_MB_2U(SCH_1):DMI_CPU0_PCH_TX_C_DP(3)
 L32 DMI_CPU0_PCH_RX_DN<3> DMI_3_TXN @S9S_MB_2U_LIB.S9S_MB_2U(SCH_1):DMI_CPU0_PCH_RX_DN(3)
 K31 DMI_CPU0_PCH_RX_DP<3> DMI_3_TXP @S9S_MB_2U_LIB.S9S_MB_2U(SCH_1):DMI_CPU0_PCH_RX_DP(3)
 A34 DMI_CPU0_PCH_TX_C_DN<4> DMI_4_SATA_19_PCIE3_19_RXN @S9S_MB_2U_LIB.S9S_MB_2U(SCH_1):DMI_CPU0_PCH_TX_C_DN(4)
 C34 DMI_CPU0_PCH_TX_C_DP<4> DMI_4_SATA_19_PCIE3_19_RXP @S9S_MB_2U_LIB.S9S_MB_2U(SCH_1):DMI_CPU0_PCH_TX_C_DP(4)
 J32 DMI_CPU0_PCH_RX_DN<4> DMI_4_SATA_19_PCIE3_19_TXN @S9S_MB_2U_LIB.S9S_MB_2U(SCH_1):DMI_CPU0_PCH_RX_DN(4)
 G32 DMI_CPU0_PCH_RX_DP<4> DMI_4_SATA_19_PCIE3_19_TXP @S9S_MB_2U_LIB.S9S_MB_2U(SCH_1):DMI_CPU0_PCH_RX_DP(4)
 B35 DMI_CPU0_PCH_TX_C_DN<5> DMI_5_SATA_18_PCIE3_18_RXN @S9S_MB_2U_LIB.S9S_MB_2U(SCH_1):DMI_CPU0_PCH_TX_C_DN(5)
 D35 DMI_CPU0_PCH_TX_C_DP<5> DMI_5_SATA_18_PCIE3_18_RXP @S9S_MB_2U_LIB.S9S_MB_2U(SCH_1):DMI_CPU0_PCH_TX_C_DP(5)
 G36 DMI_CPU0_PCH_RX_DN<5> DMI_5_SATA_18_PCIE3_18_TXN @S9S_MB_2U_LIB.S9S_MB_2U(SCH_1):DMI_CPU0_PCH_RX_DN(5)
 H34 DMI_CPU0_PCH_RX_DP<5> DMI_5_SATA_18_PCIE3_18_TXP @S9S_MB_2U_LIB.S9S_MB_2U(SCH_1):DMI_CPU0_PCH_RX_DP(5)
 A36 DMI_CPU0_PCH_TX_C_DN<6> DMI_6_SATA_17_PCIE3_17_RXN @S9S_MB_2U_LIB.S9S_MB_2U(SCH_1):DMI_CPU0_PCH_TX_C_DN(6)
 C36 DMI_CPU0_PCH_TX_C_DP<6> DMI_6_SATA_17_PCIE3_17_RXP @S9S_MB_2U_LIB.S9S_MB_2U(SCH_1):DMI_CPU0_PCH_TX_C_DP(6)
 K37 DMI_CPU0_PCH_RX_DN<6> DMI_6_SATA_17_PCIE3_17_TXN @S9S_MB_2U_LIB.S9S_MB_2U(SCH_1):DMI_CPU0_PCH_RX_DN(6)
 J36 DMI_CPU0_PCH_RX_DP<6> DMI_6_SATA_17_PCIE3_17_TXP @S9S_MB_2U_LIB.S9S_MB_2U(SCH_1):DMI_CPU0_PCH_RX_DP(6)
 B37 DMI_CPU0_PCH_TX_C_DN<7> DMI_7_SATA_16_PCIE3_16_RXN @S9S_MB_2U_LIB.S9S_MB_2U(SCH_1):DMI_CPU0_PCH_TX_C_DN(7)
 D37 DMI_CPU0_PCH_TX_C_DP<7> DMI_7_SATA_16_PCIE3_16_RXP @S9S_MB_2U_LIB.S9S_MB_2U(SCH_1):DMI_CPU0_PCH_TX_C_DP(7)
 F37 DMI_CPU0_PCH_RX_DN<7> DMI_7_SATA_16_PCIE3_16_TXN @S9S_MB_2U_LIB.S9S_MB_2U(SCH_1):DMI_CPU0_PCH_RX_DN(7)
 H37 DMI_CPU0_PCH_RX_DP<7> DMI_7_SATA_16_PCIE3_16_TXP @S9S_MB_2U_LIB.S9S_MB_2U(SCH_1):DMI_CPU0_PCH_RX_DP(7)
AP31 PCH_PCIEUP_RCOMPN PHY_PCIE3_RCOMPN @S9S_MB_2U_LIB.S9S_MB_2U(SCH_1):PCH_PCIEUP_RCOMPN
AR29 PCH_PCIEUP_RCOMPP PHY_PCIE3_RCOMPP @S9S_MB_2U_LIB.S9S_MB_2U(SCH_1):PCH_PCIEUP_RCOMPP
 N42 NC_PCH_RSVD<11> RSVD_N42 @S9S_MB_2U_LIB.S9S_MB_2U(SCH_1):NC_PCH_RSVD(11)
 N40 NC_PCH_RSVD<10> RSVD_N40 @S9S_MB_2U_LIB.S9S_MB_2U(SCH_1):NC_PCH_RSVD(10)
 D39 NC_PCH_RSVD<9> RSVD_D39 @S9S_MB_2U_LIB.S9S_MB_2U(SCH_1):NC_PCH_RSVD(9)
 C40 NC_PCH_RSVD<8> RSVD_C40 @S9S_MB_2U_LIB.S9S_MB_2U(SCH_1):NC_PCH_RSVD(8)
AE41 P3E_PCH_M2_RX_DN<0> SATA_0_PCIE3_0_USB3_0_RXN @S9S_MB_2U_LIB.S9S_MB_2U(SCH_1):P3E_PCH_M2_RX_DN(0)
AE43 P3E_PCH_M2_RX_DP<0> SATA_0_PCIE3_0_USB3_0_RXP @S9S_MB_2U_LIB.S9S_MB_2U(SCH_1):P3E_PCH_M2_RX_DP(0)
AL32 P3E_PCH_M2_TX_DN<0> SATA_0_PCIE3_0_USB3_0_TXN @S9S_MB_2U_LIB.S9S_MB_2U(SCH_1):P3E_PCH_M2_TX_DN(0)
AK31 P3E_PCH_M2_TX_DP<0> SATA_0_PCIE3_0_USB3_0_TXP @S9S_MB_2U_LIB.S9S_MB_2U(SCH_1):P3E_PCH_M2_TX_DP(0)
 M41 P3E_PCH_NVS_RX_DN<0> SATA_10_PCIE3_10_GBE_0_RXN @S9S_MB_2U_LIB.S9S_MB_2U(SCH_1):P3E_PCH_NVS_RX_DN(0)
 M43 P3E_PCH_NVS_RX_DP<0> SATA_10_PCIE3_10_GBE_0_RXP @S9S_MB_2U_LIB.S9S_MB_2U(SCH_1):P3E_PCH_NVS_RX_DP(0)
 W36 P3E_PCH_NVS_TX_DN<0> SATA_10_PCIE3_10_GBE_0_TXN @S9S_MB_2U_LIB.S9S_MB_2U(SCH_1):P3E_PCH_NVS_TX_DN(0)
 Y37 P3E_PCH_NVS_TX_DP<0> SATA_10_PCIE3_10_GBE_0_TXP @S9S_MB_2U_LIB.S9S_MB_2U(SCH_1):P3E_PCH_NVS_TX_DP(0)
 L40 P3E_PCH_NVS_RX_DN<1> SATA_11_PCIE3_11_RXN @S9S_MB_2U_LIB.S9S_MB_2U(SCH_1):P3E_PCH_NVS_RX_DN(1)
 L42 P3E_PCH_NVS_RX_DP<1> SATA_11_PCIE3_11_RXP @S9S_MB_2U_LIB.S9S_MB_2U(SCH_1):P3E_PCH_NVS_RX_DP(1)
 T37 P3E_PCH_NVS_TX_DN<1> SATA_11_PCIE3_11_TXN @S9S_MB_2U_LIB.S9S_MB_2U(SCH_1):P3E_PCH_NVS_TX_DN(1)
 V37 P3E_PCH_NVS_TX_DP<1> SATA_11_PCIE3_11_TXP @S9S_MB_2U_LIB.S9S_MB_2U(SCH_1):P3E_PCH_NVS_TX_DP(1)
 K41 TP_P3E_PCH_12_RX_DN SATA_12_PCIE3_12_GBE_1_RXN @S9S_MB_2U_LIB.S9S_MB_2U(SCH_1):TP_P3E_PCH_12_RX_DN
 K43 TP_P3E_PCH_12_RX_DP SATA_12_PCIE3_12_GBE_1_RXP @S9S_MB_2U_LIB.S9S_MB_2U(SCH_1):TP_P3E_PCH_12_RX_DP
 V34 TP_P3E_PCH_12_TX_DN SATA_12_PCIE3_12_GBE_1_TXN @S9S_MB_2U_LIB.S9S_MB_2U(SCH_1):TP_P3E_PCH_12_TX_DN
 U36 TP_P3E_PCH_12_TX_DP SATA_12_PCIE3_12_GBE_1_TXP @S9S_MB_2U_LIB.S9S_MB_2U(SCH_1):TP_P3E_PCH_12_TX_DP
 J40 TP_P3E_PCH_13_RX_DN SATA_13_PCIE3_13_RXN @S9S_MB_2U_LIB.S9S_MB_2U(SCH_1):TP_P3E_PCH_13_RX_DN
 J42 TP_P3E_PCH_13_RX_DP SATA_13_PCIE3_13_RXP @S9S_MB_2U_LIB.S9S_MB_2U(SCH_1):TP_P3E_PCH_13_RX_DP
 U32 TP_P3E_PCH_13_TX_DN SATA_13_PCIE3_13_TXN @S9S_MB_2U_LIB.S9S_MB_2U(SCH_1):TP_P3E_PCH_13_TX_DN
 W32 TP_P3E_PCH_13_TX_DP SATA_13_PCIE3_13_TXP @S9S_MB_2U_LIB.S9S_MB_2U(SCH_1):TP_P3E_PCH_13_TX_DP
 H41 TP_P3E_PCH_14_RX_DN SATA_14_PCIE3_14_GBE_2_RXN @S9S_MB_2U_LIB.S9S_MB_2U(SCH_1):TP_P3E_PCH_14_RX_DN
 H43 TP_P3E_PCH_14_RX_DP SATA_14_PCIE3_14_GBE_2_RXP @S9S_MB_2U_LIB.S9S_MB_2U(SCH_1):TP_P3E_PCH_14_RX_DP
 R32 TP_P3E_PCH_14_TX_DN SATA_14_PCIE3_14_GBE_2_TXN @S9S_MB_2U_LIB.S9S_MB_2U(SCH_1):TP_P3E_PCH_14_TX_DN
 T34 TP_P3E_PCH_14_TX_DP SATA_14_PCIE3_14_GBE_2_TXP @S9S_MB_2U_LIB.S9S_MB_2U(SCH_1):TP_P3E_PCH_14_TX_DP
 G40 TP_P3E_PCH_15_RX_DN SATA_15_PCIE3_15_RXN @S9S_MB_2U_LIB.S9S_MB_2U(SCH_1):TP_P3E_PCH_15_RX_DN
 G42 TP_P3E_PCH_15_RX_DP SATA_15_PCIE3_15_RXP @S9S_MB_2U_LIB.S9S_MB_2U(SCH_1):TP_P3E_PCH_15_RX_DP
 P34 TP_P3E_PCH_15_TX_DN SATA_15_PCIE3_15_TXN @S9S_MB_2U_LIB.S9S_MB_2U(SCH_1):TP_P3E_PCH_15_TX_DN
 N36 TP_P3E_PCH_15_TX_DP SATA_15_PCIE3_15_TXP @S9S_MB_2U_LIB.S9S_MB_2U(SCH_1):TP_P3E_PCH_15_TX_DP
AD40 P3E_PCH_M2_RX_DN<1> SATA_1_PCIE3_1_USB3_1_RXN @S9S_MB_2U_LIB.S9S_MB_2U(SCH_1):P3E_PCH_M2_RX_DN(1)
AD42 P3E_PCH_M2_RX_DP<1> SATA_1_PCIE3_1_USB3_1_RXP @S9S_MB_2U_LIB.S9S_MB_2U(SCH_1):P3E_PCH_M2_RX_DP(1)
AN36 P3E_PCH_M2_TX_DN<1> SATA_1_PCIE3_1_USB3_1_TXN @S9S_MB_2U_LIB.S9S_MB_2U(SCH_1):P3E_PCH_M2_TX_DN(1)
AP34 P3E_PCH_M2_TX_DP<1> SATA_1_PCIE3_1_USB3_1_TXP @S9S_MB_2U_LIB.S9S_MB_2U(SCH_1):P3E_PCH_M2_TX_DP(1)
AC41 P3E_PCH_M2_RX_DN<2> SATA_2_PCIE3_2_USB3_2_RXN @S9S_MB_2U_LIB.S9S_MB_2U(SCH_1):P3E_PCH_M2_RX_DN(2)
AC43 P3E_PCH_M2_RX_DP<2> SATA_2_PCIE3_2_USB3_2_RXP @S9S_MB_2U_LIB.S9S_MB_2U(SCH_1):P3E_PCH_M2_RX_DP(2)
AR36 P3E_PCH_M2_TX_DN<2> SATA_2_PCIE3_2_USB3_2_TXN @S9S_MB_2U_LIB.S9S_MB_2U(SCH_1):P3E_PCH_M2_TX_DN(2)
AT37 P3E_PCH_M2_TX_DP<2> SATA_2_PCIE3_2_USB3_2_TXP @S9S_MB_2U_LIB.S9S_MB_2U(SCH_1):P3E_PCH_M2_TX_DP(2)
AB40 P3E_PCH_M2_RX_DN<3> SATA_3_PCIE3_3_USB3_3_RXN @S9S_MB_2U_LIB.S9S_MB_2U(SCH_1):P3E_PCH_M2_RX_DN(3)
AB42 P3E_PCH_M2_RX_DP<3> SATA_3_PCIE3_3_USB3_3_RXP @S9S_MB_2U_LIB.S9S_MB_2U(SCH_1):P3E_PCH_M2_RX_DP(3)
AK34 P3E_PCH_M2_TX_DN<3> SATA_3_PCIE3_3_USB3_3_TXN @S9S_MB_2U_LIB.S9S_MB_2U(SCH_1):P3E_PCH_M2_TX_DN(3)
AM34 P3E_PCH_M2_TX_DP<3> SATA_3_PCIE3_3_USB3_3_TXP @S9S_MB_2U_LIB.S9S_MB_2U(SCH_1):P3E_PCH_M2_TX_DP(3)
AA41 P3E_PCH_E1S_RX_DN<0> SATA_4_PCIE3_4_USB3_4_RXN @S9S_MB_2U_LIB.S9S_MB_2U(SCH_1):P3E_PCH_E1S_RX_DN(0)
AA43 P3E_PCH_E1S_RX_DP<0> SATA_4_PCIE3_4_USB3_4_RXP @S9S_MB_2U_LIB.S9S_MB_2U(SCH_1):P3E_PCH_E1S_RX_DP(0)
AL36 P3E_PCH_E1S_TX_DN<0> SATA_4_PCIE3_4_USB3_4_TXN @S9S_MB_2U_LIB.S9S_MB_2U(SCH_1):P3E_PCH_E1S_TX_DN(0)
AM37 P3E_PCH_E1S_TX_DP<0> SATA_4_PCIE3_4_USB3_4_TXP @S9S_MB_2U_LIB.S9S_MB_2U(SCH_1):P3E_PCH_E1S_TX_DP(0)
 Y40 P3E_PCH_E1S_RX_DN<1> SATA_5_PCIE3_5_USB3_5_RXN @S9S_MB_2U_LIB.S9S_MB_2U(SCH_1):P3E_PCH_E1S_RX_DN(1)
 Y42 P3E_PCH_E1S_RX_DP<1> SATA_5_PCIE3_5_USB3_5_RXP @S9S_MB_2U_LIB.S9S_MB_2U(SCH_1):P3E_PCH_E1S_RX_DP(1)
AH34 P3E_PCH_E1S_TX_DN<1> SATA_5_PCIE3_5_USB3_5_TXN @S9S_MB_2U_LIB.S9S_MB_2U(SCH_1):P3E_PCH_E1S_TX_DN(1)
AJ32 P3E_PCH_E1S_TX_DP<1> SATA_5_PCIE3_5_USB3_5_TXP @S9S_MB_2U_LIB.S9S_MB_2U(SCH_1):P3E_PCH_E1S_TX_DP(1)
 W41 P3E_PCH_E1S_RX_DN<2> SATA_6_PCIE3_6_USB3_6_RXN @S9S_MB_2U_LIB.S9S_MB_2U(SCH_1):P3E_PCH_E1S_RX_DN(2)
 W43 P3E_PCH_E1S_RX_DP<2> SATA_6_PCIE3_6_USB3_6_RXP @S9S_MB_2U_LIB.S9S_MB_2U(SCH_1):P3E_PCH_E1S_RX_DP(2)
AF37 P3E_PCH_E1S_TX_DN<2> SATA_6_PCIE3_6_USB3_6_TXN @S9S_MB_2U_LIB.S9S_MB_2U(SCH_1):P3E_PCH_E1S_TX_DN(2)
AH37 P3E_PCH_E1S_TX_DP<2> SATA_6_PCIE3_6_USB3_6_TXP @S9S_MB_2U_LIB.S9S_MB_2U(SCH_1):P3E_PCH_E1S_TX_DP(2)
 V40 P3E_PCH_E1S_RX_DN<3> SATA_7_PCIE3_7_USB3_7_RXN @S9S_MB_2U_LIB.S9S_MB_2U(SCH_1):P3E_PCH_E1S_RX_DN(3)
 V42 P3E_PCH_E1S_RX_DP<3> SATA_7_PCIE3_7_USB3_7_RXP @S9S_MB_2U_LIB.S9S_MB_2U(SCH_1):P3E_PCH_E1S_RX_DP(3)
AF34 P3E_PCH_E1S_TX_DN<3> SATA_7_PCIE3_7_USB3_7_TXN @S9S_MB_2U_LIB.S9S_MB_2U(SCH_1):P3E_PCH_E1S_TX_DN(3)
AG36 P3E_PCH_E1S_TX_DP<3> SATA_7_PCIE3_7_USB3_7_TXP @S9S_MB_2U_LIB.S9S_MB_2U(SCH_1):P3E_PCH_E1S_TX_DP(3)
 U41 P3E_PCH_BMC_RX_DN SATA_8_PCIE3_8_USB3_8_RXN @S9S_MB_2U_LIB.S9S_MB_2U(SCH_1):P3E_PCH_BMC_RX_DN
 U43 P3E_PCH_BMC_RX_DP SATA_8_PCIE3_8_USB3_8_RXP @S9S_MB_2U_LIB.S9S_MB_2U(SCH_1):P3E_PCH_BMC_RX_DP
AE36 P3E_PCH_BMC_TX_DN SATA_8_PCIE3_8_USB3_8_TXN @S9S_MB_2U_LIB.S9S_MB_2U(SCH_1):P3E_PCH_BMC_TX_DN
AD37 P3E_PCH_BMC_TX_DP SATA_8_PCIE3_8_USB3_8_TXP @S9S_MB_2U_LIB.S9S_MB_2U(SCH_1):P3E_PCH_BMC_TX_DP
 R40 USB3_PCH_RX_BUF_DN<4> SATA_9_PCIE3_9_USB3_9_RXN @S9S_MB_2U_LIB.S9S_MB_2U(SCH_1):USB3_PCH_RX_BUF_DN(4)
 R42 USB3_PCH_RX_BUF_DP<4> SATA_9_PCIE3_9_USB3_9_RXP @S9S_MB_2U_LIB.S9S_MB_2U(SCH_1):USB3_PCH_RX_BUF_DP(4)
AE32 USB3_PCH_TX_DN<4> SATA_9_PCIE3_9_USB3_9_TXN @S9S_MB_2U_LIB.S9S_MB_2U(SCH_1):USB3_PCH_TX_DN(4)
AG32 USB3_PCH_TX_DP<4> SATA_9_PCIE3_9_USB3_9_TXP @S9S_MB_2U_LIB.S9S_MB_2U(SCH_1):USB3_PCH_TX_DP(4)


DRAWING: @S9S_MB_2U_LIB.S9S_MB_2U(SCH_1):PAGE329 

Q_CAP_C0402-100NF,50V,10%,EMPTA  I1  C2379
   1 UV_ADR_P2V5_COMP      A @S9S_MB_2U_LIB.S9S_MB_2U(SCH_1):UV_ADR_P2V5_COMP
   2    GND      B @S9S_MB_2U_LIB.S9S_MB_2U(SCH_1):GND

Q_RES_0402LF-5.11K,1%,1/16W,EMA  I2  R4775
   1 P12V_AUX_UV_ADR_TRIGGER      A @S9S_MB_2U_LIB.S9S_MB_2U(SCH_1):P12V_AUX_UV_ADR_TRIGGER
   2    GND      B @S9S_MB_2U_LIB.S9S_MB_2U(SCH_1):GND

LM4040AIM3X25NOPB-LM4040AIM3X-A  I3  U337
   1 UV_ADR_P2V5_COMP     1+ @S9S_MB_2U_LIB.S9S_MB_2U(SCH_1):UV_ADR_P2V5_COMP
   2    GND     2- @S9S_MB_2U_LIB.S9S_MB_2U(SCH_1):GND
   3     NC      3     NC

Q_RES_0402LF-10K,1%,1/16W,EMPTA  I6  R4784
   1 P3V3_AUX      A @S9S_MB_2U_LIB.S9S_MB_2U(SCH_1):P3V3_AUX
   2 FM_UV_ADR_TRIGGER_N      B @S9S_MB_2U_LIB.S9S_MB_2U(SCH_1):FM_UV_ADR_TRIGGER_N

Q_RES_0402LF-33.2,1%,1/16W,EMPA  I7  R4782
   1 FM_UV_ADR_TRIGGER_N_R2      A @S9S_MB_2U_LIB.S9S_MB_2U(SCH_1):FM_UV_ADR_TRIGGER_N_R2
   2 FM_UV_ADR_TRIGGER_N      B @S9S_MB_2U_LIB.S9S_MB_2U(SCH_1):FM_UV_ADR_TRIGGER_N

Q_RES_0402LF-1M,1%,1/16W,CHIP,A  I9  R4778
   1 P12V_AUX_UV_ADR_TRIGGER      A @S9S_MB_2U_LIB.S9S_MB_2U(SCH_1):P12V_AUX_UV_ADR_TRIGGER
   2 FM_UV_ADR_TRIGGER_N_R2      B @S9S_MB_2U_LIB.S9S_MB_2U(SCH_1):FM_UV_ADR_TRIGGER_N_R2

Q_CAP_C0402-100NF,50V,10%,EMPTA  I11  C2383
   1 P12V_AUX      A @S9S_MB_2U_LIB.S9S_MB_2U(SCH_1):P12V_AUX
   2    GND      B @S9S_MB_2U_LIB.S9S_MB_2U(SCH_1):GND

AP331AWG7-AP331AWG-7,SMLF,EMPTA  I12  U339
   3 P12V_AUX_UV_ADR_TRIGGER    IN+ @S9S_MB_2U_LIB.S9S_MB_2U(SCH_1):P12V_AUX_UV_ADR_TRIGGER
   1 UV_ADR_P2V5_COMP    IN- @S9S_MB_2U_LIB.S9S_MB_2U(SCH_1):UV_ADR_P2V5_COMP
   4 FM_UV_ADR_TRIGGER_N_R2 OUTPUT @S9S_MB_2U_LIB.S9S_MB_2U(SCH_1):FM_UV_ADR_TRIGGER_N_R2
   5 P12V_AUX    VCC @S9S_MB_2U_LIB.S9S_MB_2U(SCH_1):P12V_AUX
   2    GND    GND @S9S_MB_2U_LIB.S9S_MB_2U(SCH_1):GND

Q_CAP_C0402-100NF,50V,10%,EMPTA  I14  C2381
   1 P12V_AUX_UV_ADR_TRIGGER      A @S9S_MB_2U_LIB.S9S_MB_2U(SCH_1):P12V_AUX_UV_ADR_TRIGGER
   2    GND      B @S9S_MB_2U_LIB.S9S_MB_2U(SCH_1):GND

Q_RES_0402LF-17.8K,1%,1/16W,EMA  I17  R4774
   1 P12V_AUX      A @S9S_MB_2U_LIB.S9S_MB_2U(SCH_1):P12V_AUX
   2 P12V_AUX_UV_ADR_TRIGGER      B @S9S_MB_2U_LIB.S9S_MB_2U(SCH_1):P12V_AUX_UV_ADR_TRIGGER

Q_RES_0402LF-10K,1%,1/16W,EMPTA  I21  R4772
   1 P3V3_AUX      A @S9S_MB_2U_LIB.S9S_MB_2U(SCH_1):P3V3_AUX
   2 UV_ADR_P2V5_COMP      B @S9S_MB_2U_LIB.S9S_MB_2U(SCH_1):UV_ADR_P2V5_COMP

AP331AWG7-AP331AWG-7,SMLF,EMPTA  I23  U340
   3 P12V_AUX_UV_TRIGGER    IN+ @S9S_MB_2U_LIB.S9S_MB_2U(SCH_1):P12V_AUX_UV_TRIGGER
   1 UV_P2V5_COMP    IN- @S9S_MB_2U_LIB.S9S_MB_2U(SCH_1):UV_P2V5_COMP
   4 IRQ_UV_DETECT_R2_N OUTPUT @S9S_MB_2U_LIB.S9S_MB_2U(SCH_1):IRQ_UV_DETECT_R2_N
   5 P12V_AUX    VCC @S9S_MB_2U_LIB.S9S_MB_2U(SCH_1):P12V_AUX
   2    GND    GND @S9S_MB_2U_LIB.S9S_MB_2U(SCH_1):GND

Q_RES_0402LF-10K,1%,1/16W,EMPTA  I25  R4785
   1 P3V3_AUX      A @S9S_MB_2U_LIB.S9S_MB_2U(SCH_1):P3V3_AUX
   2 IRQ_UV_DETECT_N      B @S9S_MB_2U_LIB.S9S_MB_2U(SCH_1):IRQ_UV_DETECT_N

Q_RES_0402LF-33.2,1%,1/16W,EMPA  I27  R4783
   1 IRQ_UV_DETECT_R2_N      A @S9S_MB_2U_LIB.S9S_MB_2U(SCH_1):IRQ_UV_DETECT_R2_N
   2 IRQ_UV_DETECT_N      B @S9S_MB_2U_LIB.S9S_MB_2U(SCH_1):IRQ_UV_DETECT_N

Q_CAP_C0402-100NF,50V,10%,EMPTA  I29  C2384
   1 P12V_AUX      A @S9S_MB_2U_LIB.S9S_MB_2U(SCH_1):P12V_AUX
   2    GND      B @S9S_MB_2U_LIB.S9S_MB_2U(SCH_1):GND

Q_RES_0402LF-1M,1%,1/16W,CHIP,A  I31  R4779
   1 P12V_AUX_UV_TRIGGER      A @S9S_MB_2U_LIB.S9S_MB_2U(SCH_1):P12V_AUX_UV_TRIGGER
   2 IRQ_UV_DETECT_R2_N      B @S9S_MB_2U_LIB.S9S_MB_2U(SCH_1):IRQ_UV_DETECT_R2_N

Q_CAP_C0402-100NF,50V,10%,EMPTA  I33  C2382
   1 P12V_AUX_UV_TRIGGER      A @S9S_MB_2U_LIB.S9S_MB_2U(SCH_1):P12V_AUX_UV_TRIGGER
   2    GND      B @S9S_MB_2U_LIB.S9S_MB_2U(SCH_1):GND

Q_CAP_C0402-100NF,50V,10%,EMPTA  I35  C2380
   1 UV_P2V5_COMP      A @S9S_MB_2U_LIB.S9S_MB_2U(SCH_1):UV_P2V5_COMP
   2    GND      B @S9S_MB_2U_LIB.S9S_MB_2U(SCH_1):GND

Q_RES_0402LF-17.8K,1%,1/16W,EMA  I38  R4776
   1 P12V_AUX      A @S9S_MB_2U_LIB.S9S_MB_2U(SCH_1):P12V_AUX
   2 P12V_AUX_UV_TRIGGER      B @S9S_MB_2U_LIB.S9S_MB_2U(SCH_1):P12V_AUX_UV_TRIGGER

Q_RES_0402LF-5.11K,1%,1/16W,EMA  I39  R4777
   1 P12V_AUX_UV_TRIGGER      A @S9S_MB_2U_LIB.S9S_MB_2U(SCH_1):P12V_AUX_UV_TRIGGER
   2    GND      B @S9S_MB_2U_LIB.S9S_MB_2U(SCH_1):GND

Q_RES_0402LF-10K,1%,1/16W,EMPTA  I42  R4773
   1 P3V3_AUX      A @S9S_MB_2U_LIB.S9S_MB_2U(SCH_1):P3V3_AUX
   2 UV_P2V5_COMP      B @S9S_MB_2U_LIB.S9S_MB_2U(SCH_1):UV_P2V5_COMP

LM4040AIM3X25NOPB-LM4040AIM3X-A  I43  U338
   1 UV_P2V5_COMP     1+ @S9S_MB_2U_LIB.S9S_MB_2U(SCH_1):UV_P2V5_COMP
   2    GND     2- @S9S_MB_2U_LIB.S9S_MB_2U(SCH_1):GND
   3     NC      3     NC

AP331AWG7-AP331AWG-7,SMLF,EMPTA  I45  U342
   3 PWRGD_DSW_PWROK_TRIGGER    IN+ @S9S_MB_2U_LIB.S9S_MB_2U(SCH_1):PWRGD_DSW_PWROK_TRIGGER
   1 DSW_PWROK_P2V5_COMP    IN- @S9S_MB_2U_LIB.S9S_MB_2U(SCH_1):DSW_PWROK_P2V5_COMP
   4 PWRGD_DSW_PWROK_R5 OUTPUT @S9S_MB_2U_LIB.S9S_MB_2U(SCH_1):PWRGD_DSW_PWROK_R5
   5 P12V_AUX    VCC @S9S_MB_2U_LIB.S9S_MB_2U(SCH_1):P12V_AUX
   2    GND    GND @S9S_MB_2U_LIB.S9S_MB_2U(SCH_1):GND

Q_RES_0402LF-1M,1%,1/16W,EMPTYA  I46  R4787
   1 PWRGD_DSW_PWROK_TRIGGER      A @S9S_MB_2U_LIB.S9S_MB_2U(SCH_1):PWRGD_DSW_PWROK_TRIGGER
   2 PWRGD_DSW_PWROK_R5      B @S9S_MB_2U_LIB.S9S_MB_2U(SCH_1):PWRGD_DSW_PWROK_R5

Q_RES_0402LF-10K,1%,1/16W,EMPTA  I49  R4789
   1 P3V3_AUX      A @S9S_MB_2U_LIB.S9S_MB_2U(SCH_1):P3V3_AUX
   2 PWRGD_DSW_PWROK      B @S9S_MB_2U_LIB.S9S_MB_2U(SCH_1):PWRGD_DSW_PWROK

Q_RES_0402LF-33.2,1%,1/16W,EMPA  I50  R4788
   1 PWRGD_DSW_PWROK_R5      A @S9S_MB_2U_LIB.S9S_MB_2U(SCH_1):PWRGD_DSW_PWROK_R5
   2 PWRGD_DSW_PWROK      B @S9S_MB_2U_LIB.S9S_MB_2U(SCH_1):PWRGD_DSW_PWROK

Q_CAP_C0402-100NF,50V,10%,EMPTA  I51  C2387
   1 P12V_AUX      A @S9S_MB_2U_LIB.S9S_MB_2U(SCH_1):P12V_AUX
   2    GND      B @S9S_MB_2U_LIB.S9S_MB_2U(SCH_1):GND

Q_CAP_C0402-100NF,50V,10%,EMPTA  I55  C2386
   1 PWRGD_DSW_PWROK_TRIGGER      A @S9S_MB_2U_LIB.S9S_MB_2U(SCH_1):PWRGD_DSW_PWROK_TRIGGER
   2    GND      B @S9S_MB_2U_LIB.S9S_MB_2U(SCH_1):GND

Q_CAP_C0402-100NF,50V,10%,EMPTA  I57  C2385
   1 DSW_PWROK_P2V5_COMP      A @S9S_MB_2U_LIB.S9S_MB_2U(SCH_1):DSW_PWROK_P2V5_COMP
   2    GND      B @S9S_MB_2U_LIB.S9S_MB_2U(SCH_1):GND

LM4040AIM3X25NOPB-LM4040AIM3X-A  I63  U341
   1 DSW_PWROK_P2V5_COMP     1+ @S9S_MB_2U_LIB.S9S_MB_2U(SCH_1):DSW_PWROK_P2V5_COMP
   2    GND     2- @S9S_MB_2U_LIB.S9S_MB_2U(SCH_1):GND
   3     NC      3     NC

Q_RES_0402LF-10K,1%,1/16W,EMPTA  I65  R4786
   1 P3V3_AUX      A @S9S_MB_2U_LIB.S9S_MB_2U(SCH_1):P3V3_AUX
   2 DSW_PWROK_P2V5_COMP      B @S9S_MB_2U_LIB.S9S_MB_2U(SCH_1):DSW_PWROK_P2V5_COMP

Q_RES_0402LF-4.75K,1%,1/16W,EMA  I67  R4790
   1 P12V_AUX      A @S9S_MB_2U_LIB.S9S_MB_2U(SCH_1):P12V_AUX
   2 PWRGD_DSW_PWROK_TRIGGER      B @S9S_MB_2U_LIB.S9S_MB_2U(SCH_1):PWRGD_DSW_PWROK_TRIGGER

Q_RES_0402LF-2K,1%,1/16W,EMPTYA  I68  R4791
   1 PWRGD_DSW_PWROK_TRIGGER      A @S9S_MB_2U_LIB.S9S_MB_2U(SCH_1):PWRGD_DSW_PWROK_TRIGGER
   2    GND      B @S9S_MB_2U_LIB.S9S_MB_2U(SCH_1):GND


DRAWING: @S9S_MB_2U_LIB.S9S_MB_2U(SCH_1):PAGE245 

Q_DIODE_SMLF-SDMK0340L-7-F,IC,A  I71  D145
   1 MB0_P12V_STBY_PWRGD      1 @S9S_MB_2U_LIB.S9S_MB_2U(SCH_1):MB0_P12V_STBY_PWRGD
   2 P3V3_AUX_EN      2 @S9S_MB_2U_LIB.S9S_MB_2U(SCH_1):P3V3_AUX_EN

Q_RES_0402LF-100K,1%,1/16W,CHIA  I72  R1571
   1 MB0_P12V_STBY_PWRGD      A @S9S_MB_2U_LIB.S9S_MB_2U(SCH_1):MB0_P12V_STBY_PWRGD
   2 P3V3_AUX_EN      B @S9S_MB_2U_LIB.S9S_MB_2U(SCH_1):P3V3_AUX_EN

Q_CAP_C0402-0.22UF,25V,10%,X7RA  I73  C2541
   1 P3V3_AUX_EN      A @S9S_MB_2U_LIB.S9S_MB_2U(SCH_1):P3V3_AUX_EN
   2    GND      B @S9S_MB_2U_LIB.S9S_MB_2U(SCH_1):GND

Q_RES_0402LF-86.6K,1%,1/16W,EMA  I76  R3118
   1 P3V3_AUX_EN      A @S9S_MB_2U_LIB.S9S_MB_2U(SCH_1):P3V3_AUX_EN
   2    GND      B @S9S_MB_2U_LIB.S9S_MB_2U(SCH_1):GND

Q_RES_0402LF-510K,5%,1/16W,EMPA  I78  R3117
   1 P12V_AUX      A @S9S_MB_2U_LIB.S9S_MB_2U(SCH_1):P12V_AUX
   2 P3V3_AUX_EN      B @S9S_MB_2U_LIB.S9S_MB_2U(SCH_1):P3V3_AUX_EN

Q_RES_0402LF-0,5%,1/16W,CHIP,CA  I84  PR832
   1 P3V3_AUX_MODE      A @S9S_MB_2U_LIB.S9S_MB_2U(SCH_1):P3V3_AUX_MODE
   2    GND      B @S9S_MB_2U_LIB.S9S_MB_2U(SCH_1):GND

Q_CAP_C0603-4.7UF,16V,10%,X6S,A  I86  PC581
   1 P3V3_AUX_VDRV      A @S9S_MB_2U_LIB.S9S_MB_2U(SCH_1):P3V3_AUX_VDRV
   2    GND      B @S9S_MB_2U_LIB.S9S_MB_2U(SCH_1):GND

Q_RES_0402LF-1.5K,1%,1/16W,EMPA  I89  PR833
   1 P3V3_AUX_SS      A @S9S_MB_2U_LIB.S9S_MB_2U(SCH_1):P3V3_AUX_SS
   2    GND      B @S9S_MB_2U_LIB.S9S_MB_2U(SCH_1):GND

Q_RES_0402LF-21.5K,1%,1/16W,CHA  I91  PR834
   1 P3V3_AUX_ILIM      A @S9S_MB_2U_LIB.S9S_MB_2U(SCH_1):P3V3_AUX_ILIM
   2    GND      B @S9S_MB_2U_LIB.S9S_MB_2U(SCH_1):GND

Q_CAP_C0603-2.2UF,16V,10%,X6S,A  I93  PC591
   1 P3V3_AUX_VCC      A @S9S_MB_2U_LIB.S9S_MB_2U(SCH_1):P3V3_AUX_VCC
   2    GND      B @S9S_MB_2U_LIB.S9S_MB_2U(SCH_1):GND

Q_RES_0402LF-1,1%,1/16W,CHIP,CA  I94  PR389
   1 P3V3_AUX_VDRV      A @S9S_MB_2U_LIB.S9S_MB_2U(SCH_1):P3V3_AUX_VDRV
   2 P3V3_AUX_VCC      B @S9S_MB_2U_LIB.S9S_MB_2U(SCH_1):P3V3_AUX_VCC

IR3889MTRPBF-IR3889MTRPBF,SMLFA  I95  PU9
  34 NC_PU9_2    NC3 @S9S_MB_2U_LIB.S9S_MB_2U(SCH_1):NC_PU9_2
  36 P3V3_AUX_MODE TON||MODE @S9S_MB_2U_LIB.S9S_MB_2U(SCH_1):P3V3_AUX_MODE
   3 P12V_AUX    VIN @S9S_MB_2U_LIB.S9S_MB_2U(SCH_1):P12V_AUX
  30 P3V3_AUX_FB     FB @S9S_MB_2U_LIB.S9S_MB_2U(SCH_1):P3V3_AUX_FB
  26 SW_P3V3_AUX_BOOT   BOOT @S9S_MB_2U_LIB.S9S_MB_2U(SCH_1):SW_P3V3_AUX_BOOT
   1 P3V3_AUX_ILIM   ILIM @S9S_MB_2U_LIB.S9S_MB_2U(SCH_1):P3V3_AUX_ILIM
  25 SW_P3V3_AUX_BOOTR  PHASE @S9S_MB_2U_LIB.S9S_MB_2U(SCH_1):SW_P3V3_AUX_BOOTR
   4 P3V3_AUX_VCC VCC||LDO @S9S_MB_2U_LIB.S9S_MB_2U(SCH_1):P3V3_AUX_VCC
  31    GND  VSENM @S9S_MB_2U_LIB.S9S_MB_2U(SCH_1):GND
  35 NC_HICCUP    NC4 @S9S_MB_2U_LIB.S9S_MB_2U(SCH_1):NC_HICCUP
7_10-19    GND   PGND @S9S_MB_2U_LIB.S9S_MB_2U(SCH_1):GND
  33 NC_PU9_1    NC2 @S9S_MB_2U_LIB.S9S_MB_2U(SCH_1):NC_PU9_1
11_18 SW_P3V3_AUX_SW     SW @S9S_MB_2U_LIB.S9S_MB_2U(SCH_1):SW_P3V3_AUX_SW
20_24 SW_P3V3_AUX_FLT   PVIN @S9S_MB_2U_LIB.S9S_MB_2U(SCH_1):SW_P3V3_AUX_FLT
   2 PWRGD_P3V3_AUX  PGOOD @S9S_MB_2U_LIB.S9S_MB_2U(SCH_1):PWRGD_P3V3_AUX
  28 P3V3_AUX_VOS    NC1 @S9S_MB_2U_LIB.S9S_MB_2U(SCH_1):P3V3_AUX_VOS
  32    GND   AGND @S9S_MB_2U_LIB.S9S_MB_2U(SCH_1):GND
  27 P3V3_AUX_EN     EN @S9S_MB_2U_LIB.S9S_MB_2U(SCH_1):P3V3_AUX_EN
   5 P3V3_AUX_VDRV   VDRV @S9S_MB_2U_LIB.S9S_MB_2U(SCH_1):P3V3_AUX_VDRV
   6 NC_PU9_3 GATEL1 @S9S_MB_2U_LIB.S9S_MB_2U(SCH_1):NC_PU9_3
  29 P3V3_AUX_SS SS||LATCH @S9S_MB_2U_LIB.S9S_MB_2U(SCH_1):P3V3_AUX_SS
  37 NC_PU9_4 GATEL2 @S9S_MB_2U_LIB.S9S_MB_2U(SCH_1):NC_PU9_4

Q_CAP_C0402-100NF,50V,10%,X7R,A  I97  PC1649
   1 P12V_AUX      A @S9S_MB_2U_LIB.S9S_MB_2U(SCH_1):P12V_AUX
   2    GND      B @S9S_MB_2U_LIB.S9S_MB_2U(SCH_1):GND

Q_INDUCTOR_SMLF-100NH/16A,IND,A  I98  PL45
   2 SW_P3V3_AUX_FLT      2 @S9S_MB_2U_LIB.S9S_MB_2U(SCH_1):SW_P3V3_AUX_FLT
   1 P12V_AUX      1 @S9S_MB_2U_LIB.S9S_MB_2U(SCH_1):P12V_AUX

Q_CAP_C0805-22UF,16V,20%,X6S,CA  I100  PC2260
   1 SW_P3V3_AUX_FLT      A @S9S_MB_2U_LIB.S9S_MB_2U(SCH_1):SW_P3V3_AUX_FLT
   2    GND      B @S9S_MB_2U_LIB.S9S_MB_2U(SCH_1):GND

Q_CAP_C0805-22UF,16V,20%,X6S,CA  I101  PC2261
   1 SW_P3V3_AUX_FLT      A @S9S_MB_2U_LIB.S9S_MB_2U(SCH_1):SW_P3V3_AUX_FLT
   2    GND      B @S9S_MB_2U_LIB.S9S_MB_2U(SCH_1):GND

Q_CAPP_THLF-270UF,16V,20%,OSCOA  I103  PC3
   1 SW_P3V3_AUX_FLT      A @S9S_MB_2U_LIB.S9S_MB_2U(SCH_1):SW_P3V3_AUX_FLT
   2    GND      B @S9S_MB_2U_LIB.S9S_MB_2U(SCH_1):GND

Q_CAPP_THLF-270UF,16V,20%,OSCOA  I104  PC566
   1 SW_P3V3_AUX_FLT      A @S9S_MB_2U_LIB.S9S_MB_2U(SCH_1):SW_P3V3_AUX_FLT
   2    GND      B @S9S_MB_2U_LIB.S9S_MB_2U(SCH_1):GND

Q_CAP_C0805-22UF,16V,20%,X6S,CA  I105  PC2262
   1 SW_P3V3_AUX_FLT      A @S9S_MB_2U_LIB.S9S_MB_2U(SCH_1):SW_P3V3_AUX_FLT
   2    GND      B @S9S_MB_2U_LIB.S9S_MB_2U(SCH_1):GND

Q_CAP_C0805-22UF,16V,20%,X6S,CA  I106  PC567
   1 SW_P3V3_AUX_FLT      A @S9S_MB_2U_LIB.S9S_MB_2U(SCH_1):SW_P3V3_AUX_FLT
   2    GND      B @S9S_MB_2U_LIB.S9S_MB_2U(SCH_1):GND

Q_CAP_C0805-22UF,16V,20%,X6S,CA  I107  PC2263
   1 SW_P3V3_AUX_FLT      A @S9S_MB_2U_LIB.S9S_MB_2U(SCH_1):SW_P3V3_AUX_FLT
   2    GND      B @S9S_MB_2U_LIB.S9S_MB_2U(SCH_1):GND

Q_CAP_C0805-22UF,16V,20%,X6S,CA  I108  PC2342
   1 SW_P3V3_AUX_FLT      A @S9S_MB_2U_LIB.S9S_MB_2U(SCH_1):SW_P3V3_AUX_FLT
   2    GND      B @S9S_MB_2U_LIB.S9S_MB_2U(SCH_1):GND

Q_CAP_C0805-22UF,16V,20%,X6S,CA  I109  PC570
   1 SW_P3V3_AUX_FLT      A @S9S_MB_2U_LIB.S9S_MB_2U(SCH_1):SW_P3V3_AUX_FLT
   2    GND      B @S9S_MB_2U_LIB.S9S_MB_2U(SCH_1):GND

Q_CAP_C0805-22UF,16V,20%,X6S,CA  I110  PC571
   1 SW_P3V3_AUX_FLT      A @S9S_MB_2U_LIB.S9S_MB_2U(SCH_1):SW_P3V3_AUX_FLT
   2    GND      B @S9S_MB_2U_LIB.S9S_MB_2U(SCH_1):GND

Q_CAP_C0805-22UF,16V,20%,X6S,CA  I111  PC2343
   1 SW_P3V3_AUX_FLT      A @S9S_MB_2U_LIB.S9S_MB_2U(SCH_1):SW_P3V3_AUX_FLT
   2    GND      B @S9S_MB_2U_LIB.S9S_MB_2U(SCH_1):GND

Q_CAP_C0805-22UF,16V,20%,X6S,CA  I112  PC2344
   1 SW_P3V3_AUX_FLT      A @S9S_MB_2U_LIB.S9S_MB_2U(SCH_1):SW_P3V3_AUX_FLT
   2    GND      B @S9S_MB_2U_LIB.S9S_MB_2U(SCH_1):GND

Q_CAP_C0805-22UF,16V,20%,X6S,CA  I113  PC576
   1 SW_P3V3_AUX_FLT      A @S9S_MB_2U_LIB.S9S_MB_2U(SCH_1):SW_P3V3_AUX_FLT
   2    GND      B @S9S_MB_2U_LIB.S9S_MB_2U(SCH_1):GND

Q_CAP_C0805-22UF,16V,20%,X6S,CA  I114  PC71
   1 SW_P3V3_AUX_FLT      A @S9S_MB_2U_LIB.S9S_MB_2U(SCH_1):SW_P3V3_AUX_FLT
   2    GND      B @S9S_MB_2U_LIB.S9S_MB_2U(SCH_1):GND

Q_CAP_0402-0.1UF,25V,10%,X7R,CA  I115  PC577
   1 SW_P3V3_AUX_FLT      A @S9S_MB_2U_LIB.S9S_MB_2U(SCH_1):SW_P3V3_AUX_FLT
   2    GND      B @S9S_MB_2U_LIB.S9S_MB_2U(SCH_1):GND

Q_CAP_C0603-4.7UF,16V,10%,X6S,A  I118  PC8
   1 P12V_AUX      A @S9S_MB_2U_LIB.S9S_MB_2U(SCH_1):P12V_AUX
   2    GND      B @S9S_MB_2U_LIB.S9S_MB_2U(SCH_1):GND

Q_RES_0402LF-1K,1%,1/16W,EMPTYA  I121  PR836
   1 P3V3_AUX_VOS      A @S9S_MB_2U_LIB.S9S_MB_2U(SCH_1):P3V3_AUX_VOS
   2 P3V3_AUX      B @S9S_MB_2U_LIB.S9S_MB_2U(SCH_1):P3V3_AUX

Q_CAP_C0402-0.22UF,25V,10%,X7RA  I122  PC568
   1 SW_P3V3_AUX_BOOTR      A @S9S_MB_2U_LIB.S9S_MB_2U(SCH_1):SW_P3V3_AUX_BOOTR
   2 SW_P3V3_AUX_BOOT_R      B @S9S_MB_2U_LIB.S9S_MB_2U(SCH_1):SW_P3V3_AUX_BOOT_R

Q_RES_0402LF-0,5%,1/16W,CHIP,CA  I123  PR835
   1 SW_P3V3_AUX_BOOT      A @S9S_MB_2U_LIB.S9S_MB_2U(SCH_1):SW_P3V3_AUX_BOOT
   2 SW_P3V3_AUX_BOOT_R      B @S9S_MB_2U_LIB.S9S_MB_2U(SCH_1):SW_P3V3_AUX_BOOT_R

Q_RES_0402LF-15K,0.1%,1/16W,CHA  I125  PR830
   1 P3V3_AUX_FB      A @S9S_MB_2U_LIB.S9S_MB_2U(SCH_1):P3V3_AUX_FB
   2    GND      B @S9S_MB_2U_LIB.S9S_MB_2U(SCH_1):GND

Q_CAP_0402-220PF,50V,10%,X7R,TA  I127  PC569
   1 P3V3_AUX_FB      A @S9S_MB_2U_LIB.S9S_MB_2U(SCH_1):P3V3_AUX_FB
   2 P3V3_AUX      B @S9S_MB_2U_LIB.S9S_MB_2U(SCH_1):P3V3_AUX

Q_RES_0402LF-47K,0.1%,1/16W,CHA  I128  PR831
   1 P3V3_AUX_FB      A @S9S_MB_2U_LIB.S9S_MB_2U(SCH_1):P3V3_AUX_FB
   2 P3V3_AUX      B @S9S_MB_2U_LIB.S9S_MB_2U(SCH_1):P3V3_AUX

Q_INDUCTOR_SMLF-1.5UH/53A,IND,A  I129  PL66
   2 P3V3_AUX      2 @S9S_MB_2U_LIB.S9S_MB_2U(SCH_1):P3V3_AUX
   1 SW_P3V3_AUX_SW      1 @S9S_MB_2U_LIB.S9S_MB_2U(SCH_1):SW_P3V3_AUX_SW

Q_CAPP_THLF-560UF,6.3V,20%,OSCA  I131  PC1866
   1 P3V3_AUX      A @S9S_MB_2U_LIB.S9S_MB_2U(SCH_1):P3V3_AUX
   2    GND      B @S9S_MB_2U_LIB.S9S_MB_2U(SCH_1):GND

Q_CAPP_THLF-560UF,6.3V,20%,OSCA  I132  PC1867
   1 P3V3_AUX      A @S9S_MB_2U_LIB.S9S_MB_2U(SCH_1):P3V3_AUX
   2    GND      B @S9S_MB_2U_LIB.S9S_MB_2U(SCH_1):GND

Q_CAP_C0805-22UF,10V,20%,X6S,CA  I133  PC1868
   1 P3V3_AUX      A @S9S_MB_2U_LIB.S9S_MB_2U(SCH_1):P3V3_AUX
   2    GND      B @S9S_MB_2U_LIB.S9S_MB_2U(SCH_1):GND

Q_CAP_C0805-22UF,10V,20%,X6S,CA  I134  PC1599
   1 P3V3_AUX      A @S9S_MB_2U_LIB.S9S_MB_2U(SCH_1):P3V3_AUX
   2    GND      B @S9S_MB_2U_LIB.S9S_MB_2U(SCH_1):GND

Q_CAP_C0805-22UF,10V,20%,X6S,CA  I136  PC1600
   1 P3V3_AUX      A @S9S_MB_2U_LIB.S9S_MB_2U(SCH_1):P3V3_AUX
   2    GND      B @S9S_MB_2U_LIB.S9S_MB_2U(SCH_1):GND

Q_CAP_0402-0.1UF,25V,10%,X7R,CA  I137  PC1869
   1 P3V3_AUX      A @S9S_MB_2U_LIB.S9S_MB_2U(SCH_1):P3V3_AUX
   2    GND      B @S9S_MB_2U_LIB.S9S_MB_2U(SCH_1):GND

Q_RES_0402LF-10K,1%,1/16W,CHIPA  I139  PR73
   1 P3V3_AUX      A @S9S_MB_2U_LIB.S9S_MB_2U(SCH_1):P3V3_AUX
   2 PWRGD_P3V3_AUX      B @S9S_MB_2U_LIB.S9S_MB_2U(SCH_1):PWRGD_P3V3_AUX


DRAWING: @S9S_MB_2U_LIB.S9S_MB_2U(SCH_1):PAGE121 

Q_RES_0402LF-100,1%,1/16W,CHIPA  I4  R4396
   1 PVNN_TERM_CPU1      A @S9S_MB_2U_LIB.S9S_MB_2U(SCH_1):PVNN_TERM_CPU1
   2 H_CPU1_THERMTRIP_LVC1_R_N      B @S9S_MB_2U_LIB.S9S_MB_2U(SCH_1):H_CPU1_THERMTRIP_LVC1_R_N

Q_RES_0402LF-0,5%,1/16W,CHIP,CA  I5  R240
   1 H_CPU1_PROCHOT_LVC1_R_N      A @S9S_MB_2U_LIB.S9S_MB_2U(SCH_1):H_CPU1_PROCHOT_LVC1_R_N
   2 H_CPU1_PROCHOT_LVC1_N      B @S9S_MB_2U_LIB.S9S_MB_2U(SCH_1):H_CPU1_PROCHOT_LVC1_N

Q_RES_0402LF-1.5K,1%,1/16W,CHIA  I6  R238
   1 H_CPU1_THERMTRIP_LVC1_R_N      A @S9S_MB_2U_LIB.S9S_MB_2U(SCH_1):H_CPU1_THERMTRIP_LVC1_R_N
   2 H_CPU1_THERMTRIP_VT_R_N      B @S9S_MB_2U_LIB.S9S_MB_2U(SCH_1):H_CPU1_THERMTRIP_VT_R_N

Q_RES_0402LF-0,5%,1/16W,CHIP,CA  I7  R239
   1 H_CPU0_PROCHOT_LVC1_R_N      A @S9S_MB_2U_LIB.S9S_MB_2U(SCH_1):H_CPU0_PROCHOT_LVC1_R_N
   2 H_CPU0_PROCHOT_LVC1_N      B @S9S_MB_2U_LIB.S9S_MB_2U(SCH_1):H_CPU0_PROCHOT_LVC1_N

BC847BPN-BC847BPN,SMLF,IC,BA00A  I8  Q139
   5 H_CPU1_THERMTRIP_VT_R_N     B2 @S9S_MB_2U_LIB.S9S_MB_2U(SCH_1):H_CPU1_THERMTRIP_VT_R_N
   3 H_CPU1_THERMTRIP_N     C2 @S9S_MB_2U_LIB.S9S_MB_2U(SCH_1):H_CPU1_THERMTRIP_N
   4 PVNN_TERM_CPU1     E2 @S9S_MB_2U_LIB.S9S_MB_2U(SCH_1):PVNN_TERM_CPU1

Q_RES_0402LF-1.5K,1%,1/16W,CHIA  I10  R4398
   1 H_CPU1_THERMTRIP_N      A @S9S_MB_2U_LIB.S9S_MB_2U(SCH_1):H_CPU1_THERMTRIP_N
   2 H_CPU1_THERMTRIP_R_N      B @S9S_MB_2U_LIB.S9S_MB_2U(SCH_1):H_CPU1_THERMTRIP_R_N

Q_RES_0402LF-100,1%,1/16W,CHIPA  I13  R4395
   1 PVNN_TERM_CPU0      A @S9S_MB_2U_LIB.S9S_MB_2U(SCH_1):PVNN_TERM_CPU0
   2 H_CPU0_THERMTRIP_LVC1_R_N      B @S9S_MB_2U_LIB.S9S_MB_2U(SCH_1):H_CPU0_THERMTRIP_LVC1_R_N

Q_RES_0402LF-1.5K,1%,1/16W,CHIA  I15  R237
   1 H_CPU0_THERMTRIP_LVC1_R_N      A @S9S_MB_2U_LIB.S9S_MB_2U(SCH_1):H_CPU0_THERMTRIP_LVC1_R_N
   2 H_CPU0_THERMTRIP_VT_R_N      B @S9S_MB_2U_LIB.S9S_MB_2U(SCH_1):H_CPU0_THERMTRIP_VT_R_N

Q_RES_0402LF-1.5K,1%,1/16W,CHIA  I16  R4397
   1 H_CPU0_THERMTRIP_N      A @S9S_MB_2U_LIB.S9S_MB_2U(SCH_1):H_CPU0_THERMTRIP_N
   2 H_CPU0_THERMTRIP_R_N      B @S9S_MB_2U_LIB.S9S_MB_2U(SCH_1):H_CPU0_THERMTRIP_R_N

BC847BPN-BC847BPN,SMLF,IC,BA00A  I17  Q138
   5 H_CPU0_THERMTRIP_VT_R_N     B2 @S9S_MB_2U_LIB.S9S_MB_2U(SCH_1):H_CPU0_THERMTRIP_VT_R_N
   3 H_CPU0_THERMTRIP_N     C2 @S9S_MB_2U_LIB.S9S_MB_2U(SCH_1):H_CPU0_THERMTRIP_N
   4 PVNN_TERM_CPU0     E2 @S9S_MB_2U_LIB.S9S_MB_2U(SCH_1):PVNN_TERM_CPU0

Q_RES_0402LF-100,1%,1/16W,CHIPA  I19  R244
   1 PVNN_TERM_CPU1      A @S9S_MB_2U_LIB.S9S_MB_2U(SCH_1):PVNN_TERM_CPU1
   2 H_CPU1_PROCHOT_LVC1_N      B @S9S_MB_2U_LIB.S9S_MB_2U(SCH_1):H_CPU1_PROCHOT_LVC1_N

BC847BPN-BC847BPN,SMLF,IC,BA00A  I21  Q139
   2 H_CPU1_THERMTRIP_R_N     B1 @S9S_MB_2U_LIB.S9S_MB_2U(SCH_1):H_CPU1_THERMTRIP_R_N
   6 H_CPU1_THERMTRIP_VT_N     C1 @S9S_MB_2U_LIB.S9S_MB_2U(SCH_1):H_CPU1_THERMTRIP_VT_N
   1    GND     E1 @S9S_MB_2U_LIB.S9S_MB_2U(SCH_1):GND

Q_RES_0402LF-100,1%,1/16W,CHIPA  I23  R243
   1 PVNN_TERM_CPU0      A @S9S_MB_2U_LIB.S9S_MB_2U(SCH_1):PVNN_TERM_CPU0
   2 H_CPU0_PROCHOT_LVC1_N      B @S9S_MB_2U_LIB.S9S_MB_2U(SCH_1):H_CPU0_PROCHOT_LVC1_N

Q_RES_0402LF-4.75K,1%,1/16W,CHA  I26  R242
   1   P3V3      A @S9S_MB_2U_LIB.S9S_MB_2U(SCH_1):P3V3
   2 H_CPU1_THERMTRIP_VT_N      B @S9S_MB_2U_LIB.S9S_MB_2U(SCH_1):H_CPU1_THERMTRIP_VT_N

Q_RES_0402LF-33.2,1%,1/16W,CHIA  I29  R4400
   1 H_CPU1_THERMTRIP_VT_N      A @S9S_MB_2U_LIB.S9S_MB_2U(SCH_1):H_CPU1_THERMTRIP_VT_N
   2 H_CPU1_THERMTRIP_LVC1_N      B @S9S_MB_2U_LIB.S9S_MB_2U(SCH_1):H_CPU1_THERMTRIP_LVC1_N

BC847BPN-BC847BPN,SMLF,IC,BA00A  I31  Q138
   2 H_CPU0_THERMTRIP_R_N     B1 @S9S_MB_2U_LIB.S9S_MB_2U(SCH_1):H_CPU0_THERMTRIP_R_N
   6 H_CPU0_THERMTRIP_VT_N     C1 @S9S_MB_2U_LIB.S9S_MB_2U(SCH_1):H_CPU0_THERMTRIP_VT_N
   1    GND     E1 @S9S_MB_2U_LIB.S9S_MB_2U(SCH_1):GND

Q_RES_0402LF-4.75K,1%,1/16W,CHA  I33  R241
   1   P3V3      A @S9S_MB_2U_LIB.S9S_MB_2U(SCH_1):P3V3
   2 H_CPU0_THERMTRIP_VT_N      B @S9S_MB_2U_LIB.S9S_MB_2U(SCH_1):H_CPU0_THERMTRIP_VT_N

Q_RES_0402LF-33.2,1%,1/16W,CHIA  I35  R4399
   1 H_CPU0_THERMTRIP_VT_N      A @S9S_MB_2U_LIB.S9S_MB_2U(SCH_1):H_CPU0_THERMTRIP_VT_N
   2 H_CPU0_THERMTRIP_LVC1_N      B @S9S_MB_2U_LIB.S9S_MB_2U(SCH_1):H_CPU0_THERMTRIP_LVC1_N


DRAWING: @S9S_MB_2U_LIB.S9S_MB_2U(SCH_1):PAGE122 

Q_RES_0402LF-100,1%,1/16W,CHIPA  I5  R4402
   1 PVNN_TERM_CPU1      A @S9S_MB_2U_LIB.S9S_MB_2U(SCH_1):PVNN_TERM_CPU1
   2 H_CPU1_MEMHOT_OUT_LVC1_R_N      B @S9S_MB_2U_LIB.S9S_MB_2U(SCH_1):H_CPU1_MEMHOT_OUT_LVC1_R_N

Q_RES_0402LF-1.5K,1%,1/16W,CHIA  I6  R204
   1 H_CPU1_MEMHOT_OUT_LVC1_R_N      A @S9S_MB_2U_LIB.S9S_MB_2U(SCH_1):H_CPU1_MEMHOT_OUT_LVC1_R_N
   2 H_CPU1_MEMHOT_OUT_VT_R_N      B @S9S_MB_2U_LIB.S9S_MB_2U(SCH_1):H_CPU1_MEMHOT_OUT_VT_R_N

Q_RES_0402LF-100,1%,1/16W,CHIPA  I8  R4401
   1 PVNN_TERM_CPU0      A @S9S_MB_2U_LIB.S9S_MB_2U(SCH_1):PVNN_TERM_CPU0
   2 H_CPU0_MEMHOT_OUT_LVC1_R_N      B @S9S_MB_2U_LIB.S9S_MB_2U(SCH_1):H_CPU0_MEMHOT_OUT_LVC1_R_N

Q_RES_0402LF-1.5K,1%,1/16W,CHIA  I9  R203
   1 H_CPU0_MEMHOT_OUT_LVC1_R_N      A @S9S_MB_2U_LIB.S9S_MB_2U(SCH_1):H_CPU0_MEMHOT_OUT_LVC1_R_N
   2 H_CPU0_MEMHOT_OUT_VT_R_N      B @S9S_MB_2U_LIB.S9S_MB_2U(SCH_1):H_CPU0_MEMHOT_OUT_VT_R_N

BC847BPN-BC847BPN,SMLF,IC,BA00A  I10  Q142
   5 H_CPU1_MEMHOT_OUT_VT_R_N     B2 @S9S_MB_2U_LIB.S9S_MB_2U(SCH_1):H_CPU1_MEMHOT_OUT_VT_R_N
   3 H_CPU1_MEMHOT_OUT     C2 @S9S_MB_2U_LIB.S9S_MB_2U(SCH_1):H_CPU1_MEMHOT_OUT
   4 PVNN_TERM_CPU1     E2 @S9S_MB_2U_LIB.S9S_MB_2U(SCH_1):PVNN_TERM_CPU1

BC847BPN-BC847BPN,SMLF,IC,BA00A  I12  Q143
   5 H_CPU0_MEMHOT_OUT_VT_R_N     B2 @S9S_MB_2U_LIB.S9S_MB_2U(SCH_1):H_CPU0_MEMHOT_OUT_VT_R_N
   3 H_CPU0_MEMHOT_OUT     C2 @S9S_MB_2U_LIB.S9S_MB_2U(SCH_1):H_CPU0_MEMHOT_OUT
   4 PVNN_TERM_CPU0     E2 @S9S_MB_2U_LIB.S9S_MB_2U(SCH_1):PVNN_TERM_CPU0

Q_RES_0402LF-0,5%,1/16W,CHIP,CA  I15  R210
   1 H_CPU1_MEMHOT_IN_LVC1_R_N      A @S9S_MB_2U_LIB.S9S_MB_2U(SCH_1):H_CPU1_MEMHOT_IN_LVC1_R_N
   2 H_CPU1_MEMHOT_IN_LVC1_R1_N      B @S9S_MB_2U_LIB.S9S_MB_2U(SCH_1):H_CPU1_MEMHOT_IN_LVC1_R1_N

Q_RES_0402LF-0,5%,1/16W,CHIP,CA  I16  R208
   1 H_CPU0_MEMHOT_IN_LVC1_R_N      A @S9S_MB_2U_LIB.S9S_MB_2U(SCH_1):H_CPU0_MEMHOT_IN_LVC1_R_N
   2 H_CPU0_MEMHOT_IN_LVC1_R1_N      B @S9S_MB_2U_LIB.S9S_MB_2U(SCH_1):H_CPU0_MEMHOT_IN_LVC1_R1_N

BC847BPN-BC847BPN,SMLF,IC,BA00A  I17  Q142
   2 H_CPU1_MEMHOT_OUT_R     B1 @S9S_MB_2U_LIB.S9S_MB_2U(SCH_1):H_CPU1_MEMHOT_OUT_R
   6 H_CPU1_MEMHOT_OUT_VT_N     C1 @S9S_MB_2U_LIB.S9S_MB_2U(SCH_1):H_CPU1_MEMHOT_OUT_VT_N
   1    GND     E1 @S9S_MB_2U_LIB.S9S_MB_2U(SCH_1):GND

Q_RES_0402LF-33.2,1%,1/16W,CHIA  I18  R4408
   1 H_CPU1_MEMHOT_OUT_VT_N      A @S9S_MB_2U_LIB.S9S_MB_2U(SCH_1):H_CPU1_MEMHOT_OUT_VT_N
   2 H_CPU1_MEMHOT_OUT_LVC1_N      B @S9S_MB_2U_LIB.S9S_MB_2U(SCH_1):H_CPU1_MEMHOT_OUT_LVC1_N

Q_RES_0402LF-1.5K,1%,1/16W,CHIA  I20  R4404
   1 H_CPU1_MEMHOT_OUT      A @S9S_MB_2U_LIB.S9S_MB_2U(SCH_1):H_CPU1_MEMHOT_OUT
   2 H_CPU1_MEMHOT_OUT_R      B @S9S_MB_2U_LIB.S9S_MB_2U(SCH_1):H_CPU1_MEMHOT_OUT_R

Q_RES_0402LF-1.5K,1%,1/16W,CHIA  I21  R4403
   1 H_CPU0_MEMHOT_OUT      A @S9S_MB_2U_LIB.S9S_MB_2U(SCH_1):H_CPU0_MEMHOT_OUT
   2 H_CPU0_MEMHOT_OUT_R      B @S9S_MB_2U_LIB.S9S_MB_2U(SCH_1):H_CPU0_MEMHOT_OUT_R

BC847BPN-BC847BPN,SMLF,IC,BA00A  I22  Q143
   2 H_CPU0_MEMHOT_OUT_R     B1 @S9S_MB_2U_LIB.S9S_MB_2U(SCH_1):H_CPU0_MEMHOT_OUT_R
   6 H_CPU0_MEMHOT_OUT_VT_N     C1 @S9S_MB_2U_LIB.S9S_MB_2U(SCH_1):H_CPU0_MEMHOT_OUT_VT_N
   1    GND     E1 @S9S_MB_2U_LIB.S9S_MB_2U(SCH_1):GND

Q_RES_0402LF-4.75K,1%,1/16W,CHA  I24  R4406
   1   P3V3      A @S9S_MB_2U_LIB.S9S_MB_2U(SCH_1):P3V3
   2 H_CPU1_MEMHOT_OUT_VT_N      B @S9S_MB_2U_LIB.S9S_MB_2U(SCH_1):H_CPU1_MEMHOT_OUT_VT_N

Q_RES_0402LF-4.75K,1%,1/16W,CHA  I27  R4405
   1   P3V3      A @S9S_MB_2U_LIB.S9S_MB_2U(SCH_1):P3V3
   2 H_CPU0_MEMHOT_OUT_VT_N      B @S9S_MB_2U_LIB.S9S_MB_2U(SCH_1):H_CPU0_MEMHOT_OUT_VT_N

Q_RES_0402LF-100,1%,1/16W,CHIPA  I29  R220
   1 PVNN_TERM_CPU1      A @S9S_MB_2U_LIB.S9S_MB_2U(SCH_1):PVNN_TERM_CPU1
   2 H_CPU1_MEMHOT_IN_LVC1_R1_N      B @S9S_MB_2U_LIB.S9S_MB_2U(SCH_1):H_CPU1_MEMHOT_IN_LVC1_R1_N

Q_RES_0402LF-33.2,1%,1/16W,CHIA  I31  R4407
   1 H_CPU0_MEMHOT_OUT_VT_N      A @S9S_MB_2U_LIB.S9S_MB_2U(SCH_1):H_CPU0_MEMHOT_OUT_VT_N
   2 H_CPU0_MEMHOT_OUT_LVC1_N      B @S9S_MB_2U_LIB.S9S_MB_2U(SCH_1):H_CPU0_MEMHOT_OUT_LVC1_N

Q_RES_0402LF-100,1%,1/16W,CHIPA  I33  R4294
   1 H_CPU1_MEMHOT_IN_LVC1_R1_N      A @S9S_MB_2U_LIB.S9S_MB_2U(SCH_1):H_CPU1_MEMHOT_IN_LVC1_R1_N
   2 H_CPU1_MEMHOT_IN_LVC1_N      B @S9S_MB_2U_LIB.S9S_MB_2U(SCH_1):H_CPU1_MEMHOT_IN_LVC1_N

Q_RES_0402LF-100,1%,1/16W,CHIPA  I34  R4293
   1 H_CPU0_MEMHOT_IN_LVC1_R1_N      A @S9S_MB_2U_LIB.S9S_MB_2U(SCH_1):H_CPU0_MEMHOT_IN_LVC1_R1_N
   2 H_CPU0_MEMHOT_IN_LVC1_N      B @S9S_MB_2U_LIB.S9S_MB_2U(SCH_1):H_CPU0_MEMHOT_IN_LVC1_N

Q_RES_0402LF-100,1%,1/16W,CHIPA  I37  R219
   1 PVNN_TERM_CPU0      A @S9S_MB_2U_LIB.S9S_MB_2U(SCH_1):PVNN_TERM_CPU0
   2 H_CPU0_MEMHOT_IN_LVC1_R1_N      B @S9S_MB_2U_LIB.S9S_MB_2U(SCH_1):H_CPU0_MEMHOT_IN_LVC1_R1_N


DRAWING: @S9S_MB_2U_LIB.S9S_MB_2U(SCH_1):PAGE233 

Q_RES_0402LF-100K,1%,1/16W,CHIA  I3  R4769
   1 FM_PDB_BUF_EN_R      A @S9S_MB_2U_LIB.S9S_MB_2U(SCH_1):FM_PDB_BUF_EN_R
   2    GND      B @S9S_MB_2U_LIB.S9S_MB_2U(SCH_1):GND

Q_RES_0402LF-4.7K,5%,1/16W,EMPA  I4  R2950
   1 P3V3_AUX      A @S9S_MB_2U_LIB.S9S_MB_2U(SCH_1):P3V3_AUX
   2 FM_PDB_BUF_EN_R      B @S9S_MB_2U_LIB.S9S_MB_2U(SCH_1):FM_PDB_BUF_EN_R

Q_RES_0402LF-33.2,1%,1/16W,CHIA  I8  R3114
   1 SMB_FAN_3V3AUX_SDA      A @S9S_MB_2U_LIB.S9S_MB_2U(SCH_1):SMB_FAN_3V3AUX_SDA
   2 SMB_FAN_3V3AUX_R_SDA      B @S9S_MB_2U_LIB.S9S_MB_2U(SCH_1):SMB_FAN_3V3AUX_R_SDA

Q_RES_0402LF-33.2,1%,1/16W,CHIA  I9  R3113
   1 SMB_FAN_3V3AUX_SCL      A @S9S_MB_2U_LIB.S9S_MB_2U(SCH_1):SMB_FAN_3V3AUX_SCL
   2 SMB_FAN_3V3AUX_R_SCL      B @S9S_MB_2U_LIB.S9S_MB_2U(SCH_1):SMB_FAN_3V3AUX_R_SCL

Q_RES_0402LF-33.2,1%,1/16W,CHIA  I10  R2796
   1 FM_PDB_BUF_EN_R      A @S9S_MB_2U_LIB.S9S_MB_2U(SCH_1):FM_PDB_BUF_EN_R
   2 FM_MB_PDB_SMB9_R_EN      B @S9S_MB_2U_LIB.S9S_MB_2U(SCH_1):FM_MB_PDB_SMB9_R_EN

CONN60_101062636003K02LF-CONN6A  I12  J45
  A2 FM_AC_PWR_BTN_PDB_N     A2 @S9S_MB_2U_LIB.S9S_MB_2U(SCH_1):FM_AC_PWR_BTN_PDB_N
  B2 PWRGD_P3V3_AUX_PDB_BUF     B2 @S9S_MB_2U_LIB.S9S_MB_2U(SCH_1):PWRGD_P3V3_AUX_PDB_BUF
  C2 SMB_FAN_3V3AUX_BUF_R_SDA     C2 @S9S_MB_2U_LIB.S9S_MB_2U(SCH_1):SMB_FAN_3V3AUX_BUF_R_SDA
  D2 FM_GPU_HSC_EN_BUF_R1     D2 @S9S_MB_2U_LIB.S9S_MB_2U(SCH_1):FM_GPU_HSC_EN_BUF_R1
P1_1    GND   P1_1 @S9S_MB_2U_LIB.S9S_MB_2U(SCH_1):GND
P1_2    GND   P1_2 @S9S_MB_2U_LIB.S9S_MB_2U(SCH_1):GND
P1_3    GND   P1_3 @S9S_MB_2U_LIB.S9S_MB_2U(SCH_1):GND
P1_4    GND   P1_4 @S9S_MB_2U_LIB.S9S_MB_2U(SCH_1):GND
P1_5    GND   P1_5 @S9S_MB_2U_LIB.S9S_MB_2U(SCH_1):GND
P1_6    GND   P1_6 @S9S_MB_2U_LIB.S9S_MB_2U(SCH_1):GND
P1_7    GND   P1_7 @S9S_MB_2U_LIB.S9S_MB_2U(SCH_1):GND
P1_8    GND   P1_8 @S9S_MB_2U_LIB.S9S_MB_2U(SCH_1):GND
P2_1    GND   P2_1 @S9S_MB_2U_LIB.S9S_MB_2U(SCH_1):GND
P2_2    GND   P2_2 @S9S_MB_2U_LIB.S9S_MB_2U(SCH_1):GND
P2_3    GND   P2_3 @S9S_MB_2U_LIB.S9S_MB_2U(SCH_1):GND
P2_4    GND   P2_4 @S9S_MB_2U_LIB.S9S_MB_2U(SCH_1):GND
P2_5    GND   P2_5 @S9S_MB_2U_LIB.S9S_MB_2U(SCH_1):GND
P2_6    GND   P2_6 @S9S_MB_2U_LIB.S9S_MB_2U(SCH_1):GND
P2_7    GND   P2_7 @S9S_MB_2U_LIB.S9S_MB_2U(SCH_1):GND
P2_8    GND   P2_8 @S9S_MB_2U_LIB.S9S_MB_2U(SCH_1):GND
P4_1 P12V_PSU   P4_1 @S9S_MB_2U_LIB.S9S_MB_2U(SCH_1):P12V_PSU
P4_2 P12V_PSU   P4_2 @S9S_MB_2U_LIB.S9S_MB_2U(SCH_1):P12V_PSU
P4_3 P12V_PSU   P4_3 @S9S_MB_2U_LIB.S9S_MB_2U(SCH_1):P12V_PSU
P4_4 P12V_PSU   P4_4 @S9S_MB_2U_LIB.S9S_MB_2U(SCH_1):P12V_PSU
P4_5 P12V_PSU   P4_5 @S9S_MB_2U_LIB.S9S_MB_2U(SCH_1):P12V_PSU
P4_6 P12V_PSU   P4_6 @S9S_MB_2U_LIB.S9S_MB_2U(SCH_1):P12V_PSU
P4_7 P12V_PSU   P4_7 @S9S_MB_2U_LIB.S9S_MB_2U(SCH_1):P12V_PSU
P4_8 P12V_PSU   P4_8 @S9S_MB_2U_LIB.S9S_MB_2U(SCH_1):P12V_PSU
  A1 TP_J45_A1     A1 @S9S_MB_2U_LIB.S9S_MB_2U(SCH_1):TP_J45_A1
  B1 RST_SMB_SWITCH_R_N     B1 @S9S_MB_2U_LIB.S9S_MB_2U(SCH_1):RST_SMB_SWITCH_R_N
  C1 SMB_FAN_3V3AUX_BUF_R_SCL     C1 @S9S_MB_2U_LIB.S9S_MB_2U(SCH_1):SMB_FAN_3V3AUX_BUF_R_SCL
  D1 FM_FAN_PWR_EN_R     D1 @S9S_MB_2U_LIB.S9S_MB_2U(SCH_1):FM_FAN_PWR_EN_R
P5_1 P12V_PSU   P5_1 @S9S_MB_2U_LIB.S9S_MB_2U(SCH_1):P12V_PSU
P5_2 P12V_PSU   P5_2 @S9S_MB_2U_LIB.S9S_MB_2U(SCH_1):P12V_PSU
P5_3 P12V_PSU   P5_3 @S9S_MB_2U_LIB.S9S_MB_2U(SCH_1):P12V_PSU
P5_4 P12V_PSU   P5_4 @S9S_MB_2U_LIB.S9S_MB_2U(SCH_1):P12V_PSU
P5_5 P12V_PSU   P5_5 @S9S_MB_2U_LIB.S9S_MB_2U(SCH_1):P12V_PSU
P5_6 P12V_PSU   P5_6 @S9S_MB_2U_LIB.S9S_MB_2U(SCH_1):P12V_PSU
P5_7 P12V_PSU   P5_7 @S9S_MB_2U_LIB.S9S_MB_2U(SCH_1):P12V_PSU
P5_8 P12V_PSU   P5_8 @S9S_MB_2U_LIB.S9S_MB_2U(SCH_1):P12V_PSU
P3_1    GND   P3_1 @S9S_MB_2U_LIB.S9S_MB_2U(SCH_1):GND
P3_2    GND   P3_2 @S9S_MB_2U_LIB.S9S_MB_2U(SCH_1):GND
P3_3    GND   P3_3 @S9S_MB_2U_LIB.S9S_MB_2U(SCH_1):GND
P3_4    GND   P3_4 @S9S_MB_2U_LIB.S9S_MB_2U(SCH_1):GND
P3_5    GND   P3_5 @S9S_MB_2U_LIB.S9S_MB_2U(SCH_1):GND
P3_6    GND   P3_6 @S9S_MB_2U_LIB.S9S_MB_2U(SCH_1):GND
P3_7    GND   P3_7 @S9S_MB_2U_LIB.S9S_MB_2U(SCH_1):GND
P3_8    GND   P3_8 @S9S_MB_2U_LIB.S9S_MB_2U(SCH_1):GND
P6_1 P12V_PSU   P6_1 @S9S_MB_2U_LIB.S9S_MB_2U(SCH_1):P12V_PSU
P6_2 P12V_PSU   P6_2 @S9S_MB_2U_LIB.S9S_MB_2U(SCH_1):P12V_PSU
P6_3 P12V_PSU   P6_3 @S9S_MB_2U_LIB.S9S_MB_2U(SCH_1):P12V_PSU
P6_4 P12V_PSU   P6_4 @S9S_MB_2U_LIB.S9S_MB_2U(SCH_1):P12V_PSU
P6_5 P12V_PSU   P6_5 @S9S_MB_2U_LIB.S9S_MB_2U(SCH_1):P12V_PSU
P6_6 P12V_PSU   P6_6 @S9S_MB_2U_LIB.S9S_MB_2U(SCH_1):P12V_PSU
P6_7 P12V_PSU   P6_7 @S9S_MB_2U_LIB.S9S_MB_2U(SCH_1):P12V_PSU
P6_8 P12V_PSU   P6_8 @S9S_MB_2U_LIB.S9S_MB_2U(SCH_1):P12V_PSU
  A3 P3V3_PDB_AUX_ADC     A3 @S9S_MB_2U_LIB.S9S_MB_2U(SCH_1):P3V3_PDB_AUX_ADC
  B3    GND     B3 @S9S_MB_2U_LIB.S9S_MB_2U(SCH_1):GND
  C3 HPDB_HSC_PWRGD_R     C3 @S9S_MB_2U_LIB.S9S_MB_2U(SCH_1):HPDB_HSC_PWRGD_R
  D3 PDB_PRSNT_N     D3 @S9S_MB_2U_LIB.S9S_MB_2U(SCH_1):PDB_PRSNT_N

Q_RES_0402LF-0,5%,1/16W,EMPTY,A  I14  R2801
   1 SMB_FAN_3V3AUX_R_SDA      A @S9S_MB_2U_LIB.S9S_MB_2U(SCH_1):SMB_FAN_3V3AUX_R_SDA
   2 SMB_FAN_3V3AUX_BUF_SDA      B @S9S_MB_2U_LIB.S9S_MB_2U(SCH_1):SMB_FAN_3V3AUX_BUF_SDA

Q_RES_0402LF-0,5%,1/16W,EMPTY,A  I15  R2800
   1 SMB_FAN_3V3AUX_R_SCL      A @S9S_MB_2U_LIB.S9S_MB_2U(SCH_1):SMB_FAN_3V3AUX_R_SCL
   2 SMB_FAN_3V3AUX_BUF_SCL      B @S9S_MB_2U_LIB.S9S_MB_2U(SCH_1):SMB_FAN_3V3AUX_BUF_SCL

LTC4307CMS8-LTC4307CMS8,SMLF,IA  I16  U192
   1 FM_MB_PDB_SMB9_R_EN ENABLE @S9S_MB_2U_LIB.S9S_MB_2U(SCH_1):FM_MB_PDB_SMB9_R_EN
   3 SMB_FAN_3V3AUX_R_SCL SCL_IN @S9S_MB_2U_LIB.S9S_MB_2U(SCH_1):SMB_FAN_3V3AUX_R_SCL
   6 SMB_FAN_3V3AUX_R_SDA SDA_IN @S9S_MB_2U_LIB.S9S_MB_2U(SCH_1):SMB_FAN_3V3AUX_R_SDA
   2 SMB_FAN_3V3AUX_BUF_SCL SCL_OUT @S9S_MB_2U_LIB.S9S_MB_2U(SCH_1):SMB_FAN_3V3AUX_BUF_SCL
   7 SMB_FAN_3V3AUX_BUF_SDA SDA_OUT @S9S_MB_2U_LIB.S9S_MB_2U(SCH_1):SMB_FAN_3V3AUX_BUF_SDA
   5     NC  READY     NC
   4    GND    GND @S9S_MB_2U_LIB.S9S_MB_2U(SCH_1):GND
   8 P3V3_AUX    VCC @S9S_MB_2U_LIB.S9S_MB_2U(SCH_1):P3V3_AUX

Q_CAP_0402-0.1UF,25V,10%,X7R,CA  I19  C1751
   1 P3V3_AUX      A @S9S_MB_2U_LIB.S9S_MB_2U(SCH_1):P3V3_AUX
   2    GND      B @S9S_MB_2U_LIB.S9S_MB_2U(SCH_1):GND

Q_RES_0402LF-33.2,1%,1/16W,CHIA  I20  R2812
   1 SMB_FAN_3V3AUX_BUF_SDA      A @S9S_MB_2U_LIB.S9S_MB_2U(SCH_1):SMB_FAN_3V3AUX_BUF_SDA
   2 SMB_FAN_3V3AUX_BUF_R_SDA      B @S9S_MB_2U_LIB.S9S_MB_2U(SCH_1):SMB_FAN_3V3AUX_BUF_R_SDA

Q_RES_0402LF-33.2,1%,1/16W,CHIA  I21  R2811
   1 SMB_FAN_3V3AUX_BUF_SCL      A @S9S_MB_2U_LIB.S9S_MB_2U(SCH_1):SMB_FAN_3V3AUX_BUF_SCL
   2 SMB_FAN_3V3AUX_BUF_R_SCL      B @S9S_MB_2U_LIB.S9S_MB_2U(SCH_1):SMB_FAN_3V3AUX_BUF_R_SCL

Q_RES_0402LF-4.7K,5%,1/16W,EMPA  I22  R2805
   1 P3V3_AUX      A @S9S_MB_2U_LIB.S9S_MB_2U(SCH_1):P3V3_AUX
   2 SMB_FAN_3V3AUX_BUF_SCL      B @S9S_MB_2U_LIB.S9S_MB_2U(SCH_1):SMB_FAN_3V3AUX_BUF_SCL

Q_RES_0402LF-4.7K,5%,1/16W,EMPA  I24  R2807
   1 P3V3_AUX      A @S9S_MB_2U_LIB.S9S_MB_2U(SCH_1):P3V3_AUX
   2 SMB_FAN_3V3AUX_BUF_SDA      B @S9S_MB_2U_LIB.S9S_MB_2U(SCH_1):SMB_FAN_3V3AUX_BUF_SDA

Q_RES_0402LF-0,5%,1/16W,CHIP,CA  I34  R2905
   1 RST_SMB_SWITCH_N      A @S9S_MB_2U_LIB.S9S_MB_2U(SCH_1):RST_SMB_SWITCH_N
   2 RST_SMB_SWITCH_R_N      B @S9S_MB_2U_LIB.S9S_MB_2U(SCH_1):RST_SMB_SWITCH_R_N

Q_RES_0402LF-0,5%,1/16W,CHIP,CA  I35  R4721
   1 FM_AC_PWR_BTN_R_N      A @S9S_MB_2U_LIB.S9S_MB_2U(SCH_1):FM_AC_PWR_BTN_R_N
   2 FM_AC_PWR_BTN_PDB_N      B @S9S_MB_2U_LIB.S9S_MB_2U(SCH_1):FM_AC_PWR_BTN_PDB_N

Q_RES_0402LF-0,5%,1/16W,CHIP,CA  I37  R2906
   1 FM_GPU_HSC_EN_BUF_R1      A @S9S_MB_2U_LIB.S9S_MB_2U(SCH_1):FM_GPU_HSC_EN_BUF_R1
   2 FM_GPU_HSC_EN_BUF      B @S9S_MB_2U_LIB.S9S_MB_2U(SCH_1):FM_GPU_HSC_EN_BUF

Q_RES_0402LF-0,5%,1/16W,CHIP,CA  I38  R2803
   1 FM_FAN_PWR_EN_R      A @S9S_MB_2U_LIB.S9S_MB_2U(SCH_1):FM_FAN_PWR_EN_R
   2 FM_FAN_PWR_EN      B @S9S_MB_2U_LIB.S9S_MB_2U(SCH_1):FM_FAN_PWR_EN

Q_RES_0402LF-0,5%,1/16W,CHIP,CA  I39  R2802
   1 HPDB_HSC_PWRGD_R      A @S9S_MB_2U_LIB.S9S_MB_2U(SCH_1):HPDB_HSC_PWRGD_R
   2 HPDB_HSC_PWRGD      B @S9S_MB_2U_LIB.S9S_MB_2U(SCH_1):HPDB_HSC_PWRGD

Q_RES_0402LF-4.7K,5%,1/16W,CHIA  I41  R4701
   1 P3V3_AUX      A @S9S_MB_2U_LIB.S9S_MB_2U(SCH_1):P3V3_AUX
   2 FM_FAN_PWR_EN      B @S9S_MB_2U_LIB.S9S_MB_2U(SCH_1):FM_FAN_PWR_EN

Q_CAP_0402-0.1UF,25V,10%,EMPTYA  I51  C2371
   1 FM_AC_PWR_BTN_PDB_N      A @S9S_MB_2U_LIB.S9S_MB_2U(SCH_1):FM_AC_PWR_BTN_PDB_N
   2    GND      B @S9S_MB_2U_LIB.S9S_MB_2U(SCH_1):GND

Q_CAP_0402-0.1UF,25V,10%,EMPTYA  I52  C2297
   1 FM_GPU_HSC_EN_BUF_R1      A @S9S_MB_2U_LIB.S9S_MB_2U(SCH_1):FM_GPU_HSC_EN_BUF_R1
   2    GND      B @S9S_MB_2U_LIB.S9S_MB_2U(SCH_1):GND

Q_CAP_0402-0.1UF,25V,10%,EMPTYA  I53  C2296
   1 FM_FAN_PWR_EN_R      A @S9S_MB_2U_LIB.S9S_MB_2U(SCH_1):FM_FAN_PWR_EN_R
   2    GND      B @S9S_MB_2U_LIB.S9S_MB_2U(SCH_1):GND

Q_CAP_0402-0.1UF,25V,10%,EMPTYA  I54  C2295
   1 HPDB_HSC_PWRGD_R      A @S9S_MB_2U_LIB.S9S_MB_2U(SCH_1):HPDB_HSC_PWRGD_R
   2    GND      B @S9S_MB_2U_LIB.S9S_MB_2U(SCH_1):GND

Q_CAP_0402-0.1UF,25V,10%,EMPTYA  I55  C2294
   1 PDB_PRSNT_N      A @S9S_MB_2U_LIB.S9S_MB_2U(SCH_1):PDB_PRSNT_N
   2    GND      B @S9S_MB_2U_LIB.S9S_MB_2U(SCH_1):GND

Q_CAP_0402-0.1UF,25V,10%,EMPTYA  I57  C2293
   1 RST_SMB_SWITCH_R_N      A @S9S_MB_2U_LIB.S9S_MB_2U(SCH_1):RST_SMB_SWITCH_R_N
   2    GND      B @S9S_MB_2U_LIB.S9S_MB_2U(SCH_1):GND


DRAWING: @S9S_MB_2U_LIB.S9S_MB_2U(SCH_1):PAGE196 

Q_RES_0402LF-22,1%,1/16W,CHIP,A  I10  R3201
   1 CLK_100M_OCP_V3_2_D_R_DN      A @S9S_MB_2U_LIB.S9S_MB_2U(SCH_1):CLK_100M_OCP_V3_2_D_R_DN
   2 CLK_100M_OCP_V3_2_D_DN      B @S9S_MB_2U_LIB.S9S_MB_2U(SCH_1):CLK_100M_OCP_V3_2_D_DN

Q_RES_0402LF-22,1%,1/16W,CHIP,A  I11  R3200
   1 CLK_100M_OCP_V3_2_D_R_DP      A @S9S_MB_2U_LIB.S9S_MB_2U(SCH_1):CLK_100M_OCP_V3_2_D_R_DP
   2 CLK_100M_OCP_V3_2_D_DP      B @S9S_MB_2U_LIB.S9S_MB_2U(SCH_1):CLK_100M_OCP_V3_2_D_DP

Q_RES_0402LF-22,1%,1/16W,CHIP,A  I12  R3199
   1 CLK_100M_OCP_V3_2_C_R_DN      A @S9S_MB_2U_LIB.S9S_MB_2U(SCH_1):CLK_100M_OCP_V3_2_C_R_DN
   2 CLK_100M_OCP_V3_2_C_DN      B @S9S_MB_2U_LIB.S9S_MB_2U(SCH_1):CLK_100M_OCP_V3_2_C_DN

Q_RES_0402LF-22,1%,1/16W,CHIP,A  I13  R3198
   1 CLK_100M_OCP_V3_2_C_R_DP      A @S9S_MB_2U_LIB.S9S_MB_2U(SCH_1):CLK_100M_OCP_V3_2_C_R_DP
   2 CLK_100M_OCP_V3_2_C_DP      B @S9S_MB_2U_LIB.S9S_MB_2U(SCH_1):CLK_100M_OCP_V3_2_C_DP

Q_RES_0402LF-22,1%,1/16W,CHIP,A  I14  R3197
   1 CLK_100M_OCP_V3_2_B_R_DN      A @S9S_MB_2U_LIB.S9S_MB_2U(SCH_1):CLK_100M_OCP_V3_2_B_R_DN
   2 CLK_100M_OCP_V3_2_B_DN      B @S9S_MB_2U_LIB.S9S_MB_2U(SCH_1):CLK_100M_OCP_V3_2_B_DN

Q_RES_0402LF-22,1%,1/16W,CHIP,A  I15  R3196
   1 CLK_100M_OCP_V3_2_B_R_DP      A @S9S_MB_2U_LIB.S9S_MB_2U(SCH_1):CLK_100M_OCP_V3_2_B_R_DP
   2 CLK_100M_OCP_V3_2_B_DP      B @S9S_MB_2U_LIB.S9S_MB_2U(SCH_1):CLK_100M_OCP_V3_2_B_DP

Q_RES_0402LF-22,1%,1/16W,CHIP,A  I16  R3195
   1 CLK_100M_OCP_V3_2_A_R_DN      A @S9S_MB_2U_LIB.S9S_MB_2U(SCH_1):CLK_100M_OCP_V3_2_A_R_DN
   2 CLK_100M_OCP_V3_2_A_DN      B @S9S_MB_2U_LIB.S9S_MB_2U(SCH_1):CLK_100M_OCP_V3_2_A_DN

Q_RES_0402LF-22,1%,1/16W,CHIP,A  I17  R3194
   1 CLK_100M_OCP_V3_2_A_R_DP      A @S9S_MB_2U_LIB.S9S_MB_2U(SCH_1):CLK_100M_OCP_V3_2_A_R_DP
   2 CLK_100M_OCP_V3_2_A_DP      B @S9S_MB_2U_LIB.S9S_MB_2U(SCH_1):CLK_100M_OCP_V3_2_A_DP

Q_RES_0402LF-0,5%,1/16W,CHIP,CA  I18  R3355
   1 CLK_100M_GPU_2_R_DN      A @S9S_MB_2U_LIB.S9S_MB_2U(SCH_1):CLK_100M_GPU_2_R_DN
   2 CLK_100M_GPU_2_DN      B @S9S_MB_2U_LIB.S9S_MB_2U(SCH_1):CLK_100M_GPU_2_DN

Q_RES_0402LF-0,5%,1/16W,CHIP,CA  I24  R3354
   1 CLK_100M_GPU_2_R_DP      A @S9S_MB_2U_LIB.S9S_MB_2U(SCH_1):CLK_100M_GPU_2_R_DP
   2 CLK_100M_GPU_2_DP      B @S9S_MB_2U_LIB.S9S_MB_2U(SCH_1):CLK_100M_GPU_2_DP

Q_RES_0402LF-0,5%,1/16W,CHIP,CA  I25  R3353
   1 CLK_100M_GPU_1_R_DN      A @S9S_MB_2U_LIB.S9S_MB_2U(SCH_1):CLK_100M_GPU_1_R_DN
   2 CLK_100M_GPU_1_DN      B @S9S_MB_2U_LIB.S9S_MB_2U(SCH_1):CLK_100M_GPU_1_DN

Q_RES_0402LF-0,5%,1/16W,CHIP,CA  I26  R3352
   1 CLK_100M_GPU_1_R_DP      A @S9S_MB_2U_LIB.S9S_MB_2U(SCH_1):CLK_100M_GPU_1_R_DP
   2 CLK_100M_GPU_1_DP      B @S9S_MB_2U_LIB.S9S_MB_2U(SCH_1):CLK_100M_GPU_1_DP

Q_RES_0402LF-0,5%,1/16W,CHIP,CA  I27  R2659
   1 CLK_100M_SWB_R_DP      A @S9S_MB_2U_LIB.S9S_MB_2U(SCH_1):CLK_100M_SWB_R_DP
   2 CLK_100M_SWB_DP      B @S9S_MB_2U_LIB.S9S_MB_2U(SCH_1):CLK_100M_SWB_DP

Q_RES_0402LF-0,5%,1/16W,CHIP,CA  I28  R2660
   1 CLK_100M_SWB_R_DN      A @S9S_MB_2U_LIB.S9S_MB_2U(SCH_1):CLK_100M_SWB_R_DN
   2 CLK_100M_SWB_DN      B @S9S_MB_2U_LIB.S9S_MB_2U(SCH_1):CLK_100M_SWB_DN


DRAWING: @S9S_MB_2U_LIB.S9S_MB_2U(SCH_1):PAGE198 

Q_RES_0402LF-0,5%,1/16W,CHIP,CA  I7  R1011
   1 CLK_25M_CK440_ISCLK_REF_DN      A @S9S_MB_2U_LIB.S9S_MB_2U(SCH_1):CLK_25M_CK440_ISCLK_REF_DN
   2 CLK_25M_PCH_REF_NS_DN      B @S9S_MB_2U_LIB.S9S_MB_2U(SCH_1):CLK_25M_PCH_REF_NS_DN

Q_RES_0402LF-0,5%,1/16W,CHIP,CA  I8  R1010
   1 CLK_25M_CK440_ISCLK_REF_DP      A @S9S_MB_2U_LIB.S9S_MB_2U(SCH_1):CLK_25M_CK440_ISCLK_REF_DP
   2 CLK_25M_PCH_REF_NS_DP      B @S9S_MB_2U_LIB.S9S_MB_2U(SCH_1):CLK_25M_PCH_REF_NS_DP

Q_RES_0402LF-0,5%,1/16W,EMPTY,A  I9  R1019
   1 CLK_25M_PCH_CPU1_DN      A @S9S_MB_2U_LIB.S9S_MB_2U(SCH_1):CLK_25M_PCH_CPU1_DN
   2 CLK_25M_NSSC_CPU1_DN      B @S9S_MB_2U_LIB.S9S_MB_2U(SCH_1):CLK_25M_NSSC_CPU1_DN

Q_RES_0402LF-0,5%,1/16W,CHIP,CA  I10  R1018
   1 CLK_25M_CK440_CPU1_DN      A @S9S_MB_2U_LIB.S9S_MB_2U(SCH_1):CLK_25M_CK440_CPU1_DN
   2 CLK_25M_CK440_CPU1_R_DN      B @S9S_MB_2U_LIB.S9S_MB_2U(SCH_1):CLK_25M_CK440_CPU1_R_DN

Q_RES_0402LF-0,5%,1/16W,EMPTY,A  I11  R1017
   1 CLK_25M_PCH_CPU1_DP      A @S9S_MB_2U_LIB.S9S_MB_2U(SCH_1):CLK_25M_PCH_CPU1_DP
   2 CLK_25M_NSSC_CPU1_DP      B @S9S_MB_2U_LIB.S9S_MB_2U(SCH_1):CLK_25M_NSSC_CPU1_DP

Q_RES_0402LF-0,5%,1/16W,CHIP,CA  I12  R1016
   1 CLK_25M_CK440_CPU1_DP      A @S9S_MB_2U_LIB.S9S_MB_2U(SCH_1):CLK_25M_CK440_CPU1_DP
   2 CLK_25M_CK440_CPU1_R_DP      B @S9S_MB_2U_LIB.S9S_MB_2U(SCH_1):CLK_25M_CK440_CPU1_R_DP

Q_RES_0402LF-0,5%,1/16W,EMPTY,A  I19  R1015
   1 CLK_25M_PCH_CPU0_DN      A @S9S_MB_2U_LIB.S9S_MB_2U(SCH_1):CLK_25M_PCH_CPU0_DN
   2 CLK_25M_NSSC_CPU0_DN      B @S9S_MB_2U_LIB.S9S_MB_2U(SCH_1):CLK_25M_NSSC_CPU0_DN

Q_RES_0402LF-0,5%,1/16W,CHIP,CA  I20  R1014
   1 CLK_25M_CK440_CPU0_DN      A @S9S_MB_2U_LIB.S9S_MB_2U(SCH_1):CLK_25M_CK440_CPU0_DN
   2 CLK_25M_CK440_CPU0_R_DN      B @S9S_MB_2U_LIB.S9S_MB_2U(SCH_1):CLK_25M_CK440_CPU0_R_DN

Q_RES_0402LF-0,5%,1/16W,EMPTY,A  I21  R1013
   1 CLK_25M_PCH_CPU0_DP      A @S9S_MB_2U_LIB.S9S_MB_2U(SCH_1):CLK_25M_PCH_CPU0_DP
   2 CLK_25M_NSSC_CPU0_DP      B @S9S_MB_2U_LIB.S9S_MB_2U(SCH_1):CLK_25M_NSSC_CPU0_DP

Q_RES_0402LF-0,5%,1/16W,CHIP,CA  I22  R1012
   1 CLK_25M_CK440_CPU0_DP      A @S9S_MB_2U_LIB.S9S_MB_2U(SCH_1):CLK_25M_CK440_CPU0_DP
   2 CLK_25M_CK440_CPU0_R_DP      B @S9S_MB_2U_LIB.S9S_MB_2U(SCH_1):CLK_25M_CK440_CPU0_R_DP

Q_RES_0402LF-22,1%,1/16W,CHIP,A  I23  R1276
   1 CLK_100M_OCP_SFF_3_R_DN      A @S9S_MB_2U_LIB.S9S_MB_2U(SCH_1):CLK_100M_OCP_SFF_3_R_DN
   2 CLK_100M_OCP_SFF_3_DN      B @S9S_MB_2U_LIB.S9S_MB_2U(SCH_1):CLK_100M_OCP_SFF_3_DN

Q_RES_0402LF-22,1%,1/16W,CHIP,A  I24  R1275
   1 CLK_100M_OCP_SFF_3_R_DP      A @S9S_MB_2U_LIB.S9S_MB_2U(SCH_1):CLK_100M_OCP_SFF_3_R_DP
   2 CLK_100M_OCP_SFF_3_DP      B @S9S_MB_2U_LIB.S9S_MB_2U(SCH_1):CLK_100M_OCP_SFF_3_DP

Q_RES_0402LF-0,5%,1/16W,CHIP,CA  I27  R1023
   1 CLK_25M_CK440_CPU1_R_DN      A @S9S_MB_2U_LIB.S9S_MB_2U(SCH_1):CLK_25M_CK440_CPU1_R_DN
   2 CLK_25M_NSSC_CPU1_DN      B @S9S_MB_2U_LIB.S9S_MB_2U(SCH_1):CLK_25M_NSSC_CPU1_DN

Q_RES_0402LF-0,5%,1/16W,CHIP,CA  I28  R1022
   1 CLK_25M_CK440_CPU1_R_DP      A @S9S_MB_2U_LIB.S9S_MB_2U(SCH_1):CLK_25M_CK440_CPU1_R_DP
   2 CLK_25M_NSSC_CPU1_DP      B @S9S_MB_2U_LIB.S9S_MB_2U(SCH_1):CLK_25M_NSSC_CPU1_DP

Q_RES_0402LF-0,5%,1/16W,CHIP,CA  I29  R1021
   1 CLK_25M_CK440_CPU0_R_DN      A @S9S_MB_2U_LIB.S9S_MB_2U(SCH_1):CLK_25M_CK440_CPU0_R_DN
   2 CLK_25M_NSSC_CPU0_DN      B @S9S_MB_2U_LIB.S9S_MB_2U(SCH_1):CLK_25M_NSSC_CPU0_DN

Q_RES_0402LF-0,5%,1/16W,CHIP,CA  I30  R1020
   1 CLK_25M_CK440_CPU0_R_DP      A @S9S_MB_2U_LIB.S9S_MB_2U(SCH_1):CLK_25M_CK440_CPU0_R_DP
   2 CLK_25M_NSSC_CPU0_DP      B @S9S_MB_2U_LIB.S9S_MB_2U(SCH_1):CLK_25M_NSSC_CPU0_DP

Q_RES_0402LF-22,1%,1/16W,CHIP,A  I43  R1274
   1 CLK_100M_OCP_SFF_2_R_DN      A @S9S_MB_2U_LIB.S9S_MB_2U(SCH_1):CLK_100M_OCP_SFF_2_R_DN
   2 CLK_100M_OCP_SFF_2_DN      B @S9S_MB_2U_LIB.S9S_MB_2U(SCH_1):CLK_100M_OCP_SFF_2_DN

Q_RES_0402LF-22,1%,1/16W,CHIP,A  I44  R1273
   1 CLK_100M_OCP_SFF_2_R_DP      A @S9S_MB_2U_LIB.S9S_MB_2U(SCH_1):CLK_100M_OCP_SFF_2_R_DP
   2 CLK_100M_OCP_SFF_2_DP      B @S9S_MB_2U_LIB.S9S_MB_2U(SCH_1):CLK_100M_OCP_SFF_2_DP

Q_RES_0402LF-22,1%,1/16W,CHIP,A  I45  R566
   1 CLK_100M_OCP_SFF_1_R_DN      A @S9S_MB_2U_LIB.S9S_MB_2U(SCH_1):CLK_100M_OCP_SFF_1_R_DN
   2 CLK_100M_OCP_SFF_1_DN      B @S9S_MB_2U_LIB.S9S_MB_2U(SCH_1):CLK_100M_OCP_SFF_1_DN

Q_RES_0402LF-22,1%,1/16W,CHIP,A  I46  R565
   1 CLK_100M_OCP_SFF_1_R_DP      A @S9S_MB_2U_LIB.S9S_MB_2U(SCH_1):CLK_100M_OCP_SFF_1_R_DP
   2 CLK_100M_OCP_SFF_1_DP      B @S9S_MB_2U_LIB.S9S_MB_2U(SCH_1):CLK_100M_OCP_SFF_1_DP

Q_RES_0402LF-22,1%,1/16W,CHIP,A  I47  R564
   1 CLK_100M_OCP_SFF_0_R_DN      A @S9S_MB_2U_LIB.S9S_MB_2U(SCH_1):CLK_100M_OCP_SFF_0_R_DN
   2 CLK_100M_OCP_SFF_0_DN      B @S9S_MB_2U_LIB.S9S_MB_2U(SCH_1):CLK_100M_OCP_SFF_0_DN

Q_RES_0402LF-22,1%,1/16W,CHIP,A  I48  R563
   1 CLK_100M_OCP_SFF_0_R_DP      A @S9S_MB_2U_LIB.S9S_MB_2U(SCH_1):CLK_100M_OCP_SFF_0_R_DP
   2 CLK_100M_OCP_SFF_0_DP      B @S9S_MB_2U_LIB.S9S_MB_2U(SCH_1):CLK_100M_OCP_SFF_0_DP

Q_RES_0402LF-0,5%,1/16W,CHIP,CA  I57  R554
   1 CLK_100M_CK440_PCH_EXTCLK_R_DN      A @S9S_MB_2U_LIB.S9S_MB_2U(SCH_1):CLK_100M_CK440_PCH_EXTCLK_R_DN
   2 CLK_100M_CK440_PCH_EXTCLK_DN      B @S9S_MB_2U_LIB.S9S_MB_2U(SCH_1):CLK_100M_CK440_PCH_EXTCLK_DN

Q_RES_0402LF-0,5%,1/16W,CHIP,CA  I58  R553
   1 CLK_100M_CK440_PCH_EXTCLK_R_DP      A @S9S_MB_2U_LIB.S9S_MB_2U(SCH_1):CLK_100M_CK440_PCH_EXTCLK_R_DP
   2 CLK_100M_CK440_PCH_EXTCLK_DP      B @S9S_MB_2U_LIB.S9S_MB_2U(SCH_1):CLK_100M_CK440_PCH_EXTCLK_DP

END LOGICAL PART CROSS REFERENCE
GLOBAL SIGNAL CROSS REFERENCE - 24-Aug-2023 AT 15:36:33
ADC128_A0 @S9S_MB_2U_LIB.S9S_MB_2U(SCH_1):ADC128_A0
  U269    7     A0 ADC128D818CIMTXNOPB-ADC128D818A   I103 @S9S_MB_2U_LIB.S9S_MB_2U(SCH_1):PAGE239
 R3670    1      A Q_RES_0402LF-1K,1%,1/16W,CHIP,A   I227 @S9S_MB_2U_LIB.S9S_MB_2U(SCH_1):PAGE239
 R3669    2      B Q_RES_0402LF-1K,1%,1/16W,EMPTYA   I228 @S9S_MB_2U_LIB.S9S_MB_2U(SCH_1):PAGE239

ADC128_A1 @S9S_MB_2U_LIB.S9S_MB_2U(SCH_1):ADC128_A1
  U269    8     A1 ADC128D818CIMTXNOPB-ADC128D818A   I103 @S9S_MB_2U_LIB.S9S_MB_2U(SCH_1):PAGE239
 R3668    1      A Q_RES_0402LF-1K,1%,1/16W,CHIP,A   I223 @S9S_MB_2U_LIB.S9S_MB_2U(SCH_1):PAGE239
 R3667    2      B Q_RES_0402LF-1K,1%,1/16W,EMPTYA   I224 @S9S_MB_2U_LIB.S9S_MB_2U(SCH_1):PAGE239

ADC128_VREF @S9S_MB_2U_LIB.S9S_MB_2U(SCH_1):ADC128_VREF
  U269    1   VREF ADC128D818CIMTXNOPB-ADC128D818A   I103 @S9S_MB_2U_LIB.S9S_MB_2U(SCH_1):PAGE239
 R3689    2      B Q_RES_0402LF-4.7K,1%,1/16W,EMPA   I129 @S9S_MB_2U_LIB.S9S_MB_2U(SCH_1):PAGE239
 R3690    1      A Q_RES_0402LF-4.7K,1%,1/16W,EMPA   I131 @S9S_MB_2U_LIB.S9S_MB_2U(SCH_1):PAGE239

AGND_HSC @S9S_MB_2U_LIB.S9S_MB_2U(SCH_1):AGND_HSC
PC2183    2      B Q_CAP_0402-220PF,50V,10%,EMPTYA     I2 @S9S_MB_2U_LIB.S9S_MB_2U(SCH_1):PAGE301
PR3915    2      B Q_RES_0402LF-2K,0.1%,1/16W,CHIA    I12 @S9S_MB_2U_LIB.S9S_MB_2U(SCH_1):PAGE301
PR1101    2      B Q_RES_0402LF-2K,0.1%,1/16W,CHIA    I13 @S9S_MB_2U_LIB.S9S_MB_2U(SCH_1):PAGE301
PC2347    2      B Q_CAP_0402-1NF,50V,10%,EMPTY,CA    I29 @S9S_MB_2U_LIB.S9S_MB_2U(SCH_1):PAGE301
PC2181    2      B Q_CAP_C0402-1UF,25V,10%,X6S,CHA     I4 @S9S_MB_2U_LIB.S9S_MB_2U(SCH_1):PAGE301
PC1525    2      B Q_CAP_C0402-1UF,25V,10%,X6S,CHA    I20 @S9S_MB_2U_LIB.S9S_MB_2U(SCH_1):PAGE301
PC2349    2      B Q_CAP_0402-1NF,50V,10%,EMPTY,CA    I11 @S9S_MB_2U_LIB.S9S_MB_2U(SCH_1):PAGE325
PR3987    2      B Q_RES_0402LF-2K,0.1%,1/16W,CHIA    I12 @S9S_MB_2U_LIB.S9S_MB_2U(SCH_1):PAGE325
PR3991    2      B Q_RES_0402LF-2K,0.1%,1/16W,CHIA    I13 @S9S_MB_2U_LIB.S9S_MB_2U(SCH_1):PAGE325
PR3990    2      B Q_RES_0402LF-2K,0.1%,1/16W,CHIA    I34 @S9S_MB_2U_LIB.S9S_MB_2U(SCH_1):PAGE325
PC2348    2      B Q_CAP_0402-1NF,50V,10%,EMPTY,CA    I11 @S9S_MB_2U_LIB.S9S_MB_2U(SCH_1):PAGE301
PR3918    2      B Q_RES_0402LF-2K,0.1%,1/16W,CHIA    I34 @S9S_MB_2U_LIB.S9S_MB_2U(SCH_1):PAGE301
 PU297   20    GND MP5991GLUZ-MP5991GLU-Z,SMLF,ICA    I17 @S9S_MB_2U_LIB.S9S_MB_2U(SCH_1):PAGE325
PR3912    1      A Q_RES_0402LF-120K,1%,1/16W,CHIA    I15 @S9S_MB_2U_LIB.S9S_MB_2U(SCH_1):PAGE301
 PU289   18   GND1 MP5990GMA1111Z-MP5990GMA-1111-A    I56 @S9S_MB_2U_LIB.S9S_MB_2U(SCH_1):PAGE303
 PU289   44   GND2 MP5990GMA1111Z-MP5990GMA-1111-A    I56 @S9S_MB_2U_LIB.S9S_MB_2U(SCH_1):PAGE303
PR3932    2      B Q_RES_0402LF-4.99K,0.1%,1/16W,A    I59 @S9S_MB_2U_LIB.S9S_MB_2U(SCH_1):PAGE303
PC2223    2      B Q_CAP_C0402-1UF,25V,10%,X6S,CHA     I4 @S9S_MB_2U_LIB.S9S_MB_2U(SCH_1):PAGE325
PR3986    2      B Q_RES_0402LF-2K,0.1%,1/16W,CHIA    I30 @S9S_MB_2U_LIB.S9S_MB_2U(SCH_1):PAGE325
 PU296   20    GND MP5991GLUZ-MP5991GLU-Z,SMLF,ICA    I35 @S9S_MB_2U_LIB.S9S_MB_2U(SCH_1):PAGE325
PC2190    2      B Q_CAP_C0402-0.01UF,50V,10%,X7RA    I75 @S9S_MB_2U_LIB.S9S_MB_2U(SCH_1):PAGE303
PR3914    2      B Q_RES_0402LF-2K,0.1%,1/16W,CHIA    I30 @S9S_MB_2U_LIB.S9S_MB_2U(SCH_1):PAGE301
 PU287   20    GND MP5991GLUZ-MP5991GLU-Z,SMLF,ICA    I35 @S9S_MB_2U_LIB.S9S_MB_2U(SCH_1):PAGE301
PC2227    2      B Q_CAP_0402-0.068UF,16V,10%,X7RA    I38 @S9S_MB_2U_LIB.S9S_MB_2U(SCH_1):PAGE325
 PU288   20    GND MP5991GLUZ-MP5991GLU-Z,SMLF,ICA    I14 @S9S_MB_2U_LIB.S9S_MB_2U(SCH_1):PAGE301
PR1134    1      A Q_RES_0402LF-120K,1%,1/16W,CHIA    I32 @S9S_MB_2U_LIB.S9S_MB_2U(SCH_1):PAGE301
PR3927    2      B Q_RES_0402LF-4.99K,0.1%,1/16W,A    I40 @S9S_MB_2U_LIB.S9S_MB_2U(SCH_1):PAGE303
PC2189    2      B Q_CAP_C0402-0.01UF,50V,10%,X7RA    I45 @S9S_MB_2U_LIB.S9S_MB_2U(SCH_1):PAGE303
 R1117    2      B Q_RES_0402LF-6.19K,1%,1/16W,CHA    I61 @S9S_MB_2U_LIB.S9S_MB_2U(SCH_1):PAGE303
PC2191    2      B Q_CAP_0402-0.068UF,16V,10%,X7RA    I69 @S9S_MB_2U_LIB.S9S_MB_2U(SCH_1):PAGE303
PC2192    2      B Q_CAP_C0402-0.001UF,50V,10%,X7A    I77 @S9S_MB_2U_LIB.S9S_MB_2U(SCH_1):PAGE303
PC3272    2      B Q_CAP_C0402-1UF,25V,10%,X6S,CHA    I19 @S9S_MB_2U_LIB.S9S_MB_2U(SCH_1):PAGE325
PC2224    2      B Q_CAP_0402-220PF,50V,10%,EMPTYA    I23 @S9S_MB_2U_LIB.S9S_MB_2U(SCH_1):PAGE325
PC2350    2      B Q_CAP_0402-1NF,50V,10%,EMPTY,CA    I29 @S9S_MB_2U_LIB.S9S_MB_2U(SCH_1):PAGE325
PR3982    1      A Q_RES_0402LF-120K,1%,1/16W,CHIA    I32 @S9S_MB_2U_LIB.S9S_MB_2U(SCH_1):PAGE325
PC2186    2      B Q_CAP_C0402-1UF,25V,10%,X6S,CHA    I14 @S9S_MB_2U_LIB.S9S_MB_2U(SCH_1):PAGE303
PC2187    2      B Q_CAP_C0402-1UF,25V,10%,X6S,CHA    I23 @S9S_MB_2U_LIB.S9S_MB_2U(SCH_1):PAGE303
 C2179    2      B Q_CAP_C0402-100NF,50V,10%,X7R,A    I29 @S9S_MB_2U_LIB.S9S_MB_2U(SCH_1):PAGE303
PR3930    1      A Q_RES_0402LF-0,5%,1/16W,CHIP,CA    I32 @S9S_MB_2U_LIB.S9S_MB_2U(SCH_1):PAGE303
PC2103    2      B Q_CAP_C0402-1UF,25V,10%,X6S,CHA    I35 @S9S_MB_2U_LIB.S9S_MB_2U(SCH_1):PAGE303
PR3002    2      B Q_RES_0402LF-0,5%,1/16W,CHIP,CA    I54 @S9S_MB_2U_LIB.S9S_MB_2U(SCH_1):PAGE303
PR1131    2      B Q_RES_0402LF-2K,0.1%,1/16W,CHIA    I58 @S9S_MB_2U_LIB.S9S_MB_2U(SCH_1):PAGE303
PR3935    2      B Q_RES_0402LF-10K,1%,1/16W,CHIPA    I79 @S9S_MB_2U_LIB.S9S_MB_2U(SCH_1):PAGE303
PR3937    2      B Q_RES_0402LF-120K,1%,1/16W,CHIA    I84 @S9S_MB_2U_LIB.S9S_MB_2U(SCH_1):PAGE303
PC2193    2      B Q_CAP_C0402-0.047UF,25V,10%,X7A    I89 @S9S_MB_2U_LIB.S9S_MB_2U(SCH_1):PAGE303
PR1133    2      B Q_RES_0402LF-2K,0.1%,1/16W,CHIA    I91 @S9S_MB_2U_LIB.S9S_MB_2U(SCH_1):PAGE303
PC2182    2      B Q_CAP_0402-220PF,50V,10%,X7R,TA    I23 @S9S_MB_2U_LIB.S9S_MB_2U(SCH_1):PAGE301
PC2185    2      B Q_CAP_0402-0.068UF,16V,10%,X7RA    I37 @S9S_MB_2U_LIB.S9S_MB_2U(SCH_1):PAGE301
PC2184    2      B Q_CAP_0402-0.068UF,16V,10%,X7RA    I47 @S9S_MB_2U_LIB.S9S_MB_2U(SCH_1):PAGE301
PC2225    2      B Q_CAP_0402-220PF,50V,10%,EMPTYA     I2 @S9S_MB_2U_LIB.S9S_MB_2U(SCH_1):PAGE325
PR3984    1      A Q_RES_0402LF-120K,1%,1/16W,CHIA    I14 @S9S_MB_2U_LIB.S9S_MB_2U(SCH_1):PAGE325
PC2226    2      B Q_CAP_0402-0.068UF,16V,10%,X7RA    I48 @S9S_MB_2U_LIB.S9S_MB_2U(SCH_1):PAGE325

A_HSC_HIGH @S9S_MB_2U_LIB.S9S_MB_2U(SCH_1):A_HSC_HIGH
 R4670    1      A Q_RES_0402LF-10K,1%,1/16W,EMPTA    I24 @S9S_MB_2U_LIB.S9S_MB_2U(SCH_1):PAGE326
 R4669    2      B Q_RES_0402LF-160K,1%,1/16W,EMPA    I25 @S9S_MB_2U_LIB.S9S_MB_2U(SCH_1):PAGE326
  U369    4   INB- TPS3700DDCR-TPS3700DDCR,SMLF,EA    I30 @S9S_MB_2U_LIB.S9S_MB_2U(SCH_1):PAGE326

A_HSC_INAP @S9S_MB_2U_LIB.S9S_MB_2U(SCH_1):A_HSC_INAP
 R2238    1      A Q_RES_0402LF-4.99K,1%,1/16W,EMA     I2 @S9S_MB_2U_LIB.S9S_MB_2U(SCH_1):PAGE326
  U205    3   INA+ TPS3700DDCR-TPS3700DDCR,SMLF,EA     I5 @S9S_MB_2U_LIB.S9S_MB_2U(SCH_1):PAGE326
 R2236    2      B Q_RES_0402LF-100K,1%,1/16W,EMPA     I7 @S9S_MB_2U_LIB.S9S_MB_2U(SCH_1):PAGE326

A_HSC_LOW @S9S_MB_2U_LIB.S9S_MB_2U(SCH_1):A_HSC_LOW
 R4668    1      A Q_RES_0402LF-10K,1%,1/16W,EMPTA    I13 @S9S_MB_2U_LIB.S9S_MB_2U(SCH_1):PAGE326
 R4667    2      B Q_RES_0402LF-160K,1%,1/16W,EMPA    I14 @S9S_MB_2U_LIB.S9S_MB_2U(SCH_1):PAGE326
  U369    3   INA+ TPS3700DDCR-TPS3700DDCR,SMLF,EA    I30 @S9S_MB_2U_LIB.S9S_MB_2U(SCH_1):PAGE326

A_HSC_LOW_DRAIN @S9S_MB_2U_LIB.S9S_MB_2U(SCH_1):A_HSC_LOW_DRAIN
  U329    D      D MOSFET_NCH_GDS_ESD_PROTECTED-2B    I46 @S9S_MB_2U_LIB.S9S_MB_2U(SCH_1):PAGE326
 R4652    1      A Q_RES_0402LF-0,5%,1/16W,EMPTY,A    I48 @S9S_MB_2U_LIB.S9S_MB_2U(SCH_1):PAGE326

A_HSC_LOW_GATE @S9S_MB_2U_LIB.S9S_MB_2U(SCH_1):A_HSC_LOW_GATE
  U369    1   OUTA TPS3700DDCR-TPS3700DDCR,SMLF,EA    I30 @S9S_MB_2U_LIB.S9S_MB_2U(SCH_1):PAGE326
 R4673    1      A Q_RES_0402LF-0,5%,1/16W,EMPTY,A    I44 @S9S_MB_2U_LIB.S9S_MB_2U(SCH_1):PAGE326
  U329    G      G MOSFET_NCH_GDS_ESD_PROTECTED-2B    I46 @S9S_MB_2U_LIB.S9S_MB_2U(SCH_1):PAGE326
 R4672    2      B Q_RES_0402LF-10K,1%,1/16W,EMPTA    I53 @S9S_MB_2U_LIB.S9S_MB_2U(SCH_1):PAGE326
 R4794    2      B Q_RES_0402LF-33.2,1%,1/16W,EMPA    I72 @S9S_MB_2U_LIB.S9S_MB_2U(SCH_1):PAGE326
 R4797    2      B Q_RES_0402LF-10K,1%,1/16W,EMPTA    I80 @S9S_MB_2U_LIB.S9S_MB_2U(SCH_1):PAGE326

A_P12V_STBY_ADR_TRIGGER @S9S_MB_2U_LIB.S9S_MB_2U(SCH_1):A_P12V_STBY_ADR_TRIGGER
 R2219    2      B Q_RES_0402LF-26.7K,1%,1/16W,CHA   I100 @S9S_MB_2U_LIB.S9S_MB_2U(SCH_1):PAGE326
 R2227    1      A Q_RES_0402LF-1K,1%,1/16W,CHIP,A   I101 @S9S_MB_2U_LIB.S9S_MB_2U(SCH_1):PAGE326
  U206    3   INA+ LT6700CS61TRPBF-LT6700CS6-1#TRA   I102 @S9S_MB_2U_LIB.S9S_MB_2U(SCH_1):PAGE326

A_P12V_STBY_FPH_GATE @S9S_MB_2U_LIB.S9S_MB_2U(SCH_1):A_P12V_STBY_FPH_GATE
  U325    G   GATE MOSFET_N_SMLF-BSS138K,BSS138K,A    I38 @S9S_MB_2U_LIB.S9S_MB_2U(SCH_1):PAGE326
 R2230    2      B Q_RES_0402LF-10K,1%,1/16W,CHIPA    I39 @S9S_MB_2U_LIB.S9S_MB_2U(SCH_1):PAGE326
  U206    6   OUTB LT6700CS61TRPBF-LT6700CS6-1#TRA   I102 @S9S_MB_2U_LIB.S9S_MB_2U(SCH_1):PAGE326

A_P12V_STBY_FP_TRIGGER @S9S_MB_2U_LIB.S9S_MB_2U(SCH_1):A_P12V_STBY_FP_TRIGGER
 R2222    1      A Q_RES_0402LF-1K,1%,1/16W,CHIP,A    I17 @S9S_MB_2U_LIB.S9S_MB_2U(SCH_1):PAGE326
 R2221    2      B Q_RES_0402LF-26.7K,1%,1/16W,CHA    I20 @S9S_MB_2U_LIB.S9S_MB_2U(SCH_1):PAGE326
  U206    4   INB- LT6700CS61TRPBF-LT6700CS6-1#TRA   I102 @S9S_MB_2U_LIB.S9S_MB_2U(SCH_1):PAGE326

BIC_MONITER @S9S_MB_2U_LIB.S9S_MB_2U(SCH_1):BIC_MONITER
   Q67    2     G1 MOSFET_NCH_DUAL-PJT138K,SMLF,IA    I33 @S9S_MB_2U_LIB.S9S_MB_2U(SCH_1):PAGE145
 R2831    1      A Q_RES_0402LF-100K,1%,1/16W,EMPA    I56 @S9S_MB_2U_LIB.S9S_MB_2U(SCH_1):PAGE145
 R2830    2      B Q_RES_0402LF-100K,1%,1/16W,CHIA    I68 @S9S_MB_2U_LIB.S9S_MB_2U(SCH_1):PAGE145
  J109   A3     A3 CONN112_10137002101LF-CONN112_A    I53 @S9S_MB_2U_LIB.S9S_MB_2U(SCH_1):PAGE319

BIC_MONITER_ISO @S9S_MB_2U_LIB.S9S_MB_2U(SCH_1):BIC_MONITER_ISO
   Q67    3     D2 MOSFET_NCH_DUAL-PJT138K,SMLF,IA    I82 @S9S_MB_2U_LIB.S9S_MB_2U(SCH_1):PAGE145
 R2920    2      B Q_RES_0402LF-4.7K,5%,1/16W,CHIA    I84 @S9S_MB_2U_LIB.S9S_MB_2U(SCH_1):PAGE145
 C1773    1      A Q_CAP_0402-1000PF,50V,5%,EMPTYA   I114 @S9S_MB_2U_LIB.S9S_MB_2U(SCH_1):PAGE145
 R2846    1      A Q_RES_0402LF-33.2,1%,1/16W,CHIA   I134 @S9S_MB_2U_LIB.S9S_MB_2U(SCH_1):PAGE314

BIC_MONITER_ISO_R @S9S_MB_2U_LIB.S9S_MB_2U(SCH_1):BIC_MONITER_ISO_R
 R2846    2      B Q_RES_0402LF-33.2,1%,1/16W,CHIA   I134 @S9S_MB_2U_LIB.S9S_MB_2U(SCH_1):PAGE314
  U249   C3  PT10C LCMXO3LF9400C5BG484C-LCMXO3LF-A   I188 @S9S_MB_2U_LIB.S9S_MB_2U(SCH_1):PAGE314

BIC_MONITER_N @S9S_MB_2U_LIB.S9S_MB_2U(SCH_1):BIC_MONITER_N
 R2835    2      B Q_RES_0402LF-4.7K,5%,1/16W,CHIA    I14 @S9S_MB_2U_LIB.S9S_MB_2U(SCH_1):PAGE145
   Q67    6     D1 MOSFET_NCH_DUAL-PJT138K,SMLF,IA    I33 @S9S_MB_2U_LIB.S9S_MB_2U(SCH_1):PAGE145
   Q67    5     G2 MOSFET_NCH_DUAL-PJT138K,SMLF,IA    I82 @S9S_MB_2U_LIB.S9S_MB_2U(SCH_1):PAGE145

BMC_MONITER @S9S_MB_2U_LIB.S9S_MB_2U(SCH_1):BMC_MONITER
 R2845    1      A Q_RES_0402LF-33.2,1%,1/16W,CHIA   I136 @S9S_MB_2U_LIB.S9S_MB_2U(SCH_1):PAGE314
  U249   C4  PT10D LCMXO3LF9400C5BG484C-LCMXO3LF-A   I188 @S9S_MB_2U_LIB.S9S_MB_2U(SCH_1):PAGE314

BMC_MONITER_BUF @S9S_MB_2U_LIB.S9S_MB_2U(SCH_1):BMC_MONITER_BUF
  J109   A1     A1 CONN112_10137002101LF-CONN112_A    I53 @S9S_MB_2U_LIB.S9S_MB_2U(SCH_1):PAGE319
 R2917    2      B Q_RES_0402LF-49.9,1%,1/16W,CHIA   I206 @S9S_MB_2U_LIB.S9S_MB_2U(SCH_1):PAGE140

BMC_MONITER_BUF_R @S9S_MB_2U_LIB.S9S_MB_2U(SCH_1):BMC_MONITER_BUF_R
  U195    6     B0 74LVC2G17GW-74LVC2G17GW,SMLF,IA    I65 @S9S_MB_2U_LIB.S9S_MB_2U(SCH_1):PAGE140
 R2820    2      B Q_RES_0402LF-4.7K,5%,1/16W,EMPA    I78 @S9S_MB_2U_LIB.S9S_MB_2U(SCH_1):PAGE140
 R2926    1      A Q_RES_0402LF-4.7K,5%,1/16W,CHIA   I121 @S9S_MB_2U_LIB.S9S_MB_2U(SCH_1):PAGE140
 R2917    1      A Q_RES_0402LF-49.9,1%,1/16W,CHIA   I206 @S9S_MB_2U_LIB.S9S_MB_2U(SCH_1):PAGE140

BMC_MONITER_R @S9S_MB_2U_LIB.S9S_MB_2U(SCH_1):BMC_MONITER_R
  U195    1     A0 74LVC2G17GW-74LVC2G17GW,SMLF,IA    I65 @S9S_MB_2U_LIB.S9S_MB_2U(SCH_1):PAGE140
 R2815    2      B Q_RES_0402LF-100K,1%,1/16W,EMPA    I68 @S9S_MB_2U_LIB.S9S_MB_2U(SCH_1):PAGE140
 R2915    1      A Q_RES_0402LF-4.7K,5%,1/16W,CHIA    I92 @S9S_MB_2U_LIB.S9S_MB_2U(SCH_1):PAGE140
 R2845    2      B Q_RES_0402LF-33.2,1%,1/16W,CHIA   I136 @S9S_MB_2U_LIB.S9S_MB_2U(SCH_1):PAGE314

CK440Q_OE_1 @S9S_MB_2U_LIB.S9S_MB_2U(SCH_1):CK440Q_OE_1
   U13  A30   OE1# 9SQ440NQQI8-9SQ440NQQI8,SMLF,IA   I180 @S9S_MB_2U_LIB.S9S_MB_2U(SCH_1):PAGE197
 R3638    2      B Q_RES_0402LF-10K,1%,1/16W,CHIPA   I378 @S9S_MB_2U_LIB.S9S_MB_2U(SCH_1):PAGE197

CK440Q_OE_2 @S9S_MB_2U_LIB.S9S_MB_2U(SCH_1):CK440Q_OE_2
   U13  A29   OE2# 9SQ440NQQI8-9SQ440NQQI8,SMLF,IA   I180 @S9S_MB_2U_LIB.S9S_MB_2U(SCH_1):PAGE197
 R3639    2      B Q_RES_0402LF-10K,1%,1/16W,CHIPA   I379 @S9S_MB_2U_LIB.S9S_MB_2U(SCH_1):PAGE197

CK440Q_OE_3 @S9S_MB_2U_LIB.S9S_MB_2U(SCH_1):CK440Q_OE_3
   U13  A26   OE3# 9SQ440NQQI8-9SQ440NQQI8,SMLF,IA   I180 @S9S_MB_2U_LIB.S9S_MB_2U(SCH_1):PAGE197
 R3640    2      B Q_RES_0402LF-10K,1%,1/16W,CHIPA   I380 @S9S_MB_2U_LIB.S9S_MB_2U(SCH_1):PAGE197

CK440Q_OE_4 @S9S_MB_2U_LIB.S9S_MB_2U(SCH_1):CK440Q_OE_4
   U13  B19   OE4# 9SQ440NQQI8-9SQ440NQQI8,SMLF,IA   I180 @S9S_MB_2U_LIB.S9S_MB_2U(SCH_1):PAGE197
 R3641    2      B Q_RES_0402LF-10K,1%,1/16W,CHIPA   I381 @S9S_MB_2U_LIB.S9S_MB_2U(SCH_1):PAGE197

CK440Q_OE_5 @S9S_MB_2U_LIB.S9S_MB_2U(SCH_1):CK440Q_OE_5
   U13  B15   OE5# 9SQ440NQQI8-9SQ440NQQI8,SMLF,IA   I180 @S9S_MB_2U_LIB.S9S_MB_2U(SCH_1):PAGE197
 R3642    2      B Q_RES_0402LF-10K,1%,1/16W,CHIPA   I382 @S9S_MB_2U_LIB.S9S_MB_2U(SCH_1):PAGE197

CK440Q_OE_6 @S9S_MB_2U_LIB.S9S_MB_2U(SCH_1):CK440Q_OE_6
   U13  B14   OE6# 9SQ440NQQI8-9SQ440NQQI8,SMLF,IA   I180 @S9S_MB_2U_LIB.S9S_MB_2U(SCH_1):PAGE197
 R3643    2      B Q_RES_0402LF-10K,1%,1/16W,CHIPA   I383 @S9S_MB_2U_LIB.S9S_MB_2U(SCH_1):PAGE197

CLK_100M_BMC_P3E_DN @S9S_MB_2U_LIB.S9S_MB_2U(SCH_1):CLK_100M_BMC_P3E_DN
    U4  B11 CLKOUT_SRC_N_6 EMMITSBURG_REV0P9-GFNOCPU04302A    I78 @S9S_MB_2U_LIB.S9S_MB_2U(SCH_1):PAGE171
 R4536    1      A Q_RES_0402LF-10,1%,1/16W,CHIP,A    I92 @S9S_MB_2U_LIB.S9S_MB_2U(SCH_1):PAGE227

CLK_100M_BMC_P3E_DN_R @S9S_MB_2U_LIB.S9S_MB_2U(SCH_1):CLK_100M_BMC_P3E_DN_R
 R4536    2      B Q_RES_0402LF-10,1%,1/16W,CHIP,A    I92 @S9S_MB_2U_LIB.S9S_MB_2U(SCH_1):PAGE227
   J41  A15 REFCLKP1 SCONN168_ME1016810202011-SCONNA   I173 @S9S_MB_2U_LIB.S9S_MB_2U(SCH_1):PAGE227

CLK_100M_BMC_P3E_DP @S9S_MB_2U_LIB.S9S_MB_2U(SCH_1):CLK_100M_BMC_P3E_DP
    U4  D11 CLKOUT_SRC_P_6 EMMITSBURG_REV0P9-GFNOCPU04302A    I78 @S9S_MB_2U_LIB.S9S_MB_2U(SCH_1):PAGE171
 R4535    1      A Q_RES_0402LF-10,1%,1/16W,CHIP,A    I91 @S9S_MB_2U_LIB.S9S_MB_2U(SCH_1):PAGE227

CLK_100M_BMC_P3E_DP_R @S9S_MB_2U_LIB.S9S_MB_2U(SCH_1):CLK_100M_BMC_P3E_DP_R
 R4535    2      B Q_RES_0402LF-10,1%,1/16W,CHIP,A    I91 @S9S_MB_2U_LIB.S9S_MB_2U(SCH_1):PAGE227
   J41  A14 REFCLKN1 SCONN168_ME1016810202011-SCONNA   I173 @S9S_MB_2U_LIB.S9S_MB_2U(SCH_1):PAGE227

CLK_100M_BMC_RC_DN @S9S_MB_2U_LIB.S9S_MB_2U(SCH_1):CLK_100M_BMC_RC_DN
 R3336    2      B Q_RES_0402LF-0,5%,1/16W,CHIP,CA    I74 @S9S_MB_2U_LIB.S9S_MB_2U(SCH_1):PAGE201
   J41  A69 USB_DATP SCONN168_ME1016810202011-SCONNA   I173 @S9S_MB_2U_LIB.S9S_MB_2U(SCH_1):PAGE227

CLK_100M_BMC_RC_DN_R @S9S_MB_2U_LIB.S9S_MB_2U(SCH_1):CLK_100M_BMC_RC_DN_R
 R3336    1      A Q_RES_0402LF-0,5%,1/16W,CHIP,CA    I74 @S9S_MB_2U_LIB.S9S_MB_2U(SCH_1):PAGE201
  U247   14  DIF0# 9FGL0251DKILFT-9FGL0251DKILFT,A   I167 @S9S_MB_2U_LIB.S9S_MB_2U(SCH_1):PAGE201

CLK_100M_BMC_RC_DP @S9S_MB_2U_LIB.S9S_MB_2U(SCH_1):CLK_100M_BMC_RC_DP
 R3335    2      B Q_RES_0402LF-0,5%,1/16W,CHIP,CA    I69 @S9S_MB_2U_LIB.S9S_MB_2U(SCH_1):PAGE201
   J41  A68 USB_DATN SCONN168_ME1016810202011-SCONNA   I173 @S9S_MB_2U_LIB.S9S_MB_2U(SCH_1):PAGE227

CLK_100M_BMC_RC_DP_R @S9S_MB_2U_LIB.S9S_MB_2U(SCH_1):CLK_100M_BMC_RC_DP_R
 R3335    1      A Q_RES_0402LF-0,5%,1/16W,CHIP,CA    I69 @S9S_MB_2U_LIB.S9S_MB_2U(SCH_1):PAGE201
  U247   13   DIF0 9FGL0251DKILFT-9FGL0251DKILFT,A   I167 @S9S_MB_2U_LIB.S9S_MB_2U(SCH_1):PAGE201

CLK_100M_CK440_PCH_EXTCLK_DN @S9S_MB_2U_LIB.S9S_MB_2U(SCH_1):CLK_100M_CK440_PCH_EXTCLK_DN
    U4  D21 REFCLK_INJ_S_N EMMITSBURG_REV0P9-GFNOCPU04302A    I78 @S9S_MB_2U_LIB.S9S_MB_2U(SCH_1):PAGE171
  R554    2      B Q_RES_0402LF-0,5%,1/16W,CHIP,CA    I57 @S9S_MB_2U_LIB.S9S_MB_2U(SCH_1):PAGE198

CLK_100M_CK440_PCH_EXTCLK_DP @S9S_MB_2U_LIB.S9S_MB_2U(SCH_1):CLK_100M_CK440_PCH_EXTCLK_DP
    U4  B21 REFCLK_INJ_S_P EMMITSBURG_REV0P9-GFNOCPU04302A    I78 @S9S_MB_2U_LIB.S9S_MB_2U(SCH_1):PAGE171
  R553    2      B Q_RES_0402LF-0,5%,1/16W,CHIP,CA    I58 @S9S_MB_2U_LIB.S9S_MB_2U(SCH_1):PAGE198

CLK_100M_CK440_PCH_EXTCLK_R_DN @S9S_MB_2U_LIB.S9S_MB_2U(SCH_1):CLK_100M_CK440_PCH_EXTCLK_R_DN
   U13  A47 MXCK2# 9SQ440NQQI8-9SQ440NQQI8,SMLF,IA   I180 @S9S_MB_2U_LIB.S9S_MB_2U(SCH_1):PAGE197
  R554    1      A Q_RES_0402LF-0,5%,1/16W,CHIP,CA    I57 @S9S_MB_2U_LIB.S9S_MB_2U(SCH_1):PAGE198

CLK_100M_CK440_PCH_EXTCLK_R_DP @S9S_MB_2U_LIB.S9S_MB_2U(SCH_1):CLK_100M_CK440_PCH_EXTCLK_R_DP
   U13  A48  MXCK2 9SQ440NQQI8-9SQ440NQQI8,SMLF,IA   I180 @S9S_MB_2U_LIB.S9S_MB_2U(SCH_1):PAGE197
  R553    1      A Q_RES_0402LF-0,5%,1/16W,CHIP,CA    I58 @S9S_MB_2U_LIB.S9S_MB_2U(SCH_1):PAGE198

CLK_100M_DB2000_CPU0_BCLK0_DN @S9S_MB_2U_LIB.S9S_MB_2U(SCH_1):CLK_100M_DB2000_CPU0_BCLK0_DN
    U2 AT30 BCLK0_DN SOCKET4677_AZIF0045P001C01CS-SA    I57 @S9S_MB_2U_LIB.S9S_MB_2U(SCH_1):PAGE13
   U38   K1  DIF0# 9QXL2001BNHGI8-9QXL2001BNHGI8,A   I119 @S9S_MB_2U_LIB.S9S_MB_2U(SCH_1):PAGE195

CLK_100M_DB2000_CPU0_BCLK0_DP @S9S_MB_2U_LIB.S9S_MB_2U(SCH_1):CLK_100M_DB2000_CPU0_BCLK0_DP
    U2 AV30 BCLK0_DP SOCKET4677_AZIF0045P001C01CS-SA    I57 @S9S_MB_2U_LIB.S9S_MB_2U(SCH_1):PAGE13
   U38   J1   DIF0 9QXL2001BNHGI8-9QXL2001BNHGI8,A   I119 @S9S_MB_2U_LIB.S9S_MB_2U(SCH_1):PAGE195

CLK_100M_DB2000_CPU0_BCLK1_DN @S9S_MB_2U_LIB.S9S_MB_2U(SCH_1):CLK_100M_DB2000_CPU0_BCLK1_DN
    U2 CY28 BCLK1_DN SOCKET4677_AZIF0045P001C01CS-SA    I57 @S9S_MB_2U_LIB.S9S_MB_2U(SCH_1):PAGE13
   U38   M1  DIF1# 9QXL2001BNHGI8-9QXL2001BNHGI8,A   I119 @S9S_MB_2U_LIB.S9S_MB_2U(SCH_1):PAGE195

CLK_100M_DB2000_CPU0_BCLK1_DP @S9S_MB_2U_LIB.S9S_MB_2U(SCH_1):CLK_100M_DB2000_CPU0_BCLK1_DP
    U2 CW29 BCLK1_DP SOCKET4677_AZIF0045P001C01CS-SA    I57 @S9S_MB_2U_LIB.S9S_MB_2U(SCH_1):PAGE13
   U38   L1   DIF1 9QXL2001BNHGI8-9QXL2001BNHGI8,A   I119 @S9S_MB_2U_LIB.S9S_MB_2U(SCH_1):PAGE195

CLK_100M_DB2000_CPU0_BCLK2_DN @S9S_MB_2U_LIB.S9S_MB_2U(SCH_1):CLK_100M_DB2000_CPU0_BCLK2_DN
    U2 AU29 BCLK2_DN SOCKET4677_AZIF0045P001C01CS-SA    I57 @S9S_MB_2U_LIB.S9S_MB_2U(SCH_1):PAGE13
   U38   M3  DIF2# 9QXL2001BNHGI8-9QXL2001BNHGI8,A   I119 @S9S_MB_2U_LIB.S9S_MB_2U(SCH_1):PAGE195

CLK_100M_DB2000_CPU0_BCLK2_DP @S9S_MB_2U_LIB.S9S_MB_2U(SCH_1):CLK_100M_DB2000_CPU0_BCLK2_DP
    U2 AV28 BCLK2_DP SOCKET4677_AZIF0045P001C01CS-SA    I57 @S9S_MB_2U_LIB.S9S_MB_2U(SCH_1):PAGE13
   U38   M2   DIF2 9QXL2001BNHGI8-9QXL2001BNHGI8,A   I119 @S9S_MB_2U_LIB.S9S_MB_2U(SCH_1):PAGE195

CLK_100M_DB2000_CPU0_BCLK3_DN @S9S_MB_2U_LIB.S9S_MB_2U(SCH_1):CLK_100M_DB2000_CPU0_BCLK3_DN
    U2 CW27 BCLK3_DN SOCKET4677_AZIF0045P001C01CS-SA    I57 @S9S_MB_2U_LIB.S9S_MB_2U(SCH_1):PAGE13
   U38   M5  DIF3# 9QXL2001BNHGI8-9QXL2001BNHGI8,A   I119 @S9S_MB_2U_LIB.S9S_MB_2U(SCH_1):PAGE195

CLK_100M_DB2000_CPU0_BCLK3_DP @S9S_MB_2U_LIB.S9S_MB_2U(SCH_1):CLK_100M_DB2000_CPU0_BCLK3_DP
    U2 DA27 BCLK3_DP SOCKET4677_AZIF0045P001C01CS-SA    I57 @S9S_MB_2U_LIB.S9S_MB_2U(SCH_1):PAGE13
   U38   M4   DIF3 9QXL2001BNHGI8-9QXL2001BNHGI8,A   I119 @S9S_MB_2U_LIB.S9S_MB_2U(SCH_1):PAGE195

CLK_100M_DB2000_CPU1_BCLK0_DN @S9S_MB_2U_LIB.S9S_MB_2U(SCH_1):CLK_100M_DB2000_CPU1_BCLK0_DN
    U1 AT30 BCLK0_DN SOCKET4677_AZIF0045P001C01CS-SA    I51 @S9S_MB_2U_LIB.S9S_MB_2U(SCH_1):PAGE44
   U38   M8  DIF4# 9QXL2001BNHGI8-9QXL2001BNHGI8,A   I119 @S9S_MB_2U_LIB.S9S_MB_2U(SCH_1):PAGE195

CLK_100M_DB2000_CPU1_BCLK0_DP @S9S_MB_2U_LIB.S9S_MB_2U(SCH_1):CLK_100M_DB2000_CPU1_BCLK0_DP
    U1 AV30 BCLK0_DP SOCKET4677_AZIF0045P001C01CS-SA    I51 @S9S_MB_2U_LIB.S9S_MB_2U(SCH_1):PAGE44
   U38   M7   DIF4 9QXL2001BNHGI8-9QXL2001BNHGI8,A   I119 @S9S_MB_2U_LIB.S9S_MB_2U(SCH_1):PAGE195

CLK_100M_DB2000_CPU1_BCLK1_DN @S9S_MB_2U_LIB.S9S_MB_2U(SCH_1):CLK_100M_DB2000_CPU1_BCLK1_DN
    U1 CY28 BCLK1_DN SOCKET4677_AZIF0045P001C01CS-SA    I51 @S9S_MB_2U_LIB.S9S_MB_2U(SCH_1):PAGE44
   U38  M10  DIF5# 9QXL2001BNHGI8-9QXL2001BNHGI8,A   I119 @S9S_MB_2U_LIB.S9S_MB_2U(SCH_1):PAGE195

CLK_100M_DB2000_CPU1_BCLK1_DP @S9S_MB_2U_LIB.S9S_MB_2U(SCH_1):CLK_100M_DB2000_CPU1_BCLK1_DP
    U1 CW29 BCLK1_DP SOCKET4677_AZIF0045P001C01CS-SA    I51 @S9S_MB_2U_LIB.S9S_MB_2U(SCH_1):PAGE44
   U38   M9   DIF5 9QXL2001BNHGI8-9QXL2001BNHGI8,A   I119 @S9S_MB_2U_LIB.S9S_MB_2U(SCH_1):PAGE195

CLK_100M_DB2000_CPU1_BCLK2_DN @S9S_MB_2U_LIB.S9S_MB_2U(SCH_1):CLK_100M_DB2000_CPU1_BCLK2_DN
    U1 AU29 BCLK2_DN SOCKET4677_AZIF0045P001C01CS-SA    I51 @S9S_MB_2U_LIB.S9S_MB_2U(SCH_1):PAGE44
   U38  M12  DIF6# 9QXL2001BNHGI8-9QXL2001BNHGI8,A   I119 @S9S_MB_2U_LIB.S9S_MB_2U(SCH_1):PAGE195

CLK_100M_DB2000_CPU1_BCLK2_DP @S9S_MB_2U_LIB.S9S_MB_2U(SCH_1):CLK_100M_DB2000_CPU1_BCLK2_DP
    U1 AV28 BCLK2_DP SOCKET4677_AZIF0045P001C01CS-SA    I51 @S9S_MB_2U_LIB.S9S_MB_2U(SCH_1):PAGE44
   U38  M11   DIF6 9QXL2001BNHGI8-9QXL2001BNHGI8,A   I119 @S9S_MB_2U_LIB.S9S_MB_2U(SCH_1):PAGE195

CLK_100M_DB2000_CPU1_BCLK3_DN @S9S_MB_2U_LIB.S9S_MB_2U(SCH_1):CLK_100M_DB2000_CPU1_BCLK3_DN
    U1 CW27 BCLK3_DN SOCKET4677_AZIF0045P001C01CS-SA    I51 @S9S_MB_2U_LIB.S9S_MB_2U(SCH_1):PAGE44
   U38  K12  DIF7# 9QXL2001BNHGI8-9QXL2001BNHGI8,A   I119 @S9S_MB_2U_LIB.S9S_MB_2U(SCH_1):PAGE195

CLK_100M_DB2000_CPU1_BCLK3_DP @S9S_MB_2U_LIB.S9S_MB_2U(SCH_1):CLK_100M_DB2000_CPU1_BCLK3_DP
    U1 DA27 BCLK3_DP SOCKET4677_AZIF0045P001C01CS-SA    I51 @S9S_MB_2U_LIB.S9S_MB_2U(SCH_1):PAGE44
   U38  L12   DIF7 9QXL2001BNHGI8-9QXL2001BNHGI8,A   I119 @S9S_MB_2U_LIB.S9S_MB_2U(SCH_1):PAGE195

CLK_100M_DB2000_DN @S9S_MB_2U_LIB.S9S_MB_2U(SCH_1):CLK_100M_DB2000_DN
   U38   H1 DIF_IN# 9QXL2001BNHGI8-9QXL2001BNHGI8,A   I119 @S9S_MB_2U_LIB.S9S_MB_2U(SCH_1):PAGE195
   U13  A33 100M0# 9SQ440NQQI8-9SQ440NQQI8,SMLF,IA   I180 @S9S_MB_2U_LIB.S9S_MB_2U(SCH_1):PAGE197

CLK_100M_DB2000_DP @S9S_MB_2U_LIB.S9S_MB_2U(SCH_1):CLK_100M_DB2000_DP
   U38   G1 DIF_IN 9QXL2001BNHGI8-9QXL2001BNHGI8,A   I119 @S9S_MB_2U_LIB.S9S_MB_2U(SCH_1):PAGE195
   U13  A34  100M0 9SQ440NQQI8-9SQ440NQQI8,SMLF,IA   I180 @S9S_MB_2U_LIB.S9S_MB_2U(SCH_1):PAGE197

CLK_100M_E1S_0_DN @S9S_MB_2U_LIB.S9S_MB_2U(SCH_1):CLK_100M_E1S_0_DN
   J90  B14 REFCLK_N0 SCONN56_123276793-SCONN56_1-23A   I318 @S9S_MB_2U_LIB.S9S_MB_2U(SCH_1):PAGE297
 R4304    2      B Q_RES_0402LF-22,1%,1/16W,CHIP,A   I122 @S9S_MB_2U_LIB.S9S_MB_2U(SCH_1):PAGE171

CLK_100M_E1S_0_DP @S9S_MB_2U_LIB.S9S_MB_2U(SCH_1):CLK_100M_E1S_0_DP
   J90  B15 REFCLK_P0 SCONN56_123276793-SCONN56_1-23A   I318 @S9S_MB_2U_LIB.S9S_MB_2U(SCH_1):PAGE297
 R4303    2      B Q_RES_0402LF-22,1%,1/16W,CHIP,A   I121 @S9S_MB_2U_LIB.S9S_MB_2U(SCH_1):PAGE171

CLK_100M_E1S_0_R_DN @S9S_MB_2U_LIB.S9S_MB_2U(SCH_1):CLK_100M_E1S_0_R_DN
    U4  B17 CLKOUT_SRC_N_3 EMMITSBURG_REV0P9-GFNOCPU04302A    I78 @S9S_MB_2U_LIB.S9S_MB_2U(SCH_1):PAGE171
 R4304    1      A Q_RES_0402LF-22,1%,1/16W,CHIP,A   I122 @S9S_MB_2U_LIB.S9S_MB_2U(SCH_1):PAGE171

CLK_100M_E1S_0_R_DP @S9S_MB_2U_LIB.S9S_MB_2U(SCH_1):CLK_100M_E1S_0_R_DP
    U4  D17 CLKOUT_SRC_P_3 EMMITSBURG_REV0P9-GFNOCPU04302A    I78 @S9S_MB_2U_LIB.S9S_MB_2U(SCH_1):PAGE171
 R4303    1      A Q_RES_0402LF-22,1%,1/16W,CHIP,A   I121 @S9S_MB_2U_LIB.S9S_MB_2U(SCH_1):PAGE171

CLK_100M_GPU_1_DN @S9S_MB_2U_LIB.S9S_MB_2U(SCH_1):CLK_100M_GPU_1_DN
  J112   N4     N4 CONN160_10131762101LF-CONN160_A    I76 @S9S_MB_2U_LIB.S9S_MB_2U(SCH_1):PAGE149
 R3353    2      B Q_RES_0402LF-0,5%,1/16W,CHIP,CA    I25 @S9S_MB_2U_LIB.S9S_MB_2U(SCH_1):PAGE196

CLK_100M_GPU_1_DP @S9S_MB_2U_LIB.S9S_MB_2U(SCH_1):CLK_100M_GPU_1_DP
  J112   O4     O4 CONN160_10131762101LF-CONN160_A    I76 @S9S_MB_2U_LIB.S9S_MB_2U(SCH_1):PAGE149
 R3352    2      B Q_RES_0402LF-0,5%,1/16W,CHIP,CA    I26 @S9S_MB_2U_LIB.S9S_MB_2U(SCH_1):PAGE196

CLK_100M_GPU_1_R_DN @S9S_MB_2U_LIB.S9S_MB_2U(SCH_1):CLK_100M_GPU_1_R_DN
  U314   20  DIF1# 9ZXL0451EKILFT-9ZXL0451EKILFT,A     I1 @S9S_MB_2U_LIB.S9S_MB_2U(SCH_1):PAGE200
 R3353    1      A Q_RES_0402LF-0,5%,1/16W,CHIP,CA    I25 @S9S_MB_2U_LIB.S9S_MB_2U(SCH_1):PAGE196

CLK_100M_GPU_1_R_DP @S9S_MB_2U_LIB.S9S_MB_2U(SCH_1):CLK_100M_GPU_1_R_DP
  U314   19   DIF1 9ZXL0451EKILFT-9ZXL0451EKILFT,A     I1 @S9S_MB_2U_LIB.S9S_MB_2U(SCH_1):PAGE200
 R3352    1      A Q_RES_0402LF-0,5%,1/16W,CHIP,CA    I26 @S9S_MB_2U_LIB.S9S_MB_2U(SCH_1):PAGE196

CLK_100M_GPU_2_DN @S9S_MB_2U_LIB.S9S_MB_2U(SCH_1):CLK_100M_GPU_2_DN
  J112   O1     O1 CONN160_10131762101LF-CONN160_A    I76 @S9S_MB_2U_LIB.S9S_MB_2U(SCH_1):PAGE149
 R3355    2      B Q_RES_0402LF-0,5%,1/16W,CHIP,CA    I18 @S9S_MB_2U_LIB.S9S_MB_2U(SCH_1):PAGE196

CLK_100M_GPU_2_DP @S9S_MB_2U_LIB.S9S_MB_2U(SCH_1):CLK_100M_GPU_2_DP
  J112   P1     P1 CONN160_10131762101LF-CONN160_A    I76 @S9S_MB_2U_LIB.S9S_MB_2U(SCH_1):PAGE149
 R3354    2      B Q_RES_0402LF-0,5%,1/16W,CHIP,CA    I24 @S9S_MB_2U_LIB.S9S_MB_2U(SCH_1):PAGE196

CLK_100M_GPU_2_R_DN @S9S_MB_2U_LIB.S9S_MB_2U(SCH_1):CLK_100M_GPU_2_R_DN
  U314   23  DIF2# 9ZXL0451EKILFT-9ZXL0451EKILFT,A     I1 @S9S_MB_2U_LIB.S9S_MB_2U(SCH_1):PAGE200
 R3355    1      A Q_RES_0402LF-0,5%,1/16W,CHIP,CA    I18 @S9S_MB_2U_LIB.S9S_MB_2U(SCH_1):PAGE196

CLK_100M_GPU_2_R_DP @S9S_MB_2U_LIB.S9S_MB_2U(SCH_1):CLK_100M_GPU_2_R_DP
  U314   22   DIF2 9ZXL0451EKILFT-9ZXL0451EKILFT,A     I1 @S9S_MB_2U_LIB.S9S_MB_2U(SCH_1):PAGE200
 R3354    1      A Q_RES_0402LF-0,5%,1/16W,CHIP,CA    I24 @S9S_MB_2U_LIB.S9S_MB_2U(SCH_1):PAGE196

CLK_100M_GPU_FPGA_DN @S9S_MB_2U_LIB.S9S_MB_2U(SCH_1):CLK_100M_GPU_FPGA_DN
  J112   Q2     Q2 CONN160_10131762101LF-CONN160_A    I76 @S9S_MB_2U_LIB.S9S_MB_2U(SCH_1):PAGE149
 R3338    2      B Q_RES_0402LF-0,5%,1/16W,CHIP,CA    I76 @S9S_MB_2U_LIB.S9S_MB_2U(SCH_1):PAGE201

CLK_100M_GPU_FPGA_DN_R @S9S_MB_2U_LIB.S9S_MB_2U(SCH_1):CLK_100M_GPU_FPGA_DN_R
 R3338    1      A Q_RES_0402LF-0,5%,1/16W,CHIP,CA    I76 @S9S_MB_2U_LIB.S9S_MB_2U(SCH_1):PAGE201
  U247   18  DIF1# 9FGL0251DKILFT-9FGL0251DKILFT,A   I167 @S9S_MB_2U_LIB.S9S_MB_2U(SCH_1):PAGE201

CLK_100M_GPU_FPGA_DP @S9S_MB_2U_LIB.S9S_MB_2U(SCH_1):CLK_100M_GPU_FPGA_DP
  J112   R2     R2 CONN160_10131762101LF-CONN160_A    I76 @S9S_MB_2U_LIB.S9S_MB_2U(SCH_1):PAGE149
 R3337    2      B Q_RES_0402LF-0,5%,1/16W,CHIP,CA    I75 @S9S_MB_2U_LIB.S9S_MB_2U(SCH_1):PAGE201

CLK_100M_GPU_FPGA_DP_R @S9S_MB_2U_LIB.S9S_MB_2U(SCH_1):CLK_100M_GPU_FPGA_DP_R
 R3337    1      A Q_RES_0402LF-0,5%,1/16W,CHIP,CA    I75 @S9S_MB_2U_LIB.S9S_MB_2U(SCH_1):PAGE201
  U247   17   DIF1 9FGL0251DKILFT-9FGL0251DKILFT,A   I167 @S9S_MB_2U_LIB.S9S_MB_2U(SCH_1):PAGE201

CLK_100M_GPU_SWB_REF_DN @S9S_MB_2U_LIB.S9S_MB_2U(SCH_1):CLK_100M_GPU_SWB_REF_DN
   U38  H12  DIF8# 9QXL2001BNHGI8-9QXL2001BNHGI8,A   I119 @S9S_MB_2U_LIB.S9S_MB_2U(SCH_1):PAGE195
  U314    4 DIF_IN# 9ZXL0451EKILFT-9ZXL0451EKILFT,A     I1 @S9S_MB_2U_LIB.S9S_MB_2U(SCH_1):PAGE200

CLK_100M_GPU_SWB_REF_DP @S9S_MB_2U_LIB.S9S_MB_2U(SCH_1):CLK_100M_GPU_SWB_REF_DP
   U38  J12   DIF8 9QXL2001BNHGI8-9QXL2001BNHGI8,A   I119 @S9S_MB_2U_LIB.S9S_MB_2U(SCH_1):PAGE195
  U314    3 DIF_IN 9ZXL0451EKILFT-9ZXL0451EKILFT,A     I1 @S9S_MB_2U_LIB.S9S_MB_2U(SCH_1):PAGE200

CLK_100M_OCP_SFF_0_DN @S9S_MB_2U_LIB.S9S_MB_2U(SCH_1):CLK_100M_OCP_SFF_0_DN
   J37  B14 REFCLKN0 SCONN168_ME1016810202011-SCONNA   I199 @S9S_MB_2U_LIB.S9S_MB_2U(SCH_1):PAGE150
  R564    2      B Q_RES_0402LF-22,1%,1/16W,CHIP,A    I47 @S9S_MB_2U_LIB.S9S_MB_2U(SCH_1):PAGE198

CLK_100M_OCP_SFF_0_DP @S9S_MB_2U_LIB.S9S_MB_2U(SCH_1):CLK_100M_OCP_SFF_0_DP
   J37  B15 REFCLKP0 SCONN168_ME1016810202011-SCONNA   I199 @S9S_MB_2U_LIB.S9S_MB_2U(SCH_1):PAGE150
  R563    2      B Q_RES_0402LF-22,1%,1/16W,CHIP,A    I48 @S9S_MB_2U_LIB.S9S_MB_2U(SCH_1):PAGE198

CLK_100M_OCP_SFF_0_R_DN @S9S_MB_2U_LIB.S9S_MB_2U(SCH_1):CLK_100M_OCP_SFF_0_R_DN
   U38  F12  DIF9# 9QXL2001BNHGI8-9QXL2001BNHGI8,A   I119 @S9S_MB_2U_LIB.S9S_MB_2U(SCH_1):PAGE195
  R564    1      A Q_RES_0402LF-22,1%,1/16W,CHIP,A    I47 @S9S_MB_2U_LIB.S9S_MB_2U(SCH_1):PAGE198

CLK_100M_OCP_SFF_0_R_DP @S9S_MB_2U_LIB.S9S_MB_2U(SCH_1):CLK_100M_OCP_SFF_0_R_DP
   U38  G12   DIF9 9QXL2001BNHGI8-9QXL2001BNHGI8,A   I119 @S9S_MB_2U_LIB.S9S_MB_2U(SCH_1):PAGE195
  R563    1      A Q_RES_0402LF-22,1%,1/16W,CHIP,A    I48 @S9S_MB_2U_LIB.S9S_MB_2U(SCH_1):PAGE198

CLK_100M_OCP_SFF_1_DN @S9S_MB_2U_LIB.S9S_MB_2U(SCH_1):CLK_100M_OCP_SFF_1_DN
   J37  A14 REFCLKN1 SCONN168_ME1016810202011-SCONNA   I199 @S9S_MB_2U_LIB.S9S_MB_2U(SCH_1):PAGE150
  R566    2      B Q_RES_0402LF-22,1%,1/16W,CHIP,A    I45 @S9S_MB_2U_LIB.S9S_MB_2U(SCH_1):PAGE198

CLK_100M_OCP_SFF_1_DP @S9S_MB_2U_LIB.S9S_MB_2U(SCH_1):CLK_100M_OCP_SFF_1_DP
   J37  A15 REFCLKP1 SCONN168_ME1016810202011-SCONNA   I199 @S9S_MB_2U_LIB.S9S_MB_2U(SCH_1):PAGE150
  R565    2      B Q_RES_0402LF-22,1%,1/16W,CHIP,A    I46 @S9S_MB_2U_LIB.S9S_MB_2U(SCH_1):PAGE198

CLK_100M_OCP_SFF_1_R_DN @S9S_MB_2U_LIB.S9S_MB_2U(SCH_1):CLK_100M_OCP_SFF_1_R_DN
   U38  C12 DIF10# 9QXL2001BNHGI8-9QXL2001BNHGI8,A   I119 @S9S_MB_2U_LIB.S9S_MB_2U(SCH_1):PAGE195
  R566    1      A Q_RES_0402LF-22,1%,1/16W,CHIP,A    I45 @S9S_MB_2U_LIB.S9S_MB_2U(SCH_1):PAGE198

CLK_100M_OCP_SFF_1_R_DP @S9S_MB_2U_LIB.S9S_MB_2U(SCH_1):CLK_100M_OCP_SFF_1_R_DP
   U38  D12  DIF10 9QXL2001BNHGI8-9QXL2001BNHGI8,A   I119 @S9S_MB_2U_LIB.S9S_MB_2U(SCH_1):PAGE195
  R565    1      A Q_RES_0402LF-22,1%,1/16W,CHIP,A    I46 @S9S_MB_2U_LIB.S9S_MB_2U(SCH_1):PAGE198

CLK_100M_OCP_SFF_2_DN @S9S_MB_2U_LIB.S9S_MB_2U(SCH_1):CLK_100M_OCP_SFF_2_DN
   J37 OB11 REFCLKN2 SCONN168_ME1016810202011-SCONNA   I199 @S9S_MB_2U_LIB.S9S_MB_2U(SCH_1):PAGE150
 R1274    2      B Q_RES_0402LF-22,1%,1/16W,CHIP,A    I43 @S9S_MB_2U_LIB.S9S_MB_2U(SCH_1):PAGE198

CLK_100M_OCP_SFF_2_DP @S9S_MB_2U_LIB.S9S_MB_2U(SCH_1):CLK_100M_OCP_SFF_2_DP
   J37 OB12 REFCLKP2 SCONN168_ME1016810202011-SCONNA   I199 @S9S_MB_2U_LIB.S9S_MB_2U(SCH_1):PAGE150
 R1273    2      B Q_RES_0402LF-22,1%,1/16W,CHIP,A    I44 @S9S_MB_2U_LIB.S9S_MB_2U(SCH_1):PAGE198

CLK_100M_OCP_SFF_2_R_DN @S9S_MB_2U_LIB.S9S_MB_2U(SCH_1):CLK_100M_OCP_SFF_2_R_DN
   U38  A12 DIF11# 9QXL2001BNHGI8-9QXL2001BNHGI8,A   I119 @S9S_MB_2U_LIB.S9S_MB_2U(SCH_1):PAGE195
 R1274    1      A Q_RES_0402LF-22,1%,1/16W,CHIP,A    I43 @S9S_MB_2U_LIB.S9S_MB_2U(SCH_1):PAGE198

CLK_100M_OCP_SFF_2_R_DP @S9S_MB_2U_LIB.S9S_MB_2U(SCH_1):CLK_100M_OCP_SFF_2_R_DP
   U38  B12  DIF11 9QXL2001BNHGI8-9QXL2001BNHGI8,A   I119 @S9S_MB_2U_LIB.S9S_MB_2U(SCH_1):PAGE195
 R1273    1      A Q_RES_0402LF-22,1%,1/16W,CHIP,A    I44 @S9S_MB_2U_LIB.S9S_MB_2U(SCH_1):PAGE198

CLK_100M_OCP_SFF_3_DN @S9S_MB_2U_LIB.S9S_MB_2U(SCH_1):CLK_100M_OCP_SFF_3_DN
   J37 OA11 REFCLKN3 SCONN168_ME1016810202011-SCONNA   I199 @S9S_MB_2U_LIB.S9S_MB_2U(SCH_1):PAGE150
 R1276    2      B Q_RES_0402LF-22,1%,1/16W,CHIP,A    I23 @S9S_MB_2U_LIB.S9S_MB_2U(SCH_1):PAGE198

CLK_100M_OCP_SFF_3_DP @S9S_MB_2U_LIB.S9S_MB_2U(SCH_1):CLK_100M_OCP_SFF_3_DP
   J37 OA12 REFCLKP3 SCONN168_ME1016810202011-SCONNA   I199 @S9S_MB_2U_LIB.S9S_MB_2U(SCH_1):PAGE150
 R1275    2      B Q_RES_0402LF-22,1%,1/16W,CHIP,A    I24 @S9S_MB_2U_LIB.S9S_MB_2U(SCH_1):PAGE198

CLK_100M_OCP_SFF_3_R_DN @S9S_MB_2U_LIB.S9S_MB_2U(SCH_1):CLK_100M_OCP_SFF_3_R_DN
   U38  A10 DIF12# 9QXL2001BNHGI8-9QXL2001BNHGI8,A   I119 @S9S_MB_2U_LIB.S9S_MB_2U(SCH_1):PAGE195
 R1276    1      A Q_RES_0402LF-22,1%,1/16W,CHIP,A    I23 @S9S_MB_2U_LIB.S9S_MB_2U(SCH_1):PAGE198

CLK_100M_OCP_SFF_3_R_DP @S9S_MB_2U_LIB.S9S_MB_2U(SCH_1):CLK_100M_OCP_SFF_3_R_DP
   U38  A11  DIF12 9QXL2001BNHGI8-9QXL2001BNHGI8,A   I119 @S9S_MB_2U_LIB.S9S_MB_2U(SCH_1):PAGE195
 R1275    1      A Q_RES_0402LF-22,1%,1/16W,CHIP,A    I24 @S9S_MB_2U_LIB.S9S_MB_2U(SCH_1):PAGE198

CLK_100M_OCP_V3_2_A_DN @S9S_MB_2U_LIB.S9S_MB_2U(SCH_1):CLK_100M_OCP_V3_2_A_DN
   J35  B14 REFCLKN0 SCONN168_ME1016810202011-SCONNA   I303 @S9S_MB_2U_LIB.S9S_MB_2U(SCH_1):PAGE146
 R3195    2      B Q_RES_0402LF-22,1%,1/16W,CHIP,A    I16 @S9S_MB_2U_LIB.S9S_MB_2U(SCH_1):PAGE196

CLK_100M_OCP_V3_2_A_DP @S9S_MB_2U_LIB.S9S_MB_2U(SCH_1):CLK_100M_OCP_V3_2_A_DP
   J35  B15 REFCLKP0 SCONN168_ME1016810202011-SCONNA   I303 @S9S_MB_2U_LIB.S9S_MB_2U(SCH_1):PAGE146
 R3194    2      B Q_RES_0402LF-22,1%,1/16W,CHIP,A    I17 @S9S_MB_2U_LIB.S9S_MB_2U(SCH_1):PAGE196

CLK_100M_OCP_V3_2_A_R_DN @S9S_MB_2U_LIB.S9S_MB_2U(SCH_1):CLK_100M_OCP_V3_2_A_R_DN
   U38   A6 DIF14# 9QXL2001BNHGI8-9QXL2001BNHGI8,A   I119 @S9S_MB_2U_LIB.S9S_MB_2U(SCH_1):PAGE195
 R3195    1      A Q_RES_0402LF-22,1%,1/16W,CHIP,A    I16 @S9S_MB_2U_LIB.S9S_MB_2U(SCH_1):PAGE196

CLK_100M_OCP_V3_2_A_R_DP @S9S_MB_2U_LIB.S9S_MB_2U(SCH_1):CLK_100M_OCP_V3_2_A_R_DP
   U38   A7  DIF14 9QXL2001BNHGI8-9QXL2001BNHGI8,A   I119 @S9S_MB_2U_LIB.S9S_MB_2U(SCH_1):PAGE195
 R3194    1      A Q_RES_0402LF-22,1%,1/16W,CHIP,A    I17 @S9S_MB_2U_LIB.S9S_MB_2U(SCH_1):PAGE196

CLK_100M_OCP_V3_2_B_DN @S9S_MB_2U_LIB.S9S_MB_2U(SCH_1):CLK_100M_OCP_V3_2_B_DN
   J35  A14 REFCLKN1 SCONN168_ME1016810202011-SCONNA   I303 @S9S_MB_2U_LIB.S9S_MB_2U(SCH_1):PAGE146
 R3197    2      B Q_RES_0402LF-22,1%,1/16W,CHIP,A    I14 @S9S_MB_2U_LIB.S9S_MB_2U(SCH_1):PAGE196

CLK_100M_OCP_V3_2_B_DP @S9S_MB_2U_LIB.S9S_MB_2U(SCH_1):CLK_100M_OCP_V3_2_B_DP
   J35  A15 REFCLKP1 SCONN168_ME1016810202011-SCONNA   I303 @S9S_MB_2U_LIB.S9S_MB_2U(SCH_1):PAGE146
 R3196    2      B Q_RES_0402LF-22,1%,1/16W,CHIP,A    I15 @S9S_MB_2U_LIB.S9S_MB_2U(SCH_1):PAGE196

CLK_100M_OCP_V3_2_B_R_DN @S9S_MB_2U_LIB.S9S_MB_2U(SCH_1):CLK_100M_OCP_V3_2_B_R_DN
   U38   A4 DIF15# 9QXL2001BNHGI8-9QXL2001BNHGI8,A   I119 @S9S_MB_2U_LIB.S9S_MB_2U(SCH_1):PAGE195
 R3197    1      A Q_RES_0402LF-22,1%,1/16W,CHIP,A    I14 @S9S_MB_2U_LIB.S9S_MB_2U(SCH_1):PAGE196

CLK_100M_OCP_V3_2_B_R_DP @S9S_MB_2U_LIB.S9S_MB_2U(SCH_1):CLK_100M_OCP_V3_2_B_R_DP
   U38   A5  DIF15 9QXL2001BNHGI8-9QXL2001BNHGI8,A   I119 @S9S_MB_2U_LIB.S9S_MB_2U(SCH_1):PAGE195
 R3196    1      A Q_RES_0402LF-22,1%,1/16W,CHIP,A    I15 @S9S_MB_2U_LIB.S9S_MB_2U(SCH_1):PAGE196

CLK_100M_OCP_V3_2_C_DN @S9S_MB_2U_LIB.S9S_MB_2U(SCH_1):CLK_100M_OCP_V3_2_C_DN
   J35 OB11 REFCLKN2 SCONN168_ME1016810202011-SCONNA   I303 @S9S_MB_2U_LIB.S9S_MB_2U(SCH_1):PAGE146
 R3199    2      B Q_RES_0402LF-22,1%,1/16W,CHIP,A    I12 @S9S_MB_2U_LIB.S9S_MB_2U(SCH_1):PAGE196

CLK_100M_OCP_V3_2_C_DP @S9S_MB_2U_LIB.S9S_MB_2U(SCH_1):CLK_100M_OCP_V3_2_C_DP
   J35 OB12 REFCLKP2 SCONN168_ME1016810202011-SCONNA   I303 @S9S_MB_2U_LIB.S9S_MB_2U(SCH_1):PAGE146
 R3198    2      B Q_RES_0402LF-22,1%,1/16W,CHIP,A    I13 @S9S_MB_2U_LIB.S9S_MB_2U(SCH_1):PAGE196

CLK_100M_OCP_V3_2_C_R_DN @S9S_MB_2U_LIB.S9S_MB_2U(SCH_1):CLK_100M_OCP_V3_2_C_R_DN
   U38   A2 DIF16# 9QXL2001BNHGI8-9QXL2001BNHGI8,A   I119 @S9S_MB_2U_LIB.S9S_MB_2U(SCH_1):PAGE195
 R3199    1      A Q_RES_0402LF-22,1%,1/16W,CHIP,A    I12 @S9S_MB_2U_LIB.S9S_MB_2U(SCH_1):PAGE196

CLK_100M_OCP_V3_2_C_R_DP @S9S_MB_2U_LIB.S9S_MB_2U(SCH_1):CLK_100M_OCP_V3_2_C_R_DP
   U38   A3  DIF16 9QXL2001BNHGI8-9QXL2001BNHGI8,A   I119 @S9S_MB_2U_LIB.S9S_MB_2U(SCH_1):PAGE195
 R3198    1      A Q_RES_0402LF-22,1%,1/16W,CHIP,A    I13 @S9S_MB_2U_LIB.S9S_MB_2U(SCH_1):PAGE196

CLK_100M_OCP_V3_2_D_DN @S9S_MB_2U_LIB.S9S_MB_2U(SCH_1):CLK_100M_OCP_V3_2_D_DN
   J35 OA11 REFCLKN3 SCONN168_ME1016810202011-SCONNA   I303 @S9S_MB_2U_LIB.S9S_MB_2U(SCH_1):PAGE146
 R3201    2      B Q_RES_0402LF-22,1%,1/16W,CHIP,A    I10 @S9S_MB_2U_LIB.S9S_MB_2U(SCH_1):PAGE196

CLK_100M_OCP_V3_2_D_DP @S9S_MB_2U_LIB.S9S_MB_2U(SCH_1):CLK_100M_OCP_V3_2_D_DP
   J35 OA12 REFCLKP3 SCONN168_ME1016810202011-SCONNA   I303 @S9S_MB_2U_LIB.S9S_MB_2U(SCH_1):PAGE146
 R3200    2      B Q_RES_0402LF-22,1%,1/16W,CHIP,A    I11 @S9S_MB_2U_LIB.S9S_MB_2U(SCH_1):PAGE196

CLK_100M_OCP_V3_2_D_R_DN @S9S_MB_2U_LIB.S9S_MB_2U(SCH_1):CLK_100M_OCP_V3_2_D_R_DN
   U38   B1 DIF17# 9QXL2001BNHGI8-9QXL2001BNHGI8,A   I119 @S9S_MB_2U_LIB.S9S_MB_2U(SCH_1):PAGE195
 R3201    1      A Q_RES_0402LF-22,1%,1/16W,CHIP,A    I10 @S9S_MB_2U_LIB.S9S_MB_2U(SCH_1):PAGE196

CLK_100M_OCP_V3_2_D_R_DP @S9S_MB_2U_LIB.S9S_MB_2U(SCH_1):CLK_100M_OCP_V3_2_D_R_DP
   U38   A1  DIF17 9QXL2001BNHGI8-9QXL2001BNHGI8,A   I119 @S9S_MB_2U_LIB.S9S_MB_2U(SCH_1):PAGE195
 R3200    1      A Q_RES_0402LF-22,1%,1/16W,CHIP,A    I11 @S9S_MB_2U_LIB.S9S_MB_2U(SCH_1):PAGE196

CLK_100M_PE_M2_0_DN @S9S_MB_2U_LIB.S9S_MB_2U(SCH_1):CLK_100M_PE_M2_0_DN
   J59   53 REFCLKN SCONN75K_APCI0155P004A-SCONN75A   I178 @S9S_MB_2U_LIB.S9S_MB_2U(SCH_1):PAGE182
 R4306    2      B Q_RES_0402LF-0,5%,1/16W,CHIP,CA   I117 @S9S_MB_2U_LIB.S9S_MB_2U(SCH_1):PAGE171

CLK_100M_PE_M2_0_DP @S9S_MB_2U_LIB.S9S_MB_2U(SCH_1):CLK_100M_PE_M2_0_DP
   J59   55 REFCLKP SCONN75K_APCI0155P004A-SCONN75A   I178 @S9S_MB_2U_LIB.S9S_MB_2U(SCH_1):PAGE182
 R4305    2      B Q_RES_0402LF-0,5%,1/16W,CHIP,CA   I116 @S9S_MB_2U_LIB.S9S_MB_2U(SCH_1):PAGE171

CLK_100M_PE_M2_0_R_DN @S9S_MB_2U_LIB.S9S_MB_2U(SCH_1):CLK_100M_PE_M2_0_R_DN
    U4  H21 CLKOUT_SRC_N_2 EMMITSBURG_REV0P9-GFNOCPU04302A    I78 @S9S_MB_2U_LIB.S9S_MB_2U(SCH_1):PAGE171
 R4306    1      A Q_RES_0402LF-0,5%,1/16W,CHIP,CA   I117 @S9S_MB_2U_LIB.S9S_MB_2U(SCH_1):PAGE171

CLK_100M_PE_M2_0_R_DP @S9S_MB_2U_LIB.S9S_MB_2U(SCH_1):CLK_100M_PE_M2_0_R_DP
    U4  K21 CLKOUT_SRC_P_2 EMMITSBURG_REV0P9-GFNOCPU04302A    I78 @S9S_MB_2U_LIB.S9S_MB_2U(SCH_1):PAGE171
 R4305    1      A Q_RES_0402LF-0,5%,1/16W,CHIP,CA   I116 @S9S_MB_2U_LIB.S9S_MB_2U(SCH_1):PAGE171

CLK_100M_SWB_DN @S9S_MB_2U_LIB.S9S_MB_2U(SCH_1):CLK_100M_SWB_DN
  J112   O3     O3 CONN160_10131762101LF-CONN160_A    I76 @S9S_MB_2U_LIB.S9S_MB_2U(SCH_1):PAGE149
 R2660    2      B Q_RES_0402LF-0,5%,1/16W,CHIP,CA    I28 @S9S_MB_2U_LIB.S9S_MB_2U(SCH_1):PAGE196

CLK_100M_SWB_DP @S9S_MB_2U_LIB.S9S_MB_2U(SCH_1):CLK_100M_SWB_DP
  J112   P3     P3 CONN160_10131762101LF-CONN160_A    I76 @S9S_MB_2U_LIB.S9S_MB_2U(SCH_1):PAGE149
 R2659    2      B Q_RES_0402LF-0,5%,1/16W,CHIP,CA    I27 @S9S_MB_2U_LIB.S9S_MB_2U(SCH_1):PAGE196

CLK_100M_SWB_R_DN @S9S_MB_2U_LIB.S9S_MB_2U(SCH_1):CLK_100M_SWB_R_DN
  U314   14  DIF0# 9ZXL0451EKILFT-9ZXL0451EKILFT,A     I1 @S9S_MB_2U_LIB.S9S_MB_2U(SCH_1):PAGE200
 R2660    1      A Q_RES_0402LF-0,5%,1/16W,CHIP,CA    I28 @S9S_MB_2U_LIB.S9S_MB_2U(SCH_1):PAGE196

CLK_100M_SWB_R_DP @S9S_MB_2U_LIB.S9S_MB_2U(SCH_1):CLK_100M_SWB_R_DP
  U314   13   DIF0 9ZXL0451EKILFT-9ZXL0451EKILFT,A     I1 @S9S_MB_2U_LIB.S9S_MB_2U(SCH_1):PAGE200
 R2659    1      A Q_RES_0402LF-0,5%,1/16W,CHIP,CA    I27 @S9S_MB_2U_LIB.S9S_MB_2U(SCH_1):PAGE196

CLK_24M_66M_LPC0_ESPI @S9S_MB_2U_LIB.S9S_MB_2U(SCH_1):CLK_24M_66M_LPC0_ESPI
    U4 BD13 GPPC_A_9_ESPI_CLK EMMITSBURG_REV0P9-GFNOCPU04302A    I93 @S9S_MB_2U_LIB.S9S_MB_2U(SCH_1):PAGE175
 R1872    1      A Q_RES_0402LF-10,1%,1/16W,CHIP,A   I100 @S9S_MB_2U_LIB.S9S_MB_2U(SCH_1):PAGE190

CLK_25M_CK440_CPU0_DN @S9S_MB_2U_LIB.S9S_MB_2U(SCH_1):CLK_25M_CK440_CPU0_DN
   U13   A4  25M0# 9SQ440NQQI8-9SQ440NQQI8,SMLF,IA   I180 @S9S_MB_2U_LIB.S9S_MB_2U(SCH_1):PAGE197
 R1014    1      A Q_RES_0402LF-0,5%,1/16W,CHIP,CA    I20 @S9S_MB_2U_LIB.S9S_MB_2U(SCH_1):PAGE198

CLK_25M_CK440_CPU0_DP @S9S_MB_2U_LIB.S9S_MB_2U(SCH_1):CLK_25M_CK440_CPU0_DP
   U13   A5   25M0 9SQ440NQQI8-9SQ440NQQI8,SMLF,IA   I180 @S9S_MB_2U_LIB.S9S_MB_2U(SCH_1):PAGE197
 R1012    1      A Q_RES_0402LF-0,5%,1/16W,CHIP,CA    I22 @S9S_MB_2U_LIB.S9S_MB_2U(SCH_1):PAGE198

CLK_25M_CK440_CPU0_R_DN @S9S_MB_2U_LIB.S9S_MB_2U(SCH_1):CLK_25M_CK440_CPU0_R_DN
 R1014    2      B Q_RES_0402LF-0,5%,1/16W,CHIP,CA    I20 @S9S_MB_2U_LIB.S9S_MB_2U(SCH_1):PAGE198
 R1021    1      A Q_RES_0402LF-0,5%,1/16W,CHIP,CA    I29 @S9S_MB_2U_LIB.S9S_MB_2U(SCH_1):PAGE198

CLK_25M_CK440_CPU0_R_DP @S9S_MB_2U_LIB.S9S_MB_2U(SCH_1):CLK_25M_CK440_CPU0_R_DP
 R1012    2      B Q_RES_0402LF-0,5%,1/16W,CHIP,CA    I22 @S9S_MB_2U_LIB.S9S_MB_2U(SCH_1):PAGE198
 R1020    1      A Q_RES_0402LF-0,5%,1/16W,CHIP,CA    I30 @S9S_MB_2U_LIB.S9S_MB_2U(SCH_1):PAGE198

CLK_25M_CK440_CPU1_DN @S9S_MB_2U_LIB.S9S_MB_2U(SCH_1):CLK_25M_CK440_CPU1_DN
   U13   A2  25M1# 9SQ440NQQI8-9SQ440NQQI8,SMLF,IA   I180 @S9S_MB_2U_LIB.S9S_MB_2U(SCH_1):PAGE197
 R1018    1      A Q_RES_0402LF-0,5%,1/16W,CHIP,CA    I10 @S9S_MB_2U_LIB.S9S_MB_2U(SCH_1):PAGE198

CLK_25M_CK440_CPU1_DP @S9S_MB_2U_LIB.S9S_MB_2U(SCH_1):CLK_25M_CK440_CPU1_DP
   U13   A3   25M1 9SQ440NQQI8-9SQ440NQQI8,SMLF,IA   I180 @S9S_MB_2U_LIB.S9S_MB_2U(SCH_1):PAGE197
 R1016    1      A Q_RES_0402LF-0,5%,1/16W,CHIP,CA    I12 @S9S_MB_2U_LIB.S9S_MB_2U(SCH_1):PAGE198

CLK_25M_CK440_CPU1_R_DN @S9S_MB_2U_LIB.S9S_MB_2U(SCH_1):CLK_25M_CK440_CPU1_R_DN
 R1018    2      B Q_RES_0402LF-0,5%,1/16W,CHIP,CA    I10 @S9S_MB_2U_LIB.S9S_MB_2U(SCH_1):PAGE198
 R1023    1      A Q_RES_0402LF-0,5%,1/16W,CHIP,CA    I27 @S9S_MB_2U_LIB.S9S_MB_2U(SCH_1):PAGE198

CLK_25M_CK440_CPU1_R_DP @S9S_MB_2U_LIB.S9S_MB_2U(SCH_1):CLK_25M_CK440_CPU1_R_DP
 R1016    2      B Q_RES_0402LF-0,5%,1/16W,CHIP,CA    I12 @S9S_MB_2U_LIB.S9S_MB_2U(SCH_1):PAGE198
 R1022    1      A Q_RES_0402LF-0,5%,1/16W,CHIP,CA    I28 @S9S_MB_2U_LIB.S9S_MB_2U(SCH_1):PAGE198

CLK_25M_CK440_ISCLK_REF_DN @S9S_MB_2U_LIB.S9S_MB_2U(SCH_1):CLK_25M_CK440_ISCLK_REF_DN
   U13  A55  25M2# 9SQ440NQQI8-9SQ440NQQI8,SMLF,IA   I180 @S9S_MB_2U_LIB.S9S_MB_2U(SCH_1):PAGE197
 R1011    1      A Q_RES_0402LF-0,5%,1/16W,CHIP,CA     I7 @S9S_MB_2U_LIB.S9S_MB_2U(SCH_1):PAGE198

CLK_25M_CK440_ISCLK_REF_DP @S9S_MB_2U_LIB.S9S_MB_2U(SCH_1):CLK_25M_CK440_ISCLK_REF_DP
   U13  A56   25M2 9SQ440NQQI8-9SQ440NQQI8,SMLF,IA   I180 @S9S_MB_2U_LIB.S9S_MB_2U(SCH_1):PAGE197
 R1010    1      A Q_RES_0402LF-0,5%,1/16W,CHIP,CA     I8 @S9S_MB_2U_LIB.S9S_MB_2U(SCH_1):PAGE198

CLK_25M_NSSC_CPU0_DN @S9S_MB_2U_LIB.S9S_MB_2U(SCH_1):CLK_25M_NSSC_CPU0_DN
    U2 CW31 XTAL_CLK_DN SOCKET4677_AZIF0045P001C01CS-SA    I57 @S9S_MB_2U_LIB.S9S_MB_2U(SCH_1):PAGE13
 R1015    2      B Q_RES_0402LF-0,5%,1/16W,EMPTY,A    I19 @S9S_MB_2U_LIB.S9S_MB_2U(SCH_1):PAGE198
 R1021    2      B Q_RES_0402LF-0,5%,1/16W,CHIP,CA    I29 @S9S_MB_2U_LIB.S9S_MB_2U(SCH_1):PAGE198

CLK_25M_NSSC_CPU0_DP @S9S_MB_2U_LIB.S9S_MB_2U(SCH_1):CLK_25M_NSSC_CPU0_DP
    U2 CY32 XTAL_CLK_DP SOCKET4677_AZIF0045P001C01CS-SA    I57 @S9S_MB_2U_LIB.S9S_MB_2U(SCH_1):PAGE13
 R1013    2      B Q_RES_0402LF-0,5%,1/16W,EMPTY,A    I21 @S9S_MB_2U_LIB.S9S_MB_2U(SCH_1):PAGE198
 R1020    2      B Q_RES_0402LF-0,5%,1/16W,CHIP,CA    I30 @S9S_MB_2U_LIB.S9S_MB_2U(SCH_1):PAGE198

CLK_25M_NSSC_CPU1_DN @S9S_MB_2U_LIB.S9S_MB_2U(SCH_1):CLK_25M_NSSC_CPU1_DN
    U1 CW31 XTAL_CLK_DN SOCKET4677_AZIF0045P001C01CS-SA    I51 @S9S_MB_2U_LIB.S9S_MB_2U(SCH_1):PAGE44
 R1019    2      B Q_RES_0402LF-0,5%,1/16W,EMPTY,A     I9 @S9S_MB_2U_LIB.S9S_MB_2U(SCH_1):PAGE198
 R1023    2      B Q_RES_0402LF-0,5%,1/16W,CHIP,CA    I27 @S9S_MB_2U_LIB.S9S_MB_2U(SCH_1):PAGE198

CLK_25M_NSSC_CPU1_DP @S9S_MB_2U_LIB.S9S_MB_2U(SCH_1):CLK_25M_NSSC_CPU1_DP
    U1 CY32 XTAL_CLK_DP SOCKET4677_AZIF0045P001C01CS-SA    I51 @S9S_MB_2U_LIB.S9S_MB_2U(SCH_1):PAGE44
 R1017    2      B Q_RES_0402LF-0,5%,1/16W,EMPTY,A    I11 @S9S_MB_2U_LIB.S9S_MB_2U(SCH_1):PAGE198
 R1022    2      B Q_RES_0402LF-0,5%,1/16W,CHIP,CA    I28 @S9S_MB_2U_LIB.S9S_MB_2U(SCH_1):PAGE198

CLK_25M_OSC_FPGA_R @S9S_MB_2U_LIB.S9S_MB_2U(SCH_1):CLK_25M_OSC_FPGA_R
 R1100    1      A Q_RES_0402LF-33.2,1%,1/16W,CHIA   I115 @S9S_MB_2U_LIB.S9S_MB_2U(SCH_1):PAGE313
  OSC2    3    OUT Q_OSC4P_SMLF-25MHZ,OSC,BF62500A   I127 @S9S_MB_2U_LIB.S9S_MB_2U(SCH_1):PAGE313

CLK_25M_OSC_MAIN_FPGA @S9S_MB_2U_LIB.S9S_MB_2U(SCH_1):CLK_25M_OSC_MAIN_FPGA
 R1100    2      B Q_RES_0402LF-33.2,1%,1/16W,CHIA   I115 @S9S_MB_2U_LIB.S9S_MB_2U(SCH_1):PAGE313
  U249 AA10 PB22A||PCLKT2_0 LCMXO3LF9400C5BG484C-LCMXO3LF-A     I1 @S9S_MB_2U_LIB.S9S_MB_2U(SCH_1):PAGE312

CLK_25M_PCH_CPU0_DN @S9S_MB_2U_LIB.S9S_MB_2U(SCH_1):CLK_25M_PCH_CPU0_DN
    U4  D27 PMSYNC_CLK_N_0 EMMITSBURG_REV0P9-GFNOCPU04302A    I78 @S9S_MB_2U_LIB.S9S_MB_2U(SCH_1):PAGE171
 R1015    1      A Q_RES_0402LF-0,5%,1/16W,EMPTY,A    I19 @S9S_MB_2U_LIB.S9S_MB_2U(SCH_1):PAGE198

CLK_25M_PCH_CPU0_DP @S9S_MB_2U_LIB.S9S_MB_2U(SCH_1):CLK_25M_PCH_CPU0_DP
    U4  B27 PMSYNC_CLK_P_0 EMMITSBURG_REV0P9-GFNOCPU04302A    I78 @S9S_MB_2U_LIB.S9S_MB_2U(SCH_1):PAGE171
 R1013    1      A Q_RES_0402LF-0,5%,1/16W,EMPTY,A    I21 @S9S_MB_2U_LIB.S9S_MB_2U(SCH_1):PAGE198

CLK_25M_PCH_CPU1_DN @S9S_MB_2U_LIB.S9S_MB_2U(SCH_1):CLK_25M_PCH_CPU1_DN
    U4  C28 PMSYNC_CLK_N_1 EMMITSBURG_REV0P9-GFNOCPU04302A    I78 @S9S_MB_2U_LIB.S9S_MB_2U(SCH_1):PAGE171
 R1019    1      A Q_RES_0402LF-0,5%,1/16W,EMPTY,A     I9 @S9S_MB_2U_LIB.S9S_MB_2U(SCH_1):PAGE198

CLK_25M_PCH_CPU1_DP @S9S_MB_2U_LIB.S9S_MB_2U(SCH_1):CLK_25M_PCH_CPU1_DP
    U4  A28 PMSYNC_CLK_P_1 EMMITSBURG_REV0P9-GFNOCPU04302A    I78 @S9S_MB_2U_LIB.S9S_MB_2U(SCH_1):PAGE171
 R1017    1      A Q_RES_0402LF-0,5%,1/16W,EMPTY,A    I11 @S9S_MB_2U_LIB.S9S_MB_2U(SCH_1):PAGE198

CLK_25M_PCH_REF_NS_DN @S9S_MB_2U_LIB.S9S_MB_2U(SCH_1):CLK_25M_PCH_REF_NS_DN
    U4  D25 REFCLK_INJ_NS_N EMMITSBURG_REV0P9-GFNOCPU04302A    I78 @S9S_MB_2U_LIB.S9S_MB_2U(SCH_1):PAGE171
 R1011    2      B Q_RES_0402LF-0,5%,1/16W,CHIP,CA     I7 @S9S_MB_2U_LIB.S9S_MB_2U(SCH_1):PAGE198

CLK_25M_PCH_REF_NS_DP @S9S_MB_2U_LIB.S9S_MB_2U(SCH_1):CLK_25M_PCH_REF_NS_DP
    U4  B25 REFCLK_INJ_NS_P EMMITSBURG_REV0P9-GFNOCPU04302A    I78 @S9S_MB_2U_LIB.S9S_MB_2U(SCH_1):PAGE171
 R1010    2      B Q_RES_0402LF-0,5%,1/16W,CHIP,CA     I8 @S9S_MB_2U_LIB.S9S_MB_2U(SCH_1):PAGE198

CLK_50M_BMC_MAC_R @S9S_MB_2U_LIB.S9S_MB_2U(SCH_1):CLK_50M_BMC_MAC_R
   U90    3     Y0 PI6CV304LE-PI6CV304LE,SMLF,IC,A    I46 @S9S_MB_2U_LIB.S9S_MB_2U(SCH_1):PAGE152
 R1140    1      A Q_RES_0402LF-27.4,1%,1/16W,CHIA    I52 @S9S_MB_2U_LIB.S9S_MB_2U(SCH_1):PAGE152

CLK_50M_EN @S9S_MB_2U_LIB.S9S_MB_2U(SCH_1):CLK_50M_EN
   U90    2     OE PI6CV304LE-PI6CV304LE,SMLF,IC,A    I46 @S9S_MB_2U_LIB.S9S_MB_2U(SCH_1):PAGE152
 R1138    2      B Q_RES_0402LF-10K,1%,1/16W,CHIPA    I61 @S9S_MB_2U_LIB.S9S_MB_2U(SCH_1):PAGE152
  OSC1    1     OE Q_OSC4P_SMLF-50MHZ,OSC,BF65000A    I76 @S9S_MB_2U_LIB.S9S_MB_2U(SCH_1):PAGE152

CLK_50M_NCSI_OCP_1 @S9S_MB_2U_LIB.S9S_MB_2U(SCH_1):CLK_50M_NCSI_OCP_1
   U90    5     Y1 PI6CV304LE-PI6CV304LE,SMLF,IC,A    I46 @S9S_MB_2U_LIB.S9S_MB_2U(SCH_1):PAGE152
 R1141    1      A Q_RES_0402LF-27.4,1%,1/16W,CHIA    I53 @S9S_MB_2U_LIB.S9S_MB_2U(SCH_1):PAGE152

CLK_50M_NCSI_OCP_2 @S9S_MB_2U_LIB.S9S_MB_2U(SCH_1):CLK_50M_NCSI_OCP_2
   U90    7     Y2 PI6CV304LE-PI6CV304LE,SMLF,IC,A    I46 @S9S_MB_2U_LIB.S9S_MB_2U(SCH_1):PAGE152
 R3181    1      A Q_RES_0402LF-27.4,1%,1/16W,CHIA    I78 @S9S_MB_2U_LIB.S9S_MB_2U(SCH_1):PAGE152

CLK_50M_NCSI_OCP_SFF @S9S_MB_2U_LIB.S9S_MB_2U(SCH_1):CLK_50M_NCSI_OCP_SFF
 R1141    2      B Q_RES_0402LF-27.4,1%,1/16W,CHIA    I53 @S9S_MB_2U_LIB.S9S_MB_2U(SCH_1):PAGE152
  U320    1      Y 74LVC1G66GV-74LVC1G66GV,SMLF,IA    I92 @S9S_MB_2U_LIB.S9S_MB_2U(SCH_1):PAGE152

CLK_50M_NCSI_OCP_SFF_ISO @S9S_MB_2U_LIB.S9S_MB_2U(SCH_1):CLK_50M_NCSI_OCP_SFF_ISO
   J37 OA14 RBT_CLK_IN SCONN168_ME1016810202011-SCONNA   I199 @S9S_MB_2U_LIB.S9S_MB_2U(SCH_1):PAGE150
 R4601    1      A Q_RES_0402LF-0,5%,1/16W,CHIP,CA    I90 @S9S_MB_2U_LIB.S9S_MB_2U(SCH_1):PAGE152

CLK_50M_NCSI_OCP_SFF_ISO_R @S9S_MB_2U_LIB.S9S_MB_2U(SCH_1):CLK_50M_NCSI_OCP_SFF_ISO_R
 R4601    2      B Q_RES_0402LF-0,5%,1/16W,CHIP,CA    I90 @S9S_MB_2U_LIB.S9S_MB_2U(SCH_1):PAGE152
  U320    2      Z 74LVC1G66GV-74LVC1G66GV,SMLF,IA    I92 @S9S_MB_2U_LIB.S9S_MB_2U(SCH_1):PAGE152

CLK_50M_NCSI_OCP_V3_2 @S9S_MB_2U_LIB.S9S_MB_2U(SCH_1):CLK_50M_NCSI_OCP_V3_2
 R3181    2      B Q_RES_0402LF-27.4,1%,1/16W,CHIA    I78 @S9S_MB_2U_LIB.S9S_MB_2U(SCH_1):PAGE152
  U321    1      Y 74LVC1G66GV-74LVC1G66GV,SMLF,IA    I92 @S9S_MB_2U_LIB.S9S_MB_2U(SCH_1):PAGE156

CLK_50M_NCSI_OCP_V3_2_ISO @S9S_MB_2U_LIB.S9S_MB_2U(SCH_1):CLK_50M_NCSI_OCP_V3_2_ISO
   J35 OA14 RBT_CLK_IN SCONN168_ME1016810202011-SCONNA   I303 @S9S_MB_2U_LIB.S9S_MB_2U(SCH_1):PAGE146
 R4602    1      A Q_RES_0402LF-0,5%,1/16W,CHIP,CA    I90 @S9S_MB_2U_LIB.S9S_MB_2U(SCH_1):PAGE156

CLK_50M_NCSI_OCP_V3_2_ISO_R @S9S_MB_2U_LIB.S9S_MB_2U(SCH_1):CLK_50M_NCSI_OCP_V3_2_ISO_R
 R4602    2      B Q_RES_0402LF-0,5%,1/16W,CHIP,CA    I90 @S9S_MB_2U_LIB.S9S_MB_2U(SCH_1):PAGE156
  U321    2      Z 74LVC1G66GV-74LVC1G66GV,SMLF,IA    I92 @S9S_MB_2U_LIB.S9S_MB_2U(SCH_1):PAGE156

CLK_50M_RMII @S9S_MB_2U_LIB.S9S_MB_2U(SCH_1):CLK_50M_RMII
 R1139    1      A Q_RES_0402LF-0,5%,1/16W,CHIP,CA    I56 @S9S_MB_2U_LIB.S9S_MB_2U(SCH_1):PAGE152
  OSC1    3    OUT Q_OSC4P_SMLF-50MHZ,OSC,BF65000A    I76 @S9S_MB_2U_LIB.S9S_MB_2U(SCH_1):PAGE152

CLK_50M_RMII_BMC_OCP @S9S_MB_2U_LIB.S9S_MB_2U(SCH_1):CLK_50M_RMII_BMC_OCP
 R1140    2      B Q_RES_0402LF-27.4,1%,1/16W,CHIA    I52 @S9S_MB_2U_LIB.S9S_MB_2U(SCH_1):PAGE152
   J41  B18  PETP0 SCONN168_ME1016810202011-SCONNA   I173 @S9S_MB_2U_LIB.S9S_MB_2U(SCH_1):PAGE227

CLK_50M_RMII_R @S9S_MB_2U_LIB.S9S_MB_2U(SCH_1):CLK_50M_RMII_R
   U90    1 CLK_IN PI6CV304LE-PI6CV304LE,SMLF,IC,A    I46 @S9S_MB_2U_LIB.S9S_MB_2U(SCH_1):PAGE152
 R1139    2      B Q_RES_0402LF-0,5%,1/16W,CHIP,CA    I56 @S9S_MB_2U_LIB.S9S_MB_2U(SCH_1):PAGE152

CLK_9ZXL045_HIBW @S9S_MB_2U_LIB.S9S_MB_2U(SCH_1):CLK_9ZXL045_HIBW
  U314   32 ^HIBW_BYPM_LOBW# 9ZXL0451EKILFT-9ZXL0451EKILFT,A     I1 @S9S_MB_2U_LIB.S9S_MB_2U(SCH_1):PAGE200
 R4491    2      B Q_RES_0402LF-10K,1%,1/16W,CHIPA    I48 @S9S_MB_2U_LIB.S9S_MB_2U(SCH_1):PAGE200
 R4492    1      A Q_RES_0402LF-10K,1%,1/16W,CHIPA    I49 @S9S_MB_2U_LIB.S9S_MB_2U(SCH_1):PAGE200

CLK_9ZXL045_SADR0 @S9S_MB_2U_LIB.S9S_MB_2U(SCH_1):CLK_9ZXL045_SADR0
  U314    5 VSADR0_TRI 9ZXL0451EKILFT-9ZXL0451EKILFT,A     I1 @S9S_MB_2U_LIB.S9S_MB_2U(SCH_1):PAGE200
 R4489    2      B Q_RES_0402LF-4.75K,1%,1/16W,CHA    I30 @S9S_MB_2U_LIB.S9S_MB_2U(SCH_1):PAGE200
 R4490    1      A Q_RES_0402LF-4.75K,1%,1/16W,EMA    I31 @S9S_MB_2U_LIB.S9S_MB_2U(SCH_1):PAGE200

CLK_CK440_SMB_ADDR0 @S9S_MB_2U_LIB.S9S_MB_2U(SCH_1):CLK_CK440_SMB_ADDR0
   U13  A11 SMB_ADR0_TRI 9SQ440NQQI8-9SQ440NQQI8,SMLF,IA   I180 @S9S_MB_2U_LIB.S9S_MB_2U(SCH_1):PAGE197
  R912    2      B Q_RES_0402LF-4.75K,1%,1/16W,EMA   I278 @S9S_MB_2U_LIB.S9S_MB_2U(SCH_1):PAGE197
  R953    1      A Q_RES_0402LF-4.75K,1%,1/16W,CHA   I282 @S9S_MB_2U_LIB.S9S_MB_2U(SCH_1):PAGE197

CLK_CK440_SMB_ADDR1 @S9S_MB_2U_LIB.S9S_MB_2U(SCH_1):CLK_CK440_SMB_ADDR1
   U13   B9 SMB_ADR1_TRI 9SQ440NQQI8-9SQ440NQQI8,SMLF,IA   I180 @S9S_MB_2U_LIB.S9S_MB_2U(SCH_1):PAGE197
 R2481    2      B Q_RES_0402LF-4.75K,1%,1/16W,EMA   I280 @S9S_MB_2U_LIB.S9S_MB_2U(SCH_1):PAGE197
  R734    1      A Q_RES_0402LF-4.75K,1%,1/16W,CHA   I283 @S9S_MB_2U_LIB.S9S_MB_2U(SCH_1):PAGE197

CLK_GEN2_BMC_RC_OE_N @S9S_MB_2U_LIB.S9S_MB_2U(SCH_1):CLK_GEN2_BMC_RC_OE_N
  U249 AB19  PB43A LCMXO3LF9400C5BG484C-LCMXO3LF-A     I1 @S9S_MB_2U_LIB.S9S_MB_2U(SCH_1):PAGE312
 R4075    1      A Q_RES_0402LF-0,5%,1/16W,CHIP,CA   I147 @S9S_MB_2U_LIB.S9S_MB_2U(SCH_1):PAGE201
 R4521    2      B Q_RES_0402LF-10K,1%,1/16W,CHIPA   I163 @S9S_MB_2U_LIB.S9S_MB_2U(SCH_1):PAGE201

CLK_GEN2_BMC_RC_OE_R3_N @S9S_MB_2U_LIB.S9S_MB_2U(SCH_1):CLK_GEN2_BMC_RC_OE_R3_N
 R4075    2      B Q_RES_0402LF-0,5%,1/16W,CHIP,CA   I147 @S9S_MB_2U_LIB.S9S_MB_2U(SCH_1):PAGE201
  U247   12  VOE0# 9FGL0251DKILFT-9FGL0251DKILFT,A   I167 @S9S_MB_2U_LIB.S9S_MB_2U(SCH_1):PAGE201

CLK_GEN2_GPU_FPGA_OE_N @S9S_MB_2U_LIB.S9S_MB_2U(SCH_1):CLK_GEN2_GPU_FPGA_OE_N
 R3327    1      A Q_RES_0402LF-0,5%,1/16W,CHIP,CA    I85 @S9S_MB_2U_LIB.S9S_MB_2U(SCH_1):PAGE201
 R4610    2      B Q_RES_0402LF-33.2,1%,1/16W,CHIA   I200 @S9S_MB_2U_LIB.S9S_MB_2U(SCH_1):PAGE313

CLK_GEN2_GPU_FPGA_OE_OR_N @S9S_MB_2U_LIB.S9S_MB_2U(SCH_1):CLK_GEN2_GPU_FPGA_OE_OR_N
 R4537    2      B Q_RES_0402LF-0,5%,1/16W,CHIP,CA    I73 @S9S_MB_2U_LIB.S9S_MB_2U(SCH_1):PAGE136
 R4076    1      A Q_RES_0402LF-0,5%,1/16W,CHIP,CA   I146 @S9S_MB_2U_LIB.S9S_MB_2U(SCH_1):PAGE201
 R4651    2      B Q_RES_0402LF-0,5%,1/16W,CHIP,CA   I102 @S9S_MB_2U_LIB.S9S_MB_2U(SCH_1):PAGE159
  U248    4      O 74LVC1G32GW_SMLF-74LVC1G32GW,IA   I158 @S9S_MB_2U_LIB.S9S_MB_2U(SCH_1):PAGE201
 R3265    1      A Q_RES_0402LF-4.7K,1%,1/16W,EMPA    I84 @S9S_MB_2U_LIB.S9S_MB_2U(SCH_1):PAGE136
 R3292    2      B Q_RES_0402LF-4.7K,1%,1/16W,CHIA    I85 @S9S_MB_2U_LIB.S9S_MB_2U(SCH_1):PAGE136

CLK_GEN2_GPU_FPGA_OE_R2_N @S9S_MB_2U_LIB.S9S_MB_2U(SCH_1):CLK_GEN2_GPU_FPGA_OE_R2_N
 R3327    2      B Q_RES_0402LF-0,5%,1/16W,CHIP,CA    I85 @S9S_MB_2U_LIB.S9S_MB_2U(SCH_1):PAGE201
 R3322    2      B Q_RES_0402LF-4.7K,1%,1/16W,CHIA   I157 @S9S_MB_2U_LIB.S9S_MB_2U(SCH_1):PAGE201
  U248    2     I1 74LVC1G32GW_SMLF-74LVC1G32GW,IA   I158 @S9S_MB_2U_LIB.S9S_MB_2U(SCH_1):PAGE201
 R4514    1      A Q_RES_0402LF-4.7K,1%,1/16W,EMPA   I161 @S9S_MB_2U_LIB.S9S_MB_2U(SCH_1):PAGE201

CLK_GEN2_GPU_FPGA_OE_R_N @S9S_MB_2U_LIB.S9S_MB_2U(SCH_1):CLK_GEN2_GPU_FPGA_OE_R_N
  U249  V19  PR29D LCMXO3LF9400C5BG484C-LCMXO3LF-A     I1 @S9S_MB_2U_LIB.S9S_MB_2U(SCH_1):PAGE313
 R4610    1      A Q_RES_0402LF-33.2,1%,1/16W,CHIA   I200 @S9S_MB_2U_LIB.S9S_MB_2U(SCH_1):PAGE313

CLK_GEN2_GPU_OE_N @S9S_MB_2U_LIB.S9S_MB_2U(SCH_1):CLK_GEN2_GPU_OE_N
 R4076    2      B Q_RES_0402LF-0,5%,1/16W,CHIP,CA   I146 @S9S_MB_2U_LIB.S9S_MB_2U(SCH_1):PAGE201
  U247   19  VOE1# 9FGL0251DKILFT-9FGL0251DKILFT,A   I167 @S9S_MB_2U_LIB.S9S_MB_2U(SCH_1):PAGE201

CLK_GEN2_SMB_SADR @S9S_MB_2U_LIB.S9S_MB_2U(SCH_1):CLK_GEN2_SMB_SADR
 R4082    1      A Q_RES_0402LF-10K,1%,1/16W,EMPTA   I134 @S9S_MB_2U_LIB.S9S_MB_2U(SCH_1):PAGE201
 R4081    2      B Q_RES_0402LF-10K,1%,1/16W,CHIPA   I135 @S9S_MB_2U_LIB.S9S_MB_2U(SCH_1):PAGE201
  U247    4 VSADR||REF3.3 9FGL0251DKILFT-9FGL0251DKILFT,A   I167 @S9S_MB_2U_LIB.S9S_MB_2U(SCH_1):PAGE201

CLK_GEN2_XTAL_IN @S9S_MB_2U_LIB.S9S_MB_2U(SCH_1):CLK_GEN2_XTAL_IN
 R4501    2      B Q_RES_0402LF-0,5%,1/16W,CHIP,CA   I160 @S9S_MB_2U_LIB.S9S_MB_2U(SCH_1):PAGE201
  U247    1 XIN||CLKIN_25 9FGL0251DKILFT-9FGL0251DKILFT,A   I167 @S9S_MB_2U_LIB.S9S_MB_2U(SCH_1):PAGE201

CLK_GEN2_XTAL_IN_R @S9S_MB_2U_LIB.S9S_MB_2U(SCH_1):CLK_GEN2_XTAL_IN_R
    Y3    1     X1 Q_XTAL_4P_13BI_24GND-25MHZ,SMLB   I159 @S9S_MB_2U_LIB.S9S_MB_2U(SCH_1):PAGE201
 R4501    1      A Q_RES_0402LF-0,5%,1/16W,CHIP,CA   I160 @S9S_MB_2U_LIB.S9S_MB_2U(SCH_1):PAGE201
 C2255    1      A Q_CAP_C0402-8.2PF,50V,0.1P,NP0A   I165 @S9S_MB_2U_LIB.S9S_MB_2U(SCH_1):PAGE201

CLK_GEN2_XTAL_OUT @S9S_MB_2U_LIB.S9S_MB_2U(SCH_1):CLK_GEN2_XTAL_OUT
    Y3    3     X2 Q_XTAL_4P_13BI_24GND-25MHZ,SMLB   I159 @S9S_MB_2U_LIB.S9S_MB_2U(SCH_1):PAGE201
 C2256    1      A Q_CAP_C0402-8.2PF,50V,0.1P,NP0A   I166 @S9S_MB_2U_LIB.S9S_MB_2U(SCH_1):PAGE201
  U247    2     X2 9FGL0251DKILFT-9FGL0251DKILFT,A   I167 @S9S_MB_2U_LIB.S9S_MB_2U(SCH_1):PAGE201

CLK_GPU_1_OE_N @S9S_MB_2U_LIB.S9S_MB_2U(SCH_1):CLK_GPU_1_OE_N
  U249 AA18  PB41B LCMXO3LF9400C5BG484C-LCMXO3LF-A     I1 @S9S_MB_2U_LIB.S9S_MB_2U(SCH_1):PAGE312
 R4478    2      B Q_RES_0402LF-33.2,1%,1/16W,CHIA    I75 @S9S_MB_2U_LIB.S9S_MB_2U(SCH_1):PAGE200
 R4519    2      B Q_RES_0402LF-10K,1%,1/16W,CHIPA    I78 @S9S_MB_2U_LIB.S9S_MB_2U(SCH_1):PAGE200

CLK_GPU_2_OE_N @S9S_MB_2U_LIB.S9S_MB_2U(SCH_1):CLK_GPU_2_OE_N
  U249  Y18  PB41C LCMXO3LF9400C5BG484C-LCMXO3LF-A     I1 @S9S_MB_2U_LIB.S9S_MB_2U(SCH_1):PAGE312
 R4479    2      B Q_RES_0402LF-33.2,1%,1/16W,CHIA    I76 @S9S_MB_2U_LIB.S9S_MB_2U(SCH_1):PAGE200
 R4518    2      B Q_RES_0402LF-10K,1%,1/16W,CHIPA    I77 @S9S_MB_2U_LIB.S9S_MB_2U(SCH_1):PAGE200

CLK_SWB_BUF2_OE_N @S9S_MB_2U_LIB.S9S_MB_2U(SCH_1):CLK_SWB_BUF2_OE_N
  U249  T15  PB43C LCMXO3LF9400C5BG484C-LCMXO3LF-A     I1 @S9S_MB_2U_LIB.S9S_MB_2U(SCH_1):PAGE312
 R4477    2      B Q_RES_0402LF-33.2,1%,1/16W,CHIA    I74 @S9S_MB_2U_LIB.S9S_MB_2U(SCH_1):PAGE200
 R4520    2      B Q_RES_0402LF-10K,1%,1/16W,CHIPA    I79 @S9S_MB_2U_LIB.S9S_MB_2U(SCH_1):PAGE200

CLK_SWB_OE_N @S9S_MB_2U_LIB.S9S_MB_2U(SCH_1):CLK_SWB_OE_N
 R4534    1      A Q_RES_0402LF-0,5%,1/16W,CHIP,CA   I487 @S9S_MB_2U_LIB.S9S_MB_2U(SCH_1):PAGE195
  U249  W17  PB41D LCMXO3LF9400C5BG484C-LCMXO3LF-A     I1 @S9S_MB_2U_LIB.S9S_MB_2U(SCH_1):PAGE312
 R4516    2      B Q_RES_0402LF-10K,1%,1/16W,CHIPA   I539 @S9S_MB_2U_LIB.S9S_MB_2U(SCH_1):PAGE195

CPU1_RSVD<107> @S9S_MB_2U_LIB.S9S_MB_2U(SCH_1):CPU1_RSVD(107)
    U1 CL21 RSVD113 SOCKET4677_AZIF0045P001C01CS-SA    I29 @S9S_MB_2U_LIB.S9S_MB_2U(SCH_1):PAGE45

CPU1_RSVD<110> @S9S_MB_2U_LIB.S9S_MB_2U(SCH_1):CPU1_RSVD(110)
    U1 CL64 RSVD116 SOCKET4677_AZIF0045P001C01CS-SA    I29 @S9S_MB_2U_LIB.S9S_MB_2U(SCH_1):PAGE45

CPU1_RSVD<115> @S9S_MB_2U_LIB.S9S_MB_2U(SCH_1):CPU1_RSVD(115)
    U1 CM63 RSVD121 SOCKET4677_AZIF0045P001C01CS-SA    I29 @S9S_MB_2U_LIB.S9S_MB_2U(SCH_1):PAGE45

CPU1_RSVD<120> @S9S_MB_2U_LIB.S9S_MB_2U(SCH_1):CPU1_RSVD(120)
    U1 CN62 RSVD126 SOCKET4677_AZIF0045P001C01CS-SA    I29 @S9S_MB_2U_LIB.S9S_MB_2U(SCH_1):PAGE45

CPU1_RSVD<126> @S9S_MB_2U_LIB.S9S_MB_2U(SCH_1):CPU1_RSVD(126)
    U1 CR23 RSVD132 SOCKET4677_AZIF0045P001C01CS-SA    I29 @S9S_MB_2U_LIB.S9S_MB_2U(SCH_1):PAGE45

CPU1_RSVD<135> @S9S_MB_2U_LIB.S9S_MB_2U(SCH_1):CPU1_RSVD(135)
    U1 CV24 RSVD141 SOCKET4677_AZIF0045P001C01CS-SA    I29 @S9S_MB_2U_LIB.S9S_MB_2U(SCH_1):PAGE45

CPU1_RSVD<139> @S9S_MB_2U_LIB.S9S_MB_2U(SCH_1):CPU1_RSVD(139)
    U1 CW23 RSVD145 SOCKET4677_AZIF0045P001C01CS-SA    I29 @S9S_MB_2U_LIB.S9S_MB_2U(SCH_1):PAGE45

CPU1_RSVD<140> @S9S_MB_2U_LIB.S9S_MB_2U(SCH_1):CPU1_RSVD(140)
    U1 CW25 RSVD146 SOCKET4677_AZIF0045P001C01CS-SA    I29 @S9S_MB_2U_LIB.S9S_MB_2U(SCH_1):PAGE45

CPU1_RSVD<144> @S9S_MB_2U_LIB.S9S_MB_2U(SCH_1):CPU1_RSVD(144)
    U1 CW68 RSVD150 SOCKET4677_AZIF0045P001C01CS-SA    I29 @S9S_MB_2U_LIB.S9S_MB_2U(SCH_1):PAGE45

CPU1_RSVD<153> @S9S_MB_2U_LIB.S9S_MB_2U(SCH_1):CPU1_RSVD(153)
    U1   D4 RSVD157 SOCKET4677_AZIF0045P001C01CS-SA    I51 @S9S_MB_2U_LIB.S9S_MB_2U(SCH_1):PAGE44

CPU1_RSVD<157> @S9S_MB_2U_LIB.S9S_MB_2U(SCH_1):CPU1_RSVD(157)
    U1   G5 RSVD161 SOCKET4677_AZIF0045P001C01CS-SA    I51 @S9S_MB_2U_LIB.S9S_MB_2U(SCH_1):PAGE44

CPU1_RSVD<15> @S9S_MB_2U_LIB.S9S_MB_2U(SCH_1):CPU1_RSVD(15)
    U1 AV26 RSVD15 SOCKET4677_AZIF0045P001C01CS-SA    I29 @S9S_MB_2U_LIB.S9S_MB_2U(SCH_1):PAGE45

CPU1_RSVD<25> @S9S_MB_2U_LIB.S9S_MB_2U(SCH_1):CPU1_RSVD(25)
    U1 AY26 RSVD27 SOCKET4677_AZIF0045P001C01CS-SA    I29 @S9S_MB_2U_LIB.S9S_MB_2U(SCH_1):PAGE45

CPU1_RSVD<27> @S9S_MB_2U_LIB.S9S_MB_2U(SCH_1):CPU1_RSVD(27)
    U1 AY65 RSVD29 SOCKET4677_AZIF0045P001C01CS-SA    I29 @S9S_MB_2U_LIB.S9S_MB_2U(SCH_1):PAGE45

CPU1_RSVD<4> @S9S_MB_2U_LIB.S9S_MB_2U(SCH_1):CPU1_RSVD(4)
    U1 AT24  RSVD4 SOCKET4677_AZIF0045P001C01CS-SA    I29 @S9S_MB_2U_LIB.S9S_MB_2U(SCH_1):PAGE45

CPU1_RSVD<54> @S9S_MB_2U_LIB.S9S_MB_2U(SCH_1):CPU1_RSVD(54)
    U1 BJ70 RSVD59 SOCKET4677_AZIF0045P001C01CS-SA    I29 @S9S_MB_2U_LIB.S9S_MB_2U(SCH_1):PAGE45

CPU1_RSVD<64> @S9S_MB_2U_LIB.S9S_MB_2U(SCH_1):CPU1_RSVD(64)
    U1 BP67 RSVD69 SOCKET4677_AZIF0045P001C01CS-SA    I29 @S9S_MB_2U_LIB.S9S_MB_2U(SCH_1):PAGE45

CPU1_RSVD<65> @S9S_MB_2U_LIB.S9S_MB_2U(SCH_1):CPU1_RSVD(65)
    U1 BP69 RSVD70 SOCKET4677_AZIF0045P001C01CS-SA    I29 @S9S_MB_2U_LIB.S9S_MB_2U(SCH_1):PAGE45

CPU1_RSVD<6> @S9S_MB_2U_LIB.S9S_MB_2U(SCH_1):CPU1_RSVD(6)
    U1 AU25  RSVD6 SOCKET4677_AZIF0045P001C01CS-SA    I29 @S9S_MB_2U_LIB.S9S_MB_2U(SCH_1):PAGE45

CPU1_RSVD<82> @S9S_MB_2U_LIB.S9S_MB_2U(SCH_1):CPU1_RSVD(82)
    U1 CD71 RSVD88 SOCKET4677_AZIF0045P001C01CS-SA    I51 @S9S_MB_2U_LIB.S9S_MB_2U(SCH_1):PAGE44

CPU1_RSVD<85> @S9S_MB_2U_LIB.S9S_MB_2U(SCH_1):CPU1_RSVD(85)
    U1 CE70 RSVD91 SOCKET4677_AZIF0045P001C01CS-SA    I51 @S9S_MB_2U_LIB.S9S_MB_2U(SCH_1):PAGE44

CPU1_RSVD<98> @S9S_MB_2U_LIB.S9S_MB_2U(SCH_1):CPU1_RSVD(98)
    U1 CJ62 RSVD104 SOCKET4677_AZIF0045P001C01CS-SA    I29 @S9S_MB_2U_LIB.S9S_MB_2U(SCH_1):PAGE45

CPU_RMCA_CATERR_LVT3_N @S9S_MB_2U_LIB.S9S_MB_2U(SCH_1):CPU_RMCA_CATERR_LVT3_N
   Q33    G      G MOSFET_NCH_GDS_ESD_PROTECTED-2A   I272 @S9S_MB_2U_LIB.S9S_MB_2U(SCH_1):PAGE207
  R365    2      B Q_RES_0402LF-0,5%,1/16W,CHIP,CA   I273 @S9S_MB_2U_LIB.S9S_MB_2U(SCH_1):PAGE207

DBP_CPU0_HOOK8_MBP2_GTL_QS_R_N @S9S_MB_2U_LIB.S9S_MB_2U(SCH_1):DBP_CPU0_HOOK8_MBP2_GTL_QS_R_N
    U2 BJ23 MBP2_N SOCKET4677_AZIF0045P001C01CS-SA     I1 @S9S_MB_2U_LIB.S9S_MB_2U(SCH_1):PAGE16
   R24    1      A Q_RES_0402LF-10,1%,1/16W,CHIP,A    I25 @S9S_MB_2U_LIB.S9S_MB_2U(SCH_1):PAGE16

DBP_CPU0_HOOK9_MBP3_GTL_QS_R_N @S9S_MB_2U_LIB.S9S_MB_2U(SCH_1):DBP_CPU0_HOOK9_MBP3_GTL_QS_R_N
    U2 BK24 MBP3_N SOCKET4677_AZIF0045P001C01CS-SA     I1 @S9S_MB_2U_LIB.S9S_MB_2U(SCH_1):PAGE16
   R25    1      A Q_RES_0402LF-10,1%,1/16W,CHIP,A    I26 @S9S_MB_2U_LIB.S9S_MB_2U(SCH_1):PAGE16

DBP_CPU0_MBP0_GTL_R_N @S9S_MB_2U_LIB.S9S_MB_2U(SCH_1):DBP_CPU0_MBP0_GTL_R_N
    U2 BL23 MBP0_N SOCKET4677_AZIF0045P001C01CS-SA     I1 @S9S_MB_2U_LIB.S9S_MB_2U(SCH_1):PAGE16
   R22    1      A Q_RES_0402LF-100,1%,1/16W,CHIPA    I19 @S9S_MB_2U_LIB.S9S_MB_2U(SCH_1):PAGE16

DBP_CPU0_MBP1_GTL_R_N @S9S_MB_2U_LIB.S9S_MB_2U(SCH_1):DBP_CPU0_MBP1_GTL_R_N
    U2 BN25 MBP1_N SOCKET4677_AZIF0045P001C01CS-SA     I1 @S9S_MB_2U_LIB.S9S_MB_2U(SCH_1):PAGE16
   R23    1      A Q_RES_0402LF-100,1%,1/16W,CHIPA    I20 @S9S_MB_2U_LIB.S9S_MB_2U(SCH_1):PAGE16

DBP_CPU1_HOOK8_MBP2_GTL_QS_R_N @S9S_MB_2U_LIB.S9S_MB_2U(SCH_1):DBP_CPU1_HOOK8_MBP2_GTL_QS_R_N
    U1 BJ23 MBP2_N SOCKET4677_AZIF0045P001C01CS-SA    I16 @S9S_MB_2U_LIB.S9S_MB_2U(SCH_1):PAGE47
   R53    1      A Q_RES_0402LF-10,1%,1/16W,CHIP,A    I23 @S9S_MB_2U_LIB.S9S_MB_2U(SCH_1):PAGE47

DBP_CPU1_HOOK9_MBP3_GTL_QS_R_N @S9S_MB_2U_LIB.S9S_MB_2U(SCH_1):DBP_CPU1_HOOK9_MBP3_GTL_QS_R_N
    U1 BK24 MBP3_N SOCKET4677_AZIF0045P001C01CS-SA    I16 @S9S_MB_2U_LIB.S9S_MB_2U(SCH_1):PAGE47
   R54    1      A Q_RES_0402LF-10,1%,1/16W,CHIP,A    I22 @S9S_MB_2U_LIB.S9S_MB_2U(SCH_1):PAGE47

DBP_CPU1_MBP0_GTL_R_N @S9S_MB_2U_LIB.S9S_MB_2U(SCH_1):DBP_CPU1_MBP0_GTL_R_N
    U1 BL23 MBP0_N SOCKET4677_AZIF0045P001C01CS-SA    I16 @S9S_MB_2U_LIB.S9S_MB_2U(SCH_1):PAGE47
   R51    1      A Q_RES_0402LF-100,1%,1/16W,CHIPA    I24 @S9S_MB_2U_LIB.S9S_MB_2U(SCH_1):PAGE47

DBP_CPU1_MBP1_GTL_R_N @S9S_MB_2U_LIB.S9S_MB_2U(SCH_1):DBP_CPU1_MBP1_GTL_R_N
    U1 BN25 MBP1_N SOCKET4677_AZIF0045P001C01CS-SA    I16 @S9S_MB_2U_LIB.S9S_MB_2U(SCH_1):PAGE47
   R52    1      A Q_RES_0402LF-100,1%,1/16W,CHIPA    I25 @S9S_MB_2U_LIB.S9S_MB_2U(SCH_1):PAGE47

DBP_CPU_HOOK8_MBP2_GTL_QS_N @S9S_MB_2U_LIB.S9S_MB_2U(SCH_1):DBP_CPU_HOOK8_MBP2_GTL_QS_N
   R24    2      B Q_RES_0402LF-10,1%,1/16W,CHIP,A    I25 @S9S_MB_2U_LIB.S9S_MB_2U(SCH_1):PAGE16
   R53    2      B Q_RES_0402LF-10,1%,1/16W,CHIP,A    I23 @S9S_MB_2U_LIB.S9S_MB_2U(SCH_1):PAGE47
   U18    6     2B 74CBTLV3126PW-74CBTLV3126PW,SMA   I129 @S9S_MB_2U_LIB.S9S_MB_2U(SCH_1):PAGE134
  R760    2      B Q_RES_0402LF-499,1%,1/16W,CHIPA   I174 @S9S_MB_2U_LIB.S9S_MB_2U(SCH_1):PAGE134

DBP_CPU_HOOK9_MBP3_GTL_QS_N @S9S_MB_2U_LIB.S9S_MB_2U(SCH_1):DBP_CPU_HOOK9_MBP3_GTL_QS_N
   R25    2      B Q_RES_0402LF-10,1%,1/16W,CHIP,A    I26 @S9S_MB_2U_LIB.S9S_MB_2U(SCH_1):PAGE16
   R54    2      B Q_RES_0402LF-10,1%,1/16W,CHIP,A    I22 @S9S_MB_2U_LIB.S9S_MB_2U(SCH_1):PAGE47
   U18    3     1B 74CBTLV3126PW-74CBTLV3126PW,SMA   I129 @S9S_MB_2U_LIB.S9S_MB_2U(SCH_1):PAGE134
  R761    2      B Q_RES_0402LF-499,1%,1/16W,CHIPA   I175 @S9S_MB_2U_LIB.S9S_MB_2U(SCH_1):PAGE134

DBP_CPU_MBP0_GTL_N @S9S_MB_2U_LIB.S9S_MB_2U(SCH_1):DBP_CPU_MBP0_GTL_N
   R22    2      B Q_RES_0402LF-100,1%,1/16W,CHIPA    I19 @S9S_MB_2U_LIB.S9S_MB_2U(SCH_1):PAGE16
   R20    1      A Q_RES_0402LF-0,5%,1/16W,CHIP,CA    I31 @S9S_MB_2U_LIB.S9S_MB_2U(SCH_1):PAGE16
   R18    2      B Q_RES_0402LF-499,1%,1/16W,CHIPA    I35 @S9S_MB_2U_LIB.S9S_MB_2U(SCH_1):PAGE16
   R51    2      B Q_RES_0402LF-100,1%,1/16W,CHIPA    I24 @S9S_MB_2U_LIB.S9S_MB_2U(SCH_1):PAGE47
   R49    2      B Q_RES_0402LF-499,1%,1/16W,CHIPA    I34 @S9S_MB_2U_LIB.S9S_MB_2U(SCH_1):PAGE47

DBP_CPU_MBP1_GTL_N @S9S_MB_2U_LIB.S9S_MB_2U(SCH_1):DBP_CPU_MBP1_GTL_N
   R23    2      B Q_RES_0402LF-100,1%,1/16W,CHIPA    I20 @S9S_MB_2U_LIB.S9S_MB_2U(SCH_1):PAGE16
   R21    1      A Q_RES_0402LF-0,5%,1/16W,CHIP,CA    I32 @S9S_MB_2U_LIB.S9S_MB_2U(SCH_1):PAGE16
   R19    2      B Q_RES_0402LF-499,1%,1/16W,CHIPA    I36 @S9S_MB_2U_LIB.S9S_MB_2U(SCH_1):PAGE16
   R52    2      B Q_RES_0402LF-100,1%,1/16W,CHIPA    I25 @S9S_MB_2U_LIB.S9S_MB_2U(SCH_1):PAGE47
   R50    2      B Q_RES_0402LF-499,1%,1/16W,CHIPA    I35 @S9S_MB_2U_LIB.S9S_MB_2U(SCH_1):PAGE47

DELTA_L_85_10INCH_BOT_DN @S9S_MB_2U_LIB.S9S_MB_2U(SCH_1):DELTA_L_85_10INCH_BOT_DN
   J82    1    1_P PICOPROBE_BXA-DELTA-L 4.0,SMLFA    I57 @S9S_MB_2U_LIB.S9S_MB_2U(SCH_1):PAGE287
   J76    2    2_N PICOPROBE_BXA-DELTA-L 4.0,SMLFA    I51 @S9S_MB_2U_LIB.S9S_MB_2U(SCH_1):PAGE287

DELTA_L_85_10INCH_BOT_DP @S9S_MB_2U_LIB.S9S_MB_2U(SCH_1):DELTA_L_85_10INCH_BOT_DP
   J82    2    2_N PICOPROBE_BXA-DELTA-L 4.0,SMLFA    I57 @S9S_MB_2U_LIB.S9S_MB_2U(SCH_1):PAGE287
   J76    1    1_P PICOPROBE_BXA-DELTA-L 4.0,SMLFA    I51 @S9S_MB_2U_LIB.S9S_MB_2U(SCH_1):PAGE287

DELTA_L_85_10INCH_IN1_DN @S9S_MB_2U_LIB.S9S_MB_2U(SCH_1):DELTA_L_85_10INCH_IN1_DN
   J77    2    2_N PICOPROBE_BXA-DELTA-L 4.0,SMLFA    I48 @S9S_MB_2U_LIB.S9S_MB_2U(SCH_1):PAGE287
   J83    1    1_P PICOPROBE_BXA-DELTA-L 4.0,SMLFA    I56 @S9S_MB_2U_LIB.S9S_MB_2U(SCH_1):PAGE287

DELTA_L_85_10INCH_IN1_DP @S9S_MB_2U_LIB.S9S_MB_2U(SCH_1):DELTA_L_85_10INCH_IN1_DP
   J77    1    1_P PICOPROBE_BXA-DELTA-L 4.0,SMLFA    I48 @S9S_MB_2U_LIB.S9S_MB_2U(SCH_1):PAGE287
   J83    2    2_N PICOPROBE_BXA-DELTA-L 4.0,SMLFA    I56 @S9S_MB_2U_LIB.S9S_MB_2U(SCH_1):PAGE287

DELTA_L_85_10INCH_IN2_DN @S9S_MB_2U_LIB.S9S_MB_2U(SCH_1):DELTA_L_85_10INCH_IN2_DN
   J78    2    2_N PICOPROBE_BXA-DELTA-L 4.0,SMLFA    I43 @S9S_MB_2U_LIB.S9S_MB_2U(SCH_1):PAGE287
   J84    1    1_P PICOPROBE_BXA-DELTA-L 4.0,SMLFA    I55 @S9S_MB_2U_LIB.S9S_MB_2U(SCH_1):PAGE287

DELTA_L_85_10INCH_IN2_DP @S9S_MB_2U_LIB.S9S_MB_2U(SCH_1):DELTA_L_85_10INCH_IN2_DP
   J78    1    1_P PICOPROBE_BXA-DELTA-L 4.0,SMLFA    I43 @S9S_MB_2U_LIB.S9S_MB_2U(SCH_1):PAGE287
   J84    2    2_N PICOPROBE_BXA-DELTA-L 4.0,SMLFA    I55 @S9S_MB_2U_LIB.S9S_MB_2U(SCH_1):PAGE287

DELTA_L_85_10INCH_IN3_DN @S9S_MB_2U_LIB.S9S_MB_2U(SCH_1):DELTA_L_85_10INCH_IN3_DN
   J79    2    2_N PICOPROBE_BXA-DELTA-L 4.0,SMLFA    I42 @S9S_MB_2U_LIB.S9S_MB_2U(SCH_1):PAGE287
   J85    1    1_P PICOPROBE_BXA-DELTA-L 4.0,SMLFA    I54 @S9S_MB_2U_LIB.S9S_MB_2U(SCH_1):PAGE287

DELTA_L_85_10INCH_IN3_DP @S9S_MB_2U_LIB.S9S_MB_2U(SCH_1):DELTA_L_85_10INCH_IN3_DP
   J79    1    1_P PICOPROBE_BXA-DELTA-L 4.0,SMLFA    I42 @S9S_MB_2U_LIB.S9S_MB_2U(SCH_1):PAGE287
   J85    2    2_N PICOPROBE_BXA-DELTA-L 4.0,SMLFA    I54 @S9S_MB_2U_LIB.S9S_MB_2U(SCH_1):PAGE287

DELTA_L_85_10INCH_IN4_DN @S9S_MB_2U_LIB.S9S_MB_2U(SCH_1):DELTA_L_85_10INCH_IN4_DN
   J80    2    2_N PICOPROBE_BXA-DELTA-L 4.0,SMLFA    I39 @S9S_MB_2U_LIB.S9S_MB_2U(SCH_1):PAGE287
   J86    1    1_P PICOPROBE_BXA-DELTA-L 4.0,SMLFA    I53 @S9S_MB_2U_LIB.S9S_MB_2U(SCH_1):PAGE287

DELTA_L_85_10INCH_IN4_DP @S9S_MB_2U_LIB.S9S_MB_2U(SCH_1):DELTA_L_85_10INCH_IN4_DP
   J80    1    1_P PICOPROBE_BXA-DELTA-L 4.0,SMLFA    I39 @S9S_MB_2U_LIB.S9S_MB_2U(SCH_1):PAGE287
   J86    2    2_N PICOPROBE_BXA-DELTA-L 4.0,SMLFA    I53 @S9S_MB_2U_LIB.S9S_MB_2U(SCH_1):PAGE287

DELTA_L_85_10INCH_IN5_DN @S9S_MB_2U_LIB.S9S_MB_2U(SCH_1):DELTA_L_85_10INCH_IN5_DN
  J118    2    2_N PICOPROBE_BXA-DELTA-L 4.0,SMLFA    I30 @S9S_MB_2U_LIB.S9S_MB_2U(SCH_1):PAGE287
  J120    1    1_P PICOPROBE_BXA-DELTA-L 4.0,SMLFA    I32 @S9S_MB_2U_LIB.S9S_MB_2U(SCH_1):PAGE287

DELTA_L_85_10INCH_IN5_DP @S9S_MB_2U_LIB.S9S_MB_2U(SCH_1):DELTA_L_85_10INCH_IN5_DP
  J118    1    1_P PICOPROBE_BXA-DELTA-L 4.0,SMLFA    I30 @S9S_MB_2U_LIB.S9S_MB_2U(SCH_1):PAGE287
  J120    2    2_N PICOPROBE_BXA-DELTA-L 4.0,SMLFA    I32 @S9S_MB_2U_LIB.S9S_MB_2U(SCH_1):PAGE287

DELTA_L_85_10INCH_IN6_DN @S9S_MB_2U_LIB.S9S_MB_2U(SCH_1):DELTA_L_85_10INCH_IN6_DN
  J121    1    1_P PICOPROBE_BXA-DELTA-L 4.0,SMLFA    I31 @S9S_MB_2U_LIB.S9S_MB_2U(SCH_1):PAGE287
  J119    2    2_N PICOPROBE_BXA-DELTA-L 4.0,SMLFA    I28 @S9S_MB_2U_LIB.S9S_MB_2U(SCH_1):PAGE287

DELTA_L_85_10INCH_IN6_DP @S9S_MB_2U_LIB.S9S_MB_2U(SCH_1):DELTA_L_85_10INCH_IN6_DP
  J121    2    2_N PICOPROBE_BXA-DELTA-L 4.0,SMLFA    I31 @S9S_MB_2U_LIB.S9S_MB_2U(SCH_1):PAGE287
  J119    1    1_P PICOPROBE_BXA-DELTA-L 4.0,SMLFA    I28 @S9S_MB_2U_LIB.S9S_MB_2U(SCH_1):PAGE287

DELTA_L_85_10INCH_TOP_DN @S9S_MB_2U_LIB.S9S_MB_2U(SCH_1):DELTA_L_85_10INCH_TOP_DN
   J75    2    2_N PICOPROBE_BXA-DELTA-L 4.0,SMLFA    I52 @S9S_MB_2U_LIB.S9S_MB_2U(SCH_1):PAGE287
   J81    1    1_P PICOPROBE_BXA-DELTA-L 4.0,SMLFA    I58 @S9S_MB_2U_LIB.S9S_MB_2U(SCH_1):PAGE287

DELTA_L_85_10INCH_TOP_DP @S9S_MB_2U_LIB.S9S_MB_2U(SCH_1):DELTA_L_85_10INCH_TOP_DP
   J75    1    1_P PICOPROBE_BXA-DELTA-L 4.0,SMLFA    I52 @S9S_MB_2U_LIB.S9S_MB_2U(SCH_1):PAGE287
   J81    2    2_N PICOPROBE_BXA-DELTA-L 4.0,SMLFA    I58 @S9S_MB_2U_LIB.S9S_MB_2U(SCH_1):PAGE287

DELTA_L_85_5INCH_BOT_DN @S9S_MB_2U_LIB.S9S_MB_2U(SCH_1):DELTA_L_85_5INCH_BOT_DN
   J70    1    1_P PICOPROBE_BXA-DELTA-L 4.0,SMLFA    I23 @S9S_MB_2U_LIB.S9S_MB_2U(SCH_1):PAGE287
   J64    2    2_N PICOPROBE_BXA-DELTA-L 4.0,SMLFA    I17 @S9S_MB_2U_LIB.S9S_MB_2U(SCH_1):PAGE287

DELTA_L_85_5INCH_BOT_DP @S9S_MB_2U_LIB.S9S_MB_2U(SCH_1):DELTA_L_85_5INCH_BOT_DP
   J70    2    2_N PICOPROBE_BXA-DELTA-L 4.0,SMLFA    I23 @S9S_MB_2U_LIB.S9S_MB_2U(SCH_1):PAGE287
   J64    1    1_P PICOPROBE_BXA-DELTA-L 4.0,SMLFA    I17 @S9S_MB_2U_LIB.S9S_MB_2U(SCH_1):PAGE287

DELTA_L_85_5INCH_IN1_DN @S9S_MB_2U_LIB.S9S_MB_2U(SCH_1):DELTA_L_85_5INCH_IN1_DN
   J65    2    2_N PICOPROBE_BXA-DELTA-L 4.0,SMLFA    I14 @S9S_MB_2U_LIB.S9S_MB_2U(SCH_1):PAGE287
   J71    1    1_P PICOPROBE_BXA-DELTA-L 4.0,SMLFA    I22 @S9S_MB_2U_LIB.S9S_MB_2U(SCH_1):PAGE287

DELTA_L_85_5INCH_IN1_DP @S9S_MB_2U_LIB.S9S_MB_2U(SCH_1):DELTA_L_85_5INCH_IN1_DP
   J65    1    1_P PICOPROBE_BXA-DELTA-L 4.0,SMLFA    I14 @S9S_MB_2U_LIB.S9S_MB_2U(SCH_1):PAGE287
   J71    2    2_N PICOPROBE_BXA-DELTA-L 4.0,SMLFA    I22 @S9S_MB_2U_LIB.S9S_MB_2U(SCH_1):PAGE287

DELTA_L_85_5INCH_IN2_DN @S9S_MB_2U_LIB.S9S_MB_2U(SCH_1):DELTA_L_85_5INCH_IN2_DN
   J66    2    2_N PICOPROBE_BXA-DELTA-L 4.0,SMLFA    I12 @S9S_MB_2U_LIB.S9S_MB_2U(SCH_1):PAGE287
   J72    1    1_P PICOPROBE_BXA-DELTA-L 4.0,SMLFA    I21 @S9S_MB_2U_LIB.S9S_MB_2U(SCH_1):PAGE287

DELTA_L_85_5INCH_IN2_DP @S9S_MB_2U_LIB.S9S_MB_2U(SCH_1):DELTA_L_85_5INCH_IN2_DP
   J66    1    1_P PICOPROBE_BXA-DELTA-L 4.0,SMLFA    I12 @S9S_MB_2U_LIB.S9S_MB_2U(SCH_1):PAGE287
   J72    2    2_N PICOPROBE_BXA-DELTA-L 4.0,SMLFA    I21 @S9S_MB_2U_LIB.S9S_MB_2U(SCH_1):PAGE287

DELTA_L_85_5INCH_IN3_DN @S9S_MB_2U_LIB.S9S_MB_2U(SCH_1):DELTA_L_85_5INCH_IN3_DN
   J67    2    2_N PICOPROBE_BXA-DELTA-L 4.0,SMLFA    I11 @S9S_MB_2U_LIB.S9S_MB_2U(SCH_1):PAGE287
   J73    1    1_P PICOPROBE_BXA-DELTA-L 4.0,SMLFA    I20 @S9S_MB_2U_LIB.S9S_MB_2U(SCH_1):PAGE287

DELTA_L_85_5INCH_IN3_DP @S9S_MB_2U_LIB.S9S_MB_2U(SCH_1):DELTA_L_85_5INCH_IN3_DP
   J67    1    1_P PICOPROBE_BXA-DELTA-L 4.0,SMLFA    I11 @S9S_MB_2U_LIB.S9S_MB_2U(SCH_1):PAGE287
   J73    2    2_N PICOPROBE_BXA-DELTA-L 4.0,SMLFA    I20 @S9S_MB_2U_LIB.S9S_MB_2U(SCH_1):PAGE287

DELTA_L_85_5INCH_IN4_DN @S9S_MB_2U_LIB.S9S_MB_2U(SCH_1):DELTA_L_85_5INCH_IN4_DN
   J68    2    2_N PICOPROBE_BXA-DELTA-L 4.0,SMLFA     I8 @S9S_MB_2U_LIB.S9S_MB_2U(SCH_1):PAGE287
   J74    1    1_P PICOPROBE_BXA-DELTA-L 4.0,SMLFA    I19 @S9S_MB_2U_LIB.S9S_MB_2U(SCH_1):PAGE287

DELTA_L_85_5INCH_IN4_DP @S9S_MB_2U_LIB.S9S_MB_2U(SCH_1):DELTA_L_85_5INCH_IN4_DP
   J68    1    1_P PICOPROBE_BXA-DELTA-L 4.0,SMLFA     I8 @S9S_MB_2U_LIB.S9S_MB_2U(SCH_1):PAGE287
   J74    2    2_N PICOPROBE_BXA-DELTA-L 4.0,SMLFA    I19 @S9S_MB_2U_LIB.S9S_MB_2U(SCH_1):PAGE287

DELTA_L_85_5INCH_IN5_DN @S9S_MB_2U_LIB.S9S_MB_2U(SCH_1):DELTA_L_85_5INCH_IN5_DN
  J114    2    2_N PICOPROBE_BXA-DELTA-L 4.0,SMLFA     I4 @S9S_MB_2U_LIB.S9S_MB_2U(SCH_1):PAGE287
  J116    1    1_P PICOPROBE_BXA-DELTA-L 4.0,SMLFA     I6 @S9S_MB_2U_LIB.S9S_MB_2U(SCH_1):PAGE287

DELTA_L_85_5INCH_IN5_DP @S9S_MB_2U_LIB.S9S_MB_2U(SCH_1):DELTA_L_85_5INCH_IN5_DP
  J114    1    1_P PICOPROBE_BXA-DELTA-L 4.0,SMLFA     I4 @S9S_MB_2U_LIB.S9S_MB_2U(SCH_1):PAGE287
  J116    2    2_N PICOPROBE_BXA-DELTA-L 4.0,SMLFA     I6 @S9S_MB_2U_LIB.S9S_MB_2U(SCH_1):PAGE287

DELTA_L_85_5INCH_IN6_DN @S9S_MB_2U_LIB.S9S_MB_2U(SCH_1):DELTA_L_85_5INCH_IN6_DN
  J115    2    2_N PICOPROBE_BXA-DELTA-L 4.0,SMLFA     I3 @S9S_MB_2U_LIB.S9S_MB_2U(SCH_1):PAGE287
  J117    1    1_P PICOPROBE_BXA-DELTA-L 4.0,SMLFA     I5 @S9S_MB_2U_LIB.S9S_MB_2U(SCH_1):PAGE287

DELTA_L_85_5INCH_IN6_DP @S9S_MB_2U_LIB.S9S_MB_2U(SCH_1):DELTA_L_85_5INCH_IN6_DP
  J115    1    1_P PICOPROBE_BXA-DELTA-L 4.0,SMLFA     I3 @S9S_MB_2U_LIB.S9S_MB_2U(SCH_1):PAGE287
  J117    2    2_N PICOPROBE_BXA-DELTA-L 4.0,SMLFA     I5 @S9S_MB_2U_LIB.S9S_MB_2U(SCH_1):PAGE287

DELTA_L_85_5INCH_TOP_DN @S9S_MB_2U_LIB.S9S_MB_2U(SCH_1):DELTA_L_85_5INCH_TOP_DN
   J63    2    2_N PICOPROBE_BXA-DELTA-L 4.0,SMLFA    I18 @S9S_MB_2U_LIB.S9S_MB_2U(SCH_1):PAGE287
   J69    1    1_P PICOPROBE_BXA-DELTA-L 4.0,SMLFA    I24 @S9S_MB_2U_LIB.S9S_MB_2U(SCH_1):PAGE287

DELTA_L_85_5INCH_TOP_DP @S9S_MB_2U_LIB.S9S_MB_2U(SCH_1):DELTA_L_85_5INCH_TOP_DP
   J63    1    1_P PICOPROBE_BXA-DELTA-L 4.0,SMLFA    I18 @S9S_MB_2U_LIB.S9S_MB_2U(SCH_1):PAGE287
   J69    2    2_N PICOPROBE_BXA-DELTA-L 4.0,SMLFA    I24 @S9S_MB_2U_LIB.S9S_MB_2U(SCH_1):PAGE287

DELTA_L_GND_1 @S9S_MB_2U_LIB.S9S_MB_2U(SCH_1):DELTA_L_GND_1
   J68    3    3_G PICOPROBE_BXA-DELTA-L 4.0,SMLFA     I8 @S9S_MB_2U_LIB.S9S_MB_2U(SCH_1):PAGE287
   J67    3    3_G PICOPROBE_BXA-DELTA-L 4.0,SMLFA    I11 @S9S_MB_2U_LIB.S9S_MB_2U(SCH_1):PAGE287
   J66    3    3_G PICOPROBE_BXA-DELTA-L 4.0,SMLFA    I12 @S9S_MB_2U_LIB.S9S_MB_2U(SCH_1):PAGE287
   J74    3    3_G PICOPROBE_BXA-DELTA-L 4.0,SMLFA    I19 @S9S_MB_2U_LIB.S9S_MB_2U(SCH_1):PAGE287
   J72    3    3_G PICOPROBE_BXA-DELTA-L 4.0,SMLFA    I21 @S9S_MB_2U_LIB.S9S_MB_2U(SCH_1):PAGE287
   J70    3    3_G PICOPROBE_BXA-DELTA-L 4.0,SMLFA    I23 @S9S_MB_2U_LIB.S9S_MB_2U(SCH_1):PAGE287
  J118    3    3_G PICOPROBE_BXA-DELTA-L 4.0,SMLFA    I30 @S9S_MB_2U_LIB.S9S_MB_2U(SCH_1):PAGE287
  J121    3    3_G PICOPROBE_BXA-DELTA-L 4.0,SMLFA    I31 @S9S_MB_2U_LIB.S9S_MB_2U(SCH_1):PAGE287
  J120    3    3_G PICOPROBE_BXA-DELTA-L 4.0,SMLFA    I32 @S9S_MB_2U_LIB.S9S_MB_2U(SCH_1):PAGE287
   J80    3    3_G PICOPROBE_BXA-DELTA-L 4.0,SMLFA    I39 @S9S_MB_2U_LIB.S9S_MB_2U(SCH_1):PAGE287
   J78    3    3_G PICOPROBE_BXA-DELTA-L 4.0,SMLFA    I43 @S9S_MB_2U_LIB.S9S_MB_2U(SCH_1):PAGE287
   J75    3    3_G PICOPROBE_BXA-DELTA-L 4.0,SMLFA    I52 @S9S_MB_2U_LIB.S9S_MB_2U(SCH_1):PAGE287
   J86    3    3_G PICOPROBE_BXA-DELTA-L 4.0,SMLFA    I53 @S9S_MB_2U_LIB.S9S_MB_2U(SCH_1):PAGE287
   J84    3    3_G PICOPROBE_BXA-DELTA-L 4.0,SMLFA    I55 @S9S_MB_2U_LIB.S9S_MB_2U(SCH_1):PAGE287
   J82    3    3_G PICOPROBE_BXA-DELTA-L 4.0,SMLFA    I57 @S9S_MB_2U_LIB.S9S_MB_2U(SCH_1):PAGE287
  J115    3    3_G PICOPROBE_BXA-DELTA-L 4.0,SMLFA     I3 @S9S_MB_2U_LIB.S9S_MB_2U(SCH_1):PAGE287
  J114    3    3_G PICOPROBE_BXA-DELTA-L 4.0,SMLFA     I4 @S9S_MB_2U_LIB.S9S_MB_2U(SCH_1):PAGE287
  J117    3    3_G PICOPROBE_BXA-DELTA-L 4.0,SMLFA     I5 @S9S_MB_2U_LIB.S9S_MB_2U(SCH_1):PAGE287
  J116    3    3_G PICOPROBE_BXA-DELTA-L 4.0,SMLFA     I6 @S9S_MB_2U_LIB.S9S_MB_2U(SCH_1):PAGE287
   J65    3    3_G PICOPROBE_BXA-DELTA-L 4.0,SMLFA    I14 @S9S_MB_2U_LIB.S9S_MB_2U(SCH_1):PAGE287
   J64    3    3_G PICOPROBE_BXA-DELTA-L 4.0,SMLFA    I17 @S9S_MB_2U_LIB.S9S_MB_2U(SCH_1):PAGE287
   J63    3    3_G PICOPROBE_BXA-DELTA-L 4.0,SMLFA    I18 @S9S_MB_2U_LIB.S9S_MB_2U(SCH_1):PAGE287
   J73    3    3_G PICOPROBE_BXA-DELTA-L 4.0,SMLFA    I20 @S9S_MB_2U_LIB.S9S_MB_2U(SCH_1):PAGE287
   J71    3    3_G PICOPROBE_BXA-DELTA-L 4.0,SMLFA    I22 @S9S_MB_2U_LIB.S9S_MB_2U(SCH_1):PAGE287
   J69    3    3_G PICOPROBE_BXA-DELTA-L 4.0,SMLFA    I24 @S9S_MB_2U_LIB.S9S_MB_2U(SCH_1):PAGE287
  J119    3    3_G PICOPROBE_BXA-DELTA-L 4.0,SMLFA    I28 @S9S_MB_2U_LIB.S9S_MB_2U(SCH_1):PAGE287
   J79    3    3_G PICOPROBE_BXA-DELTA-L 4.0,SMLFA    I42 @S9S_MB_2U_LIB.S9S_MB_2U(SCH_1):PAGE287
   J77    3    3_G PICOPROBE_BXA-DELTA-L 4.0,SMLFA    I48 @S9S_MB_2U_LIB.S9S_MB_2U(SCH_1):PAGE287
   J76    3    3_G PICOPROBE_BXA-DELTA-L 4.0,SMLFA    I51 @S9S_MB_2U_LIB.S9S_MB_2U(SCH_1):PAGE287
   J85    3    3_G PICOPROBE_BXA-DELTA-L 4.0,SMLFA    I54 @S9S_MB_2U_LIB.S9S_MB_2U(SCH_1):PAGE287
   J83    3    3_G PICOPROBE_BXA-DELTA-L 4.0,SMLFA    I56 @S9S_MB_2U_LIB.S9S_MB_2U(SCH_1):PAGE287
   J81    3    3_G PICOPROBE_BXA-DELTA-L 4.0,SMLFA    I58 @S9S_MB_2U_LIB.S9S_MB_2U(SCH_1):PAGE287

DMI_CPU0_PCH_RX_C_DN<0> @S9S_MB_2U_LIB.S9S_MB_2U(SCH_1):DMI_CPU0_PCH_RX_C_DN(0)
    U2 BB18 DMI_RX_DN0 SOCKET4677_AZIF0045P001C01CS-SA   I169 @S9S_MB_2U_LIB.S9S_MB_2U(SCH_1):PAGE28
  C169    1      1 Q_CAP_DIFFBUS_C0201-DIFF BUS_0A   I127 @S9S_MB_2U_LIB.S9S_MB_2U(SCH_1):PAGE169

DMI_CPU0_PCH_RX_C_DN<1> @S9S_MB_2U_LIB.S9S_MB_2U(SCH_1):DMI_CPU0_PCH_RX_C_DN(1)
    U2 BD18 DMI_RX_DP1 SOCKET4677_AZIF0045P001C01CS-SA   I169 @S9S_MB_2U_LIB.S9S_MB_2U(SCH_1):PAGE28
  C167    1      1 Q_CAP_DIFFBUS_C0201-DIFF BUS_0A   I126 @S9S_MB_2U_LIB.S9S_MB_2U(SCH_1):PAGE169

DMI_CPU0_PCH_RX_C_DN<2> @S9S_MB_2U_LIB.S9S_MB_2U(SCH_1):DMI_CPU0_PCH_RX_C_DN(2)
    U2 BF18 DMI_RX_DN2 SOCKET4677_AZIF0045P001C01CS-SA   I169 @S9S_MB_2U_LIB.S9S_MB_2U(SCH_1):PAGE28
  C165    1      1 Q_CAP_DIFFBUS_C0201-DIFF BUS_0A   I123 @S9S_MB_2U_LIB.S9S_MB_2U(SCH_1):PAGE169

DMI_CPU0_PCH_RX_C_DN<3> @S9S_MB_2U_LIB.S9S_MB_2U(SCH_1):DMI_CPU0_PCH_RX_C_DN(3)
    U2 BH18 DMI_RX_DP3 SOCKET4677_AZIF0045P001C01CS-SA   I169 @S9S_MB_2U_LIB.S9S_MB_2U(SCH_1):PAGE28
  C163    1      1 Q_CAP_DIFFBUS_C0201-DIFF BUS_0A   I121 @S9S_MB_2U_LIB.S9S_MB_2U(SCH_1):PAGE169

DMI_CPU0_PCH_RX_C_DN<4> @S9S_MB_2U_LIB.S9S_MB_2U(SCH_1):DMI_CPU0_PCH_RX_C_DN(4)
    U2 BL19 DMI_RX_DP4 SOCKET4677_AZIF0045P001C01CS-SA   I169 @S9S_MB_2U_LIB.S9S_MB_2U(SCH_1):PAGE28
  C161    1      1 Q_CAP_DIFFBUS_C0201-DIFF BUS_0A   I119 @S9S_MB_2U_LIB.S9S_MB_2U(SCH_1):PAGE169

DMI_CPU0_PCH_RX_C_DN<5> @S9S_MB_2U_LIB.S9S_MB_2U(SCH_1):DMI_CPU0_PCH_RX_C_DN(5)
    U2 BM18 DMI_RX_DP5 SOCKET4677_AZIF0045P001C01CS-SA   I169 @S9S_MB_2U_LIB.S9S_MB_2U(SCH_1):PAGE28
  C159    1      1 Q_CAP_DIFFBUS_C0201-DIFF BUS_0A   I117 @S9S_MB_2U_LIB.S9S_MB_2U(SCH_1):PAGE169

DMI_CPU0_PCH_RX_C_DN<6> @S9S_MB_2U_LIB.S9S_MB_2U(SCH_1):DMI_CPU0_PCH_RX_C_DN(6)
    U2 BR19 DMI_RX_DP6 SOCKET4677_AZIF0045P001C01CS-SA   I169 @S9S_MB_2U_LIB.S9S_MB_2U(SCH_1):PAGE28
  C157    1      1 Q_CAP_DIFFBUS_C0201-DIFF BUS_0A   I115 @S9S_MB_2U_LIB.S9S_MB_2U(SCH_1):PAGE169

DMI_CPU0_PCH_RX_C_DN<7> @S9S_MB_2U_LIB.S9S_MB_2U(SCH_1):DMI_CPU0_PCH_RX_C_DN(7)
    U2 BU17 DMI_RX_DN7 SOCKET4677_AZIF0045P001C01CS-SA   I169 @S9S_MB_2U_LIB.S9S_MB_2U(SCH_1):PAGE28
  C155    1      1 Q_CAP_DIFFBUS_C0201-DIFF BUS_0A   I113 @S9S_MB_2U_LIB.S9S_MB_2U(SCH_1):PAGE169

DMI_CPU0_PCH_RX_C_DP<0> @S9S_MB_2U_LIB.S9S_MB_2U(SCH_1):DMI_CPU0_PCH_RX_C_DP(0)
    U2 BC19 DMI_RX_DP0 SOCKET4677_AZIF0045P001C01CS-SA   I169 @S9S_MB_2U_LIB.S9S_MB_2U(SCH_1):PAGE28
  C170    1      1 Q_CAP_DIFFBUS_C0201-DIFF BUS_0A   I128 @S9S_MB_2U_LIB.S9S_MB_2U(SCH_1):PAGE169

DMI_CPU0_PCH_RX_C_DP<1> @S9S_MB_2U_LIB.S9S_MB_2U(SCH_1):DMI_CPU0_PCH_RX_C_DP(1)
    U2 BE17 DMI_RX_DN1 SOCKET4677_AZIF0045P001C01CS-SA   I169 @S9S_MB_2U_LIB.S9S_MB_2U(SCH_1):PAGE28
  C168    1      1 Q_CAP_DIFFBUS_C0201-DIFF BUS_0A   I125 @S9S_MB_2U_LIB.S9S_MB_2U(SCH_1):PAGE169

DMI_CPU0_PCH_RX_C_DP<2> @S9S_MB_2U_LIB.S9S_MB_2U(SCH_1):DMI_CPU0_PCH_RX_C_DP(2)
    U2 BG19 DMI_RX_DP2 SOCKET4677_AZIF0045P001C01CS-SA   I169 @S9S_MB_2U_LIB.S9S_MB_2U(SCH_1):PAGE28
  C166    1      1 Q_CAP_DIFFBUS_C0201-DIFF BUS_0A   I124 @S9S_MB_2U_LIB.S9S_MB_2U(SCH_1):PAGE169

DMI_CPU0_PCH_RX_C_DP<3> @S9S_MB_2U_LIB.S9S_MB_2U(SCH_1):DMI_CPU0_PCH_RX_C_DP(3)
    U2 BJ17 DMI_RX_DN3 SOCKET4677_AZIF0045P001C01CS-SA   I169 @S9S_MB_2U_LIB.S9S_MB_2U(SCH_1):PAGE28
  C164    1      1 Q_CAP_DIFFBUS_C0201-DIFF BUS_0A   I122 @S9S_MB_2U_LIB.S9S_MB_2U(SCH_1):PAGE169

DMI_CPU0_PCH_RX_C_DP<4> @S9S_MB_2U_LIB.S9S_MB_2U(SCH_1):DMI_CPU0_PCH_RX_C_DP(4)
    U2 BK18 DMI_RX_DN4 SOCKET4677_AZIF0045P001C01CS-SA   I169 @S9S_MB_2U_LIB.S9S_MB_2U(SCH_1):PAGE28
  C162    1      1 Q_CAP_DIFFBUS_C0201-DIFF BUS_0A   I120 @S9S_MB_2U_LIB.S9S_MB_2U(SCH_1):PAGE169

DMI_CPU0_PCH_RX_C_DP<5> @S9S_MB_2U_LIB.S9S_MB_2U(SCH_1):DMI_CPU0_PCH_RX_C_DP(5)
    U2 BN17 DMI_RX_DN5 SOCKET4677_AZIF0045P001C01CS-SA   I169 @S9S_MB_2U_LIB.S9S_MB_2U(SCH_1):PAGE28
  C160    1      1 Q_CAP_DIFFBUS_C0201-DIFF BUS_0A   I118 @S9S_MB_2U_LIB.S9S_MB_2U(SCH_1):PAGE169

DMI_CPU0_PCH_RX_C_DP<6> @S9S_MB_2U_LIB.S9S_MB_2U(SCH_1):DMI_CPU0_PCH_RX_C_DP(6)
    U2 BP18 DMI_RX_DN6 SOCKET4677_AZIF0045P001C01CS-SA   I169 @S9S_MB_2U_LIB.S9S_MB_2U(SCH_1):PAGE28
  C158    1      1 Q_CAP_DIFFBUS_C0201-DIFF BUS_0A   I116 @S9S_MB_2U_LIB.S9S_MB_2U(SCH_1):PAGE169

DMI_CPU0_PCH_RX_C_DP<7> @S9S_MB_2U_LIB.S9S_MB_2U(SCH_1):DMI_CPU0_PCH_RX_C_DP(7)
    U2 BT18 DMI_RX_DP7 SOCKET4677_AZIF0045P001C01CS-SA   I169 @S9S_MB_2U_LIB.S9S_MB_2U(SCH_1):PAGE28
  C156    1      1 Q_CAP_DIFFBUS_C0201-DIFF BUS_0A   I114 @S9S_MB_2U_LIB.S9S_MB_2U(SCH_1):PAGE169

DMI_CPU0_PCH_RX_DN<0> @S9S_MB_2U_LIB.S9S_MB_2U(SCH_1):DMI_CPU0_PCH_RX_DN(0)
  C169    2      2 Q_CAP_DIFFBUS_C0201-DIFF BUS_0A   I127 @S9S_MB_2U_LIB.S9S_MB_2U(SCH_1):PAGE169
    U4  K28 DMI_0_TXN EMMITSBURG_REV0P9-GFNOCPU04302A   I110 @S9S_MB_2U_LIB.S9S_MB_2U(SCH_1):PAGE173

DMI_CPU0_PCH_RX_DN<1> @S9S_MB_2U_LIB.S9S_MB_2U(SCH_1):DMI_CPU0_PCH_RX_DN(1)
  C167    2      2 Q_CAP_DIFFBUS_C0201-DIFF BUS_0A   I126 @S9S_MB_2U_LIB.S9S_MB_2U(SCH_1):PAGE169
    U4  G29 DMI_1_TXN EMMITSBURG_REV0P9-GFNOCPU04302A   I110 @S9S_MB_2U_LIB.S9S_MB_2U(SCH_1):PAGE173

DMI_CPU0_PCH_RX_DN<2> @S9S_MB_2U_LIB.S9S_MB_2U(SCH_1):DMI_CPU0_PCH_RX_DN(2)
  C165    2      2 Q_CAP_DIFFBUS_C0201-DIFF BUS_0A   I123 @S9S_MB_2U_LIB.S9S_MB_2U(SCH_1):PAGE169
    U4  J29 DMI_2_TXN EMMITSBURG_REV0P9-GFNOCPU04302A   I110 @S9S_MB_2U_LIB.S9S_MB_2U(SCH_1):PAGE173

DMI_CPU0_PCH_RX_DN<3> @S9S_MB_2U_LIB.S9S_MB_2U(SCH_1):DMI_CPU0_PCH_RX_DN(3)
  C163    2      2 Q_CAP_DIFFBUS_C0201-DIFF BUS_0A   I121 @S9S_MB_2U_LIB.S9S_MB_2U(SCH_1):PAGE169
    U4  L32 DMI_3_TXN EMMITSBURG_REV0P9-GFNOCPU04302A   I110 @S9S_MB_2U_LIB.S9S_MB_2U(SCH_1):PAGE173

DMI_CPU0_PCH_RX_DN<4> @S9S_MB_2U_LIB.S9S_MB_2U(SCH_1):DMI_CPU0_PCH_RX_DN(4)
  C161    2      2 Q_CAP_DIFFBUS_C0201-DIFF BUS_0A   I119 @S9S_MB_2U_LIB.S9S_MB_2U(SCH_1):PAGE169
    U4  J32 DMI_4_SATA_19_PCIE3_19_TXN EMMITSBURG_REV0P9-GFNOCPU04302A   I110 @S9S_MB_2U_LIB.S9S_MB_2U(SCH_1):PAGE173

DMI_CPU0_PCH_RX_DN<5> @S9S_MB_2U_LIB.S9S_MB_2U(SCH_1):DMI_CPU0_PCH_RX_DN(5)
  C159    2      2 Q_CAP_DIFFBUS_C0201-DIFF BUS_0A   I117 @S9S_MB_2U_LIB.S9S_MB_2U(SCH_1):PAGE169
    U4  G36 DMI_5_SATA_18_PCIE3_18_TXN EMMITSBURG_REV0P9-GFNOCPU04302A   I110 @S9S_MB_2U_LIB.S9S_MB_2U(SCH_1):PAGE173

DMI_CPU0_PCH_RX_DN<6> @S9S_MB_2U_LIB.S9S_MB_2U(SCH_1):DMI_CPU0_PCH_RX_DN(6)
  C157    2      2 Q_CAP_DIFFBUS_C0201-DIFF BUS_0A   I115 @S9S_MB_2U_LIB.S9S_MB_2U(SCH_1):PAGE169
    U4  K37 DMI_6_SATA_17_PCIE3_17_TXN EMMITSBURG_REV0P9-GFNOCPU04302A   I110 @S9S_MB_2U_LIB.S9S_MB_2U(SCH_1):PAGE173

DMI_CPU0_PCH_RX_DN<7> @S9S_MB_2U_LIB.S9S_MB_2U(SCH_1):DMI_CPU0_PCH_RX_DN(7)
  C155    2      2 Q_CAP_DIFFBUS_C0201-DIFF BUS_0A   I113 @S9S_MB_2U_LIB.S9S_MB_2U(SCH_1):PAGE169
    U4  F37 DMI_7_SATA_16_PCIE3_16_TXN EMMITSBURG_REV0P9-GFNOCPU04302A   I110 @S9S_MB_2U_LIB.S9S_MB_2U(SCH_1):PAGE173

DMI_CPU0_PCH_RX_DP<0> @S9S_MB_2U_LIB.S9S_MB_2U(SCH_1):DMI_CPU0_PCH_RX_DP(0)
  C170    2      2 Q_CAP_DIFFBUS_C0201-DIFF BUS_0A   I128 @S9S_MB_2U_LIB.S9S_MB_2U(SCH_1):PAGE169
    U4  H28 DMI_0_TXP EMMITSBURG_REV0P9-GFNOCPU04302A   I110 @S9S_MB_2U_LIB.S9S_MB_2U(SCH_1):PAGE173

DMI_CPU0_PCH_RX_DP<1> @S9S_MB_2U_LIB.S9S_MB_2U(SCH_1):DMI_CPU0_PCH_RX_DP(1)
  C168    2      2 Q_CAP_DIFFBUS_C0201-DIFF BUS_0A   I125 @S9S_MB_2U_LIB.S9S_MB_2U(SCH_1):PAGE169
    U4  F28 DMI_1_TXP EMMITSBURG_REV0P9-GFNOCPU04302A   I110 @S9S_MB_2U_LIB.S9S_MB_2U(SCH_1):PAGE173

DMI_CPU0_PCH_RX_DP<2> @S9S_MB_2U_LIB.S9S_MB_2U(SCH_1):DMI_CPU0_PCH_RX_DP(2)
  C166    2      2 Q_CAP_DIFFBUS_C0201-DIFF BUS_0A   I124 @S9S_MB_2U_LIB.S9S_MB_2U(SCH_1):PAGE169
    U4  H31 DMI_2_TXP EMMITSBURG_REV0P9-GFNOCPU04302A   I110 @S9S_MB_2U_LIB.S9S_MB_2U(SCH_1):PAGE173

DMI_CPU0_PCH_RX_DP<3> @S9S_MB_2U_LIB.S9S_MB_2U(SCH_1):DMI_CPU0_PCH_RX_DP(3)
  C164    2      2 Q_CAP_DIFFBUS_C0201-DIFF BUS_0A   I122 @S9S_MB_2U_LIB.S9S_MB_2U(SCH_1):PAGE169
    U4  K31 DMI_3_TXP EMMITSBURG_REV0P9-GFNOCPU04302A   I110 @S9S_MB_2U_LIB.S9S_MB_2U(SCH_1):PAGE173

DMI_CPU0_PCH_RX_DP<4> @S9S_MB_2U_LIB.S9S_MB_2U(SCH_1):DMI_CPU0_PCH_RX_DP(4)
  C162    2      2 Q_CAP_DIFFBUS_C0201-DIFF BUS_0A   I120 @S9S_MB_2U_LIB.S9S_MB_2U(SCH_1):PAGE169
    U4  G32 DMI_4_SATA_19_PCIE3_19_TXP EMMITSBURG_REV0P9-GFNOCPU04302A   I110 @S9S_MB_2U_LIB.S9S_MB_2U(SCH_1):PAGE173

DMI_CPU0_PCH_RX_DP<5> @S9S_MB_2U_LIB.S9S_MB_2U(SCH_1):DMI_CPU0_PCH_RX_DP(5)
  C160    2      2 Q_CAP_DIFFBUS_C0201-DIFF BUS_0A   I118 @S9S_MB_2U_LIB.S9S_MB_2U(SCH_1):PAGE169
    U4  H34 DMI_5_SATA_18_PCIE3_18_TXP EMMITSBURG_REV0P9-GFNOCPU04302A   I110 @S9S_MB_2U_LIB.S9S_MB_2U(SCH_1):PAGE173

DMI_CPU0_PCH_RX_DP<6> @S9S_MB_2U_LIB.S9S_MB_2U(SCH_1):DMI_CPU0_PCH_RX_DP(6)
  C158    2      2 Q_CAP_DIFFBUS_C0201-DIFF BUS_0A   I116 @S9S_MB_2U_LIB.S9S_MB_2U(SCH_1):PAGE169
    U4  J36 DMI_6_SATA_17_PCIE3_17_TXP EMMITSBURG_REV0P9-GFNOCPU04302A   I110 @S9S_MB_2U_LIB.S9S_MB_2U(SCH_1):PAGE173

DMI_CPU0_PCH_RX_DP<7> @S9S_MB_2U_LIB.S9S_MB_2U(SCH_1):DMI_CPU0_PCH_RX_DP(7)
  C156    2      2 Q_CAP_DIFFBUS_C0201-DIFF BUS_0A   I114 @S9S_MB_2U_LIB.S9S_MB_2U(SCH_1):PAGE169
    U4  H37 DMI_7_SATA_16_PCIE3_16_TXP EMMITSBURG_REV0P9-GFNOCPU04302A   I110 @S9S_MB_2U_LIB.S9S_MB_2U(SCH_1):PAGE173

DMI_CPU0_PCH_TX_C_DN<0> @S9S_MB_2U_LIB.S9S_MB_2U(SCH_1):DMI_CPU0_PCH_TX_C_DN(0)
  C153    1      1 Q_CAP_DIFFBUS_C0201-DIFF BUS_0A    I21 @S9S_MB_2U_LIB.S9S_MB_2U(SCH_1):PAGE169
    U4  A30 DMI_0_RXN EMMITSBURG_REV0P9-GFNOCPU04302A   I110 @S9S_MB_2U_LIB.S9S_MB_2U(SCH_1):PAGE173

DMI_CPU0_PCH_TX_C_DN<1> @S9S_MB_2U_LIB.S9S_MB_2U(SCH_1):DMI_CPU0_PCH_TX_C_DN(1)
  C151    1      1 Q_CAP_DIFFBUS_C0201-DIFF BUS_0A    I24 @S9S_MB_2U_LIB.S9S_MB_2U(SCH_1):PAGE169
    U4  B31 DMI_1_RXN EMMITSBURG_REV0P9-GFNOCPU04302A   I110 @S9S_MB_2U_LIB.S9S_MB_2U(SCH_1):PAGE173

DMI_CPU0_PCH_TX_C_DN<2> @S9S_MB_2U_LIB.S9S_MB_2U(SCH_1):DMI_CPU0_PCH_TX_C_DN(2)
  C149    1      1 Q_CAP_DIFFBUS_C0201-DIFF BUS_0A    I25 @S9S_MB_2U_LIB.S9S_MB_2U(SCH_1):PAGE169
    U4  A32 DMI_2_RXN EMMITSBURG_REV0P9-GFNOCPU04302A   I110 @S9S_MB_2U_LIB.S9S_MB_2U(SCH_1):PAGE173

DMI_CPU0_PCH_TX_C_DN<3> @S9S_MB_2U_LIB.S9S_MB_2U(SCH_1):DMI_CPU0_PCH_TX_C_DN(3)
  C147    1      1 Q_CAP_DIFFBUS_C0201-DIFF BUS_0A    I28 @S9S_MB_2U_LIB.S9S_MB_2U(SCH_1):PAGE169
    U4  B33 DMI_3_RXN EMMITSBURG_REV0P9-GFNOCPU04302A   I110 @S9S_MB_2U_LIB.S9S_MB_2U(SCH_1):PAGE173

DMI_CPU0_PCH_TX_C_DN<4> @S9S_MB_2U_LIB.S9S_MB_2U(SCH_1):DMI_CPU0_PCH_TX_C_DN(4)
  C145    1      1 Q_CAP_DIFFBUS_C0201-DIFF BUS_0A    I30 @S9S_MB_2U_LIB.S9S_MB_2U(SCH_1):PAGE169
    U4  A34 DMI_4_SATA_19_PCIE3_19_RXN EMMITSBURG_REV0P9-GFNOCPU04302A   I110 @S9S_MB_2U_LIB.S9S_MB_2U(SCH_1):PAGE173

DMI_CPU0_PCH_TX_C_DN<5> @S9S_MB_2U_LIB.S9S_MB_2U(SCH_1):DMI_CPU0_PCH_TX_C_DN(5)
  C143    1      1 Q_CAP_DIFFBUS_C0201-DIFF BUS_0A    I32 @S9S_MB_2U_LIB.S9S_MB_2U(SCH_1):PAGE169
    U4  B35 DMI_5_SATA_18_PCIE3_18_RXN EMMITSBURG_REV0P9-GFNOCPU04302A   I110 @S9S_MB_2U_LIB.S9S_MB_2U(SCH_1):PAGE173

DMI_CPU0_PCH_TX_C_DN<6> @S9S_MB_2U_LIB.S9S_MB_2U(SCH_1):DMI_CPU0_PCH_TX_C_DN(6)
  C141    1      1 Q_CAP_DIFFBUS_C0201-DIFF BUS_0A    I34 @S9S_MB_2U_LIB.S9S_MB_2U(SCH_1):PAGE169
    U4  A36 DMI_6_SATA_17_PCIE3_17_RXN EMMITSBURG_REV0P9-GFNOCPU04302A   I110 @S9S_MB_2U_LIB.S9S_MB_2U(SCH_1):PAGE173

DMI_CPU0_PCH_TX_C_DN<7> @S9S_MB_2U_LIB.S9S_MB_2U(SCH_1):DMI_CPU0_PCH_TX_C_DN(7)
  C139    1      1 Q_CAP_DIFFBUS_C0201-DIFF BUS_0A    I35 @S9S_MB_2U_LIB.S9S_MB_2U(SCH_1):PAGE169
    U4  B37 DMI_7_SATA_16_PCIE3_16_RXN EMMITSBURG_REV0P9-GFNOCPU04302A   I110 @S9S_MB_2U_LIB.S9S_MB_2U(SCH_1):PAGE173

DMI_CPU0_PCH_TX_C_DP<0> @S9S_MB_2U_LIB.S9S_MB_2U(SCH_1):DMI_CPU0_PCH_TX_C_DP(0)
  C154    1      1 Q_CAP_DIFFBUS_C0201-DIFF BUS_0A    I22 @S9S_MB_2U_LIB.S9S_MB_2U(SCH_1):PAGE169
    U4  C30 DMI_0_RXP EMMITSBURG_REV0P9-GFNOCPU04302A   I110 @S9S_MB_2U_LIB.S9S_MB_2U(SCH_1):PAGE173

DMI_CPU0_PCH_TX_C_DP<1> @S9S_MB_2U_LIB.S9S_MB_2U(SCH_1):DMI_CPU0_PCH_TX_C_DP(1)
  C152    1      1 Q_CAP_DIFFBUS_C0201-DIFF BUS_0A    I23 @S9S_MB_2U_LIB.S9S_MB_2U(SCH_1):PAGE169
    U4  D31 DMI_1_RXP EMMITSBURG_REV0P9-GFNOCPU04302A   I110 @S9S_MB_2U_LIB.S9S_MB_2U(SCH_1):PAGE173

DMI_CPU0_PCH_TX_C_DP<2> @S9S_MB_2U_LIB.S9S_MB_2U(SCH_1):DMI_CPU0_PCH_TX_C_DP(2)
  C150    1      1 Q_CAP_DIFFBUS_C0201-DIFF BUS_0A    I26 @S9S_MB_2U_LIB.S9S_MB_2U(SCH_1):PAGE169
    U4  C32 DMI_2_RXP EMMITSBURG_REV0P9-GFNOCPU04302A   I110 @S9S_MB_2U_LIB.S9S_MB_2U(SCH_1):PAGE173

DMI_CPU0_PCH_TX_C_DP<3> @S9S_MB_2U_LIB.S9S_MB_2U(SCH_1):DMI_CPU0_PCH_TX_C_DP(3)
  C148    1      1 Q_CAP_DIFFBUS_C0201-DIFF BUS_0A    I27 @S9S_MB_2U_LIB.S9S_MB_2U(SCH_1):PAGE169
    U4  D33 DMI_3_RXP EMMITSBURG_REV0P9-GFNOCPU04302A   I110 @S9S_MB_2U_LIB.S9S_MB_2U(SCH_1):PAGE173

DMI_CPU0_PCH_TX_C_DP<4> @S9S_MB_2U_LIB.S9S_MB_2U(SCH_1):DMI_CPU0_PCH_TX_C_DP(4)
  C146    1      1 Q_CAP_DIFFBUS_C0201-DIFF BUS_0A    I29 @S9S_MB_2U_LIB.S9S_MB_2U(SCH_1):PAGE169
    U4  C34 DMI_4_SATA_19_PCIE3_19_RXP EMMITSBURG_REV0P9-GFNOCPU04302A   I110 @S9S_MB_2U_LIB.S9S_MB_2U(SCH_1):PAGE173

DMI_CPU0_PCH_TX_C_DP<5> @S9S_MB_2U_LIB.S9S_MB_2U(SCH_1):DMI_CPU0_PCH_TX_C_DP(5)
  C144    1      1 Q_CAP_DIFFBUS_C0201-DIFF BUS_0A    I31 @S9S_MB_2U_LIB.S9S_MB_2U(SCH_1):PAGE169
    U4  D35 DMI_5_SATA_18_PCIE3_18_RXP EMMITSBURG_REV0P9-GFNOCPU04302A   I110 @S9S_MB_2U_LIB.S9S_MB_2U(SCH_1):PAGE173

DMI_CPU0_PCH_TX_C_DP<6> @S9S_MB_2U_LIB.S9S_MB_2U(SCH_1):DMI_CPU0_PCH_TX_C_DP(6)
  C142    1      1 Q_CAP_DIFFBUS_C0201-DIFF BUS_0A    I33 @S9S_MB_2U_LIB.S9S_MB_2U(SCH_1):PAGE169
    U4  C36 DMI_6_SATA_17_PCIE3_17_RXP EMMITSBURG_REV0P9-GFNOCPU04302A   I110 @S9S_MB_2U_LIB.S9S_MB_2U(SCH_1):PAGE173

DMI_CPU0_PCH_TX_C_DP<7> @S9S_MB_2U_LIB.S9S_MB_2U(SCH_1):DMI_CPU0_PCH_TX_C_DP(7)
 C1791    1      1 Q_CAP_DIFFBUS_C0201-DIFF BUS_0A    I36 @S9S_MB_2U_LIB.S9S_MB_2U(SCH_1):PAGE169
    U4  D37 DMI_7_SATA_16_PCIE3_16_RXP EMMITSBURG_REV0P9-GFNOCPU04302A   I110 @S9S_MB_2U_LIB.S9S_MB_2U(SCH_1):PAGE173

DMI_CPU0_PCH_TX_DN<0> @S9S_MB_2U_LIB.S9S_MB_2U(SCH_1):DMI_CPU0_PCH_TX_DN(0)
    U2 CA19 DMI_TX_DP0 SOCKET4677_AZIF0045P001C01CS-SA   I169 @S9S_MB_2U_LIB.S9S_MB_2U(SCH_1):PAGE28
  C153    2      2 Q_CAP_DIFFBUS_C0201-DIFF BUS_0A    I21 @S9S_MB_2U_LIB.S9S_MB_2U(SCH_1):PAGE169

DMI_CPU0_PCH_TX_DN<1> @S9S_MB_2U_LIB.S9S_MB_2U(SCH_1):DMI_CPU0_PCH_TX_DN(1)
    U2 BY18 DMI_TX_DP1 SOCKET4677_AZIF0045P001C01CS-SA   I169 @S9S_MB_2U_LIB.S9S_MB_2U(SCH_1):PAGE28
  C151    2      2 Q_CAP_DIFFBUS_C0201-DIFF BUS_0A    I24 @S9S_MB_2U_LIB.S9S_MB_2U(SCH_1):PAGE169

DMI_CPU0_PCH_TX_DN<2> @S9S_MB_2U_LIB.S9S_MB_2U(SCH_1):DMI_CPU0_PCH_TX_DN(2)
    U2 CC19 DMI_TX_DP2 SOCKET4677_AZIF0045P001C01CS-SA   I169 @S9S_MB_2U_LIB.S9S_MB_2U(SCH_1):PAGE28
  C149    2      2 Q_CAP_DIFFBUS_C0201-DIFF BUS_0A    I25 @S9S_MB_2U_LIB.S9S_MB_2U(SCH_1):PAGE169

DMI_CPU0_PCH_TX_DN<3> @S9S_MB_2U_LIB.S9S_MB_2U(SCH_1):DMI_CPU0_PCH_TX_DN(3)
    U2 CD18 DMI_TX_DP3 SOCKET4677_AZIF0045P001C01CS-SA   I169 @S9S_MB_2U_LIB.S9S_MB_2U(SCH_1):PAGE28
  C147    2      2 Q_CAP_DIFFBUS_C0201-DIFF BUS_0A    I28 @S9S_MB_2U_LIB.S9S_MB_2U(SCH_1):PAGE169

DMI_CPU0_PCH_TX_DN<4> @S9S_MB_2U_LIB.S9S_MB_2U(SCH_1):DMI_CPU0_PCH_TX_DN(4)
    U2 CF18 DMI_TX_DN4 SOCKET4677_AZIF0045P001C01CS-SA   I169 @S9S_MB_2U_LIB.S9S_MB_2U(SCH_1):PAGE28
  C145    2      2 Q_CAP_DIFFBUS_C0201-DIFF BUS_0A    I30 @S9S_MB_2U_LIB.S9S_MB_2U(SCH_1):PAGE169

DMI_CPU0_PCH_TX_DN<5> @S9S_MB_2U_LIB.S9S_MB_2U(SCH_1):DMI_CPU0_PCH_TX_DN(5)
    U2 CJ17 DMI_TX_DN5 SOCKET4677_AZIF0045P001C01CS-SA   I169 @S9S_MB_2U_LIB.S9S_MB_2U(SCH_1):PAGE28
  C143    2      2 Q_CAP_DIFFBUS_C0201-DIFF BUS_0A    I32 @S9S_MB_2U_LIB.S9S_MB_2U(SCH_1):PAGE169

DMI_CPU0_PCH_TX_DN<6> @S9S_MB_2U_LIB.S9S_MB_2U(SCH_1):DMI_CPU0_PCH_TX_DN(6)
    U2 CK18 DMI_TX_DN6 SOCKET4677_AZIF0045P001C01CS-SA   I169 @S9S_MB_2U_LIB.S9S_MB_2U(SCH_1):PAGE28
  C141    2      2 Q_CAP_DIFFBUS_C0201-DIFF BUS_0A    I34 @S9S_MB_2U_LIB.S9S_MB_2U(SCH_1):PAGE169

DMI_CPU0_PCH_TX_DN<7> @S9S_MB_2U_LIB.S9S_MB_2U(SCH_1):DMI_CPU0_PCH_TX_DN(7)
    U2 CM18 DMI_TX_DP7 SOCKET4677_AZIF0045P001C01CS-SA   I169 @S9S_MB_2U_LIB.S9S_MB_2U(SCH_1):PAGE28
  C139    2      2 Q_CAP_DIFFBUS_C0201-DIFF BUS_0A    I35 @S9S_MB_2U_LIB.S9S_MB_2U(SCH_1):PAGE169

DMI_CPU0_PCH_TX_DP<0> @S9S_MB_2U_LIB.S9S_MB_2U(SCH_1):DMI_CPU0_PCH_TX_DP(0)
    U2 BW19 DMI_TX_DN0 SOCKET4677_AZIF0045P001C01CS-SA   I169 @S9S_MB_2U_LIB.S9S_MB_2U(SCH_1):PAGE28
  C154    2      2 Q_CAP_DIFFBUS_C0201-DIFF BUS_0A    I22 @S9S_MB_2U_LIB.S9S_MB_2U(SCH_1):PAGE169

DMI_CPU0_PCH_TX_DP<1> @S9S_MB_2U_LIB.S9S_MB_2U(SCH_1):DMI_CPU0_PCH_TX_DP(1)
    U2 CA17 DMI_TX_DN1 SOCKET4677_AZIF0045P001C01CS-SA   I169 @S9S_MB_2U_LIB.S9S_MB_2U(SCH_1):PAGE28
  C152    2      2 Q_CAP_DIFFBUS_C0201-DIFF BUS_0A    I23 @S9S_MB_2U_LIB.S9S_MB_2U(SCH_1):PAGE169

DMI_CPU0_PCH_TX_DP<2> @S9S_MB_2U_LIB.S9S_MB_2U(SCH_1):DMI_CPU0_PCH_TX_DP(2)
    U2 CB18 DMI_TX_DN2 SOCKET4677_AZIF0045P001C01CS-SA   I169 @S9S_MB_2U_LIB.S9S_MB_2U(SCH_1):PAGE28
  C150    2      2 Q_CAP_DIFFBUS_C0201-DIFF BUS_0A    I26 @S9S_MB_2U_LIB.S9S_MB_2U(SCH_1):PAGE169

DMI_CPU0_PCH_TX_DP<3> @S9S_MB_2U_LIB.S9S_MB_2U(SCH_1):DMI_CPU0_PCH_TX_DP(3)
    U2 CE17 DMI_TX_DN3 SOCKET4677_AZIF0045P001C01CS-SA   I169 @S9S_MB_2U_LIB.S9S_MB_2U(SCH_1):PAGE28
  C148    2      2 Q_CAP_DIFFBUS_C0201-DIFF BUS_0A    I27 @S9S_MB_2U_LIB.S9S_MB_2U(SCH_1):PAGE169

DMI_CPU0_PCH_TX_DP<4> @S9S_MB_2U_LIB.S9S_MB_2U(SCH_1):DMI_CPU0_PCH_TX_DP(4)
    U2 CG19 DMI_TX_DP4 SOCKET4677_AZIF0045P001C01CS-SA   I169 @S9S_MB_2U_LIB.S9S_MB_2U(SCH_1):PAGE28
  C146    2      2 Q_CAP_DIFFBUS_C0201-DIFF BUS_0A    I29 @S9S_MB_2U_LIB.S9S_MB_2U(SCH_1):PAGE169

DMI_CPU0_PCH_TX_DP<5> @S9S_MB_2U_LIB.S9S_MB_2U(SCH_1):DMI_CPU0_PCH_TX_DP(5)
    U2 CH18 DMI_TX_DP5 SOCKET4677_AZIF0045P001C01CS-SA   I169 @S9S_MB_2U_LIB.S9S_MB_2U(SCH_1):PAGE28
  C144    2      2 Q_CAP_DIFFBUS_C0201-DIFF BUS_0A    I31 @S9S_MB_2U_LIB.S9S_MB_2U(SCH_1):PAGE169

DMI_CPU0_PCH_TX_DP<6> @S9S_MB_2U_LIB.S9S_MB_2U(SCH_1):DMI_CPU0_PCH_TX_DP(6)
    U2 CL19 DMI_TX_DP6 SOCKET4677_AZIF0045P001C01CS-SA   I169 @S9S_MB_2U_LIB.S9S_MB_2U(SCH_1):PAGE28
  C142    2      2 Q_CAP_DIFFBUS_C0201-DIFF BUS_0A    I33 @S9S_MB_2U_LIB.S9S_MB_2U(SCH_1):PAGE169

DMI_CPU0_PCH_TX_DP<7> @S9S_MB_2U_LIB.S9S_MB_2U(SCH_1):DMI_CPU0_PCH_TX_DP(7)
    U2 CN17 DMI_TX_DN7 SOCKET4677_AZIF0045P001C01CS-SA   I169 @S9S_MB_2U_LIB.S9S_MB_2U(SCH_1):PAGE28
 C1791    2      2 Q_CAP_DIFFBUS_C0201-DIFF BUS_0A    I36 @S9S_MB_2U_LIB.S9S_MB_2U(SCH_1):PAGE169

DSW_PWROK_P2V5_COMP @S9S_MB_2U_LIB.S9S_MB_2U(SCH_1):DSW_PWROK_P2V5_COMP
  U342    1    IN- AP331AWG7-AP331AWG-7,SMLF,EMPTA    I45 @S9S_MB_2U_LIB.S9S_MB_2U(SCH_1):PAGE329
 C2385    1      A Q_CAP_C0402-100NF,50V,10%,EMPTA    I57 @S9S_MB_2U_LIB.S9S_MB_2U(SCH_1):PAGE329
  U341    1     1+ LM4040AIM3X25NOPB-LM4040AIM3X-A    I63 @S9S_MB_2U_LIB.S9S_MB_2U(SCH_1):PAGE329
 R4786    2      B Q_RES_0402LF-10K,1%,1/16W,EMPTA    I65 @S9S_MB_2U_LIB.S9S_MB_2U(SCH_1):PAGE329

E1S_0_CLKREQ_N @S9S_MB_2U_LIB.S9S_MB_2U(SCH_1):E1S_0_CLKREQ_N
    U4 BG18 GPPC_A_11_SRCCLKREQ_N_1 EMMITSBURG_REV0P9-GFNOCPU04302A    I93 @S9S_MB_2U_LIB.S9S_MB_2U(SCH_1):PAGE175
 R4084    2      B Q_RES_0402LF-0,5%,1/16W,EMPTY,A   I275 @S9S_MB_2U_LIB.S9S_MB_2U(SCH_1):PAGE175
 R4083    2      B Q_RES_0402LF-0,5%,1/16W,EMPTY,A   I274 @S9S_MB_2U_LIB.S9S_MB_2U(SCH_1):PAGE175
 R4766    2      B Q_RES_0402LF-49.9,1%,1/16W,CHIA   I314 @S9S_MB_2U_LIB.S9S_MB_2U(SCH_1):PAGE175

E1S_0_CLK_OE_N @S9S_MB_2U_LIB.S9S_MB_2U(SCH_1):E1S_0_CLK_OE_N
  U249   L6  PL14C LCMXO3LF9400C5BG484C-LCMXO3LF-A    I33 @S9S_MB_2U_LIB.S9S_MB_2U(SCH_1):PAGE311
 R4766    1      A Q_RES_0402LF-49.9,1%,1/16W,CHIA   I314 @S9S_MB_2U_LIB.S9S_MB_2U(SCH_1):PAGE175
 R4768    1      A Q_RES_0402LF-10K,1%,1/16W,CHIPA   I315 @S9S_MB_2U_LIB.S9S_MB_2U(SCH_1):PAGE175

E1S_0_EN @S9S_MB_2U_LIB.S9S_MB_2U(SCH_1):E1S_0_EN
  U145    4      Y 74LVC1G126SE7-74LVC1G126SE-7,SA   I163 @S9S_MB_2U_LIB.S9S_MB_2U(SCH_1):PAGE297
 R2457    1      A Q_RES_0402LF-100K,1%,1/16W,CHIA   I165 @S9S_MB_2U_LIB.S9S_MB_2U(SCH_1):PAGE297
 R4064    1      A Q_RES_0402LF-0,5%,1/16W,CHIP,CA    I21 @S9S_MB_2U_LIB.S9S_MB_2U(SCH_1):PAGE324
 R3943    1      A Q_RES_0402LF-0,5%,1/16W,CHIP,CA    I45 @S9S_MB_2U_LIB.S9S_MB_2U(SCH_1):PAGE323
 R4063    1      A Q_RES_0402LF-0,5%,1/16W,CHIP,CA     I1 @S9S_MB_2U_LIB.S9S_MB_2U(SCH_1):PAGE324
 R3946    1      A Q_RES_0402LF-0,5%,1/16W,EMPTY,A     I5 @S9S_MB_2U_LIB.S9S_MB_2U(SCH_1):PAGE323

E1S_0_LED_ACT_N @S9S_MB_2U_LIB.S9S_MB_2U(SCH_1):E1S_0_LED_ACT_N
   J90  A10 LED#_ACTIVITY SCONN56_123276793-SCONN56_1-23A   I318 @S9S_MB_2U_LIB.S9S_MB_2U(SCH_1):PAGE297
 R4606    2      B Q_RES_0402LF-0,5%,1/16W,CHIP,CA   I180 @S9S_MB_2U_LIB.S9S_MB_2U(SCH_1):PAGE313

E1S_0_LED_ACT_R_N @S9S_MB_2U_LIB.S9S_MB_2U(SCH_1):E1S_0_LED_ACT_R_N
  U249  U18  PR28D LCMXO3LF9400C5BG484C-LCMXO3LF-A     I1 @S9S_MB_2U_LIB.S9S_MB_2U(SCH_1):PAGE313
 R4606    1      A Q_RES_0402LF-0,5%,1/16W,CHIP,CA   I180 @S9S_MB_2U_LIB.S9S_MB_2U(SCH_1):PAGE313

E1S_0_P3V3_ADC_ALERT @S9S_MB_2U_LIB.S9S_MB_2U(SCH_1):E1S_0_P3V3_ADC_ALERT
  U249  J20  PR12C LCMXO3LF9400C5BG484C-LCMXO3LF-A     I1 @S9S_MB_2U_LIB.S9S_MB_2U(SCH_1):PAGE313
 R3752    2      B Q_RES_0402LF-0,5%,1/16W,CHIP,CA   I122 @S9S_MB_2U_LIB.S9S_MB_2U(SCH_1):PAGE295

E1S_0_P3V3_ADC_ALERT_R @S9S_MB_2U_LIB.S9S_MB_2U(SCH_1):E1S_0_P3V3_ADC_ALERT_R
 R3752    1      A Q_RES_0402LF-0,5%,1/16W,CHIP,CA   I122 @S9S_MB_2U_LIB.S9S_MB_2U(SCH_1):PAGE295
  U276    3  ALERT INA230AIRGTR-INA230AIRGTR,SMLFB   I129 @S9S_MB_2U_LIB.S9S_MB_2U(SCH_1):PAGE295
 R4093    2      B Q_RES_0402LF-4.7K,1%,1/16W,CHIA   I149 @S9S_MB_2U_LIB.S9S_MB_2U(SCH_1):PAGE295

E1S_0_PERST1_CLKREQ_N @S9S_MB_2U_LIB.S9S_MB_2U(SCH_1):E1S_0_PERST1_CLKREQ_N
 R2426    1      A Q_RES_0402LF-100,1%,1/16W,EMPTA   I311 @S9S_MB_2U_LIB.S9S_MB_2U(SCH_1):PAGE297
 R2287    2      B Q_RES_0402LF-10K,1%,1/16W,CHIPA   I313 @S9S_MB_2U_LIB.S9S_MB_2U(SCH_1):PAGE297
 R4083    1      A Q_RES_0402LF-0,5%,1/16W,EMPTY,A   I274 @S9S_MB_2U_LIB.S9S_MB_2U(SCH_1):PAGE175
   J90  A11 PERST1#_CLKREQ# SCONN56_123276793-SCONN56_1-23A   I318 @S9S_MB_2U_LIB.S9S_MB_2U(SCH_1):PAGE297

E1S_0_PRSNT @S9S_MB_2U_LIB.S9S_MB_2U(SCH_1):E1S_0_PRSNT
  U145    2      A 74LVC1G126SE7-74LVC1G126SE-7,SA   I163 @S9S_MB_2U_LIB.S9S_MB_2U(SCH_1):PAGE297
 R2282    2      B Q_RES_0402LF-10K,1%,1/16W,CHIPA   I169 @S9S_MB_2U_LIB.S9S_MB_2U(SCH_1):PAGE297
   Q46    D      D MOSFET_NCH_GDS_ESD_PROTECTED-2A   I316 @S9S_MB_2U_LIB.S9S_MB_2U(SCH_1):PAGE297

E1S_0_PRSNT_N @S9S_MB_2U_LIB.S9S_MB_2U(SCH_1):E1S_0_PRSNT_N
  U249  V10  PB21A LCMXO3LF9400C5BG484C-LCMXO3LF-A     I1 @S9S_MB_2U_LIB.S9S_MB_2U(SCH_1):PAGE312
 R2304    2      B Q_RES_0402LF-10K,1%,1/16W,CHIPA   I159 @S9S_MB_2U_LIB.S9S_MB_2U(SCH_1):PAGE297
   Q46    G      G MOSFET_NCH_GDS_ESD_PROTECTED-2A   I316 @S9S_MB_2U_LIB.S9S_MB_2U(SCH_1):PAGE297
 R4084    1      A Q_RES_0402LF-0,5%,1/16W,EMPTY,A   I275 @S9S_MB_2U_LIB.S9S_MB_2U(SCH_1):PAGE175
   J90  A12 PRSNT0# SCONN56_123276793-SCONN56_1-23A   I318 @S9S_MB_2U_LIB.S9S_MB_2U(SCH_1):PAGE297

E1S_0_PWRDIS @S9S_MB_2U_LIB.S9S_MB_2U(SCH_1):E1S_0_PWRDIS
 R3771    2      B Q_RES_0402LF-10K,1%,1/16W,CHIPA   I291 @S9S_MB_2U_LIB.S9S_MB_2U(SCH_1):PAGE297
 R2296    1      A Q_RES_0402LF-1K,1%,1/16W,CHIP,A   I293 @S9S_MB_2U_LIB.S9S_MB_2U(SCH_1):PAGE297
   J90  B12 PWRDIS SCONN56_123276793-SCONN56_1-23A   I318 @S9S_MB_2U_LIB.S9S_MB_2U(SCH_1):PAGE297

ESPI_ALERT1_N_LPC_RCIN_N @S9S_MB_2U_LIB.S9S_MB_2U(SCH_1):ESPI_ALERT1_N_LPC_RCIN_N
    U4 BD15 GPPC_A_1_ESPI_ALERT1_N EMMITSBURG_REV0P9-GFNOCPU04302A    I93 @S9S_MB_2U_LIB.S9S_MB_2U(SCH_1):PAGE175
 R1255    2      B Q_RES_0402LF-1K,1%,1/16W,CHIP,A    I26 @S9S_MB_2U_LIB.S9S_MB_2U(SCH_1):PAGE192

ESPI_BMC_LPC_RST_N @S9S_MB_2U_LIB.S9S_MB_2U(SCH_1):ESPI_BMC_LPC_RST_N
   U61    4      A NC7SB3157_SMLF-NC7SB3157P6X,NCA    I39 @S9S_MB_2U_LIB.S9S_MB_2U(SCH_1):PAGE190
   J41   B4 +12V_EDGE_B4 SCONN168_ME1016810202011-SCONNA   I173 @S9S_MB_2U_LIB.S9S_MB_2U(SCH_1):PAGE227

ESPI_HOST_LPC_BMC_CLK @S9S_MB_2U_LIB.S9S_MB_2U(SCH_1):ESPI_HOST_LPC_BMC_CLK
 R1872    2      B Q_RES_0402LF-10,1%,1/16W,CHIP,A   I100 @S9S_MB_2U_LIB.S9S_MB_2U(SCH_1):PAGE190
   J41   B1 +12V_EDGE_B1 SCONN168_ME1016810202011-SCONNA   I173 @S9S_MB_2U_LIB.S9S_MB_2U(SCH_1):PAGE227

ESPI_HOST_LPC_BMC_LFRAME_N @S9S_MB_2U_LIB.S9S_MB_2U(SCH_1):ESPI_HOST_LPC_BMC_LFRAME_N
 R1479    2      B Q_RES_0402LF-10,1%,1/16W,CHIP,A   I102 @S9S_MB_2U_LIB.S9S_MB_2U(SCH_1):PAGE190
   J41   B2 +12V_EDGE_B2 SCONN168_ME1016810202011-SCONNA   I173 @S9S_MB_2U_LIB.S9S_MB_2U(SCH_1):PAGE227

ESPI_LAD0_DATA_IO0 @S9S_MB_2U_LIB.S9S_MB_2U(SCH_1):ESPI_LAD0_DATA_IO0
    U4 BG12 GPPC_A_2_ESPI_IO_0 EMMITSBURG_REV0P9-GFNOCPU04302A    I93 @S9S_MB_2U_LIB.S9S_MB_2U(SCH_1):PAGE175
 R1871    1      A Q_RES_0402LF-10,1%,1/16W,CHIP,A    I99 @S9S_MB_2U_LIB.S9S_MB_2U(SCH_1):PAGE190

ESPI_LAD0_DATA_IO1 @S9S_MB_2U_LIB.S9S_MB_2U(SCH_1):ESPI_LAD0_DATA_IO1
    U4 BF19 GPPC_A_3_ESPI_IO_1 EMMITSBURG_REV0P9-GFNOCPU04302A    I93 @S9S_MB_2U_LIB.S9S_MB_2U(SCH_1):PAGE175
 R1870    1      A Q_RES_0402LF-10,1%,1/16W,CHIP,A    I98 @S9S_MB_2U_LIB.S9S_MB_2U(SCH_1):PAGE190

ESPI_LAD0_DATA_IO2 @S9S_MB_2U_LIB.S9S_MB_2U(SCH_1):ESPI_LAD0_DATA_IO2
    U4 BE18 GPPC_A_4_ESPI_IO_2 EMMITSBURG_REV0P9-GFNOCPU04302A    I93 @S9S_MB_2U_LIB.S9S_MB_2U(SCH_1):PAGE175
 R1869    1      A Q_RES_0402LF-10,1%,1/16W,CHIP,A    I97 @S9S_MB_2U_LIB.S9S_MB_2U(SCH_1):PAGE190

ESPI_LAD0_DATA_IO3 @S9S_MB_2U_LIB.S9S_MB_2U(SCH_1):ESPI_LAD0_DATA_IO3
    U4 BD19 GPPC_A_5_ESPI_IO_3 EMMITSBURG_REV0P9-GFNOCPU04302A    I93 @S9S_MB_2U_LIB.S9S_MB_2U(SCH_1):PAGE175
 R1868    1      A Q_RES_0402LF-10,1%,1/16W,CHIP,A    I96 @S9S_MB_2U_LIB.S9S_MB_2U(SCH_1):PAGE190

ESPI_LFRAME_N_BMC_CS0_N @S9S_MB_2U_LIB.S9S_MB_2U(SCH_1):ESPI_LFRAME_N_BMC_CS0_N
    U4 BE20 GPPC_A_6_ESPI_CS0_N EMMITSBURG_REV0P9-GFNOCPU04302A    I93 @S9S_MB_2U_LIB.S9S_MB_2U(SCH_1):PAGE175
 R1961    2      B Q_RES_0402LF-10K,1%,1/16W,CHIPA    I70 @S9S_MB_2U_LIB.S9S_MB_2U(SCH_1):PAGE190
 R1479    1      A Q_RES_0402LF-10,1%,1/16W,CHIP,A   I102 @S9S_MB_2U_LIB.S9S_MB_2U(SCH_1):PAGE190

ESPI_LPC_LAD0_IO0 @S9S_MB_2U_LIB.S9S_MB_2U(SCH_1):ESPI_LPC_LAD0_IO0
 R1871    2      B Q_RES_0402LF-10,1%,1/16W,CHIP,A    I99 @S9S_MB_2U_LIB.S9S_MB_2U(SCH_1):PAGE190
   J41   B5 +12V_EDGE_B5 SCONN168_ME1016810202011-SCONNA   I173 @S9S_MB_2U_LIB.S9S_MB_2U(SCH_1):PAGE227

ESPI_LPC_LAD0_IO1 @S9S_MB_2U_LIB.S9S_MB_2U(SCH_1):ESPI_LPC_LAD0_IO1
 R1870    2      B Q_RES_0402LF-10,1%,1/16W,CHIP,A    I98 @S9S_MB_2U_LIB.S9S_MB_2U(SCH_1):PAGE190
   J41   B6 +12V_EDGE_B6 SCONN168_ME1016810202011-SCONNA   I173 @S9S_MB_2U_LIB.S9S_MB_2U(SCH_1):PAGE227

ESPI_LPC_LAD0_IO2 @S9S_MB_2U_LIB.S9S_MB_2U(SCH_1):ESPI_LPC_LAD0_IO2
 R1869    2      B Q_RES_0402LF-10,1%,1/16W,CHIP,A    I97 @S9S_MB_2U_LIB.S9S_MB_2U(SCH_1):PAGE190
   J41   B7  BIF0# SCONN168_ME1016810202011-SCONNA   I173 @S9S_MB_2U_LIB.S9S_MB_2U(SCH_1):PAGE227

ESPI_LPC_LAD0_IO3 @S9S_MB_2U_LIB.S9S_MB_2U(SCH_1):ESPI_LPC_LAD0_IO3
 R1868    2      B Q_RES_0402LF-10,1%,1/16W,CHIP,A    I96 @S9S_MB_2U_LIB.S9S_MB_2U(SCH_1):PAGE190
   J41   B8  BIF1# SCONN168_ME1016810202011-SCONNA   I173 @S9S_MB_2U_LIB.S9S_MB_2U(SCH_1):PAGE227

FAB_BMC_REV_ID0 @S9S_MB_2U_LIB.S9S_MB_2U(SCH_1):FAB_BMC_REV_ID0
  U249   K6  PL12D LCMXO3LF9400C5BG484C-LCMXO3LF-A    I33 @S9S_MB_2U_LIB.S9S_MB_2U(SCH_1):PAGE311
 R4596    1      A Q_RES_0402LF-1K,1%,1/16W,EMPTYA    I61 @S9S_MB_2U_LIB.S9S_MB_2U(SCH_1):PAGE184
 R4579    2      B Q_RES_0402LF-10K,1%,1/16W,CHIPA    I67 @S9S_MB_2U_LIB.S9S_MB_2U(SCH_1):PAGE184

FAB_BMC_REV_ID1 @S9S_MB_2U_LIB.S9S_MB_2U(SCH_1):FAB_BMC_REV_ID1
  U249   K7  PL12C LCMXO3LF9400C5BG484C-LCMXO3LF-A    I33 @S9S_MB_2U_LIB.S9S_MB_2U(SCH_1):PAGE311
 R4590    1      A Q_RES_0402LF-1K,1%,1/16W,EMPTYA    I59 @S9S_MB_2U_LIB.S9S_MB_2U(SCH_1):PAGE184
 R4589    2      B Q_RES_0402LF-10K,1%,1/16W,CHIPA    I63 @S9S_MB_2U_LIB.S9S_MB_2U(SCH_1):PAGE184

FAB_BMC_REV_ID2 @S9S_MB_2U_LIB.S9S_MB_2U(SCH_1):FAB_BMC_REV_ID2
  U249   J1  PL12B LCMXO3LF9400C5BG484C-LCMXO3LF-A    I33 @S9S_MB_2U_LIB.S9S_MB_2U(SCH_1):PAGE311
 R4588    1      A Q_RES_0402LF-1K,1%,1/16W,EMPTYA    I58 @S9S_MB_2U_LIB.S9S_MB_2U(SCH_1):PAGE184
 R4586    2      B Q_RES_0402LF-10K,1%,1/16W,CHIPA    I62 @S9S_MB_2U_LIB.S9S_MB_2U(SCH_1):PAGE184

FAB_REV_ID0 @S9S_MB_2U_LIB.S9S_MB_2U(SCH_1):FAB_REV_ID0
    U4   N7 GPP_M_0 EMMITSBURG_REV0P9-GFNOCPU04302A    I22 @S9S_MB_2U_LIB.S9S_MB_2U(SCH_1):PAGE176
 R2978    1      A Q_RES_0402LF-1K,1%,1/16W,EMPTYA    I74 @S9S_MB_2U_LIB.S9S_MB_2U(SCH_1):PAGE184
 R2232    2      B Q_RES_0402LF-10K,1%,1/16W,CHIPA    I75 @S9S_MB_2U_LIB.S9S_MB_2U(SCH_1):PAGE184

FAB_REV_ID1 @S9S_MB_2U_LIB.S9S_MB_2U(SCH_1):FAB_REV_ID1
    U4 AA13 GPP_M_1 EMMITSBURG_REV0P9-GFNOCPU04302A    I22 @S9S_MB_2U_LIB.S9S_MB_2U(SCH_1):PAGE176
 R2975    1      A Q_RES_0402LF-1K,1%,1/16W,EMPTYA    I70 @S9S_MB_2U_LIB.S9S_MB_2U(SCH_1):PAGE184
 R2974    2      B Q_RES_0402LF-10K,1%,1/16W,CHIPA    I72 @S9S_MB_2U_LIB.S9S_MB_2U(SCH_1):PAGE184

FAB_REV_ID2 @S9S_MB_2U_LIB.S9S_MB_2U(SCH_1):FAB_REV_ID2
    U4  AA7 GPP_M_2 EMMITSBURG_REV0P9-GFNOCPU04302A    I22 @S9S_MB_2U_LIB.S9S_MB_2U(SCH_1):PAGE176
 R2973    1      A Q_RES_0402LF-1K,1%,1/16W,EMPTYA    I69 @S9S_MB_2U_LIB.S9S_MB_2U(SCH_1):PAGE184
 R2972    2      B Q_RES_0402LF-10K,1%,1/16W,CHIPA    I71 @S9S_MB_2U_LIB.S9S_MB_2U(SCH_1):PAGE184

FB_BMC_ISOLATE @S9S_MB_2U_LIB.S9S_MB_2U(SCH_1):FB_BMC_ISOLATE
  U320    4      E 74LVC1G66GV-74LVC1G66GV,SMLF,IA    I92 @S9S_MB_2U_LIB.S9S_MB_2U(SCH_1):PAGE152
 R2474    2      B Q_RES_0402LF-0,5%,1/16W,EMPTY,A    I19 @S9S_MB_2U_LIB.S9S_MB_2U(SCH_1):PAGE151
 R1289    1      A Q_RES_0402LF-100K,1%,1/16W,CHIA    I21 @S9S_MB_2U_LIB.S9S_MB_2U(SCH_1):PAGE151
   U68    1    1OE 74CBTLV3126PW-74CBTLV3126PW,SMA    I30 @S9S_MB_2U_LIB.S9S_MB_2U(SCH_1):PAGE151
   U68    4    2OE 74CBTLV3126PW-74CBTLV3126PW,SMA    I30 @S9S_MB_2U_LIB.S9S_MB_2U(SCH_1):PAGE151
   U68   10    3OE 74CBTLV3126PW-74CBTLV3126PW,SMA    I30 @S9S_MB_2U_LIB.S9S_MB_2U(SCH_1):PAGE151
   U68   13    4OE 74CBTLV3126PW-74CBTLV3126PW,SMA    I30 @S9S_MB_2U_LIB.S9S_MB_2U(SCH_1):PAGE151
   U67    1    1OE 74CBTLV3126PW-74CBTLV3126PW,SMA    I39 @S9S_MB_2U_LIB.S9S_MB_2U(SCH_1):PAGE151
   U67    4    2OE 74CBTLV3126PW-74CBTLV3126PW,SMA    I39 @S9S_MB_2U_LIB.S9S_MB_2U(SCH_1):PAGE151
   U67   10    3OE 74CBTLV3126PW-74CBTLV3126PW,SMA    I39 @S9S_MB_2U_LIB.S9S_MB_2U(SCH_1):PAGE151
   U67   13    4OE 74CBTLV3126PW-74CBTLV3126PW,SMA    I39 @S9S_MB_2U_LIB.S9S_MB_2U(SCH_1):PAGE151
 R2473    2      B Q_RES_0402LF-49.9,1%,1/16W,CHIA    I83 @S9S_MB_2U_LIB.S9S_MB_2U(SCH_1):PAGE151

FB_BMC_ISOLATE1 @S9S_MB_2U_LIB.S9S_MB_2U(SCH_1):FB_BMC_ISOLATE1
 R3206    2      B Q_RES_0402LF-0,5%,1/16W,EMPTY,A    I12 @S9S_MB_2U_LIB.S9S_MB_2U(SCH_1):PAGE307
 R3207    1      A Q_RES_0402LF-100K,1%,1/16W,CHIA    I15 @S9S_MB_2U_LIB.S9S_MB_2U(SCH_1):PAGE307
  U222    1    1OE 74CBTLV3126PW-74CBTLV3126PW,SMA    I32 @S9S_MB_2U_LIB.S9S_MB_2U(SCH_1):PAGE307
  U222    4    2OE 74CBTLV3126PW-74CBTLV3126PW,SMA    I32 @S9S_MB_2U_LIB.S9S_MB_2U(SCH_1):PAGE307
  U222   10    3OE 74CBTLV3126PW-74CBTLV3126PW,SMA    I32 @S9S_MB_2U_LIB.S9S_MB_2U(SCH_1):PAGE307
  U222   13    4OE 74CBTLV3126PW-74CBTLV3126PW,SMA    I32 @S9S_MB_2U_LIB.S9S_MB_2U(SCH_1):PAGE307
  U223    1    1OE 74CBTLV3126PW-74CBTLV3126PW,SMA    I78 @S9S_MB_2U_LIB.S9S_MB_2U(SCH_1):PAGE307
  U223    4    2OE 74CBTLV3126PW-74CBTLV3126PW,SMA    I78 @S9S_MB_2U_LIB.S9S_MB_2U(SCH_1):PAGE307
  U223   10    3OE 74CBTLV3126PW-74CBTLV3126PW,SMA    I78 @S9S_MB_2U_LIB.S9S_MB_2U(SCH_1):PAGE307
  U223   13    4OE 74CBTLV3126PW-74CBTLV3126PW,SMA    I78 @S9S_MB_2U_LIB.S9S_MB_2U(SCH_1):PAGE307
  U321    4      E 74LVC1G66GV-74LVC1G66GV,SMLF,IA    I92 @S9S_MB_2U_LIB.S9S_MB_2U(SCH_1):PAGE156
 R3205    2      B Q_RES_0402LF-49.9,1%,1/16W,CHIA    I85 @S9S_MB_2U_LIB.S9S_MB_2U(SCH_1):PAGE307

FB_BMC_ISOLATE_R1 @S9S_MB_2U_LIB.S9S_MB_2U(SCH_1):FB_BMC_ISOLATE_R1
   U66    4      Y 74LVC1G126SE7-74LVC1G126SE-7,SA    I15 @S9S_MB_2U_LIB.S9S_MB_2U(SCH_1):PAGE151
 R2473    1      A Q_RES_0402LF-49.9,1%,1/16W,CHIA    I83 @S9S_MB_2U_LIB.S9S_MB_2U(SCH_1):PAGE151

FB_BMC_ISOLATE_R2 @S9S_MB_2U_LIB.S9S_MB_2U(SCH_1):FB_BMC_ISOLATE_R2
  U286    4      Y 74LVC1G126SE7-74LVC1G126SE-7,SA    I80 @S9S_MB_2U_LIB.S9S_MB_2U(SCH_1):PAGE307
 R3205    1      A Q_RES_0402LF-49.9,1%,1/16W,CHIA    I85 @S9S_MB_2U_LIB.S9S_MB_2U(SCH_1):PAGE307

FG_SS_EN @S9S_MB_2U_LIB.S9S_MB_2U(SCH_1):FG_SS_EN
 R4078    2      B Q_RES_0402LF-10K,1%,1/16W,EMPTA   I127 @S9S_MB_2U_LIB.S9S_MB_2U(SCH_1):PAGE201
 R4079    1      A Q_RES_0402LF-10K,1%,1/16W,CHIPA   I128 @S9S_MB_2U_LIB.S9S_MB_2U(SCH_1):PAGE201
  U247   23 ^VSS_EN_TRI 9FGL0251DKILFT-9FGL0251DKILFT,A   I167 @S9S_MB_2U_LIB.S9S_MB_2U(SCH_1):PAGE201

FM_9ZXL045_0_OE_N @S9S_MB_2U_LIB.S9S_MB_2U(SCH_1):FM_9ZXL045_0_OE_N
  U314   15  VOE0# 9ZXL0451EKILFT-9ZXL0451EKILFT,A     I1 @S9S_MB_2U_LIB.S9S_MB_2U(SCH_1):PAGE200
 R4477    1      A Q_RES_0402LF-33.2,1%,1/16W,CHIA    I74 @S9S_MB_2U_LIB.S9S_MB_2U(SCH_1):PAGE200

FM_9ZXL045_1_OE_N @S9S_MB_2U_LIB.S9S_MB_2U(SCH_1):FM_9ZXL045_1_OE_N
  U314   18  VOE1# 9ZXL0451EKILFT-9ZXL0451EKILFT,A     I1 @S9S_MB_2U_LIB.S9S_MB_2U(SCH_1):PAGE200
 R4478    1      A Q_RES_0402LF-33.2,1%,1/16W,CHIA    I75 @S9S_MB_2U_LIB.S9S_MB_2U(SCH_1):PAGE200

FM_9ZXL045_2_OE_N @S9S_MB_2U_LIB.S9S_MB_2U(SCH_1):FM_9ZXL045_2_OE_N
  U314   24  VOE2# 9ZXL0451EKILFT-9ZXL0451EKILFT,A     I1 @S9S_MB_2U_LIB.S9S_MB_2U(SCH_1):PAGE200
 R4479    1      A Q_RES_0402LF-33.2,1%,1/16W,CHIA    I76 @S9S_MB_2U_LIB.S9S_MB_2U(SCH_1):PAGE200

FM_9ZXL045_3_OE_N @S9S_MB_2U_LIB.S9S_MB_2U(SCH_1):FM_9ZXL045_3_OE_N
  U314   26  VOE3# 9ZXL0451EKILFT-9ZXL0451EKILFT,A     I1 @S9S_MB_2U_LIB.S9S_MB_2U(SCH_1):PAGE200
 R4494    1      A Q_RES_0402LF-10K,1%,1/16W,CHIPA    I69 @S9S_MB_2U_LIB.S9S_MB_2U(SCH_1):PAGE200

FM_9ZXL045_DEV_EN @S9S_MB_2U_LIB.S9S_MB_2U(SCH_1):FM_9ZXL045_DEV_EN
  U314    1 ^CKPWRGD_PD# 9ZXL0451EKILFT-9ZXL0451EKILFT,A     I1 @S9S_MB_2U_LIB.S9S_MB_2U(SCH_1):PAGE200
 R4476    2      B Q_RES_0402LF-49.9,1%,1/16W,CHIA    I39 @S9S_MB_2U_LIB.S9S_MB_2U(SCH_1):PAGE200

FM_AC_PWR_BTN_N @S9S_MB_2U_LIB.S9S_MB_2U(SCH_1):FM_AC_PWR_BTN_N
 R4720    1      A Q_RES_0402LF-0,5%,1/16W,CHIP,CA    I57 @S9S_MB_2U_LIB.S9S_MB_2U(SCH_1):PAGE227
   J41  B42 PRSNTB0# SCONN168_ME1016810202011-SCONNA   I173 @S9S_MB_2U_LIB.S9S_MB_2U(SCH_1):PAGE227

FM_AC_PWR_BTN_PDB_N @S9S_MB_2U_LIB.S9S_MB_2U(SCH_1):FM_AC_PWR_BTN_PDB_N
   J45   A2     A2 CONN60_101062636003K02LF-CONN6A    I12 @S9S_MB_2U_LIB.S9S_MB_2U(SCH_1):PAGE233
 R4721    2      B Q_RES_0402LF-0,5%,1/16W,CHIP,CA    I35 @S9S_MB_2U_LIB.S9S_MB_2U(SCH_1):PAGE233
 C2371    1      A Q_CAP_0402-0.1UF,25V,10%,EMPTYA    I51 @S9S_MB_2U_LIB.S9S_MB_2U(SCH_1):PAGE233

FM_AC_PWR_BTN_PLD_ISO_N @S9S_MB_2U_LIB.S9S_MB_2U(SCH_1):FM_AC_PWR_BTN_PLD_ISO_N
  U249  T16  PB46D LCMXO3LF9400C5BG484C-LCMXO3LF-A     I1 @S9S_MB_2U_LIB.S9S_MB_2U(SCH_1):PAGE312
 R4719    2      B Q_RES_0402LF-10K,1%,1/16W,CHIPA    I32 @S9S_MB_2U_LIB.S9S_MB_2U(SCH_1):PAGE213
 R4718    2      B Q_RES_0402LF-33.2,1%,1/16W,EMPA    I33 @S9S_MB_2U_LIB.S9S_MB_2U(SCH_1):PAGE213

FM_AC_PWR_BTN_PLD_ISO_R_N @S9S_MB_2U_LIB.S9S_MB_2U(SCH_1):FM_AC_PWR_BTN_PLD_ISO_R_N
 R4718    1      A Q_RES_0402LF-33.2,1%,1/16W,EMPA    I33 @S9S_MB_2U_LIB.S9S_MB_2U(SCH_1):PAGE213
  U332    6     1Y 74LVC2G07DW7-74LVC2G07DW-7,SMLB    I37 @S9S_MB_2U_LIB.S9S_MB_2U(SCH_1):PAGE213

FM_AC_PWR_BTN_PLD_N @S9S_MB_2U_LIB.S9S_MB_2U(SCH_1):FM_AC_PWR_BTN_PLD_N
  U332    1     1A 74LVC2G07DW7-74LVC2G07DW-7,SMLB    I37 @S9S_MB_2U_LIB.S9S_MB_2U(SCH_1):PAGE213
 R4717    2      B Q_RES_0402LF-0,5%,1/16W,EMPTY,A    I41 @S9S_MB_2U_LIB.S9S_MB_2U(SCH_1):PAGE213

FM_AC_PWR_BTN_R_N @S9S_MB_2U_LIB.S9S_MB_2U(SCH_1):FM_AC_PWR_BTN_R_N
 R4716    2      B Q_RES_0402LF-8.45K,1%,1/16W,EMA    I40 @S9S_MB_2U_LIB.S9S_MB_2U(SCH_1):PAGE213
 R4717    1      A Q_RES_0402LF-0,5%,1/16W,EMPTY,A    I41 @S9S_MB_2U_LIB.S9S_MB_2U(SCH_1):PAGE213
 C2369    1      A Q_CAP_C0402-1UF,25V,10%,EMPTY,A    I42 @S9S_MB_2U_LIB.S9S_MB_2U(SCH_1):PAGE213
 R4721    1      A Q_RES_0402LF-0,5%,1/16W,CHIP,CA    I35 @S9S_MB_2U_LIB.S9S_MB_2U(SCH_1):PAGE233
 R4720    2      B Q_RES_0402LF-0,5%,1/16W,CHIP,CA    I57 @S9S_MB_2U_LIB.S9S_MB_2U(SCH_1):PAGE227

FM_ADR_ACK @S9S_MB_2U_LIB.S9S_MB_2U(SCH_1):FM_ADR_ACK
    U4  AD4 GPP_D_16_ADR_ACK EMMITSBURG_REV0P9-GFNOCPU04302A    I93 @S9S_MB_2U_LIB.S9S_MB_2U(SCH_1):PAGE175
  R369    2      B Q_RES_0402LF-1K,1%,1/16W,CHIP,A    I16 @S9S_MB_2U_LIB.S9S_MB_2U(SCH_1):PAGE186
  R700    2      B Q_RES_0402LF-0,5%,1/16W,CHIP,CA   I169 @S9S_MB_2U_LIB.S9S_MB_2U(SCH_1):PAGE312

FM_ADR_ACK_R @S9S_MB_2U_LIB.S9S_MB_2U(SCH_1):FM_ADR_ACK_R
  U249  AA2   PB5A LCMXO3LF9400C5BG484C-LCMXO3LF-A     I1 @S9S_MB_2U_LIB.S9S_MB_2U(SCH_1):PAGE312
  R700    1      A Q_RES_0402LF-0,5%,1/16W,CHIP,CA   I169 @S9S_MB_2U_LIB.S9S_MB_2U(SCH_1):PAGE312

FM_ADR_COMPLETE @S9S_MB_2U_LIB.S9S_MB_2U(SCH_1):FM_ADR_COMPLETE
    U4  AC1 GPP_D_13_ADR_COMPLETE EMMITSBURG_REV0P9-GFNOCPU04302A    I93 @S9S_MB_2U_LIB.S9S_MB_2U(SCH_1):PAGE175
 R1341    1      A Q_RES_0402LF-10K,1%,1/16W,CHIPA   I106 @S9S_MB_2U_LIB.S9S_MB_2U(SCH_1):PAGE189
  U249   U6   PB5D LCMXO3LF9400C5BG484C-LCMXO3LF-A     I1 @S9S_MB_2U_LIB.S9S_MB_2U(SCH_1):PAGE312
  J104    6      6 CONN14_210HP207GBR1-CONN14_210A   I134 @S9S_MB_2U_LIB.S9S_MB_2U(SCH_1):PAGE189

FM_ADR_MODE0 @S9S_MB_2U_LIB.S9S_MB_2U(SCH_1):FM_ADR_MODE0
  R773    2      B Q_RES_0402LF-1K,1%,1/16W,CHIP,A   I124 @S9S_MB_2U_LIB.S9S_MB_2U(SCH_1):PAGE133
    U4 AV11 GPPC_S_3_CPU_GP_1 EMMITSBURG_REV0P9-GFNOCPU04302A    I27 @S9S_MB_2U_LIB.S9S_MB_2U(SCH_1):PAGE177
 R1810    1      A Q_RES_0402LF-1K,1%,1/16W,EMPTYA    I88 @S9S_MB_2U_LIB.S9S_MB_2U(SCH_1):PAGE186
 R1809    2      B Q_RES_0402LF-20K,1%,1/16W,CHIPA    I89 @S9S_MB_2U_LIB.S9S_MB_2U(SCH_1):PAGE186
 R1455    2      B Q_RES_0402LF-49.9,1%,1/16W,CHIA    I27 @S9S_MB_2U_LIB.S9S_MB_2U(SCH_1):PAGE193

FM_ADR_MODE0_R @S9S_MB_2U_LIB.S9S_MB_2U(SCH_1):FM_ADR_MODE0_R
 R1455    1      A Q_RES_0402LF-49.9,1%,1/16W,CHIA    I27 @S9S_MB_2U_LIB.S9S_MB_2U(SCH_1):PAGE193
  U249  AA3 PB7A||CSSPIN LCMXO3LF9400C5BG484C-LCMXO3LF-A     I1 @S9S_MB_2U_LIB.S9S_MB_2U(SCH_1):PAGE312

FM_ADR_MODE1 @S9S_MB_2U_LIB.S9S_MB_2U(SCH_1):FM_ADR_MODE1
    U4  AL5 GPPC_C_18 EMMITSBURG_REV0P9-GFNOCPU04302A    I93 @S9S_MB_2U_LIB.S9S_MB_2U(SCH_1):PAGE175
  R379    1      A Q_RES_0402LF-1K,1%,1/16W,CHIP,A    I76 @S9S_MB_2U_LIB.S9S_MB_2U(SCH_1):PAGE186
  R378    2      B Q_RES_0402LF-1K,1%,1/16W,EMPTYA    I77 @S9S_MB_2U_LIB.S9S_MB_2U(SCH_1):PAGE186
  R269    1      A Q_RES_0402LF-33.2,1%,1/16W,CHIA    I91 @S9S_MB_2U_LIB.S9S_MB_2U(SCH_1):PAGE212

FM_ADR_MODE1_R @S9S_MB_2U_LIB.S9S_MB_2U(SCH_1):FM_ADR_MODE1_R
  R269    2      B Q_RES_0402LF-33.2,1%,1/16W,CHIA    I91 @S9S_MB_2U_LIB.S9S_MB_2U(SCH_1):PAGE212
  U249  AB3   PB7B LCMXO3LF9400C5BG484C-LCMXO3LF-A     I1 @S9S_MB_2U_LIB.S9S_MB_2U(SCH_1):PAGE312

FM_ADR_TRIGGER_N @S9S_MB_2U_LIB.S9S_MB_2U(SCH_1):FM_ADR_TRIGGER_N
  R698    2      B Q_RES_0402LF-49.9,1%,1/16W,CHIA    I32 @S9S_MB_2U_LIB.S9S_MB_2U(SCH_1):PAGE193
  U249   V6   PB5C LCMXO3LF9400C5BG484C-LCMXO3LF-A     I1 @S9S_MB_2U_LIB.S9S_MB_2U(SCH_1):PAGE312
 R1435    1      A Q_RES_0402LF-10K,1%,1/16W,CHIPA    I43 @S9S_MB_2U_LIB.S9S_MB_2U(SCH_1):PAGE209

FM_ADR_TRIGGER_R_N @S9S_MB_2U_LIB.S9S_MB_2U(SCH_1):FM_ADR_TRIGGER_R_N
    U4  AH4 GPP_D_14_ADR_TRIGGER_N EMMITSBURG_REV0P9-GFNOCPU04302A    I93 @S9S_MB_2U_LIB.S9S_MB_2U(SCH_1):PAGE175
  R698    1      A Q_RES_0402LF-49.9,1%,1/16W,CHIA    I32 @S9S_MB_2U_LIB.S9S_MB_2U(SCH_1):PAGE193

FM_AUX_SW_EN @S9S_MB_2U_LIB.S9S_MB_2U(SCH_1):FM_AUX_SW_EN
  R991    1      A Q_RES_0402LF-2K,1%,1/16W,CHIP,A    I20 @S9S_MB_2U_LIB.S9S_MB_2U(SCH_1):PAGE208
  U249  F18   PR5C LCMXO3LF9400C5BG484C-LCMXO3LF-A     I1 @S9S_MB_2U_LIB.S9S_MB_2U(SCH_1):PAGE313

FM_BIOS_ADV_FUNCTIONS @S9S_MB_2U_LIB.S9S_MB_2U(SCH_1):FM_BIOS_ADV_FUNCTIONS
    U4 AF11 GPP_L_3 EMMITSBURG_REV0P9-GFNOCPU04302A    I22 @S9S_MB_2U_LIB.S9S_MB_2U(SCH_1):PAGE176
 R1498    2      B Q_RES_0402LF-1K,1%,1/16W,EMPTYA    I76 @S9S_MB_2U_LIB.S9S_MB_2U(SCH_1):PAGE188
 R1499    1      A Q_RES_0402LF-1K,1%,1/16W,CHIP,A    I77 @S9S_MB_2U_LIB.S9S_MB_2U(SCH_1):PAGE188

FM_BIOS_DEBUG_EN_N @S9S_MB_2U_LIB.S9S_MB_2U(SCH_1):FM_BIOS_DEBUG_EN_N
 R2971    1      A Q_RES_0402LF-0,5%,1/16W,CHIP,CA   I253 @S9S_MB_2U_LIB.S9S_MB_2U(SCH_1):PAGE175
  U249  W14  PB33D LCMXO3LF9400C5BG484C-LCMXO3LF-A     I1 @S9S_MB_2U_LIB.S9S_MB_2U(SCH_1):PAGE312

FM_BIOS_DEBUG_EN_R_N @S9S_MB_2U_LIB.S9S_MB_2U(SCH_1):FM_BIOS_DEBUG_EN_R_N
    U4  AA3 GPP_D_22_USB2_OCB_7 EMMITSBURG_REV0P9-GFNOCPU04302A    I93 @S9S_MB_2U_LIB.S9S_MB_2U(SCH_1):PAGE175
 R2971    2      B Q_RES_0402LF-0,5%,1/16W,CHIP,CA   I253 @S9S_MB_2U_LIB.S9S_MB_2U(SCH_1):PAGE175

FM_BIOS_IMAGE_SWAP_N @S9S_MB_2U_LIB.S9S_MB_2U(SCH_1):FM_BIOS_IMAGE_SWAP_N
    U4   Y4 GPP_D_19_MSMI_N EMMITSBURG_REV0P9-GFNOCPU04302A    I93 @S9S_MB_2U_LIB.S9S_MB_2U(SCH_1):PAGE175
 R1339    2      B Q_RES_0402LF-10K,1%,1/16W,CHIPA   I100 @S9S_MB_2U_LIB.S9S_MB_2U(SCH_1):PAGE189
  J104    8      8 CONN14_210HP207GBR1-CONN14_210A   I134 @S9S_MB_2U_LIB.S9S_MB_2U(SCH_1):PAGE189

FM_BIOS_POST_CMPLT_BMC_N @S9S_MB_2U_LIB.S9S_MB_2U(SCH_1):FM_BIOS_POST_CMPLT_BMC_N
 R1300    2      B Q_RES_0402LF-33.2,1%,1/16W,CHIA     I5 @S9S_MB_2U_LIB.S9S_MB_2U(SCH_1):PAGE193
  U249   T9 PB16A||MCLK||CCLK LCMXO3LF9400C5BG484C-LCMXO3LF-A     I1 @S9S_MB_2U_LIB.S9S_MB_2U(SCH_1):PAGE312

FM_BIOS_POST_CMPLT_HDR_N @S9S_MB_2U_LIB.S9S_MB_2U(SCH_1):FM_BIOS_POST_CMPLT_HDR_N
 R3065    2      B Q_RES_0402LF-33.2,1%,1/16W,CHIA    I40 @S9S_MB_2U_LIB.S9S_MB_2U(SCH_1):PAGE193
  J100   19     19 SCONN20_513860200CV01-SCONN20_A    I32 @S9S_MB_2U_LIB.S9S_MB_2U(SCH_1):PAGE215

FM_BIOS_POST_CMPLT_N @S9S_MB_2U_LIB.S9S_MB_2U(SCH_1):FM_BIOS_POST_CMPLT_N
    U4  AL3 GPPC_C_17_ME_SML4ALERT_N EMMITSBURG_REV0P9-GFNOCPU04302A    I93 @S9S_MB_2U_LIB.S9S_MB_2U(SCH_1):PAGE175
 R1449    2      B Q_RES_0402LF-10K,1%,1/16W,CHIPA    I41 @S9S_MB_2U_LIB.S9S_MB_2U(SCH_1):PAGE192
 R1300    1      A Q_RES_0402LF-33.2,1%,1/16W,CHIA     I5 @S9S_MB_2U_LIB.S9S_MB_2U(SCH_1):PAGE193
 R3065    1      A Q_RES_0402LF-33.2,1%,1/16W,CHIA    I40 @S9S_MB_2U_LIB.S9S_MB_2U(SCH_1):PAGE193

FM_BMC_CPU_FBRK_OUT_N @S9S_MB_2U_LIB.S9S_MB_2U(SCH_1):FM_BMC_CPU_FBRK_OUT_N
 R1381    2      B Q_RES_0402LF-1K,1%,1/16W,CHIP,A     I7 @S9S_MB_2U_LIB.S9S_MB_2U(SCH_1):PAGE226
   U84   12     A1 GTL2014PW-GTL2014PW,SMLF,IC,ALA    I18 @S9S_MB_2U_LIB.S9S_MB_2U(SCH_1):PAGE226
 R4611    2      B Q_RES_0402LF-33.2,1%,1/16W,CHIA   I206 @S9S_MB_2U_LIB.S9S_MB_2U(SCH_1):PAGE313

FM_BMC_CPU_FBRK_OUT_R_N @S9S_MB_2U_LIB.S9S_MB_2U(SCH_1):FM_BMC_CPU_FBRK_OUT_R_N
  U249  V18  PR30A LCMXO3LF9400C5BG484C-LCMXO3LF-A     I1 @S9S_MB_2U_LIB.S9S_MB_2U(SCH_1):PAGE313
 R4611    1      A Q_RES_0402LF-33.2,1%,1/16W,CHIA   I206 @S9S_MB_2U_LIB.S9S_MB_2U(SCH_1):PAGE313

FM_BMC_DBP_PRESENT_R_N @S9S_MB_2U_LIB.S9S_MB_2U(SCH_1):FM_BMC_DBP_PRESENT_R_N
 R1472    2      B Q_RES_0402LF-33.2,1%,1/16W,CHIA   I144 @S9S_MB_2U_LIB.S9S_MB_2U(SCH_1):PAGE133
  U249   U8  PB13D LCMXO3LF9400C5BG484C-LCMXO3LF-A     I1 @S9S_MB_2U_LIB.S9S_MB_2U(SCH_1):PAGE312

FM_BMC_EN_DET @S9S_MB_2U_LIB.S9S_MB_2U(SCH_1):FM_BMC_EN_DET
   U86    2     1A 74CBTLV3126PW-74CBTLV3126PW,SMA    I84 @S9S_MB_2U_LIB.S9S_MB_2U(SCH_1):PAGE137
   U86    5     2A 74CBTLV3126PW-74CBTLV3126PW,SMA    I84 @S9S_MB_2U_LIB.S9S_MB_2U(SCH_1):PAGE137
   U86    9     3A 74CBTLV3126PW-74CBTLV3126PW,SMA    I84 @S9S_MB_2U_LIB.S9S_MB_2U(SCH_1):PAGE137
   U86   12     4A 74CBTLV3126PW-74CBTLV3126PW,SMA    I84 @S9S_MB_2U_LIB.S9S_MB_2U(SCH_1):PAGE137
 C1293    1      A Q_CAP_C0402-1UF,25V,10%,X6S,CHA    I95 @S9S_MB_2U_LIB.S9S_MB_2U(SCH_1):PAGE137
   U87    S SOURCE MOSFET_N_SMLF-BSS138K,BSS138K,A    I96 @S9S_MB_2U_LIB.S9S_MB_2U(SCH_1):PAGE137
 R1375    1      A Q_RES_0402LF-10K,1%,1/16W,CHIPA    I97 @S9S_MB_2U_LIB.S9S_MB_2U(SCH_1):PAGE137

FM_BMC_INTRUDER_N @S9S_MB_2U_LIB.S9S_MB_2U(SCH_1):FM_BMC_INTRUDER_N
 R4809    1      A Q_RES_0402LF-0,5%,1/16W,CHIP,CA     I2 @S9S_MB_2U_LIB.S9S_MB_2U(SCH_1):PAGE227
   J41  A54 PERP11 SCONN168_ME1016810202011-SCONNA   I173 @S9S_MB_2U_LIB.S9S_MB_2U(SCH_1):PAGE227

FM_BMC_PWRBTN_N @S9S_MB_2U_LIB.S9S_MB_2U(SCH_1):FM_BMC_PWRBTN_N
    U4 AR10 PWRBTN_N EMMITSBURG_REV0P9-GFNOCPU04302A    I36 @S9S_MB_2U_LIB.S9S_MB_2U(SCH_1):PAGE174
 R1744    2      B Q_RES_0402LF-0,5%,1/16W,CHIP,CA    I94 @S9S_MB_2U_LIB.S9S_MB_2U(SCH_1):PAGE212
  R139    1      A Q_RES_0402LF-10K,1%,1/16W,EMPTA    I40 @S9S_MB_2U_LIB.S9S_MB_2U(SCH_1):PAGE209

FM_BMC_PWRBTN_OUT_N @S9S_MB_2U_LIB.S9S_MB_2U(SCH_1):FM_BMC_PWRBTN_OUT_N
 R1744    1      A Q_RES_0402LF-0,5%,1/16W,CHIP,CA    I94 @S9S_MB_2U_LIB.S9S_MB_2U(SCH_1):PAGE212
 R1815    1      A Q_RES_0402LF-0,5%,1/16W,CHIP,CA    I26 @S9S_MB_2U_LIB.S9S_MB_2U(SCH_1):PAGE227

FM_BMC_PWRBTN_OUT_R_N @S9S_MB_2U_LIB.S9S_MB_2U(SCH_1):FM_BMC_PWRBTN_OUT_R_N
 R1815    2      B Q_RES_0402LF-0,5%,1/16W,CHIP,CA    I26 @S9S_MB_2U_LIB.S9S_MB_2U(SCH_1):PAGE227
   J41  A47  PERN9 SCONN168_ME1016810202011-SCONNA   I173 @S9S_MB_2U_LIB.S9S_MB_2U(SCH_1):PAGE227

FM_BMC_READY_R_N @S9S_MB_2U_LIB.S9S_MB_2U(SCH_1):FM_BMC_READY_R_N
    U4 BF15 GPPC_A_13_SRCCLKREQ_N_3 EMMITSBURG_REV0P9-GFNOCPU04302A    I93 @S9S_MB_2U_LIB.S9S_MB_2U(SCH_1):PAGE175
 R2155    2      B Q_RES_0402LF-0,5%,1/16W,CHIP,CA   I177 @S9S_MB_2U_LIB.S9S_MB_2U(SCH_1):PAGE312

FM_BMC_READY_R_PLD_N @S9S_MB_2U_LIB.S9S_MB_2U(SCH_1):FM_BMC_READY_R_PLD_N
  U249 AA17  PB40B LCMXO3LF9400C5BG484C-LCMXO3LF-A     I1 @S9S_MB_2U_LIB.S9S_MB_2U(SCH_1):PAGE312
 R2155    1      A Q_RES_0402LF-0,5%,1/16W,CHIP,CA   I177 @S9S_MB_2U_LIB.S9S_MB_2U(SCH_1):PAGE312

FM_BMC_RSTBTN_OUT_N @S9S_MB_2U_LIB.S9S_MB_2U(SCH_1):FM_BMC_RSTBTN_OUT_N
  R697    1      A Q_RES_0402LF-33.2,1%,1/16W,CHIA    I66 @S9S_MB_2U_LIB.S9S_MB_2U(SCH_1):PAGE174
  U249   U9 PB16B||SO||SPISO LCMXO3LF9400C5BG484C-LCMXO3LF-A     I1 @S9S_MB_2U_LIB.S9S_MB_2U(SCH_1):PAGE312

FM_BMC_SUSACK_R_N @S9S_MB_2U_LIB.S9S_MB_2U(SCH_1):FM_BMC_SUSACK_R_N
 R2071    1      A Q_RES_0402LF-0,5%,1/16W,EMPTY,A   I137 @S9S_MB_2U_LIB.S9S_MB_2U(SCH_1):PAGE314
  U249   C5  PT12D LCMXO3LF9400C5BG484C-LCMXO3LF-A   I188 @S9S_MB_2U_LIB.S9S_MB_2U(SCH_1):PAGE314

FM_BOARD_BMC_SKU_ID0 @S9S_MB_2U_LIB.S9S_MB_2U(SCH_1):FM_BOARD_BMC_SKU_ID0
  U249   J2  PL12A LCMXO3LF9400C5BG484C-LCMXO3LF-A    I33 @S9S_MB_2U_LIB.S9S_MB_2U(SCH_1):PAGE311
 R4585    1      A Q_RES_0402LF-1K,1%,1/16W,CHIP,A    I20 @S9S_MB_2U_LIB.S9S_MB_2U(SCH_1):PAGE184
 R4584    2      B Q_RES_0402LF-10K,1%,1/16W,EMPTA    I24 @S9S_MB_2U_LIB.S9S_MB_2U(SCH_1):PAGE184

FM_BOARD_BMC_SKU_ID1 @S9S_MB_2U_LIB.S9S_MB_2U(SCH_1):FM_BOARD_BMC_SKU_ID1
  U249   J3  PL11D LCMXO3LF9400C5BG484C-LCMXO3LF-A    I33 @S9S_MB_2U_LIB.S9S_MB_2U(SCH_1):PAGE311
 R4583    1      A Q_RES_0402LF-1K,1%,1/16W,CHIP,A    I18 @S9S_MB_2U_LIB.S9S_MB_2U(SCH_1):PAGE184
 R4582    2      B Q_RES_0402LF-10K,1%,1/16W,EMPTA    I23 @S9S_MB_2U_LIB.S9S_MB_2U(SCH_1):PAGE184

FM_BOARD_BMC_SKU_ID2 @S9S_MB_2U_LIB.S9S_MB_2U(SCH_1):FM_BOARD_BMC_SKU_ID2
  U249   J4  PL11C LCMXO3LF9400C5BG484C-LCMXO3LF-A    I33 @S9S_MB_2U_LIB.S9S_MB_2U(SCH_1):PAGE311
 R4597    2      B Q_RES_0402LF-10K,1%,1/16W,EMPTA    I22 @S9S_MB_2U_LIB.S9S_MB_2U(SCH_1):PAGE184
 R4598    1      A Q_RES_0402LF-1K,1%,1/16W,CHIP,A    I16 @S9S_MB_2U_LIB.S9S_MB_2U(SCH_1):PAGE184

FM_BOARD_BMC_SKU_ID3 @S9S_MB_2U_LIB.S9S_MB_2U(SCH_1):FM_BOARD_BMC_SKU_ID3
  U249   J5  PL11B LCMXO3LF9400C5BG484C-LCMXO3LF-A    I33 @S9S_MB_2U_LIB.S9S_MB_2U(SCH_1):PAGE311
 R4592    1      A Q_RES_0402LF-1K,1%,1/16W,CHIP,A     I4 @S9S_MB_2U_LIB.S9S_MB_2U(SCH_1):PAGE184
 R4591    2      B Q_RES_0402LF-10K,1%,1/16W,EMPTA     I6 @S9S_MB_2U_LIB.S9S_MB_2U(SCH_1):PAGE184

FM_BOARD_BMC_SKU_ID4 @S9S_MB_2U_LIB.S9S_MB_2U(SCH_1):FM_BOARD_BMC_SKU_ID4
  U249   H5  PL11A LCMXO3LF9400C5BG484C-LCMXO3LF-A    I33 @S9S_MB_2U_LIB.S9S_MB_2U(SCH_1):PAGE311
 R4581    1      A Q_RES_0402LF-1K,1%,1/16W,CHIP,A     I1 @S9S_MB_2U_LIB.S9S_MB_2U(SCH_1):PAGE184
 R4580    2      B Q_RES_0402LF-10K,1%,1/16W,EMPTA     I5 @S9S_MB_2U_LIB.S9S_MB_2U(SCH_1):PAGE184

FM_BOARD_SKU_ID0 @S9S_MB_2U_LIB.S9S_MB_2U(SCH_1):FM_BOARD_SKU_ID0
    U4 AA10 GPP_M_3 EMMITSBURG_REV0P9-GFNOCPU04302A    I22 @S9S_MB_2U_LIB.S9S_MB_2U(SCH_1):PAGE176
 R2243    1      A Q_RES_0402LF-1K,1%,1/16W,CHIP,A    I30 @S9S_MB_2U_LIB.S9S_MB_2U(SCH_1):PAGE184
 R2242    2      B Q_RES_0402LF-10K,1%,1/16W,EMPTA    I50 @S9S_MB_2U_LIB.S9S_MB_2U(SCH_1):PAGE184

FM_BOARD_SKU_ID1 @S9S_MB_2U_LIB.S9S_MB_2U(SCH_1):FM_BOARD_SKU_ID1
    U4   W7 GPP_M_4 EMMITSBURG_REV0P9-GFNOCPU04302A    I22 @S9S_MB_2U_LIB.S9S_MB_2U(SCH_1):PAGE176
 R2241    1      A Q_RES_0402LF-1K,1%,1/16W,CHIP,A    I28 @S9S_MB_2U_LIB.S9S_MB_2U(SCH_1):PAGE184
 R2240    2      B Q_RES_0402LF-10K,1%,1/16W,EMPTA    I49 @S9S_MB_2U_LIB.S9S_MB_2U(SCH_1):PAGE184

FM_BOARD_SKU_ID2 @S9S_MB_2U_LIB.S9S_MB_2U(SCH_1):FM_BOARD_SKU_ID2
    U4   V8 GPP_M_5 EMMITSBURG_REV0P9-GFNOCPU04302A    I22 @S9S_MB_2U_LIB.S9S_MB_2U(SCH_1):PAGE176
 R2980    1      A Q_RES_0402LF-1K,1%,1/16W,CHIP,A    I26 @S9S_MB_2U_LIB.S9S_MB_2U(SCH_1):PAGE184
 R2979    2      B Q_RES_0402LF-10K,1%,1/16W,EMPTA    I48 @S9S_MB_2U_LIB.S9S_MB_2U(SCH_1):PAGE184

FM_BOARD_SKU_ID3 @S9S_MB_2U_LIB.S9S_MB_2U(SCH_1):FM_BOARD_SKU_ID3
    U4  R10 GPP_M_6 EMMITSBURG_REV0P9-GFNOCPU04302A    I22 @S9S_MB_2U_LIB.S9S_MB_2U(SCH_1):PAGE176
 R2977    1      A Q_RES_0402LF-1K,1%,1/16W,CHIP,A    I11 @S9S_MB_2U_LIB.S9S_MB_2U(SCH_1):PAGE184
 R2976    2      B Q_RES_0402LF-10K,1%,1/16W,EMPTA    I13 @S9S_MB_2U_LIB.S9S_MB_2U(SCH_1):PAGE184

FM_BOARD_SKU_ID4 @S9S_MB_2U_LIB.S9S_MB_2U(SCH_1):FM_BOARD_SKU_ID4
    U4 AB11 GPP_M_7 EMMITSBURG_REV0P9-GFNOCPU04302A    I22 @S9S_MB_2U_LIB.S9S_MB_2U(SCH_1):PAGE176
 R2235    1      A Q_RES_0402LF-1K,1%,1/16W,CHIP,A     I9 @S9S_MB_2U_LIB.S9S_MB_2U(SCH_1):PAGE184
 R2234    2      B Q_RES_0402LF-10K,1%,1/16W,EMPTA    I12 @S9S_MB_2U_LIB.S9S_MB_2U(SCH_1):PAGE184

FM_CK440Q_DEV_25M_EN @S9S_MB_2U_LIB.S9S_MB_2U(SCH_1):FM_CK440Q_DEV_25M_EN
   U13   A1  25MPG 9SQ440NQQI8-9SQ440NQQI8,SMLF,IA   I180 @S9S_MB_2U_LIB.S9S_MB_2U(SCH_1):PAGE197
 R1680    2      B Q_RES_0402LF-0,5%,1/16W,CHIP,CA   I252 @S9S_MB_2U_LIB.S9S_MB_2U(SCH_1):PAGE197
 R1483    2      B Q_RES_0402LF-10K,1%,1/16W,EMPTA   I265 @S9S_MB_2U_LIB.S9S_MB_2U(SCH_1):PAGE197
 R1484    1      A Q_RES_0402LF-1K,1%,1/16W,EMPTYA   I268 @S9S_MB_2U_LIB.S9S_MB_2U(SCH_1):PAGE197
 C1324    1      A Q_CAP_0402-0.1UF,25V,10%,EMPTYA   I286 @S9S_MB_2U_LIB.S9S_MB_2U(SCH_1):PAGE197

FM_CK440_MXCK_25M_100M @S9S_MB_2U_LIB.S9S_MB_2U(SCH_1):FM_CK440_MXCK_25M_100M
   U13  B38 MXCK_SEL_100M# 9SQ440NQQI8-9SQ440NQQI8,SMLF,IA   I180 @S9S_MB_2U_LIB.S9S_MB_2U(SCH_1):PAGE197
 R1194    2      B Q_RES_0402LF-4.75K,1%,1/16W,EMA   I277 @S9S_MB_2U_LIB.S9S_MB_2U(SCH_1):PAGE197
 R1196    1      A Q_RES_0402LF-4.75K,1%,1/16W,CHA   I281 @S9S_MB_2U_LIB.S9S_MB_2U(SCH_1):PAGE197

FM_CLK_CK440_SS_EN @S9S_MB_2U_LIB.S9S_MB_2U(SCH_1):FM_CLK_CK440_SS_EN
   U13  A16 SS_EN_TRI 9SQ440NQQI8-9SQ440NQQI8,SMLF,IA   I180 @S9S_MB_2U_LIB.S9S_MB_2U(SCH_1):PAGE197
 R1471    2      B Q_RES_0402LF-4.75K,1%,1/16W,CHA   I267 @S9S_MB_2U_LIB.S9S_MB_2U(SCH_1):PAGE197
 R1502    1      A Q_RES_0402LF-4.75K,1%,1/16W,CHA   I270 @S9S_MB_2U_LIB.S9S_MB_2U(SCH_1):PAGE197

FM_CLK_GEN1_OE0_N @S9S_MB_2U_LIB.S9S_MB_2U(SCH_1):FM_CLK_GEN1_OE0_N
   U13  B27   OE0# 9SQ440NQQI8-9SQ440NQQI8,SMLF,IA   I180 @S9S_MB_2U_LIB.S9S_MB_2U(SCH_1):PAGE197
 R1527    1      A Q_RES_0402LF-1K,1%,1/16W,CHIP,A   I269 @S9S_MB_2U_LIB.S9S_MB_2U(SCH_1):PAGE197

FM_COMP_P3V3_AUX_ENIN @S9S_MB_2U_LIB.S9S_MB_2U(SCH_1):FM_COMP_P3V3_AUX_ENIN
 R1745    1      A Q_RES_0402LF-0,5%,1/16W,EMPTY,A    I21 @S9S_MB_2U_LIB.S9S_MB_2U(SCH_1):PAGE232
 R1690    2      B Q_RES_0402LF-10K,1%,1/16W,CHIPA    I22 @S9S_MB_2U_LIB.S9S_MB_2U(SCH_1):PAGE232
  U117    1 ENABLE TPS3895ADRYR-TPS3895ADRYR,SMLFA    I26 @S9S_MB_2U_LIB.S9S_MB_2U(SCH_1):PAGE232
   U94    1   ENIN ADM1086AKSZREEL7-ADM1086AKSZ-RA    I27 @S9S_MB_2U_LIB.S9S_MB_2U(SCH_1):PAGE232

FM_COMP_P3V3_AUX_VIN @S9S_MB_2U_LIB.S9S_MB_2U(SCH_1):FM_COMP_P3V3_AUX_VIN
 R1689    1      A Q_RES_0402LF-6.19K,1%,1/16W,CHA    I16 @S9S_MB_2U_LIB.S9S_MB_2U(SCH_1):PAGE232
 R1688    2      B Q_RES_0402LF-100K,1%,1/16W,CHIA    I18 @S9S_MB_2U_LIB.S9S_MB_2U(SCH_1):PAGE232
 R1950    1      A Q_RES_0402LF-0,5%,1/16W,CHIP,CA    I20 @S9S_MB_2U_LIB.S9S_MB_2U(SCH_1):PAGE232
  U117    3  SENSE TPS3895ADRYR-TPS3895ADRYR,SMLFA    I26 @S9S_MB_2U_LIB.S9S_MB_2U(SCH_1):PAGE232
   U94    3    VIN ADM1086AKSZREEL7-ADM1086AKSZ-RA    I27 @S9S_MB_2U_LIB.S9S_MB_2U(SCH_1):PAGE232

FM_COMP_P3V3_AUX_VIN_R @S9S_MB_2U_LIB.S9S_MB_2U(SCH_1):FM_COMP_P3V3_AUX_VIN_R
   Q52    D      D MOSFET_NCH_GDS_ESD_PROTECTED-2A    I14 @S9S_MB_2U_LIB.S9S_MB_2U(SCH_1):PAGE232
 R1950    2      B Q_RES_0402LF-0,5%,1/16W,CHIP,CA    I20 @S9S_MB_2U_LIB.S9S_MB_2U(SCH_1):PAGE232

FM_COMP_P3V3_STBY_CEXT @S9S_MB_2U_LIB.S9S_MB_2U(SCH_1):FM_COMP_P3V3_STBY_CEXT
 C1316    1      A Q_CAP_C0402-0.047UF,25V,10%,X7A    I47 @S9S_MB_2U_LIB.S9S_MB_2U(SCH_1):PAGE232
  U117    5     CT TPS3895ADRYR-TPS3895ADRYR,SMLFA    I26 @S9S_MB_2U_LIB.S9S_MB_2U(SCH_1):PAGE232
   U94    5   CEXT ADM1086AKSZREEL7-ADM1086AKSZ-RA    I27 @S9S_MB_2U_LIB.S9S_MB_2U(SCH_1):PAGE232

FM_CPU0_PKGID0 @S9S_MB_2U_LIB.S9S_MB_2U(SCH_1):FM_CPU0_PKGID0
    U2 BL64 PKG_ID0 SOCKET4677_AZIF0045P001C01CS-SA    I57 @S9S_MB_2U_LIB.S9S_MB_2U(SCH_1):PAGE13
  R283    2      B Q_RES_0402LF-10K,1%,1/16W,CHIPA   I147 @S9S_MB_2U_LIB.S9S_MB_2U(SCH_1):PAGE119
  U249  N20  PR19C LCMXO3LF9400C5BG484C-LCMXO3LF-A     I1 @S9S_MB_2U_LIB.S9S_MB_2U(SCH_1):PAGE313

FM_CPU0_PKGID1 @S9S_MB_2U_LIB.S9S_MB_2U(SCH_1):FM_CPU0_PKGID1
    U2 AY63 PKG_ID1 SOCKET4677_AZIF0045P001C01CS-SA    I57 @S9S_MB_2U_LIB.S9S_MB_2U(SCH_1):PAGE13
  R284    2      B Q_RES_0402LF-10K,1%,1/16W,CHIPA   I148 @S9S_MB_2U_LIB.S9S_MB_2U(SCH_1):PAGE119
  U249  N19  PR19D LCMXO3LF9400C5BG484C-LCMXO3LF-A     I1 @S9S_MB_2U_LIB.S9S_MB_2U(SCH_1):PAGE313

FM_CPU0_PKGID2 @S9S_MB_2U_LIB.S9S_MB_2U(SCH_1):FM_CPU0_PKGID2
    U2 BN64 PKG_ID2 SOCKET4677_AZIF0045P001C01CS-SA    I57 @S9S_MB_2U_LIB.S9S_MB_2U(SCH_1):PAGE13
  R285    2      B Q_RES_0402LF-10K,1%,1/16W,CHIPA   I150 @S9S_MB_2U_LIB.S9S_MB_2U(SCH_1):PAGE119
  U249  R22  PR20A LCMXO3LF9400C5BG484C-LCMXO3LF-A     I1 @S9S_MB_2U_LIB.S9S_MB_2U(SCH_1):PAGE313

FM_CPU0_PROC_ID0 @S9S_MB_2U_LIB.S9S_MB_2U(SCH_1):FM_CPU0_PROC_ID0
    U2 BG72 PROC_ID0 SOCKET4677_AZIF0045P001C01CS-SA    I57 @S9S_MB_2U_LIB.S9S_MB_2U(SCH_1):PAGE13
  R286    2      B Q_RES_0402LF-10K,1%,1/16W,CHIPA   I151 @S9S_MB_2U_LIB.S9S_MB_2U(SCH_1):PAGE119
  U249  N17  PR18C LCMXO3LF9400C5BG484C-LCMXO3LF-A     I1 @S9S_MB_2U_LIB.S9S_MB_2U(SCH_1):PAGE313

FM_CPU0_PROC_ID1 @S9S_MB_2U_LIB.S9S_MB_2U(SCH_1):FM_CPU0_PROC_ID1
    U2 BH71 PROC_ID1 SOCKET4677_AZIF0045P001C01CS-SA    I57 @S9S_MB_2U_LIB.S9S_MB_2U(SCH_1):PAGE13
  R287    2      B Q_RES_0402LF-10K,1%,1/16W,CHIPA   I152 @S9S_MB_2U_LIB.S9S_MB_2U(SCH_1):PAGE119
  U249  N18  PR18D LCMXO3LF9400C5BG484C-LCMXO3LF-A     I1 @S9S_MB_2U_LIB.S9S_MB_2U(SCH_1):PAGE313

FM_CPU0_SKTOCC_LVT3_N @S9S_MB_2U_LIB.S9S_MB_2U(SCH_1):FM_CPU0_SKTOCC_LVT3_N
    U2 CG66 SKTOCC_N SOCKET4677_AZIF0045P001C01CS-SA     I1 @S9S_MB_2U_LIB.S9S_MB_2U(SCH_1):PAGE14
  R738    1      A Q_RES_0402LF-0,5%,1/16W,CHIP,CA   I110 @S9S_MB_2U_LIB.S9S_MB_2U(SCH_1):PAGE135
 R1447    1      A Q_RES_0402LF-33.2,1%,1/16W,CHIA    I68 @S9S_MB_2U_LIB.S9S_MB_2U(SCH_1):PAGE211

FM_CPU0_SKTOCC_LVT3_PLD_N @S9S_MB_2U_LIB.S9S_MB_2U(SCH_1):FM_CPU0_SKTOCC_LVT3_PLD_N
 R1447    2      B Q_RES_0402LF-33.2,1%,1/16W,CHIA    I68 @S9S_MB_2U_LIB.S9S_MB_2U(SCH_1):PAGE211
  U249  M16  PR18A LCMXO3LF9400C5BG484C-LCMXO3LF-A     I1 @S9S_MB_2U_LIB.S9S_MB_2U(SCH_1):PAGE313

FM_CPU0_SKTOCC_N @S9S_MB_2U_LIB.S9S_MB_2U(SCH_1):FM_CPU0_SKTOCC_N
   U21    6      S NC7SB3157_SMLF-NC7SB3157P6X,NCA    I58 @S9S_MB_2U_LIB.S9S_MB_2U(SCH_1):PAGE135
   U23    2      A 74LVC1G02GW_SMLF-74LVC1G02GW,IA    I96 @S9S_MB_2U_LIB.S9S_MB_2U(SCH_1):PAGE135
  R740    2      B Q_RES_0402LF-10K,1%,1/16W,CHIPA   I107 @S9S_MB_2U_LIB.S9S_MB_2U(SCH_1):PAGE135
  R738    2      B Q_RES_0402LF-0,5%,1/16W,CHIP,CA   I110 @S9S_MB_2U_LIB.S9S_MB_2U(SCH_1):PAGE135

FM_CPU1_PKGID0 @S9S_MB_2U_LIB.S9S_MB_2U(SCH_1):FM_CPU1_PKGID0
    U1 BL64 PKG_ID0 SOCKET4677_AZIF0045P001C01CS-SA    I51 @S9S_MB_2U_LIB.S9S_MB_2U(SCH_1):PAGE44
  R270    2      B Q_RES_0402LF-10K,1%,1/16W,CHIPA    I93 @S9S_MB_2U_LIB.S9S_MB_2U(SCH_1):PAGE119
  U249  R21  PR20B LCMXO3LF9400C5BG484C-LCMXO3LF-A     I1 @S9S_MB_2U_LIB.S9S_MB_2U(SCH_1):PAGE313

FM_CPU1_PKGID1 @S9S_MB_2U_LIB.S9S_MB_2U(SCH_1):FM_CPU1_PKGID1
    U1 AY63 PKG_ID1 SOCKET4677_AZIF0045P001C01CS-SA    I51 @S9S_MB_2U_LIB.S9S_MB_2U(SCH_1):PAGE44
  R271    2      B Q_RES_0402LF-10K,1%,1/16W,CHIPA    I92 @S9S_MB_2U_LIB.S9S_MB_2U(SCH_1):PAGE119
  U249  P22  PR20C LCMXO3LF9400C5BG484C-LCMXO3LF-A     I1 @S9S_MB_2U_LIB.S9S_MB_2U(SCH_1):PAGE313

FM_CPU1_PKGID2 @S9S_MB_2U_LIB.S9S_MB_2U(SCH_1):FM_CPU1_PKGID2
    U1 BN64 PKG_ID2 SOCKET4677_AZIF0045P001C01CS-SA    I51 @S9S_MB_2U_LIB.S9S_MB_2U(SCH_1):PAGE44
  R272    2      B Q_RES_0402LF-10K,1%,1/16W,CHIPA    I90 @S9S_MB_2U_LIB.S9S_MB_2U(SCH_1):PAGE119
  U249  P20  PR20D LCMXO3LF9400C5BG484C-LCMXO3LF-A     I1 @S9S_MB_2U_LIB.S9S_MB_2U(SCH_1):PAGE313

FM_CPU1_PROC_ID0 @S9S_MB_2U_LIB.S9S_MB_2U(SCH_1):FM_CPU1_PROC_ID0
    U1 BG72 PROC_ID0 SOCKET4677_AZIF0045P001C01CS-SA    I51 @S9S_MB_2U_LIB.S9S_MB_2U(SCH_1):PAGE44
  R273    2      B Q_RES_0402LF-10K,1%,1/16W,CHIPA    I89 @S9S_MB_2U_LIB.S9S_MB_2U(SCH_1):PAGE119
  U249  N22  PR19A LCMXO3LF9400C5BG484C-LCMXO3LF-A     I1 @S9S_MB_2U_LIB.S9S_MB_2U(SCH_1):PAGE313

FM_CPU1_PROC_ID1 @S9S_MB_2U_LIB.S9S_MB_2U(SCH_1):FM_CPU1_PROC_ID1
    U1 BH71 PROC_ID1 SOCKET4677_AZIF0045P001C01CS-SA    I51 @S9S_MB_2U_LIB.S9S_MB_2U(SCH_1):PAGE44
  R274    2      B Q_RES_0402LF-10K,1%,1/16W,CHIPA    I88 @S9S_MB_2U_LIB.S9S_MB_2U(SCH_1):PAGE119
  U249  P21  PR19B LCMXO3LF9400C5BG484C-LCMXO3LF-A     I1 @S9S_MB_2U_LIB.S9S_MB_2U(SCH_1):PAGE313

FM_CPU1_SKTOCC_LVT3_N @S9S_MB_2U_LIB.S9S_MB_2U(SCH_1):FM_CPU1_SKTOCC_LVT3_N
    U1 CG66 SKTOCC_N SOCKET4677_AZIF0045P001C01CS-SA    I29 @S9S_MB_2U_LIB.S9S_MB_2U(SCH_1):PAGE45
  R737    1      A Q_RES_0402LF-0,5%,1/16W,CHIP,CA   I106 @S9S_MB_2U_LIB.S9S_MB_2U(SCH_1):PAGE135
 R1448    1      A Q_RES_0402LF-33.2,1%,1/16W,CHIA    I62 @S9S_MB_2U_LIB.S9S_MB_2U(SCH_1):PAGE211

FM_CPU1_SKTOCC_LVT3_PLD_N @S9S_MB_2U_LIB.S9S_MB_2U(SCH_1):FM_CPU1_SKTOCC_LVT3_PLD_N
 R1448    2      B Q_RES_0402LF-33.2,1%,1/16W,CHIA    I62 @S9S_MB_2U_LIB.S9S_MB_2U(SCH_1):PAGE211
  U249  N16  PR18B LCMXO3LF9400C5BG484C-LCMXO3LF-A     I1 @S9S_MB_2U_LIB.S9S_MB_2U(SCH_1):PAGE313

FM_CPU1_SKTOCC_N @S9S_MB_2U_LIB.S9S_MB_2U(SCH_1):FM_CPU1_SKTOCC_N
   U22    6      S NC7SB3157_SMLF-NC7SB3157P6X,NCA    I71 @S9S_MB_2U_LIB.S9S_MB_2U(SCH_1):PAGE135
   U23    1      B 74LVC1G02GW_SMLF-74LVC1G02GW,IA    I96 @S9S_MB_2U_LIB.S9S_MB_2U(SCH_1):PAGE135
  R737    2      B Q_RES_0402LF-0,5%,1/16W,CHIP,CA   I106 @S9S_MB_2U_LIB.S9S_MB_2U(SCH_1):PAGE135
  R739    2      B Q_RES_0402LF-10K,1%,1/16W,CHIPA   I109 @S9S_MB_2U_LIB.S9S_MB_2U(SCH_1):PAGE135

FM_CPU_EN @S9S_MB_2U_LIB.S9S_MB_2U(SCH_1):FM_CPU_EN
   U23    4      Y 74LVC1G02GW_SMLF-74LVC1G02GW,IA    I96 @S9S_MB_2U_LIB.S9S_MB_2U(SCH_1):PAGE135
  R745    1      A Q_RES_0402LF-33.2,1%,1/16W,CHIA    I97 @S9S_MB_2U_LIB.S9S_MB_2U(SCH_1):PAGE135

FM_CPU_EN_R @S9S_MB_2U_LIB.S9S_MB_2U(SCH_1):FM_CPU_EN_R
  R745    2      B Q_RES_0402LF-33.2,1%,1/16W,CHIA    I97 @S9S_MB_2U_LIB.S9S_MB_2U(SCH_1):PAGE135
   U16    4      E 74LVC1G66GV-74LVC1G66GV,SMLF,IA   I115 @S9S_MB_2U_LIB.S9S_MB_2U(SCH_1):PAGE135

FM_CPU_FBRK_DEBUG_N @S9S_MB_2U_LIB.S9S_MB_2U(SCH_1):FM_CPU_FBRK_DEBUG_N
   J42   38     38 SCONN60_ASP21410801-SCONN60_ASA    I44 @S9S_MB_2U_LIB.S9S_MB_2U(SCH_1):PAGE133
  R780    1      A Q_RES_0402LF-49.9,1%,1/16W,CHIA    I92 @S9S_MB_2U_LIB.S9S_MB_2U(SCH_1):PAGE133
  R779    2      B Q_RES_0402LF-150,1%,1/16W,CHIPA    I95 @S9S_MB_2U_LIB.S9S_MB_2U(SCH_1):PAGE133
  C552    1      A Q_CAP_0402-0.1UF,25V,10%,X7R,CA    I96 @S9S_MB_2U_LIB.S9S_MB_2U(SCH_1):PAGE133
 R1247    2      B Q_RES_0402LF-0,5%,1/16W,CHIP,CA    I14 @S9S_MB_2U_LIB.S9S_MB_2U(SCH_1):PAGE191
   U84    3     B1 GTL2014PW-GTL2014PW,SMLF,IC,ALA    I18 @S9S_MB_2U_LIB.S9S_MB_2U(SCH_1):PAGE226

FM_CPU_FBRK_DEBUG_R_N @S9S_MB_2U_LIB.S9S_MB_2U(SCH_1):FM_CPU_FBRK_DEBUG_R_N
    U2 AV57 FBRK_N SOCKET4677_AZIF0045P001C01CS-SA     I1 @S9S_MB_2U_LIB.S9S_MB_2U(SCH_1):PAGE14
    U1 AV57 FBRK_N SOCKET4677_AZIF0045P001C01CS-SA    I29 @S9S_MB_2U_LIB.S9S_MB_2U(SCH_1):PAGE45
  R780    2      B Q_RES_0402LF-49.9,1%,1/16W,CHIA    I92 @S9S_MB_2U_LIB.S9S_MB_2U(SCH_1):PAGE133

FM_CPU_RMCA_CATERR_DLY_LVT3_R_N @S9S_MB_2U_LIB.S9S_MB_2U(SCH_1):FM_CPU_RMCA_CATERR_DLY_LVT3_R_N
 R1456    1      A Q_RES_0402LF-49.9,1%,1/16W,CHIA    I28 @S9S_MB_2U_LIB.S9S_MB_2U(SCH_1):PAGE193
  U249  P16  PR24B LCMXO3LF9400C5BG484C-LCMXO3LF-A     I1 @S9S_MB_2U_LIB.S9S_MB_2U(SCH_1):PAGE313

FM_CPU_RMCA_CATERR_DLY_N @S9S_MB_2U_LIB.S9S_MB_2U(SCH_1):FM_CPU_RMCA_CATERR_DLY_N
    U4  AF4 GPP_D_18_MEMTRIP_N EMMITSBURG_REV0P9-GFNOCPU04302A    I93 @S9S_MB_2U_LIB.S9S_MB_2U(SCH_1):PAGE175
 R1456    2      B Q_RES_0402LF-49.9,1%,1/16W,CHIA    I28 @S9S_MB_2U_LIB.S9S_MB_2U(SCH_1):PAGE193

FM_CPU_RMCA_CATERR_LVT3_R_N @S9S_MB_2U_LIB.S9S_MB_2U(SCH_1):FM_CPU_RMCA_CATERR_LVT3_R_N
  U249  AA8  PB18A LCMXO3LF9400C5BG484C-LCMXO3LF-A     I1 @S9S_MB_2U_LIB.S9S_MB_2U(SCH_1):PAGE312
  R365    1      A Q_RES_0402LF-0,5%,1/16W,CHIP,CA   I273 @S9S_MB_2U_LIB.S9S_MB_2U(SCH_1):PAGE207
 R1841    2      B Q_RES_0402LF-10K,1%,1/16W,CHIPA   I275 @S9S_MB_2U_LIB.S9S_MB_2U(SCH_1):PAGE207
 R1558    1      A Q_RES_0402LF-10K,1%,1/16W,EMPTA    I15 @S9S_MB_2U_LIB.S9S_MB_2U(SCH_1):PAGE209

FM_DB2000_10_OE_N @S9S_MB_2U_LIB.S9S_MB_2U(SCH_1):FM_DB2000_10_OE_N
   U38  E11 VOE10#||SHFT_LD# 9QXL2001BNHGI8-9QXL2001BNHGI8,A   I119 @S9S_MB_2U_LIB.S9S_MB_2U(SCH_1):PAGE195
 R2562    2      B Q_RES_0402LF-0,5%,1/16W,CHIP,CA   I535 @S9S_MB_2U_LIB.S9S_MB_2U(SCH_1):PAGE195

FM_DB2000_11_OE_N @S9S_MB_2U_LIB.S9S_MB_2U(SCH_1):FM_DB2000_11_OE_N
   U38  C11 VOE11# 9QXL2001BNHGI8-9QXL2001BNHGI8,A   I119 @S9S_MB_2U_LIB.S9S_MB_2U(SCH_1):PAGE195
 R3636    2      B Q_RES_0402LF-0,5%,1/16W,CHIP,CA   I536 @S9S_MB_2U_LIB.S9S_MB_2U(SCH_1):PAGE195

FM_DB2000_12_OE_N @S9S_MB_2U_LIB.S9S_MB_2U(SCH_1):FM_DB2000_12_OE_N
   U38  B10 VOE12# 9QXL2001BNHGI8-9QXL2001BNHGI8,A   I119 @S9S_MB_2U_LIB.S9S_MB_2U(SCH_1):PAGE195
 R3637    2      B Q_RES_0402LF-0,5%,1/16W,CHIP,CA   I537 @S9S_MB_2U_LIB.S9S_MB_2U(SCH_1):PAGE195

FM_DB2000_1_OE_N @S9S_MB_2U_LIB.S9S_MB_2U(SCH_1):FM_DB2000_1_OE_N
   U38   L8 VOE5#||DATA 9QXL2001BNHGI8-9QXL2001BNHGI8,A   I119 @S9S_MB_2U_LIB.S9S_MB_2U(SCH_1):PAGE195
   U38  L10 VOE6#||CLK 9QXL2001BNHGI8-9QXL2001BNHGI8,A   I119 @S9S_MB_2U_LIB.S9S_MB_2U(SCH_1):PAGE195
   U38  K11  VOE7# 9QXL2001BNHGI8-9QXL2001BNHGI8,A   I119 @S9S_MB_2U_LIB.S9S_MB_2U(SCH_1):PAGE195
  R576    2      B Q_RES_0402LF-49.9,1%,1/16W,CHIA   I156 @S9S_MB_2U_LIB.S9S_MB_2U(SCH_1):PAGE195

FM_DB2000_8_OE_N @S9S_MB_2U_LIB.S9S_MB_2U(SCH_1):FM_DB2000_8_OE_N
   U38  H11  VOE8# 9QXL2001BNHGI8-9QXL2001BNHGI8,A   I119 @S9S_MB_2U_LIB.S9S_MB_2U(SCH_1):PAGE195
 R4534    2      B Q_RES_0402LF-0,5%,1/16W,CHIP,CA   I487 @S9S_MB_2U_LIB.S9S_MB_2U(SCH_1):PAGE195

FM_DB2000_9_OE_N @S9S_MB_2U_LIB.S9S_MB_2U(SCH_1):FM_DB2000_9_OE_N
   U38  E12  VOE9# 9QXL2001BNHGI8-9QXL2001BNHGI8,A   I119 @S9S_MB_2U_LIB.S9S_MB_2U(SCH_1):PAGE195
 R1543    2      B Q_RES_0402LF-0,5%,1/16W,CHIP,CA   I534 @S9S_MB_2U_LIB.S9S_MB_2U(SCH_1):PAGE195

FM_DB2000_DEV_EN @S9S_MB_2U_LIB.S9S_MB_2U(SCH_1):FM_DB2000_DEV_EN
   U38   M6 VCKPWRGD_PD# 9QXL2001BNHGI8-9QXL2001BNHGI8,A   I119 @S9S_MB_2U_LIB.S9S_MB_2U(SCH_1):PAGE195
  R575    2      B Q_RES_0402LF-49.9,1%,1/16W,CHIA   I199 @S9S_MB_2U_LIB.S9S_MB_2U(SCH_1):PAGE195

FM_DB2000_OE_N @S9S_MB_2U_LIB.S9S_MB_2U(SCH_1):FM_DB2000_OE_N
  R576    1      A Q_RES_0402LF-49.9,1%,1/16W,CHIA   I156 @S9S_MB_2U_LIB.S9S_MB_2U(SCH_1):PAGE195
  R113    2      B Q_RES_0402LF-33.2,1%,1/16W,CHIA    I27 @S9S_MB_2U_LIB.S9S_MB_2U(SCH_1):PAGE212

FM_DB2000_VSBEN @S9S_MB_2U_LIB.S9S_MB_2U(SCH_1):FM_DB2000_VSBEN
   U38   E2  VSBEN 9QXL2001BNHGI8-9QXL2001BNHGI8,A   I119 @S9S_MB_2U_LIB.S9S_MB_2U(SCH_1):PAGE195
  R573    2      B Q_RES_0402LF-4.7K,1%,1/16W,EMPA   I194 @S9S_MB_2U_LIB.S9S_MB_2U(SCH_1):PAGE195
  R574    1      A Q_RES_0402LF-4.7K,1%,1/16W,CHIA   I197 @S9S_MB_2U_LIB.S9S_MB_2U(SCH_1):PAGE195

FM_DEBUG_PORT_PRSNT_N @S9S_MB_2U_LIB.S9S_MB_2U(SCH_1):FM_DEBUG_PORT_PRSNT_N
  U249  AB9  PB19B LCMXO3LF9400C5BG484C-LCMXO3LF-A     I1 @S9S_MB_2U_LIB.S9S_MB_2U(SCH_1):PAGE312
 R2348    1      A Q_RES_0402LF-0,5%,1/16W,CHIP,CA   I184 @S9S_MB_2U_LIB.S9S_MB_2U(SCH_1):PAGE312

FM_DEBUG_PORT_PRSNT_R_N @S9S_MB_2U_LIB.S9S_MB_2U(SCH_1):FM_DEBUG_PORT_PRSNT_R_N
    U4 BA36 GPP_E_17_ERR0_N EMMITSBURG_REV0P9-GFNOCPU04302A    I22 @S9S_MB_2U_LIB.S9S_MB_2U(SCH_1):PAGE176
 R2342    2      B Q_RES_0402LF-10K,1%,1/16W,CHIPA    I75 @S9S_MB_2U_LIB.S9S_MB_2U(SCH_1):PAGE192
 R2348    2      B Q_RES_0402LF-0,5%,1/16W,CHIP,CA   I184 @S9S_MB_2U_LIB.S9S_MB_2U(SCH_1):PAGE312

FM_DIMM_12V_CPS_SX_N @S9S_MB_2U_LIB.S9S_MB_2U(SCH_1):FM_DIMM_12V_CPS_SX_N
  U249  W15  PB35D LCMXO3LF9400C5BG484C-LCMXO3LF-A     I1 @S9S_MB_2U_LIB.S9S_MB_2U(SCH_1):PAGE312
  R736    1      A Q_RES_0402LF-1K,1%,1/16W,EMPTYA    I11 @S9S_MB_2U_LIB.S9S_MB_2U(SCH_1):PAGE209
  R735    2      B Q_RES_0402LF-10K,1%,1/16W,CHIPA    I13 @S9S_MB_2U_LIB.S9S_MB_2U(SCH_1):PAGE209

FM_DIS_PS_PWROK_DLY @S9S_MB_2U_LIB.S9S_MB_2U(SCH_1):FM_DIS_PS_PWROK_DLY
  U249  AA7  PB13A LCMXO3LF9400C5BG484C-LCMXO3LF-A     I1 @S9S_MB_2U_LIB.S9S_MB_2U(SCH_1):PAGE312
 R1494    1      A Q_RES_0402LF-1K,1%,1/16W,EMPTYA    I21 @S9S_MB_2U_LIB.S9S_MB_2U(SCH_1):PAGE209
 R1492    1      A Q_RES_0402LF-10K,1%,1/16W,CHIPA    I35 @S9S_MB_2U_LIB.S9S_MB_2U(SCH_1):PAGE209

FM_ESPI_CS_SWIZZLE @S9S_MB_2U_LIB.S9S_MB_2U(SCH_1):FM_ESPI_CS_SWIZZLE
    U4  BB8 GPPC_S_11 EMMITSBURG_REV0P9-GFNOCPU04302A    I27 @S9S_MB_2U_LIB.S9S_MB_2U(SCH_1):PAGE177
  R609    2      B Q_RES_0402LF-1K,1%,1/16W,EMPTYA    I39 @S9S_MB_2U_LIB.S9S_MB_2U(SCH_1):PAGE187
  R610    1      A Q_RES_0402LF-10K,1%,1/16W,CHIPA    I40 @S9S_MB_2U_LIB.S9S_MB_2U(SCH_1):PAGE187

FM_ESPI_FLASH_MODE @S9S_MB_2U_LIB.S9S_MB_2U(SCH_1):FM_ESPI_FLASH_MODE
    U4  AG1 GPP_D_7 EMMITSBURG_REV0P9-GFNOCPU04302A    I93 @S9S_MB_2U_LIB.S9S_MB_2U(SCH_1):PAGE175
  R607    2      B Q_RES_0402LF-1K,1%,1/16W,EMPTYA    I21 @S9S_MB_2U_LIB.S9S_MB_2U(SCH_1):PAGE187
  R608    1      A Q_RES_0402LF-10K,1%,1/16W,CHIPA    I36 @S9S_MB_2U_LIB.S9S_MB_2U(SCH_1):PAGE187

FM_ESPI_PLD_EN @S9S_MB_2U_LIB.S9S_MB_2U(SCH_1):FM_ESPI_PLD_EN
   U60    6      S NC7SB3157_SMLF-NC7SB3157P6X,NCA    I34 @S9S_MB_2U_LIB.S9S_MB_2U(SCH_1):PAGE190
   U61    6      S NC7SB3157_SMLF-NC7SB3157P6X,NCA    I39 @S9S_MB_2U_LIB.S9S_MB_2U(SCH_1):PAGE190
 R1748    1      A Q_RES_0402LF-0,5%,1/16W,CHIP,CA    I54 @S9S_MB_2U_LIB.S9S_MB_2U(SCH_1):PAGE190

FM_ESPI_PLD_R1_EN @S9S_MB_2U_LIB.S9S_MB_2U(SCH_1):FM_ESPI_PLD_R1_EN
 R1749    1      A Q_RES_0402LF-10K,1%,1/16W,EMPTA    I89 @S9S_MB_2U_LIB.S9S_MB_2U(SCH_1):PAGE190
 R2132    2      B Q_RES_0402LF-0,5%,1/16W,EMPTY,A    I91 @S9S_MB_2U_LIB.S9S_MB_2U(SCH_1):PAGE190
 R2451    2      B Q_RES_0402LF-10K,1%,1/16W,EMPTA    I94 @S9S_MB_2U_LIB.S9S_MB_2U(SCH_1):PAGE190
 R2452    2      B Q_RES_0402LF-0,5%,1/16W,CHIP,CA    I84 @S9S_MB_2U_LIB.S9S_MB_2U(SCH_1):PAGE313
  U154    2      A 74LVC1G07SE7-74LVC1G07SE-7,SMLA    I95 @S9S_MB_2U_LIB.S9S_MB_2U(SCH_1):PAGE190

FM_ESPI_PLD_R_EN @S9S_MB_2U_LIB.S9S_MB_2U(SCH_1):FM_ESPI_PLD_R_EN
  U249  G19   PR6C LCMXO3LF9400C5BG484C-LCMXO3LF-A     I1 @S9S_MB_2U_LIB.S9S_MB_2U(SCH_1):PAGE313
 R2452    1      A Q_RES_0402LF-0,5%,1/16W,CHIP,CA    I84 @S9S_MB_2U_LIB.S9S_MB_2U(SCH_1):PAGE313

FM_ESPI_PLD_R_EN_BUF @S9S_MB_2U_LIB.S9S_MB_2U(SCH_1):FM_ESPI_PLD_R_EN_BUF
 R1748    2      B Q_RES_0402LF-0,5%,1/16W,CHIP,CA    I54 @S9S_MB_2U_LIB.S9S_MB_2U(SCH_1):PAGE190
 R1750    2      B Q_RES_0402LF-1K,1%,1/16W,CHIP,A    I87 @S9S_MB_2U_LIB.S9S_MB_2U(SCH_1):PAGE190
  U154    4      Y 74LVC1G07SE7-74LVC1G07SE-7,SMLA    I95 @S9S_MB_2U_LIB.S9S_MB_2U(SCH_1):PAGE190
 R4177    2      B Q_RES_0402LF-0,5%,1/16W,CHIP,CA    I19 @S9S_MB_2U_LIB.S9S_MB_2U(SCH_1):PAGE243

FM_ESPI_PLD_R_EN_BUF_R @S9S_MB_2U_LIB.S9S_MB_2U(SCH_1):FM_ESPI_PLD_R_EN_BUF_R
  U307    G   GATE MOSFET_N_SMLF-BSS138K,BSS138K,A    I15 @S9S_MB_2U_LIB.S9S_MB_2U(SCH_1):PAGE243
 R4177    1      A Q_RES_0402LF-0,5%,1/16W,CHIP,CA    I19 @S9S_MB_2U_LIB.S9S_MB_2U(SCH_1):PAGE243

FM_EUP_LOT6_N @S9S_MB_2U_LIB.S9S_MB_2U(SCH_1):FM_EUP_LOT6_N
    U4 AR13 GPPC_S_6_SUSWARN_N_SUSPWRDNACK EMMITSBURG_REV0P9-GFNOCPU04302A    I27 @S9S_MB_2U_LIB.S9S_MB_2U(SCH_1):PAGE177
 R1461    1      A Q_RES_0402LF-0,5%,1/16W,CHIP,CA    I80 @S9S_MB_2U_LIB.S9S_MB_2U(SCH_1):PAGE177

FM_FAN_PWR_EN @S9S_MB_2U_LIB.S9S_MB_2U(SCH_1):FM_FAN_PWR_EN
  U249   B2  PT10A LCMXO3LF9400C5BG484C-LCMXO3LF-A   I188 @S9S_MB_2U_LIB.S9S_MB_2U(SCH_1):PAGE314
 R2803    2      B Q_RES_0402LF-0,5%,1/16W,CHIP,CA    I38 @S9S_MB_2U_LIB.S9S_MB_2U(SCH_1):PAGE233
 R4701    2      B Q_RES_0402LF-4.7K,5%,1/16W,CHIA    I41 @S9S_MB_2U_LIB.S9S_MB_2U(SCH_1):PAGE233

FM_FAN_PWR_EN_R @S9S_MB_2U_LIB.S9S_MB_2U(SCH_1):FM_FAN_PWR_EN_R
   J45   D1     D1 CONN60_101062636003K02LF-CONN6A    I12 @S9S_MB_2U_LIB.S9S_MB_2U(SCH_1):PAGE233
 R2803    1      A Q_RES_0402LF-0,5%,1/16W,CHIP,CA    I38 @S9S_MB_2U_LIB.S9S_MB_2U(SCH_1):PAGE233
 C2296    1      A Q_CAP_0402-0.1UF,25V,10%,EMPTYA    I53 @S9S_MB_2U_LIB.S9S_MB_2U(SCH_1):PAGE233

FM_FLASH_SECURITY_STRAP @S9S_MB_2U_LIB.S9S_MB_2U(SCH_1):FM_FLASH_SECURITY_STRAP
    U4  AJ1 GPP_D_6 EMMITSBURG_REV0P9-GFNOCPU04302A    I93 @S9S_MB_2U_LIB.S9S_MB_2U(SCH_1):PAGE175
  R380    2      B Q_RES_0402LF-1K,1%,1/16W,EMPTYA    I78 @S9S_MB_2U_LIB.S9S_MB_2U(SCH_1):PAGE186
  R381    1      A Q_RES_0402LF-10K,1%,1/16W,CHIPA    I81 @S9S_MB_2U_LIB.S9S_MB_2U(SCH_1):PAGE186
  J104   10     10 CONN14_210HP207GBR1-CONN14_210A   I134 @S9S_MB_2U_LIB.S9S_MB_2U(SCH_1):PAGE189

FM_FORCE_PWRON_LVC3 @S9S_MB_2U_LIB.S9S_MB_2U(SCH_1):FM_FORCE_PWRON_LVC3
  U249  U10  PB19D LCMXO3LF9400C5BG484C-LCMXO3LF-A     I1 @S9S_MB_2U_LIB.S9S_MB_2U(SCH_1):PAGE312
  JP15    2      2 CONN3_210HP1030BR1-CONN3_210-HB   I187 @S9S_MB_2U_LIB.S9S_MB_2U(SCH_1):PAGE312

FM_G751_0_ALERT_N @S9S_MB_2U_LIB.S9S_MB_2U(SCH_1):FM_G751_0_ALERT_N
 R4215    2      B Q_RES_0402LF-0,5%,1/16W,CHIP,CA    I79 @S9S_MB_2U_LIB.S9S_MB_2U(SCH_1):PAGE161
  U270    3     OS LM75BD-LM75BD,SMLF,IC,AL0075BDA   I164 @S9S_MB_2U_LIB.S9S_MB_2U(SCH_1):PAGE161

FM_G751_1_ALERT_N @S9S_MB_2U_LIB.S9S_MB_2U(SCH_1):FM_G751_1_ALERT_N
 R4214    2      B Q_RES_0402LF-0,5%,1/16W,CHIP,CA   I108 @S9S_MB_2U_LIB.S9S_MB_2U(SCH_1):PAGE161
  U271    3     OS LM75BD-LM75BD,SMLF,IC,AL0075BDA   I165 @S9S_MB_2U_LIB.S9S_MB_2U(SCH_1):PAGE161

FM_GPU_HSC_EN @S9S_MB_2U_LIB.S9S_MB_2U(SCH_1):FM_GPU_HSC_EN
 R2940    2      B Q_RES_0402LF-4.7K,5%,1/16W,EMPA    I28 @S9S_MB_2U_LIB.S9S_MB_2U(SCH_1):PAGE230
 R2941    1      A Q_RES_0402LF-100K,1%,1/16W,CHIA    I29 @S9S_MB_2U_LIB.S9S_MB_2U(SCH_1):PAGE230
  U278    1      A 74LVC1G08W57-74LVC1G08W5-7,SMLA    I31 @S9S_MB_2U_LIB.S9S_MB_2U(SCH_1):PAGE230
 R2939    2      B Q_RES_0402LF-33.2,1%,1/16W,CHIA   I106 @S9S_MB_2U_LIB.S9S_MB_2U(SCH_1):PAGE314

FM_GPU_HSC_EN_BUF @S9S_MB_2U_LIB.S9S_MB_2U(SCH_1):FM_GPU_HSC_EN_BUF
 R2944    2      B Q_RES_0402LF-33.2,1%,1/16W,CHIA    I24 @S9S_MB_2U_LIB.S9S_MB_2U(SCH_1):PAGE230
 R2906    2      B Q_RES_0402LF-0,5%,1/16W,CHIP,CA    I37 @S9S_MB_2U_LIB.S9S_MB_2U(SCH_1):PAGE233

FM_GPU_HSC_EN_BUF_R @S9S_MB_2U_LIB.S9S_MB_2U(SCH_1):FM_GPU_HSC_EN_BUF_R
 R2944    1      A Q_RES_0402LF-33.2,1%,1/16W,CHIA    I24 @S9S_MB_2U_LIB.S9S_MB_2U(SCH_1):PAGE230
 R2946    2      B Q_RES_0402LF-4.7K,5%,1/16W,EMPA    I25 @S9S_MB_2U_LIB.S9S_MB_2U(SCH_1):PAGE230
 R2948    1      A Q_RES_0402LF-4.7K,5%,1/16W,EMPA    I30 @S9S_MB_2U_LIB.S9S_MB_2U(SCH_1):PAGE230
  U278    4      Y 74LVC1G08W57-74LVC1G08W5-7,SMLA    I31 @S9S_MB_2U_LIB.S9S_MB_2U(SCH_1):PAGE230

FM_GPU_HSC_EN_BUF_R1 @S9S_MB_2U_LIB.S9S_MB_2U(SCH_1):FM_GPU_HSC_EN_BUF_R1
   J45   D2     D2 CONN60_101062636003K02LF-CONN6A    I12 @S9S_MB_2U_LIB.S9S_MB_2U(SCH_1):PAGE233
 R2906    1      A Q_RES_0402LF-0,5%,1/16W,CHIP,CA    I37 @S9S_MB_2U_LIB.S9S_MB_2U(SCH_1):PAGE233
 C2297    1      A Q_CAP_0402-0.1UF,25V,10%,EMPTYA    I52 @S9S_MB_2U_LIB.S9S_MB_2U(SCH_1):PAGE233

FM_GPU_HSC_EN_R @S9S_MB_2U_LIB.S9S_MB_2U(SCH_1):FM_GPU_HSC_EN_R
 R2939    1      A Q_RES_0402LF-33.2,1%,1/16W,CHIA   I106 @S9S_MB_2U_LIB.S9S_MB_2U(SCH_1):PAGE314
  U249   A3  PT10B LCMXO3LF9400C5BG484C-LCMXO3LF-A   I188 @S9S_MB_2U_LIB.S9S_MB_2U(SCH_1):PAGE314

FM_GPU_PWRGD @S9S_MB_2U_LIB.S9S_MB_2U(SCH_1):FM_GPU_PWRGD
  J111   N6     N6 CONN112_10137002101LF-CONN112_A    I74 @S9S_MB_2U_LIB.S9S_MB_2U(SCH_1):PAGE148
   Q72    2     G1 MOSFET_NCH_DUAL-PJT138K,SMLF,IA    I37 @S9S_MB_2U_LIB.S9S_MB_2U(SCH_1):PAGE145
 R3513    1      A Q_RES_0402LF-54.9K,1%,1/16W,CHA   I173 @S9S_MB_2U_LIB.S9S_MB_2U(SCH_1):PAGE145
 R3512    2      B Q_RES_0402LF-100K,1%,1/16W,EMPA   I174 @S9S_MB_2U_LIB.S9S_MB_2U(SCH_1):PAGE145

FM_GPU_PWRGD_ISO @S9S_MB_2U_LIB.S9S_MB_2U(SCH_1):FM_GPU_PWRGD_ISO
 C1756    1      A Q_CAP_0402-1000PF,50V,5%,EMPTYA   I105 @S9S_MB_2U_LIB.S9S_MB_2U(SCH_1):PAGE145
 R2935    2      B Q_RES_0402LF-4.7K,5%,1/16W,CHIA   I109 @S9S_MB_2U_LIB.S9S_MB_2U(SCH_1):PAGE145
   Q72    3     D2 MOSFET_NCH_DUAL-PJT138K,SMLF,IA   I119 @S9S_MB_2U_LIB.S9S_MB_2U(SCH_1):PAGE145
 R2664    1      A Q_RES_0402LF-33.2,1%,1/16W,CHIA   I113 @S9S_MB_2U_LIB.S9S_MB_2U(SCH_1):PAGE314

FM_GPU_PWRGD_ISO_R @S9S_MB_2U_LIB.S9S_MB_2U(SCH_1):FM_GPU_PWRGD_ISO_R
 R2664    2      B Q_RES_0402LF-33.2,1%,1/16W,CHIA   I113 @S9S_MB_2U_LIB.S9S_MB_2U(SCH_1):PAGE314
  U249   F7   PT9D LCMXO3LF9400C5BG484C-LCMXO3LF-A   I188 @S9S_MB_2U_LIB.S9S_MB_2U(SCH_1):PAGE314

FM_GPU_PWRGD_N @S9S_MB_2U_LIB.S9S_MB_2U(SCH_1):FM_GPU_PWRGD_N
 R2842    2      B Q_RES_0402LF-4.7K,5%,1/16W,CHIA    I30 @S9S_MB_2U_LIB.S9S_MB_2U(SCH_1):PAGE145
   Q72    6     D1 MOSFET_NCH_DUAL-PJT138K,SMLF,IA    I37 @S9S_MB_2U_LIB.S9S_MB_2U(SCH_1):PAGE145
   Q72    5     G2 MOSFET_NCH_DUAL-PJT138K,SMLF,IA   I119 @S9S_MB_2U_LIB.S9S_MB_2U(SCH_1):PAGE145

FM_GPU_PWR_EN @S9S_MB_2U_LIB.S9S_MB_2U(SCH_1):FM_GPU_PWR_EN
 R2662    1      A Q_RES_0402LF-33.2,1%,1/16W,CHIA   I115 @S9S_MB_2U_LIB.S9S_MB_2U(SCH_1):PAGE314
  U249   A2 PT9B||L_GPLLC LCMXO3LF9400C5BG484C-LCMXO3LF-A   I188 @S9S_MB_2U_LIB.S9S_MB_2U(SCH_1):PAGE314

FM_GPU_PWR_EN_R @S9S_MB_2U_LIB.S9S_MB_2U(SCH_1):FM_GPU_PWR_EN_R
  U196    1     A0 74LVC2G17GW-74LVC2G17GW,SMLF,IA   I127 @S9S_MB_2U_LIB.S9S_MB_2U(SCH_1):PAGE140
 R2937    1      A Q_RES_0402LF-4.7K,5%,1/16W,CHIA   I160 @S9S_MB_2U_LIB.S9S_MB_2U(SCH_1):PAGE140
 R2936    2      B Q_RES_0402LF-100K,1%,1/16W,EMPA   I162 @S9S_MB_2U_LIB.S9S_MB_2U(SCH_1):PAGE140
 R2662    2      B Q_RES_0402LF-33.2,1%,1/16W,CHIA   I115 @S9S_MB_2U_LIB.S9S_MB_2U(SCH_1):PAGE314

FM_GPU_PWR_EN_R1 @S9S_MB_2U_LIB.S9S_MB_2U(SCH_1):FM_GPU_PWR_EN_R1
  U196    6     B0 74LVC2G17GW-74LVC2G17GW,SMLF,IA   I127 @S9S_MB_2U_LIB.S9S_MB_2U(SCH_1):PAGE140
 R2912    2      B Q_RES_0402LF-4.7K,5%,1/16W,EMPA   I147 @S9S_MB_2U_LIB.S9S_MB_2U(SCH_1):PAGE140
 R3508    1      A Q_RES_0402LF-54.9K,1%,1/16W,CHA   I194 @S9S_MB_2U_LIB.S9S_MB_2U(SCH_1):PAGE140
 R2925    1      A Q_RES_0402LF-49.9,1%,1/16W,CHIA   I204 @S9S_MB_2U_LIB.S9S_MB_2U(SCH_1):PAGE140

FM_GPU_PWR_EN_R_BUF @S9S_MB_2U_LIB.S9S_MB_2U(SCH_1):FM_GPU_PWR_EN_R_BUF
  J111   N4     N4 CONN112_10137002101LF-CONN112_A    I75 @S9S_MB_2U_LIB.S9S_MB_2U(SCH_1):PAGE148
 R2925    2      B Q_RES_0402LF-49.9,1%,1/16W,CHIA   I204 @S9S_MB_2U_LIB.S9S_MB_2U(SCH_1):PAGE140

FM_HBM2_HBM3_VPP_SEL @S9S_MB_2U_LIB.S9S_MB_2U(SCH_1):FM_HBM2_HBM3_VPP_SEL
  U249   Y6  PB10D LCMXO3LF9400C5BG484C-LCMXO3LF-A     I1 @S9S_MB_2U_LIB.S9S_MB_2U(SCH_1):PAGE312
 PU173    G   GATE MOSFET_N_SMLF-BSS138K,BSS138K,B    I31 @S9S_MB_2U_LIB.S9S_MB_2U(SCH_1):PAGE267
 PU174    G   GATE MOSFET_N_SMLF-BSS138K,BSS138K,B    I29 @S9S_MB_2U_LIB.S9S_MB_2U(SCH_1):PAGE285

FM_HBM_VPP_SEL_CPU0_D @S9S_MB_2U_LIB.S9S_MB_2U(SCH_1):FM_HBM_VPP_SEL_CPU0_D
PR2336    2      B Q_RES_0402LF-26.1K,0.1%,1/16W,A    I34 @S9S_MB_2U_LIB.S9S_MB_2U(SCH_1):PAGE267
 PU173    D  DRAIN MOSFET_N_SMLF-BSS138K,BSS138K,B    I31 @S9S_MB_2U_LIB.S9S_MB_2U(SCH_1):PAGE267

FM_HBM_VPP_SEL_CPU1_D @S9S_MB_2U_LIB.S9S_MB_2U(SCH_1):FM_HBM_VPP_SEL_CPU1_D
PR2381    2      B Q_RES_0402LF-26.1K,0.1%,1/16W,A    I30 @S9S_MB_2U_LIB.S9S_MB_2U(SCH_1):PAGE285
 PU174    D  DRAIN MOSFET_N_SMLF-BSS138K,BSS138K,B    I29 @S9S_MB_2U_LIB.S9S_MB_2U(SCH_1):PAGE285

FM_INTRUDER_HDR_PCH_N @S9S_MB_2U_LIB.S9S_MB_2U(SCH_1):FM_INTRUDER_HDR_PCH_N
    U4  BG8 INTRUDER_N EMMITSBURG_REV0P9-GFNOCPU04302A    I36 @S9S_MB_2U_LIB.S9S_MB_2U(SCH_1):PAGE174
 R2966    2      B Q_RES_0402LF-1M,1%,1/16W,CHIP,A    I96 @S9S_MB_2U_LIB.S9S_MB_2U(SCH_1):PAGE174

FM_JTAG_BMC_MUX_SEL @S9S_MB_2U_LIB.S9S_MB_2U(SCH_1):FM_JTAG_BMC_MUX_SEL
   U97    8     1S NX3L2267GM-NX3L2267GM,SMLF,IC,A    I38 @S9S_MB_2U_LIB.S9S_MB_2U(SCH_1):PAGE226
   U97    7     2S NX3L2267GM-NX3L2267GM,SMLF,IC,A    I38 @S9S_MB_2U_LIB.S9S_MB_2U(SCH_1):PAGE226
   U96    8     1S NX3L2267GM-NX3L2267GM,SMLF,IC,A    I68 @S9S_MB_2U_LIB.S9S_MB_2U(SCH_1):PAGE226
   U96    7     2S NX3L2267GM-NX3L2267GM,SMLF,IC,A    I68 @S9S_MB_2U_LIB.S9S_MB_2U(SCH_1):PAGE226
 R1814    1      A Q_RES_0402LF-1K,1%,1/16W,EMPTYA    I77 @S9S_MB_2U_LIB.S9S_MB_2U(SCH_1):PAGE226
 R1813    2      B Q_RES_0402LF-10K,1%,1/16W,EMPTA    I79 @S9S_MB_2U_LIB.S9S_MB_2U(SCH_1):PAGE226
 R4088    2      B Q_RES_0402LF-0,5%,1/16W,CHIP,CA   I166 @S9S_MB_2U_LIB.S9S_MB_2U(SCH_1):PAGE313
 R1833    2      B Q_RES_0402LF-0,5%,1/16W,EMPTY,A   I167 @S9S_MB_2U_LIB.S9S_MB_2U(SCH_1):PAGE313

FM_JTAG_BMC_MUX_SEL_FROM_BMC_R @S9S_MB_2U_LIB.S9S_MB_2U(SCH_1):FM_JTAG_BMC_MUX_SEL_FROM_BMC_R
 R4088    1      A Q_RES_0402LF-0,5%,1/16W,CHIP,CA   I166 @S9S_MB_2U_LIB.S9S_MB_2U(SCH_1):PAGE313
 R4087    1      A Q_RES_0402LF-33.2,1%,1/16W,CHIA    I28 @S9S_MB_2U_LIB.S9S_MB_2U(SCH_1):PAGE227

FM_JTAG_BMC_MUX_SEL_FROM_BMC_R2 @S9S_MB_2U_LIB.S9S_MB_2U(SCH_1):FM_JTAG_BMC_MUX_SEL_FROM_BMC_R2
 R4087    2      B Q_RES_0402LF-33.2,1%,1/16W,CHIA    I28 @S9S_MB_2U_LIB.S9S_MB_2U(SCH_1):PAGE227
   J41  A43 GND_A43 SCONN168_ME1016810202011-SCONNA   I173 @S9S_MB_2U_LIB.S9S_MB_2U(SCH_1):PAGE227

FM_JTAG_BMC_MUX_SEL_R @S9S_MB_2U_LIB.S9S_MB_2U(SCH_1):FM_JTAG_BMC_MUX_SEL_R
  U249  U22  PR24C LCMXO3LF9400C5BG484C-LCMXO3LF-A     I1 @S9S_MB_2U_LIB.S9S_MB_2U(SCH_1):PAGE313
 R1833    1      A Q_RES_0402LF-0,5%,1/16W,EMPTY,A   I167 @S9S_MB_2U_LIB.S9S_MB_2U(SCH_1):PAGE313

FM_JTAG_ODT_DISABLE @S9S_MB_2U_LIB.S9S_MB_2U(SCH_1):FM_JTAG_ODT_DISABLE
    U4 AW10 GPPC_S_10 EMMITSBURG_REV0P9-GFNOCPU04302A    I27 @S9S_MB_2U_LIB.S9S_MB_2U(SCH_1):PAGE177
  R613    2      B Q_RES_0402LF-10K,1%,1/16W,CHIPA    I18 @S9S_MB_2U_LIB.S9S_MB_2U(SCH_1):PAGE187
  R614    1      A Q_RES_0402LF-1K,1%,1/16W,EMPTYA    I23 @S9S_MB_2U_LIB.S9S_MB_2U(SCH_1):PAGE187

FM_JTAG_TCK_MUX_SEL @S9S_MB_2U_LIB.S9S_MB_2U(SCH_1):FM_JTAG_TCK_MUX_SEL
   U85    6      S NC7SB3157_SMLF-NC7SB3157P6X,NCA   I109 @S9S_MB_2U_LIB.S9S_MB_2U(SCH_1):PAGE137
 R1365    1      A Q_RES_0402LF-1K,1%,1/16W,CHIP,A   I116 @S9S_MB_2U_LIB.S9S_MB_2U(SCH_1):PAGE137
 R4609    2      B Q_RES_0402LF-33.2,1%,1/16W,CHIA   I194 @S9S_MB_2U_LIB.S9S_MB_2U(SCH_1):PAGE313

FM_JTAG_TCK_MUX_SEL_R @S9S_MB_2U_LIB.S9S_MB_2U(SCH_1):FM_JTAG_TCK_MUX_SEL_R
  U249  U17  PR29C LCMXO3LF9400C5BG484C-LCMXO3LF-A     I1 @S9S_MB_2U_LIB.S9S_MB_2U(SCH_1):PAGE313
 R4609    1      A Q_RES_0402LF-33.2,1%,1/16W,CHIA   I194 @S9S_MB_2U_LIB.S9S_MB_2U(SCH_1):PAGE313

FM_LM75_2_ALERT_N @S9S_MB_2U_LIB.S9S_MB_2U(SCH_1):FM_LM75_2_ALERT_N
 R4213    2      B Q_RES_0402LF-0,5%,1/16W,CHIP,CA   I115 @S9S_MB_2U_LIB.S9S_MB_2U(SCH_1):PAGE161
  U272    3     OS LM75BD-LM75BD,SMLF,IC,AL0075BDA   I166 @S9S_MB_2U_LIB.S9S_MB_2U(SCH_1):PAGE161

FM_LM75_3_ALERT_N @S9S_MB_2U_LIB.S9S_MB_2U(SCH_1):FM_LM75_3_ALERT_N
 R4212    2      B Q_RES_0402LF-0,5%,1/16W,CHIP,CA   I135 @S9S_MB_2U_LIB.S9S_MB_2U(SCH_1):PAGE161
  U273    3     OS LM75BD-LM75BD,SMLF,IC,AL0075BDA   I167 @S9S_MB_2U_LIB.S9S_MB_2U(SCH_1):PAGE161

FM_LPC_ESPI_SEL @S9S_MB_2U_LIB.S9S_MB_2U(SCH_1):FM_LPC_ESPI_SEL
 R1763    2      B Q_RES_0402LF-10K,1%,1/16W,EMPTA     I7 @S9S_MB_2U_LIB.S9S_MB_2U(SCH_1):PAGE243
 R1764    1      A Q_RES_0402LF-1K,1%,1/16W,EMPTYA     I8 @S9S_MB_2U_LIB.S9S_MB_2U(SCH_1):PAGE243
  U307    D  DRAIN MOSFET_N_SMLF-BSS138K,BSS138K,A    I15 @S9S_MB_2U_LIB.S9S_MB_2U(SCH_1):PAGE243
 R4176    2      B Q_RES_0402LF-10K,1%,1/16W,CHIPA    I16 @S9S_MB_2U_LIB.S9S_MB_2U(SCH_1):PAGE243
   J41   B9  BIF2# SCONN168_ME1016810202011-SCONNA   I173 @S9S_MB_2U_LIB.S9S_MB_2U(SCH_1):PAGE227

FM_LT_KEY_DOWNGRADE_N @S9S_MB_2U_LIB.S9S_MB_2U(SCH_1):FM_LT_KEY_DOWNGRADE_N
    U4   L4 GPPC_H_19 EMMITSBURG_REV0P9-GFNOCPU04302A    I22 @S9S_MB_2U_LIB.S9S_MB_2U(SCH_1):PAGE176
  R619    2      B Q_RES_0402LF-10K,1%,1/16W,CHIPA    I48 @S9S_MB_2U_LIB.S9S_MB_2U(SCH_1):PAGE187

FM_M2_E1S_E6_PEDET @S9S_MB_2U_LIB.S9S_MB_2U(SCH_1):FM_M2_E1S_E6_PEDET
    U4 BB24 GPP_E_6_SATA0_USB3_XPCIE_0 EMMITSBURG_REV0P9-GFNOCPU04302A    I22 @S9S_MB_2U_LIB.S9S_MB_2U(SCH_1):PAGE176
 R2510    2      B Q_RES_0402LF-10K,1%,1/16W,EMPTA   I175 @S9S_MB_2U_LIB.S9S_MB_2U(SCH_1):PAGE176
 R2511    1      A Q_RES_0402LF-1K,1%,1/16W,EMPTYA   I176 @S9S_MB_2U_LIB.S9S_MB_2U(SCH_1):PAGE176

FM_M2_SSD0_E7_PEDET @S9S_MB_2U_LIB.S9S_MB_2U(SCH_1):FM_M2_SSD0_E7_PEDET
    U4 AW32 GPP_E_7_SATA0_USB3_XPCIE_1 EMMITSBURG_REV0P9-GFNOCPU04302A    I22 @S9S_MB_2U_LIB.S9S_MB_2U(SCH_1):PAGE176
 R2508    2      B Q_RES_0402LF-10K,1%,1/16W,EMPTA   I173 @S9S_MB_2U_LIB.S9S_MB_2U(SCH_1):PAGE176
 R2509    1      A Q_RES_0402LF-1K,1%,1/16W,EMPTYA   I174 @S9S_MB_2U_LIB.S9S_MB_2U(SCH_1):PAGE176
 R2526    2      B Q_RES_0402LF-0,5%,1/16W,CHIP,CA   I247 @S9S_MB_2U_LIB.S9S_MB_2U(SCH_1):PAGE182

FM_M2_SSD_0_PEDET @S9S_MB_2U_LIB.S9S_MB_2U(SCH_1):FM_M2_SSD_0_PEDET
 R1396    1      A Q_RES_0402LF-10K,1%,1/16W,CHIPA   I167 @S9S_MB_2U_LIB.S9S_MB_2U(SCH_1):PAGE182
   J59   69  PEDET SCONN75K_APCI0155P004A-SCONN75A   I178 @S9S_MB_2U_LIB.S9S_MB_2U(SCH_1):PAGE182
 R2526    1      A Q_RES_0402LF-0,5%,1/16W,CHIP,CA   I247 @S9S_MB_2U_LIB.S9S_MB_2U(SCH_1):PAGE182

FM_MB_PDB_SMB9_R_EN @S9S_MB_2U_LIB.S9S_MB_2U(SCH_1):FM_MB_PDB_SMB9_R_EN
 R2796    2      B Q_RES_0402LF-33.2,1%,1/16W,CHIA    I10 @S9S_MB_2U_LIB.S9S_MB_2U(SCH_1):PAGE233
  U192    1 ENABLE LTC4307CMS8-LTC4307CMS8,SMLF,IA    I16 @S9S_MB_2U_LIB.S9S_MB_2U(SCH_1):PAGE233

FM_ME_AUTHN_FAIL @S9S_MB_2U_LIB.S9S_MB_2U(SCH_1):FM_ME_AUTHN_FAIL
    U4 AW20 GPP_E_15_SATA2_SLOAD_SATA2_GP EMMITSBURG_REV0P9-GFNOCPU04302A    I22 @S9S_MB_2U_LIB.S9S_MB_2U(SCH_1):PAGE176
 R1554    2      B Q_RES_0402LF-10K,1%,1/16W,CHIPA    I62 @S9S_MB_2U_LIB.S9S_MB_2U(SCH_1):PAGE192
  U249   Y8  PB18C LCMXO3LF9400C5BG484C-LCMXO3LF-A     I1 @S9S_MB_2U_LIB.S9S_MB_2U(SCH_1):PAGE312

FM_ME_BT_DONE @S9S_MB_2U_LIB.S9S_MB_2U(SCH_1):FM_ME_BT_DONE
    U4 AW29 GPP_E_16_SATA2_SDATAOUT_SATA2_DEVSLP EMMITSBURG_REV0P9-GFNOCPU04302A    I22 @S9S_MB_2U_LIB.S9S_MB_2U(SCH_1):PAGE176
   R71    2      B Q_RES_0402LF-10K,1%,1/16W,CHIPA    I60 @S9S_MB_2U_LIB.S9S_MB_2U(SCH_1):PAGE192
  U249  T14  PB32B LCMXO3LF9400C5BG484C-LCMXO3LF-A     I1 @S9S_MB_2U_LIB.S9S_MB_2U(SCH_1):PAGE312

FM_ME_RCVR_N @S9S_MB_2U_LIB.S9S_MB_2U(SCH_1):FM_ME_RCVR_N
    U4  AG7 GPP_L_4 EMMITSBURG_REV0P9-GFNOCPU04302A    I22 @S9S_MB_2U_LIB.S9S_MB_2U(SCH_1):PAGE176
 R1342    2      B Q_RES_0402LF-10K,1%,1/16W,CHIPA   I114 @S9S_MB_2U_LIB.S9S_MB_2U(SCH_1):PAGE189
  J104   12     12 CONN14_210HP207GBR1-CONN14_210A   I134 @S9S_MB_2U_LIB.S9S_MB_2U(SCH_1):PAGE189

FM_MFG_MODE @S9S_MB_2U_LIB.S9S_MB_2U(SCH_1):FM_MFG_MODE
    U4 AG10 GPP_L_6 EMMITSBURG_REV0P9-GFNOCPU04302A    I22 @S9S_MB_2U_LIB.S9S_MB_2U(SCH_1):PAGE176
 R1299    1      A Q_RES_0402LF-10K,1%,1/16W,CHIPA    I21 @S9S_MB_2U_LIB.S9S_MB_2U(SCH_1):PAGE188
 R1298    2      B Q_RES_0402LF-1K,1%,1/16W,EMPTYA    I22 @S9S_MB_2U_LIB.S9S_MB_2U(SCH_1):PAGE188

FM_NCSI_OCP_V3_1_R_OE @S9S_MB_2U_LIB.S9S_MB_2U(SCH_1):FM_NCSI_OCP_V3_1_R_OE
  U249  Y14  PB33C LCMXO3LF9400C5BG484C-LCMXO3LF-A     I1 @S9S_MB_2U_LIB.S9S_MB_2U(SCH_1):PAGE312
 R2474    1      A Q_RES_0402LF-0,5%,1/16W,EMPTY,A    I19 @S9S_MB_2U_LIB.S9S_MB_2U(SCH_1):PAGE151

FM_NCSI_OCP_V3_2_R_OE @S9S_MB_2U_LIB.S9S_MB_2U(SCH_1):FM_NCSI_OCP_V3_2_R_OE
 R3206    1      A Q_RES_0402LF-0,5%,1/16W,EMPTY,A    I12 @S9S_MB_2U_LIB.S9S_MB_2U(SCH_1):PAGE307
  U249  B14  PT30B LCMXO3LF9400C5BG484C-LCMXO3LF-A   I188 @S9S_MB_2U_LIB.S9S_MB_2U(SCH_1):PAGE314

FM_OCP_SFF_PWR_GOOD @S9S_MB_2U_LIB.S9S_MB_2U(SCH_1):FM_OCP_SFF_PWR_GOOD
 R3132    2      B Q_RES_0402LF-100K,1%,1/16W,CHIA    I35 @S9S_MB_2U_LIB.S9S_MB_2U(SCH_1):PAGE150
   J37  OB1 NIC_PWR_GOOD SCONN168_ME1016810202011-SCONNA   I199 @S9S_MB_2U_LIB.S9S_MB_2U(SCH_1):PAGE150
 R1606    1      A Q_RES_0402LF-33.2,1%,1/16W,CHIA   I109 @S9S_MB_2U_LIB.S9S_MB_2U(SCH_1):PAGE314
   U66    2      A 74LVC1G126SE7-74LVC1G126SE-7,SA    I15 @S9S_MB_2U_LIB.S9S_MB_2U(SCH_1):PAGE151

FM_OCP_SFF_PWR_GOOD_R @S9S_MB_2U_LIB.S9S_MB_2U(SCH_1):FM_OCP_SFF_PWR_GOOD_R
 R1606    2      B Q_RES_0402LF-33.2,1%,1/16W,CHIA   I109 @S9S_MB_2U_LIB.S9S_MB_2U(SCH_1):PAGE314
  U249   A7  PT14B LCMXO3LF9400C5BG484C-LCMXO3LF-A   I188 @S9S_MB_2U_LIB.S9S_MB_2U(SCH_1):PAGE314

FM_OCP_V3_2_PWR_GOOD @S9S_MB_2U_LIB.S9S_MB_2U(SCH_1):FM_OCP_V3_2_PWR_GOOD
  R413    2      B Q_RES_0402LF-100K,1%,1/16W,CHIA    I43 @S9S_MB_2U_LIB.S9S_MB_2U(SCH_1):PAGE146
   J35  OB1 NIC_PWR_GOOD SCONN168_ME1016810202011-SCONNA   I303 @S9S_MB_2U_LIB.S9S_MB_2U(SCH_1):PAGE146
  U286    2      A 74LVC1G126SE7-74LVC1G126SE-7,SA    I80 @S9S_MB_2U_LIB.S9S_MB_2U(SCH_1):PAGE307
 R3230    1      A Q_RES_0402LF-33.2,1%,1/16W,CHIA   I110 @S9S_MB_2U_LIB.S9S_MB_2U(SCH_1):PAGE314

FM_OCP_V3_2_PWR_GOOD_R @S9S_MB_2U_LIB.S9S_MB_2U(SCH_1):FM_OCP_V3_2_PWR_GOOD_R
 R3230    2      B Q_RES_0402LF-33.2,1%,1/16W,CHIA   I110 @S9S_MB_2U_LIB.S9S_MB_2U(SCH_1):PAGE314
  U249   B6  PT14A LCMXO3LF9400C5BG484C-LCMXO3LF-A   I188 @S9S_MB_2U_LIB.S9S_MB_2U(SCH_1):PAGE314

FM_P12V_HSC_EN_N @S9S_MB_2U_LIB.S9S_MB_2U(SCH_1):FM_P12V_HSC_EN_N
  U158    D      D MOSFET_NCH_GDS_ESD_PROTECTED-2A     I6 @S9S_MB_2U_LIB.S9S_MB_2U(SCH_1):PAGE234
 R2529    1      A Q_RES_0402LF-0,5%,1/16W,CHIP,CA     I7 @S9S_MB_2U_LIB.S9S_MB_2U(SCH_1):PAGE234
 R2528    2      B Q_RES_0402LF-100K,1%,1/16W,CHIA     I8 @S9S_MB_2U_LIB.S9S_MB_2U(SCH_1):PAGE234

FM_P12V_HSC_EN_R @S9S_MB_2U_LIB.S9S_MB_2U(SCH_1):FM_P12V_HSC_EN_R
 R2531    2      B Q_RES_0402LF-0,5%,1/16W,CHIP,CA     I3 @S9S_MB_2U_LIB.S9S_MB_2U(SCH_1):PAGE234
  U158    G      G MOSFET_NCH_GDS_ESD_PROTECTED-2A     I6 @S9S_MB_2U_LIB.S9S_MB_2U(SCH_1):PAGE234

FM_P12V_HSC_EN_R_N @S9S_MB_2U_LIB.S9S_MB_2U(SCH_1):FM_P12V_HSC_EN_R_N
 R2529    2      B Q_RES_0402LF-0,5%,1/16W,CHIP,CA     I7 @S9S_MB_2U_LIB.S9S_MB_2U(SCH_1):PAGE234
   Q54    G      G MOSFET_NCH_GDS_ESD_PROTECTED-2A    I14 @S9S_MB_2U_LIB.S9S_MB_2U(SCH_1):PAGE234

FM_P1V05_PCH_AUX_EN @S9S_MB_2U_LIB.S9S_MB_2U(SCH_1):FM_P1V05_PCH_AUX_EN
  U249  G20   PR6B LCMXO3LF9400C5BG484C-LCMXO3LF-A     I1 @S9S_MB_2U_LIB.S9S_MB_2U(SCH_1):PAGE313
 R1389    1      A Q_RES_0402LF-0,5%,1/16W,CHIP,CA    I27 @S9S_MB_2U_LIB.S9S_MB_2U(SCH_1):PAGE248

FM_P1V05_PCH_AUX_R_EN @S9S_MB_2U_LIB.S9S_MB_2U(SCH_1):FM_P1V05_PCH_AUX_R_EN
PC2286    1      A Q_CAP_0402-1000PF,50V,5%,EMPTYA     I8 @S9S_MB_2U_LIB.S9S_MB_2U(SCH_1):PAGE248
PR1649    1      A Q_RES_0402LF-2K,1%,1/16W,CHIP,A     I9 @S9S_MB_2U_LIB.S9S_MB_2U(SCH_1):PAGE248
PR1647    2      B Q_RES_0402LF-10K,1%,1/16W,EMPTA    I26 @S9S_MB_2U_LIB.S9S_MB_2U(SCH_1):PAGE248
 R1389    2      B Q_RES_0402LF-0,5%,1/16W,CHIP,CA    I27 @S9S_MB_2U_LIB.S9S_MB_2U(SCH_1):PAGE248
  PU73    8     EN RS53319LR-RS53319LR,SMLF,IC,ALA    I11 @S9S_MB_2U_LIB.S9S_MB_2U(SCH_1):PAGE248

FM_P2E_BUF2_EQA0 @S9S_MB_2U_LIB.S9S_MB_2U(SCH_1):FM_P2E_BUF2_EQA0
  U328   10 EQA0||AD0 DS125BR111RTWR-DS125BR111RTWR,A    I95 @S9S_MB_2U_LIB.S9S_MB_2U(SCH_1):PAGE159
 R4650    1      A Q_RES_0402LF-1K,1%,1/16W,EMPTYA    I71 @S9S_MB_2U_LIB.S9S_MB_2U(SCH_1):PAGE159
 R4649    2      B Q_RES_0402LF-1K,1%,1/16W,EMPTYA    I74 @S9S_MB_2U_LIB.S9S_MB_2U(SCH_1):PAGE159

FM_P2E_BUF2_EQA1 @S9S_MB_2U_LIB.S9S_MB_2U(SCH_1):FM_P2E_BUF2_EQA1
 R4654    1      A Q_RES_0402LF-1K,1%,1/16W,CHIP,A    I67 @S9S_MB_2U_LIB.S9S_MB_2U(SCH_1):PAGE159
  U328    9 EQA1||AD1 DS125BR111RTWR-DS125BR111RTWR,A    I95 @S9S_MB_2U_LIB.S9S_MB_2U(SCH_1):PAGE159
 R4648    2      B Q_RES_0402LF-1K,1%,1/16W,EMPTYA    I72 @S9S_MB_2U_LIB.S9S_MB_2U(SCH_1):PAGE159

FM_P2E_BUF2_EQB0 @S9S_MB_2U_LIB.S9S_MB_2U(SCH_1):FM_P2E_BUF2_EQB0
 R4646    1      A Q_RES_0402LF-1K,1%,1/16W,EMPTYA    I15 @S9S_MB_2U_LIB.S9S_MB_2U(SCH_1):PAGE159
 R4645    2      B Q_RES_0402LF-1K,1%,1/16W,EMPTYA    I16 @S9S_MB_2U_LIB.S9S_MB_2U(SCH_1):PAGE159
  U328    1 EQB0||AD3 DS125BR111RTWR-DS125BR111RTWR,A    I95 @S9S_MB_2U_LIB.S9S_MB_2U(SCH_1):PAGE159

FM_P2E_BUF2_EQB1 @S9S_MB_2U_LIB.S9S_MB_2U(SCH_1):FM_P2E_BUF2_EQB1
  U328    2 EQB1||AD2 DS125BR111RTWR-DS125BR111RTWR,A    I95 @S9S_MB_2U_LIB.S9S_MB_2U(SCH_1):PAGE159
 R4694    1      A Q_RES_0402LF-1K,1%,1/16W,CHIP,A    I10 @S9S_MB_2U_LIB.S9S_MB_2U(SCH_1):PAGE159
 R4644    2      B Q_RES_0402LF-1K,1%,1/16W,EMPTYA    I11 @S9S_MB_2U_LIB.S9S_MB_2U(SCH_1):PAGE159

FM_P2E_BUF2_RXDET @S9S_MB_2U_LIB.S9S_MB_2U(SCH_1):FM_P2E_BUF2_RXDET
 R4655    2      B Q_RES_0402LF-1K,1%,1/16W,EMPTYA    I62 @S9S_MB_2U_LIB.S9S_MB_2U(SCH_1):PAGE159
  U328   18 RXDET||DONE# DS125BR111RTWR-DS125BR111RTWR,A    I95 @S9S_MB_2U_LIB.S9S_MB_2U(SCH_1):PAGE159
 R3381    1      A Q_RES_0402LF-1K,1%,1/16W,EMPTYA    I61 @S9S_MB_2U_LIB.S9S_MB_2U(SCH_1):PAGE159

FM_P2E_BUF2_SD_TH @S9S_MB_2U_LIB.S9S_MB_2U(SCH_1):FM_P2E_BUF2_SD_TH
 R4656    2      B Q_RES_0402LF-1K,1%,1/16W,CHIP,A    I66 @S9S_MB_2U_LIB.S9S_MB_2U(SCH_1):PAGE159
  U328   14  SD_TH DS125BR111RTWR-DS125BR111RTWR,A    I95 @S9S_MB_2U_LIB.S9S_MB_2U(SCH_1):PAGE159
 R4657    1      A Q_RES_0402LF-1K,1%,1/16W,EMPTYA    I65 @S9S_MB_2U_LIB.S9S_MB_2U(SCH_1):PAGE159

FM_P2E_BUF2_VODA_DB @S9S_MB_2U_LIB.S9S_MB_2U(SCH_1):FM_P2E_BUF2_VODA_DB
 R4647    1      A Q_RES_0402LF-1K,1%,1/16W,CHIP,A     I4 @S9S_MB_2U_LIB.S9S_MB_2U(SCH_1):PAGE159
  U328    4 SDA||VODA_DB DS125BR111RTWR-DS125BR111RTWR,A    I95 @S9S_MB_2U_LIB.S9S_MB_2U(SCH_1):PAGE159
 R4643    2      B Q_RES_0402LF-1K,1%,1/16W,EMPTYA    I13 @S9S_MB_2U_LIB.S9S_MB_2U(SCH_1):PAGE159

FM_P2E_BUF2_VODB_DB @S9S_MB_2U_LIB.S9S_MB_2U(SCH_1):FM_P2E_BUF2_VODB_DB
 R4653    1      A Q_RES_0402LF-1K,1%,1/16W,CHIP,A     I2 @S9S_MB_2U_LIB.S9S_MB_2U(SCH_1):PAGE159
  U328    5 SCL||VODB_DB DS125BR111RTWR-DS125BR111RTWR,A    I95 @S9S_MB_2U_LIB.S9S_MB_2U(SCH_1):PAGE159
 R4642    2      B Q_RES_0402LF-1K,1%,1/16W,EMPTYA     I7 @S9S_MB_2U_LIB.S9S_MB_2U(SCH_1):PAGE159

FM_P2E_BUF2_VOD_SEL @S9S_MB_2U_LIB.S9S_MB_2U(SCH_1):FM_P2E_BUF2_VOD_SEL
 R3386    2      B Q_RES_0402LF-1K,1%,1/16W,CHIP,A    I81 @S9S_MB_2U_LIB.S9S_MB_2U(SCH_1):PAGE159
  U328   17 VOD_SEL||READEN# DS125BR111RTWR-DS125BR111RTWR,A    I95 @S9S_MB_2U_LIB.S9S_MB_2U(SCH_1):PAGE159
 R4658    1      A Q_RES_0402LF-1K,1%,1/16W,EMPTYA    I80 @S9S_MB_2U_LIB.S9S_MB_2U(SCH_1):PAGE159

FM_P2E_EN2_N @S9S_MB_2U_LIB.S9S_MB_2U(SCH_1):FM_P2E_EN2_N
  U328    6   PWDN DS125BR111RTWR-DS125BR111RTWR,A    I95 @S9S_MB_2U_LIB.S9S_MB_2U(SCH_1):PAGE159
 R4651    1      A Q_RES_0402LF-0,5%,1/16W,CHIP,CA   I102 @S9S_MB_2U_LIB.S9S_MB_2U(SCH_1):PAGE159

FM_P2E_EN_N @S9S_MB_2U_LIB.S9S_MB_2U(SCH_1):FM_P2E_EN_N
 R4537    1      A Q_RES_0402LF-0,5%,1/16W,CHIP,CA    I73 @S9S_MB_2U_LIB.S9S_MB_2U(SCH_1):PAGE136
  U237   11    EN# PI3EQX12902AZLEX-PI3EQX12902AZA    I50 @S9S_MB_2U_LIB.S9S_MB_2U(SCH_1):PAGE136

FM_P2E_EQA0 @S9S_MB_2U_LIB.S9S_MB_2U(SCH_1):FM_P2E_EQA0
 R3277    2      B Q_RES_0402LF-1K,1%,1/16W,EMPTYA    I16 @S9S_MB_2U_LIB.S9S_MB_2U(SCH_1):PAGE136
 R3274    1      A Q_RES_0402LF-68K,1%,1/16W,EMPTA     I6 @S9S_MB_2U_LIB.S9S_MB_2U(SCH_1):PAGE136
 R3278    1      A Q_RES_0402LF-1K,1%,1/16W,CHIP,A     I8 @S9S_MB_2U_LIB.S9S_MB_2U(SCH_1):PAGE136
  U237   21   EQA0 PI3EQX12902AZLEX-PI3EQX12902AZA    I50 @S9S_MB_2U_LIB.S9S_MB_2U(SCH_1):PAGE136

FM_P2E_EQA1 @S9S_MB_2U_LIB.S9S_MB_2U(SCH_1):FM_P2E_EQA1
 R3268    1      A Q_RES_0402LF-68K,1%,1/16W,EMPTA     I2 @S9S_MB_2U_LIB.S9S_MB_2U(SCH_1):PAGE136
 R3272    1      A Q_RES_0402LF-1K,1%,1/16W,EMPTYA     I4 @S9S_MB_2U_LIB.S9S_MB_2U(SCH_1):PAGE136
 R3271    2      B Q_RES_0402LF-1K,1%,1/16W,EMPTYA     I9 @S9S_MB_2U_LIB.S9S_MB_2U(SCH_1):PAGE136
  U237   26   EQA1 PI3EQX12902AZLEX-PI3EQX12902AZA    I50 @S9S_MB_2U_LIB.S9S_MB_2U(SCH_1):PAGE136

FM_P2E_EQB0 @S9S_MB_2U_LIB.S9S_MB_2U(SCH_1):FM_P2E_EQB0
 R3282    1      A Q_RES_0402LF-68K,1%,1/16W,EMPTA    I27 @S9S_MB_2U_LIB.S9S_MB_2U(SCH_1):PAGE136
  U237   20   EQB0 PI3EQX12902AZLEX-PI3EQX12902AZA    I50 @S9S_MB_2U_LIB.S9S_MB_2U(SCH_1):PAGE136
 R3284    1      A Q_RES_0402LF-1K,1%,1/16W,CHIP,A    I56 @S9S_MB_2U_LIB.S9S_MB_2U(SCH_1):PAGE136
 R3283    2      B Q_RES_0402LF-1K,1%,1/16W,EMPTYA    I57 @S9S_MB_2U_LIB.S9S_MB_2U(SCH_1):PAGE136

FM_P2E_EQB1 @S9S_MB_2U_LIB.S9S_MB_2U(SCH_1):FM_P2E_EQB1
 R3279    1      A Q_RES_0402LF-68K,1%,1/16W,EMPTA    I23 @S9S_MB_2U_LIB.S9S_MB_2U(SCH_1):PAGE136
 R3281    1      A Q_RES_0402LF-1K,1%,1/16W,EMPTYA    I25 @S9S_MB_2U_LIB.S9S_MB_2U(SCH_1):PAGE136
 R3280    2      B Q_RES_0402LF-1K,1%,1/16W,EMPTYA    I32 @S9S_MB_2U_LIB.S9S_MB_2U(SCH_1):PAGE136
  U237   15   EQB1 PI3EQX12902AZLEX-PI3EQX12902AZA    I50 @S9S_MB_2U_LIB.S9S_MB_2U(SCH_1):PAGE136

FM_P2E_FGA @S9S_MB_2U_LIB.S9S_MB_2U(SCH_1):FM_P2E_FGA
 R3273    1      A Q_RES_0402LF-68K,1%,1/16W,EMPTA    I18 @S9S_MB_2U_LIB.S9S_MB_2U(SCH_1):PAGE136
 R3276    1      A Q_RES_0402LF-1K,1%,1/16W,EMPTYA    I20 @S9S_MB_2U_LIB.S9S_MB_2U(SCH_1):PAGE136
 R3275    2      B Q_RES_0402LF-1K,1%,1/16W,EMPTYA    I21 @S9S_MB_2U_LIB.S9S_MB_2U(SCH_1):PAGE136
  U237   27    FGA PI3EQX12902AZLEX-PI3EQX12902AZA    I50 @S9S_MB_2U_LIB.S9S_MB_2U(SCH_1):PAGE136

FM_P2E_FGB @S9S_MB_2U_LIB.S9S_MB_2U(SCH_1):FM_P2E_FGB
 R3267    1      A Q_RES_0402LF-68K,1%,1/16W,EMPTA    I12 @S9S_MB_2U_LIB.S9S_MB_2U(SCH_1):PAGE136
 R3270    1      A Q_RES_0402LF-1K,1%,1/16W,EMPTYA    I14 @S9S_MB_2U_LIB.S9S_MB_2U(SCH_1):PAGE136
 R3269    2      B Q_RES_0402LF-1K,1%,1/16W,EMPTYA    I15 @S9S_MB_2U_LIB.S9S_MB_2U(SCH_1):PAGE136
  U237   14    FGB PI3EQX12902AZLEX-PI3EQX12902AZA    I50 @S9S_MB_2U_LIB.S9S_MB_2U(SCH_1):PAGE136

FM_P2E_MODE @S9S_MB_2U_LIB.S9S_MB_2U(SCH_1):FM_P2E_MODE
 R3293    1      A Q_RES_0402LF-4.7K,1%,1/16W,EMPA    I88 @S9S_MB_2U_LIB.S9S_MB_2U(SCH_1):PAGE136
  U237   30   MODE PI3EQX12902AZLEX-PI3EQX12902AZA    I50 @S9S_MB_2U_LIB.S9S_MB_2U(SCH_1):PAGE136
 R3266    2      B Q_RES_0402LF-4.7K,1%,1/16W,CHIA    I89 @S9S_MB_2U_LIB.S9S_MB_2U(SCH_1):PAGE136

FM_P2E_SWA @S9S_MB_2U_LIB.S9S_MB_2U(SCH_1):FM_P2E_SWA
 R3290    1      A Q_RES_0402LF-1K,1%,1/16W,EMPTYA    I68 @S9S_MB_2U_LIB.S9S_MB_2U(SCH_1):PAGE136
 R3289    2      B Q_RES_0402LF-1K,1%,1/16W,EMPTYA    I69 @S9S_MB_2U_LIB.S9S_MB_2U(SCH_1):PAGE136
  U237   29    SWA PI3EQX12902AZLEX-PI3EQX12902AZA    I50 @S9S_MB_2U_LIB.S9S_MB_2U(SCH_1):PAGE136
 R3288    1      A Q_RES_0402LF-68K,1%,1/16W,EMPTA    I66 @S9S_MB_2U_LIB.S9S_MB_2U(SCH_1):PAGE136

FM_P2E_SWB @S9S_MB_2U_LIB.S9S_MB_2U(SCH_1):FM_P2E_SWB
  U237   12    SWB PI3EQX12902AZLEX-PI3EQX12902AZA    I50 @S9S_MB_2U_LIB.S9S_MB_2U(SCH_1):PAGE136
 R3285    1      A Q_RES_0402LF-68K,1%,1/16W,EMPTA    I61 @S9S_MB_2U_LIB.S9S_MB_2U(SCH_1):PAGE136
 R3287    1      A Q_RES_0402LF-1K,1%,1/16W,EMPTYA    I63 @S9S_MB_2U_LIB.S9S_MB_2U(SCH_1):PAGE136
 R3286    2      B Q_RES_0402LF-1K,1%,1/16W,EMPTYA    I64 @S9S_MB_2U_LIB.S9S_MB_2U(SCH_1):PAGE136

FM_P5V_EN @S9S_MB_2U_LIB.S9S_MB_2U(SCH_1):FM_P5V_EN
  U249  G21   PR6A LCMXO3LF9400C5BG484C-LCMXO3LF-A     I1 @S9S_MB_2U_LIB.S9S_MB_2U(SCH_1):PAGE313
 R1640    1      A Q_RES_0402LF-0,5%,1/16W,CHIP,CA     I9 @S9S_MB_2U_LIB.S9S_MB_2U(SCH_1):PAGE246

FM_PASSWORD_CLEAR_N @S9S_MB_2U_LIB.S9S_MB_2U(SCH_1):FM_PASSWORD_CLEAR_N
    U4  AB8 GPP_L_5 EMMITSBURG_REV0P9-GFNOCPU04302A    I22 @S9S_MB_2U_LIB.S9S_MB_2U(SCH_1):PAGE176
 R1343    2      B Q_RES_0402LF-10K,1%,1/16W,CHIPA   I113 @S9S_MB_2U_LIB.S9S_MB_2U(SCH_1):PAGE189
  J104   14     14 CONN14_210HP207GBR1-CONN14_210A   I134 @S9S_MB_2U_LIB.S9S_MB_2U(SCH_1):PAGE189

FM_PCHHOT_N @S9S_MB_2U_LIB.S9S_MB_2U(SCH_1):FM_PCHHOT_N
    U4  AH2 GPP_D_12_PCHHOT_N EMMITSBURG_REV0P9-GFNOCPU04302A    I93 @S9S_MB_2U_LIB.S9S_MB_2U(SCH_1):PAGE175
  R474    1      A Q_RES_0402LF-33.2,1%,1/16W,CHIA   I213 @S9S_MB_2U_LIB.S9S_MB_2U(SCH_1):PAGE175
 R1955    2      B Q_RES_0402LF-10K,1%,1/16W,CHIPA    I72 @S9S_MB_2U_LIB.S9S_MB_2U(SCH_1):PAGE192

FM_PCHHOT_R_N @S9S_MB_2U_LIB.S9S_MB_2U(SCH_1):FM_PCHHOT_R_N
  R474    2      B Q_RES_0402LF-33.2,1%,1/16W,CHIA   I213 @S9S_MB_2U_LIB.S9S_MB_2U(SCH_1):PAGE175
  U249 AB17  PB40A LCMXO3LF9400C5BG484C-LCMXO3LF-A     I1 @S9S_MB_2U_LIB.S9S_MB_2U(SCH_1):PAGE312

FM_PCH_BIOS_RCVR_MODE @S9S_MB_2U_LIB.S9S_MB_2U(SCH_1):FM_PCH_BIOS_RCVR_MODE
    U4   R7 GPP_M_11 EMMITSBURG_REV0P9-GFNOCPU04302A    I22 @S9S_MB_2U_LIB.S9S_MB_2U(SCH_1):PAGE176
 R1338    1      A Q_RES_0402LF-10K,1%,1/16W,CHIPA   I107 @S9S_MB_2U_LIB.S9S_MB_2U(SCH_1):PAGE189
  J104    4      4 CONN14_210HP207GBR1-CONN14_210A   I134 @S9S_MB_2U_LIB.S9S_MB_2U(SCH_1):PAGE189

FM_PCH_BMC_RST_N @S9S_MB_2U_LIB.S9S_MB_2U(SCH_1):FM_PCH_BMC_RST_N
  U249  Y10  PB21D LCMXO3LF9400C5BG484C-LCMXO3LF-A     I1 @S9S_MB_2U_LIB.S9S_MB_2U(SCH_1):PAGE312
 R4723    2      B Q_RES_0402LF-33.2,1%,1/16W,CHIA   I213 @S9S_MB_2U_LIB.S9S_MB_2U(SCH_1):PAGE312

FM_PCH_BMC_RST_R_N @S9S_MB_2U_LIB.S9S_MB_2U(SCH_1):FM_PCH_BMC_RST_R_N
    U4   U3 GPP_I_12_HDA_BCLK EMMITSBURG_REV0P9-GFNOCPU04302A    I22 @S9S_MB_2U_LIB.S9S_MB_2U(SCH_1):PAGE176
 R4722    1      A Q_RES_0402LF-10K,1%,1/16W,CHIPA   I246 @S9S_MB_2U_LIB.S9S_MB_2U(SCH_1):PAGE176
 R4723    1      A Q_RES_0402LF-33.2,1%,1/16W,CHIA   I213 @S9S_MB_2U_LIB.S9S_MB_2U(SCH_1):PAGE312

FM_PCH_BMC_THERMTRIP_N @S9S_MB_2U_LIB.S9S_MB_2U(SCH_1):FM_PCH_BMC_THERMTRIP_N
 R1263    2      B Q_RES_0402LF-33.2,1%,1/16W,CHIA    I29 @S9S_MB_2U_LIB.S9S_MB_2U(SCH_1):PAGE191
  U249  AB8  PB18B LCMXO3LF9400C5BG484C-LCMXO3LF-A     I1 @S9S_MB_2U_LIB.S9S_MB_2U(SCH_1):PAGE312

FM_PCH_BOOT_BIOS_STRAP @S9S_MB_2U_LIB.S9S_MB_2U(SCH_1):FM_PCH_BOOT_BIOS_STRAP
    U4   W1 GPP_D_23 EMMITSBURG_REV0P9-GFNOCPU04302A    I93 @S9S_MB_2U_LIB.S9S_MB_2U(SCH_1):PAGE175
  R371    2      B Q_RES_0402LF-1K,1%,1/16W,EMPTYA    I45 @S9S_MB_2U_LIB.S9S_MB_2U(SCH_1):PAGE186
  R372    1      A Q_RES_0402LF-10K,1%,1/16W,CHIPA    I46 @S9S_MB_2U_LIB.S9S_MB_2U(SCH_1):PAGE186

FM_PCH_CONSENT_STRAP_N @S9S_MB_2U_LIB.S9S_MB_2U(SCH_1):FM_PCH_CONSENT_STRAP_N
  R771    2      B Q_RES_0402LF-1K,1%,1/16W,CHIP,A   I120 @S9S_MB_2U_LIB.S9S_MB_2U(SCH_1):PAGE133
    U4 AT18 GPPC_S_5_CPU_GP_3 EMMITSBURG_REV0P9-GFNOCPU04302A    I27 @S9S_MB_2U_LIB.S9S_MB_2U(SCH_1):PAGE177
  R502    2      B Q_RES_0402LF-20K,1%,1/16W,CHIPA    I68 @S9S_MB_2U_LIB.S9S_MB_2U(SCH_1):PAGE186
 R1962    1      A Q_RES_0402LF-20K,1%,1/16W,EMPTA    I90 @S9S_MB_2U_LIB.S9S_MB_2U(SCH_1):PAGE186

FM_PCH_CPU_PWR_DEBUG_N @S9S_MB_2U_LIB.S9S_MB_2U(SCH_1):FM_PCH_CPU_PWR_DEBUG_N
    U4   F5 CPU_PWR_DEBUG_N EMMITSBURG_REV0P9-GFNOCPU04302A    I36 @S9S_MB_2U_LIB.S9S_MB_2U(SCH_1):PAGE174
 R1247    1      A Q_RES_0402LF-0,5%,1/16W,CHIP,CA    I14 @S9S_MB_2U_LIB.S9S_MB_2U(SCH_1):PAGE191

FM_PCH_CRASHLOG_TRIG_N @S9S_MB_2U_LIB.S9S_MB_2U(SCH_1):FM_PCH_CRASHLOG_TRIG_N
    U4  AE3 GPP_D_8_CRASHLOG_TRIG_N EMMITSBURG_REV0P9-GFNOCPU04302A    I93 @S9S_MB_2U_LIB.S9S_MB_2U(SCH_1):PAGE175
  R699    2      B Q_RES_0402LF-33.2,1%,1/16W,CHIA   I102 @S9S_MB_2U_LIB.S9S_MB_2U(SCH_1):PAGE175

FM_PCH_CRASHLOG_TRIG_R_N @S9S_MB_2U_LIB.S9S_MB_2U(SCH_1):FM_PCH_CRASHLOG_TRIG_R_N
  R699    1      A Q_RES_0402LF-33.2,1%,1/16W,CHIA   I102 @S9S_MB_2U_LIB.S9S_MB_2U(SCH_1):PAGE175
  U249  AB7  PB13B LCMXO3LF9400C5BG484C-LCMXO3LF-A     I1 @S9S_MB_2U_LIB.S9S_MB_2U(SCH_1):PAGE312

FM_PCH_DFXTESTMODE @S9S_MB_2U_LIB.S9S_MB_2U(SCH_1):FM_PCH_DFXTESTMODE
    U4   P3 GPP_I_22 EMMITSBURG_REV0P9-GFNOCPU04302A    I22 @S9S_MB_2U_LIB.S9S_MB_2U(SCH_1):PAGE176
 R1497    1      A Q_RES_0402LF-12K,1%,1/16W,EMPTA    I70 @S9S_MB_2U_LIB.S9S_MB_2U(SCH_1):PAGE188
 R1496    2      B Q_RES_0402LF-10K,1%,1/16W,CHIPA    I71 @S9S_MB_2U_LIB.S9S_MB_2U(SCH_1):PAGE188

FM_PCH_EXTERNALCLKMODE @S9S_MB_2U_LIB.S9S_MB_2U(SCH_1):FM_PCH_EXTERNALCLKMODE
    U4   L2 GPPC_H_6 EMMITSBURG_REV0P9-GFNOCPU04302A    I22 @S9S_MB_2U_LIB.S9S_MB_2U(SCH_1):PAGE176
  R611    2      B Q_RES_0402LF-1K,1%,1/16W,CHIP,A    I43 @S9S_MB_2U_LIB.S9S_MB_2U(SCH_1):PAGE187
  R612    1      A Q_RES_0402LF-10K,1%,1/16W,EMPTA    I44 @S9S_MB_2U_LIB.S9S_MB_2U(SCH_1):PAGE187

FM_PCH_GLB_RST_WARN_N @S9S_MB_2U_LIB.S9S_MB_2U(SCH_1):FM_PCH_GLB_RST_WARN_N
    U4  AA1 GPP_D_21_GLB_RST_WARN_N EMMITSBURG_REV0P9-GFNOCPU04302A    I93 @S9S_MB_2U_LIB.S9S_MB_2U(SCH_1):PAGE175
 R3041    2      B Q_RES_0402LF-10K,1%,1/16W,CHIPA     I6 @S9S_MB_2U_LIB.S9S_MB_2U(SCH_1):PAGE192
 R1313    1      A Q_RES_0402LF-33.2,1%,1/16W,CHIA    I21 @S9S_MB_2U_LIB.S9S_MB_2U(SCH_1):PAGE193

FM_PCH_IO_EXPANDER @S9S_MB_2U_LIB.S9S_MB_2U(SCH_1):FM_PCH_IO_EXPANDER
    U4   K1 GPPC_H_1 EMMITSBURG_REV0P9-GFNOCPU04302A    I22 @S9S_MB_2U_LIB.S9S_MB_2U(SCH_1):PAGE176
  R618    1      A Q_RES_0402LF-10K,1%,1/16W,CHIPA    I53 @S9S_MB_2U_LIB.S9S_MB_2U(SCH_1):PAGE187
  R617    2      B Q_RES_0402LF-1K,1%,1/16W,EMPTYA    I54 @S9S_MB_2U_LIB.S9S_MB_2U(SCH_1):PAGE187

FM_PCH_MCRO_LDO @S9S_MB_2U_LIB.S9S_MB_2U(SCH_1):FM_PCH_MCRO_LDO
    U4   K3 GPPC_H_7 EMMITSBURG_REV0P9-GFNOCPU04302A    I22 @S9S_MB_2U_LIB.S9S_MB_2U(SCH_1):PAGE176
 R1220    2      B Q_RES_0402LF-1K,1%,1/16W,EMPTYA    I63 @S9S_MB_2U_LIB.S9S_MB_2U(SCH_1):PAGE188
 R1221    1      A Q_RES_0402LF-1K,1%,1/16W,CHIP,A    I64 @S9S_MB_2U_LIB.S9S_MB_2U(SCH_1):PAGE188

FM_PCH_P1V8_AUX_EN @S9S_MB_2U_LIB.S9S_MB_2U(SCH_1):FM_PCH_P1V8_AUX_EN
 R1404    1      A Q_RES_0402LF-2K,1%,1/16W,CHIP,A    I25 @S9S_MB_2U_LIB.S9S_MB_2U(SCH_1):PAGE208
  U249  F19   PR5D LCMXO3LF9400C5BG484C-LCMXO3LF-A     I1 @S9S_MB_2U_LIB.S9S_MB_2U(SCH_1):PAGE313
 R2358    1      A Q_RES_0402LF-0,5%,1/16W,CHIP,CA    I17 @S9S_MB_2U_LIB.S9S_MB_2U(SCH_1):PAGE249

FM_PCH_P1V8_AUX_EN_R @S9S_MB_2U_LIB.S9S_MB_2U(SCH_1):FM_PCH_P1V8_AUX_EN_R
  PU74    5     EN NB682GDZ-NB682GD-Z,SMLF,IC,AL0A    I26 @S9S_MB_2U_LIB.S9S_MB_2U(SCH_1):PAGE249
 R2358    2      B Q_RES_0402LF-0,5%,1/16W,CHIP,CA    I17 @S9S_MB_2U_LIB.S9S_MB_2U(SCH_1):PAGE249
PR1850    2      B Q_RES_0402LF-1K,1%,1/16W,EMPTYA    I11 @S9S_MB_2U_LIB.S9S_MB_2U(SCH_1):PAGE249

FM_PCH_PLD_GLB_RST_WARN_N @S9S_MB_2U_LIB.S9S_MB_2U(SCH_1):FM_PCH_PLD_GLB_RST_WARN_N
 R1313    2      B Q_RES_0402LF-33.2,1%,1/16W,CHIA    I21 @S9S_MB_2U_LIB.S9S_MB_2U(SCH_1):PAGE193
  U249 AA16  PB38B LCMXO3LF9400C5BG484C-LCMXO3LF-A     I1 @S9S_MB_2U_LIB.S9S_MB_2U(SCH_1):PAGE312

FM_PCH_PRSNT_N @S9S_MB_2U_LIB.S9S_MB_2U(SCH_1):FM_PCH_PRSNT_N
  R498    2      B Q_RES_0402LF-10K,1%,1/16W,CHIPA    I24 @S9S_MB_2U_LIB.S9S_MB_2U(SCH_1):PAGE177
    U4  A41 VSS_A41 EMMITSBURG_REV0P9-GFNOCPU04302A    I27 @S9S_MB_2U_LIB.S9S_MB_2U(SCH_1):PAGE177
  U249   B4  PT12A LCMXO3LF9400C5BG484C-LCMXO3LF-A   I188 @S9S_MB_2U_LIB.S9S_MB_2U(SCH_1):PAGE314

FM_PCH_RING_OSC_BYPASS_MGPIO_TE @S9S_MB_2U_LIB.S9S_MB_2U(SCH_1):FM_PCH_RING_OSC_BYPASS_MGPIO_TEST2
    U4   G2 GPPC_H_16_FLEX_CLK_OUT_1 EMMITSBURG_REV0P9-GFNOCPU04302A    I22 @S9S_MB_2U_LIB.S9S_MB_2U(SCH_1):PAGE176
 R1476    1      A Q_RES_0402LF-1K,1%,1/16W,CHIP,A    I43 @S9S_MB_2U_LIB.S9S_MB_2U(SCH_1):PAGE188
 R1475    2      B Q_RES_0402LF-1K,1%,1/16W,EMPTYA    I44 @S9S_MB_2U_LIB.S9S_MB_2U(SCH_1):PAGE188

FM_PCH_SATA_RAID_KEY @S9S_MB_2U_LIB.S9S_MB_2U(SCH_1):FM_PCH_SATA_RAID_KEY
    U4 BD11 GPPC_A_16_SRCCLKREQ_N_6 EMMITSBURG_REV0P9-GFNOCPU04302A    I93 @S9S_MB_2U_LIB.S9S_MB_2U(SCH_1):PAGE175
 R1487    1      A Q_RES_0402LF-100,1%,1/16W,CHIPA   I125 @S9S_MB_2U_LIB.S9S_MB_2U(SCH_1):PAGE175
 R1271    2      B Q_RES_0402LF-2.21K,1%,1/16W,EMA     I5 @S9S_MB_2U_LIB.S9S_MB_2U(SCH_1):PAGE183

FM_PCH_SKIP_RTC_CLOCK @S9S_MB_2U_LIB.S9S_MB_2U(SCH_1):FM_PCH_SKIP_RTC_CLOCK
    U4 AU10 GPP_O_7 EMMITSBURG_REV0P9-GFNOCPU04302A    I36 @S9S_MB_2U_LIB.S9S_MB_2U(SCH_1):PAGE174
  R621    2      B Q_RES_0402LF-1K,1%,1/16W,EMPTYA    I55 @S9S_MB_2U_LIB.S9S_MB_2U(SCH_1):PAGE187
  R622    1      A Q_RES_0402LF-1K,1%,1/16W,CHIP,A    I56 @S9S_MB_2U_LIB.S9S_MB_2U(SCH_1):PAGE187

FM_PCH_SLP_S3_N @S9S_MB_2U_LIB.S9S_MB_2U(SCH_1):FM_PCH_SLP_S3_N
    U4  AP8 SLP_S3_N EMMITSBURG_REV0P9-GFNOCPU04302A    I36 @S9S_MB_2U_LIB.S9S_MB_2U(SCH_1):PAGE174
 R1995    1      A Q_RES_0402LF-33.2,1%,1/16W,CHIA    I86 @S9S_MB_2U_LIB.S9S_MB_2U(SCH_1):PAGE212
   Q78    2     G1 MOSFET_NCH_DUAL-PJT138K,SMLF,IA    I34 @S9S_MB_2U_LIB.S9S_MB_2U(SCH_1):PAGE242

FM_PCH_SLP_S4_N @S9S_MB_2U_LIB.S9S_MB_2U(SCH_1):FM_PCH_SLP_S4_N
    U4 AL13 SLP_S4_N EMMITSBURG_REV0P9-GFNOCPU04302A    I36 @S9S_MB_2U_LIB.S9S_MB_2U(SCH_1):PAGE174
 R1996    1      A Q_RES_0402LF-33.2,1%,1/16W,CHIA    I87 @S9S_MB_2U_LIB.S9S_MB_2U(SCH_1):PAGE212
   Q77    5     G2 MOSFET_NCH_DUAL-PJT138K,SMLF,IA     I3 @S9S_MB_2U_LIB.S9S_MB_2U(SCH_1):PAGE242

FM_PCH_SLP_SUS_N @S9S_MB_2U_LIB.S9S_MB_2U(SCH_1):FM_PCH_SLP_SUS_N
    U4  AL7 SLP_SUS_N EMMITSBURG_REV0P9-GFNOCPU04302A    I36 @S9S_MB_2U_LIB.S9S_MB_2U(SCH_1):PAGE174
 R1736    1      A Q_RES_0402LF-33.2,1%,1/16W,CHIA    I99 @S9S_MB_2U_LIB.S9S_MB_2U(SCH_1):PAGE174

FM_PCH_SPARE0 @S9S_MB_2U_LIB.S9S_MB_2U(SCH_1):FM_PCH_SPARE0
    U4 AN10 GPP_O_0 EMMITSBURG_REV0P9-GFNOCPU04302A    I36 @S9S_MB_2U_LIB.S9S_MB_2U(SCH_1):PAGE174
 R3038    2      B Q_RES_0402LF-5.11K,1%,1/16W,CHA    I57 @S9S_MB_2U_LIB.S9S_MB_2U(SCH_1):PAGE188

FM_PCH_SPKR @S9S_MB_2U_LIB.S9S_MB_2U(SCH_1):FM_PCH_SPKR
    U4 AU16 GPPC_S_1_SPKR_TIME_SYNC_1 EMMITSBURG_REV0P9-GFNOCPU04302A    I27 @S9S_MB_2U_LIB.S9S_MB_2U(SCH_1):PAGE177
  R367    2      B Q_RES_0402LF-1K,1%,1/16W,EMPTYA    I11 @S9S_MB_2U_LIB.S9S_MB_2U(SCH_1):PAGE186
 R3325    1      A Q_RES_0402LF-10K,1%,1/16W,CHIPA    I92 @S9S_MB_2U_LIB.S9S_MB_2U(SCH_1):PAGE186
 R4612    1      A Q_RES_0402LF-33.2,1%,1/16W,CHIA   I211 @S9S_MB_2U_LIB.S9S_MB_2U(SCH_1):PAGE313
 R3302    2      B Q_RES_0402LF-0,5%,1/16W,EMPTY,A    I48 @S9S_MB_2U_LIB.S9S_MB_2U(SCH_1):PAGE227

FM_PCH_SPKR_R @S9S_MB_2U_LIB.S9S_MB_2U(SCH_1):FM_PCH_SPKR_R
  U249  W20  PR30B LCMXO3LF9400C5BG484C-LCMXO3LF-A     I1 @S9S_MB_2U_LIB.S9S_MB_2U(SCH_1):PAGE313
 R4612    2      B Q_RES_0402LF-33.2,1%,1/16W,CHIA   I211 @S9S_MB_2U_LIB.S9S_MB_2U(SCH_1):PAGE313

FM_PCH_TRIGGER0_N @S9S_MB_2U_LIB.S9S_MB_2U(SCH_1):FM_PCH_TRIGGER0_N
   R20    2      B Q_RES_0402LF-0,5%,1/16W,CHIP,CA    I31 @S9S_MB_2U_LIB.S9S_MB_2U(SCH_1):PAGE16
 R1200    1      A Q_RES_0402LF-100,1%,1/16W,CHIPA    I60 @S9S_MB_2U_LIB.S9S_MB_2U(SCH_1):PAGE174

FM_PCH_TRIGGER0_R_N @S9S_MB_2U_LIB.S9S_MB_2U(SCH_1):FM_PCH_TRIGGER0_R_N
    U4  H11 TRIGGER0_N EMMITSBURG_REV0P9-GFNOCPU04302A    I36 @S9S_MB_2U_LIB.S9S_MB_2U(SCH_1):PAGE174
 R1200    2      B Q_RES_0402LF-100,1%,1/16W,CHIPA    I60 @S9S_MB_2U_LIB.S9S_MB_2U(SCH_1):PAGE174
 R1485    2      B Q_RES_0402LF-200,1%,1/16W,EMPTA    I75 @S9S_MB_2U_LIB.S9S_MB_2U(SCH_1):PAGE174

FM_PCH_TRIGGER1_N @S9S_MB_2U_LIB.S9S_MB_2U(SCH_1):FM_PCH_TRIGGER1_N
   R21    2      B Q_RES_0402LF-0,5%,1/16W,CHIP,CA    I32 @S9S_MB_2U_LIB.S9S_MB_2U(SCH_1):PAGE16
 R1201    1      A Q_RES_0402LF-49.9,1%,1/16W,CHIA    I58 @S9S_MB_2U_LIB.S9S_MB_2U(SCH_1):PAGE174

FM_PCH_TRIGGER1_R_N @S9S_MB_2U_LIB.S9S_MB_2U(SCH_1):FM_PCH_TRIGGER1_R_N
    U4   K8 TRIGGER1_N EMMITSBURG_REV0P9-GFNOCPU04302A    I36 @S9S_MB_2U_LIB.S9S_MB_2U(SCH_1):PAGE174
 R1201    2      B Q_RES_0402LF-49.9,1%,1/16W,CHIA    I58 @S9S_MB_2U_LIB.S9S_MB_2U(SCH_1):PAGE174
 R1486    2      B Q_RES_0402LF-200,1%,1/16W,EMPTA    I74 @S9S_MB_2U_LIB.S9S_MB_2U(SCH_1):PAGE174

FM_PCH_VISA_DEFAULT @S9S_MB_2U_LIB.S9S_MB_2U(SCH_1):FM_PCH_VISA_DEFAULT
    U4   G4 GPPC_H_0 EMMITSBURG_REV0P9-GFNOCPU04302A    I22 @S9S_MB_2U_LIB.S9S_MB_2U(SCH_1):PAGE176
  R615    2      B Q_RES_0402LF-1K,1%,1/16W,CHIP,A    I51 @S9S_MB_2U_LIB.S9S_MB_2U(SCH_1):PAGE187

FM_PCH_XTALSEL @S9S_MB_2U_LIB.S9S_MB_2U(SCH_1):FM_PCH_XTALSEL
    U4   R4 GPP_I_23 EMMITSBURG_REV0P9-GFNOCPU04302A    I22 @S9S_MB_2U_LIB.S9S_MB_2U(SCH_1):PAGE176
  R623    2      B Q_RES_0402LF-1K,1%,1/16W,EMPTYA    I13 @S9S_MB_2U_LIB.S9S_MB_2U(SCH_1):PAGE187
  R624    1      A Q_RES_0402LF-10K,1%,1/16W,CHIPA    I14 @S9S_MB_2U_LIB.S9S_MB_2U(SCH_1):PAGE187

FM_PCH_XTAL_INPUT_MODE_MGPIO_TE @S9S_MB_2U_LIB.S9S_MB_2U(SCH_1):FM_PCH_XTAL_INPUT_MODE_MGPIO_TEST3
    U4   H3 GPPC_H_17_FLEX_CLK_OUT_2 EMMITSBURG_REV0P9-GFNOCPU04302A    I22 @S9S_MB_2U_LIB.S9S_MB_2U(SCH_1):PAGE176
 R1477    2      B Q_RES_0402LF-1K,1%,1/16W,EMPTYA    I47 @S9S_MB_2U_LIB.S9S_MB_2U(SCH_1):PAGE188
 R1478    1      A Q_RES_0402LF-10K,1%,1/16W,CHIPA    I50 @S9S_MB_2U_LIB.S9S_MB_2U(SCH_1):PAGE188

FM_PCIE_EV_BIF_EN @S9S_MB_2U_LIB.S9S_MB_2U(SCH_1):FM_PCIE_EV_BIF_EN
    U4   F8 CPU_CATERR_N EMMITSBURG_REV0P9-GFNOCPU04302A    I36 @S9S_MB_2U_LIB.S9S_MB_2U(SCH_1):PAGE174
 R1675    1      A Q_RES_0402LF-2.49K,1%,1/16W,CHA    I82 @S9S_MB_2U_LIB.S9S_MB_2U(SCH_1):PAGE174
 R1676    1      A Q_RES_0402LF-1K,1%,1/16W,EMPTYA    I94 @S9S_MB_2U_LIB.S9S_MB_2U(SCH_1):PAGE174

FM_PDB_BUF_EN @S9S_MB_2U_LIB.S9S_MB_2U(SCH_1):FM_PDB_BUF_EN
  U249  V17  PB46C LCMXO3LF9400C5BG484C-LCMXO3LF-A     I1 @S9S_MB_2U_LIB.S9S_MB_2U(SCH_1):PAGE312
 R2792    1      A Q_RES_0402LF-0,5%,1/16W,CHIP,CA   I178 @S9S_MB_2U_LIB.S9S_MB_2U(SCH_1):PAGE312

FM_PDB_BUF_EN_R @S9S_MB_2U_LIB.S9S_MB_2U(SCH_1):FM_PDB_BUF_EN_R
 R2792    2      B Q_RES_0402LF-0,5%,1/16W,CHIP,CA   I178 @S9S_MB_2U_LIB.S9S_MB_2U(SCH_1):PAGE312
 R3063    1      A Q_RES_0402LF-33.2,1%,1/16W,CHIA   I208 @S9S_MB_2U_LIB.S9S_MB_2U(SCH_1):PAGE140
 R4769    1      A Q_RES_0402LF-100K,1%,1/16W,CHIA     I3 @S9S_MB_2U_LIB.S9S_MB_2U(SCH_1):PAGE233
 R2950    2      B Q_RES_0402LF-4.7K,5%,1/16W,EMPA     I4 @S9S_MB_2U_LIB.S9S_MB_2U(SCH_1):PAGE233
 R2796    1      A Q_RES_0402LF-33.2,1%,1/16W,CHIA    I10 @S9S_MB_2U_LIB.S9S_MB_2U(SCH_1):PAGE233

FM_PECI_MUX_SEL_N @S9S_MB_2U_LIB.S9S_MB_2U(SCH_1):FM_PECI_MUX_SEL_N
 R2255    2      B Q_RES_0402LF-0,5%,1/16W,CHIP,CA    I41 @S9S_MB_2U_LIB.S9S_MB_2U(SCH_1):PAGE185
  U249   A6  PT13B LCMXO3LF9400C5BG484C-LCMXO3LF-A   I188 @S9S_MB_2U_LIB.S9S_MB_2U(SCH_1):PAGE314

FM_PEHPCPU0_ALERT_N @S9S_MB_2U_LIB.S9S_MB_2U(SCH_1):FM_PEHPCPU0_ALERT_N
    U2 BV26 CXPSMBUS_ALERT_N SOCKET4677_AZIF0045P001C01CS-SA     I1 @S9S_MB_2U_LIB.S9S_MB_2U(SCH_1):PAGE14
 R1006    2      B Q_RES_0402LF-4.7K,5%,1/16W,CHIA     I8 @S9S_MB_2U_LIB.S9S_MB_2U(SCH_1):PAGE223
   Q15    3     D2 MOSFET_NCH_DUAL-PJT138K,SMLF,IA   I108 @S9S_MB_2U_LIB.S9S_MB_2U(SCH_1):PAGE223

FM_PEHPCPU1_ALERT_N @S9S_MB_2U_LIB.S9S_MB_2U(SCH_1):FM_PEHPCPU1_ALERT_N
    U1 BV26 CXPSMBUS_ALERT_N SOCKET4677_AZIF0045P001C01CS-SA    I29 @S9S_MB_2U_LIB.S9S_MB_2U(SCH_1):PAGE45
 R1007    2      B Q_RES_0402LF-4.7K,5%,1/16W,CHIA    I12 @S9S_MB_2U_LIB.S9S_MB_2U(SCH_1):PAGE223
   Q16    3     D2 MOSFET_NCH_DUAL-PJT138K,SMLF,IA   I109 @S9S_MB_2U_LIB.S9S_MB_2U(SCH_1):PAGE223

FM_PFR_DSW_PWROK_N @S9S_MB_2U_LIB.S9S_MB_2U(SCH_1):FM_PFR_DSW_PWROK_N
  U249  H17  PR10C LCMXO3LF9400C5BG484C-LCMXO3LF-A     I1 @S9S_MB_2U_LIB.S9S_MB_2U(SCH_1):PAGE313
 R1399    1      A Q_RES_0402LF-10K,1%,1/16W,CHIPA    I17 @S9S_MB_2U_LIB.S9S_MB_2U(SCH_1):PAGE209
 R1745    2      B Q_RES_0402LF-0,5%,1/16W,EMPTY,A    I21 @S9S_MB_2U_LIB.S9S_MB_2U(SCH_1):PAGE232

FM_PLD_CLKS_DEV_EN @S9S_MB_2U_LIB.S9S_MB_2U(SCH_1):FM_PLD_CLKS_DEV_EN
  R575    1      A Q_RES_0402LF-49.9,1%,1/16W,CHIA   I199 @S9S_MB_2U_LIB.S9S_MB_2U(SCH_1):PAGE195
  R106    2      B Q_RES_0402LF-2K,1%,1/16W,CHIP,A   I304 @S9S_MB_2U_LIB.S9S_MB_2U(SCH_1):PAGE195
   U13  A17 PWRGD||PWRDN# 9SQ440NQQI8-9SQ440NQQI8,SMLF,IA   I180 @S9S_MB_2U_LIB.S9S_MB_2U(SCH_1):PAGE197
 R1305    2      B Q_RES_0402LF-10K,1%,1/16W,EMPTA   I272 @S9S_MB_2U_LIB.S9S_MB_2U(SCH_1):PAGE197
 R1390    1      A Q_RES_0402LF-1K,1%,1/16W,EMPTYA   I275 @S9S_MB_2U_LIB.S9S_MB_2U(SCH_1):PAGE197
  R110    2      B Q_RES_0402LF-33.2,1%,1/16W,CHIA    I17 @S9S_MB_2U_LIB.S9S_MB_2U(SCH_1):PAGE212
   U70    G   GATE MOSFET_N_SMLF-BSS138K,BSS138K,A    I19 @S9S_MB_2U_LIB.S9S_MB_2U(SCH_1):PAGE212
 R4476    1      A Q_RES_0402LF-49.9,1%,1/16W,CHIA    I39 @S9S_MB_2U_LIB.S9S_MB_2U(SCH_1):PAGE200

FM_PLD_CLKS_DEV_R_EN @S9S_MB_2U_LIB.S9S_MB_2U(SCH_1):FM_PLD_CLKS_DEV_R_EN
  R110    1      A Q_RES_0402LF-33.2,1%,1/16W,CHIA    I17 @S9S_MB_2U_LIB.S9S_MB_2U(SCH_1):PAGE212
  U249   U7   PB8C LCMXO3LF9400C5BG484C-LCMXO3LF-A     I1 @S9S_MB_2U_LIB.S9S_MB_2U(SCH_1):PAGE312

FM_PLD_CLKS_OE_R_N @S9S_MB_2U_LIB.S9S_MB_2U(SCH_1):FM_PLD_CLKS_OE_R_N
   U70    D  DRAIN MOSFET_N_SMLF-BSS138K,BSS138K,A    I19 @S9S_MB_2U_LIB.S9S_MB_2U(SCH_1):PAGE212
  R111    2      B Q_RES_0402LF-10K,1%,1/16W,CHIPA    I24 @S9S_MB_2U_LIB.S9S_MB_2U(SCH_1):PAGE212
  R113    1      A Q_RES_0402LF-33.2,1%,1/16W,CHIA    I27 @S9S_MB_2U_LIB.S9S_MB_2U(SCH_1):PAGE212

FM_PLD_CLK_25M_EN @S9S_MB_2U_LIB.S9S_MB_2U(SCH_1):FM_PLD_CLK_25M_EN
 R1680    1      A Q_RES_0402LF-0,5%,1/16W,CHIP,CA   I252 @S9S_MB_2U_LIB.S9S_MB_2U(SCH_1):PAGE197
  R109    2      B Q_RES_0402LF-33.2,1%,1/16W,CHIA    I44 @S9S_MB_2U_LIB.S9S_MB_2U(SCH_1):PAGE212

FM_PLD_CLK_25M_R_EN @S9S_MB_2U_LIB.S9S_MB_2U(SCH_1):FM_PLD_CLK_25M_R_EN
  R990    1      A Q_RES_0402LF-2K,1%,1/16W,CHIP,A    I18 @S9S_MB_2U_LIB.S9S_MB_2U(SCH_1):PAGE208
  R109    1      A Q_RES_0402LF-33.2,1%,1/16W,CHIA    I44 @S9S_MB_2U_LIB.S9S_MB_2U(SCH_1):PAGE212
  U249   T8   PB8D LCMXO3LF9400C5BG484C-LCMXO3LF-A     I1 @S9S_MB_2U_LIB.S9S_MB_2U(SCH_1):PAGE312

FM_PLD_HEARTBEAT_LVC3 @S9S_MB_2U_LIB.S9S_MB_2U(SCH_1):FM_PLD_HEARTBEAT_LVC3
   U89    G   GATE MOSFET_N_SMLF-BSS138K,BSS138K,A   I236 @S9S_MB_2U_LIB.S9S_MB_2U(SCH_1):PAGE207
  U249  T10  PB19C LCMXO3LF9400C5BG484C-LCMXO3LF-A     I1 @S9S_MB_2U_LIB.S9S_MB_2U(SCH_1):PAGE312
 R1437    1      A Q_RES_0402LF-10K,1%,1/16W,CHIPA    I42 @S9S_MB_2U_LIB.S9S_MB_2U(SCH_1):PAGE209

FM_PLD_HEARTBEAT_LVC3_D @S9S_MB_2U_LIB.S9S_MB_2U(SCH_1):FM_PLD_HEARTBEAT_LVC3_D
   U89    D  DRAIN MOSFET_N_SMLF-BSS138K,BSS138K,A   I236 @S9S_MB_2U_LIB.S9S_MB_2U(SCH_1):PAGE207
    D0    C      C Q_LED_SMLF-LED_BLUE,LTST-C281TA   I277 @S9S_MB_2U_LIB.S9S_MB_2U(SCH_1):PAGE207

FM_PLD_REV_N @S9S_MB_2U_LIB.S9S_MB_2U(SCH_1):FM_PLD_REV_N
  U249 AA19  PB43B LCMXO3LF9400C5BG484C-LCMXO3LF-A     I1 @S9S_MB_2U_LIB.S9S_MB_2U(SCH_1):PAGE312
 R1710    1      A Q_RES_0402LF-49.9,1%,1/16W,CHIA    I38 @S9S_MB_2U_LIB.S9S_MB_2U(SCH_1):PAGE312
 C1325    1      A Q_CAP_0402-0.1UF,25V,10%,X7R,CA    I39 @S9S_MB_2U_LIB.S9S_MB_2U(SCH_1):PAGE312

FM_PLD_REV_R_N @S9S_MB_2U_LIB.S9S_MB_2U(SCH_1):FM_PLD_REV_R_N
 R1106    2      B Q_RES_0402LF-10K,1%,1/16W,CHIPA     I5 @S9S_MB_2U_LIB.S9S_MB_2U(SCH_1):PAGE312
 R1710    2      B Q_RES_0402LF-49.9,1%,1/16W,CHIA    I38 @S9S_MB_2U_LIB.S9S_MB_2U(SCH_1):PAGE312

FM_PLT_BMC_THERMTRIP_R_N @S9S_MB_2U_LIB.S9S_MB_2U(SCH_1):FM_PLT_BMC_THERMTRIP_R_N
    U4   Y2 GPP_D_17_THERMTRIP_N EMMITSBURG_REV0P9-GFNOCPU04302A    I93 @S9S_MB_2U_LIB.S9S_MB_2U(SCH_1):PAGE175
 R1263    1      A Q_RES_0402LF-33.2,1%,1/16W,CHIA    I29 @S9S_MB_2U_LIB.S9S_MB_2U(SCH_1):PAGE191
 R1820    2      B Q_RES_0402LF-10K,1%,1/16W,CHIPA    I35 @S9S_MB_2U_LIB.S9S_MB_2U(SCH_1):PAGE191

FM_PMBUS_ALERT_B_EN @S9S_MB_2U_LIB.S9S_MB_2U(SCH_1):FM_PMBUS_ALERT_B_EN
    U4  AV3 GPPC_C_11_ME_SML2ALERT_N EMMITSBURG_REV0P9-GFNOCPU04302A    I93 @S9S_MB_2U_LIB.S9S_MB_2U(SCH_1):PAGE175
 R1659    1      A Q_RES_0402LF-10K,1%,1/16W,CHIPA   I181 @S9S_MB_2U_LIB.S9S_MB_2U(SCH_1):PAGE175

FM_PS_EN_PLD_BUF1 @S9S_MB_2U_LIB.S9S_MB_2U(SCH_1):FM_PS_EN_PLD_BUF1
 R2350    1      A Q_RES_0402LF-0,5%,1/16W,CHIP,CA   I157 @S9S_MB_2U_LIB.S9S_MB_2U(SCH_1):PAGE297
  U150    6     B0 74LVC2G17GW-74LVC2G17GW,SMLF,IA     I2 @S9S_MB_2U_LIB.S9S_MB_2U(SCH_1):PAGE213
 R2355    2      B Q_RES_0402LF-4.7K,5%,1/16W,EMPA     I7 @S9S_MB_2U_LIB.S9S_MB_2U(SCH_1):PAGE213

FM_PS_EN_PLD_BUF1_R1 @S9S_MB_2U_LIB.S9S_MB_2U(SCH_1):FM_PS_EN_PLD_BUF1_R1
 R2350    2      B Q_RES_0402LF-0,5%,1/16W,CHIP,CA   I157 @S9S_MB_2U_LIB.S9S_MB_2U(SCH_1):PAGE297
  U145    1     OE 74LVC1G126SE7-74LVC1G126SE-7,SA   I163 @S9S_MB_2U_LIB.S9S_MB_2U(SCH_1):PAGE297

FM_PS_EN_PLD_R @S9S_MB_2U_LIB.S9S_MB_2U(SCH_1):FM_PS_EN_PLD_R
  U249  V22  PR25A LCMXO3LF9400C5BG484C-LCMXO3LF-A     I1 @S9S_MB_2U_LIB.S9S_MB_2U(SCH_1):PAGE313
  U150    1     A0 74LVC2G17GW-74LVC2G17GW,SMLF,IA     I2 @S9S_MB_2U_LIB.S9S_MB_2U(SCH_1):PAGE213
 R1607    1      A Q_RES_0402LF-0,5%,1/16W,EMPTY,A    I10 @S9S_MB_2U_LIB.S9S_MB_2U(SCH_1):PAGE246

FM_PS_PWROK_DLY_R_SEL @S9S_MB_2U_LIB.S9S_MB_2U(SCH_1):FM_PS_PWROK_DLY_R_SEL
    U4 BA20 GPP_E_18_ERR1_N EMMITSBURG_REV0P9-GFNOCPU04302A    I22 @S9S_MB_2U_LIB.S9S_MB_2U(SCH_1):PAGE176
    R8    2      B Q_RES_0402LF-10K,1%,1/16W,CHIPA    I59 @S9S_MB_2U_LIB.S9S_MB_2U(SCH_1):PAGE192
 R1306    1      A Q_RES_0402LF-33.2,1%,1/16W,CHIA    I13 @S9S_MB_2U_LIB.S9S_MB_2U(SCH_1):PAGE193

FM_PS_PWROK_DLY_SEL @S9S_MB_2U_LIB.S9S_MB_2U(SCH_1):FM_PS_PWROK_DLY_SEL
 R1306    2      B Q_RES_0402LF-33.2,1%,1/16W,CHIA    I13 @S9S_MB_2U_LIB.S9S_MB_2U(SCH_1):PAGE193
  U249   V9  PB16C LCMXO3LF9400C5BG484C-LCMXO3LF-A     I1 @S9S_MB_2U_LIB.S9S_MB_2U(SCH_1):PAGE312

FM_PVCCD_HV_CPU0_EN @S9S_MB_2U_LIB.S9S_MB_2U(SCH_1):FM_PVCCD_HV_CPU0_EN
 R1413    1      A Q_RES_0402LF-2K,1%,1/16W,CHIP,A    I59 @S9S_MB_2U_LIB.S9S_MB_2U(SCH_1):PAGE208
  R363    1      A Q_RES_0402LF-0,5%,1/16W,CHIP,CA    I45 @S9S_MB_2U_LIB.S9S_MB_2U(SCH_1):PAGE264
  U249  C21 PR2A||R_GPLLT_FB LCMXO3LF9400C5BG484C-LCMXO3LF-A     I1 @S9S_MB_2U_LIB.S9S_MB_2U(SCH_1):PAGE313

FM_PVCCD_HV_CPU1_EN @S9S_MB_2U_LIB.S9S_MB_2U(SCH_1):FM_PVCCD_HV_CPU1_EN
 R1414    1      A Q_RES_0402LF-2K,1%,1/16W,CHIP,A    I58 @S9S_MB_2U_LIB.S9S_MB_2U(SCH_1):PAGE208
  U249  C22 PR2B||R_GPLLC_FB LCMXO3LF9400C5BG484C-LCMXO3LF-A     I1 @S9S_MB_2U_LIB.S9S_MB_2U(SCH_1):PAGE313
 R2577    1      A Q_RES_0402LF-0,5%,1/16W,CHIP,CA    I43 @S9S_MB_2U_LIB.S9S_MB_2U(SCH_1):PAGE282

FM_PVCCFA_EHV_CPU0_EN @S9S_MB_2U_LIB.S9S_MB_2U(SCH_1):FM_PVCCFA_EHV_CPU0_EN
  R982    2      B Q_RES_0402LF-33.2,1%,1/16W,CHIA    I10 @S9S_MB_2U_LIB.S9S_MB_2U(SCH_1):PAGE211
 R2394    1      A Q_RES_0402LF-0,5%,1/16W,CHIP,CA    I14 @S9S_MB_2U_LIB.S9S_MB_2U(SCH_1):PAGE260

FM_PVCCFA_EHV_CPU0_R_EN @S9S_MB_2U_LIB.S9S_MB_2U(SCH_1):FM_PVCCFA_EHV_CPU0_R_EN
 R1409    1      A Q_RES_0402LF-2K,1%,1/16W,CHIP,A    I55 @S9S_MB_2U_LIB.S9S_MB_2U(SCH_1):PAGE208
  R982    1      A Q_RES_0402LF-33.2,1%,1/16W,CHIA    I10 @S9S_MB_2U_LIB.S9S_MB_2U(SCH_1):PAGE211
  U249  F17   PR2C LCMXO3LF9400C5BG484C-LCMXO3LF-A     I1 @S9S_MB_2U_LIB.S9S_MB_2U(SCH_1):PAGE313

FM_PVCCFA_EHV_CPU1_EN @S9S_MB_2U_LIB.S9S_MB_2U(SCH_1):FM_PVCCFA_EHV_CPU1_EN
  R986    2      B Q_RES_0402LF-33.2,1%,1/16W,CHIA    I25 @S9S_MB_2U_LIB.S9S_MB_2U(SCH_1):PAGE211
 R2570    1      A Q_RES_0402LF-0,5%,1/16W,CHIP,CA    I31 @S9S_MB_2U_LIB.S9S_MB_2U(SCH_1):PAGE278

FM_PVCCFA_EHV_CPU1_R_EN @S9S_MB_2U_LIB.S9S_MB_2U(SCH_1):FM_PVCCFA_EHV_CPU1_R_EN
 R1410    1      A Q_RES_0402LF-2K,1%,1/16W,CHIP,A    I54 @S9S_MB_2U_LIB.S9S_MB_2U(SCH_1):PAGE208
  R986    1      A Q_RES_0402LF-33.2,1%,1/16W,CHIA    I25 @S9S_MB_2U_LIB.S9S_MB_2U(SCH_1):PAGE211
  U249  G16   PR2D LCMXO3LF9400C5BG484C-LCMXO3LF-A     I1 @S9S_MB_2U_LIB.S9S_MB_2U(SCH_1):PAGE313

FM_PVCCFA_EHV_FIVRA_CPU0_EN @S9S_MB_2U_LIB.S9S_MB_2U(SCH_1):FM_PVCCFA_EHV_FIVRA_CPU0_EN
  R984    2      B Q_RES_0402LF-33.2,1%,1/16W,CHIA    I15 @S9S_MB_2U_LIB.S9S_MB_2U(SCH_1):PAGE211
 R4216    1      A Q_RES_0402LF-0,5%,1/16W,CHIP,CA    I56 @S9S_MB_2U_LIB.S9S_MB_2U(SCH_1):PAGE252

FM_PVCCFA_EHV_FIVRA_CPU0_R_EN @S9S_MB_2U_LIB.S9S_MB_2U(SCH_1):FM_PVCCFA_EHV_FIVRA_CPU0_R_EN
 R1411    1      A Q_RES_0402LF-2K,1%,1/16W,CHIP,A    I56 @S9S_MB_2U_LIB.S9S_MB_2U(SCH_1):PAGE208
  R984    1      A Q_RES_0402LF-33.2,1%,1/16W,CHIA    I15 @S9S_MB_2U_LIB.S9S_MB_2U(SCH_1):PAGE211
  U249  D22 PR3A||R_GPLLT_IN LCMXO3LF9400C5BG484C-LCMXO3LF-A     I1 @S9S_MB_2U_LIB.S9S_MB_2U(SCH_1):PAGE313

FM_PVCCFA_EHV_FIVRA_CPU1_EN @S9S_MB_2U_LIB.S9S_MB_2U(SCH_1):FM_PVCCFA_EHV_FIVRA_CPU1_EN
  R988    2      B Q_RES_0402LF-33.2,1%,1/16W,CHIA    I23 @S9S_MB_2U_LIB.S9S_MB_2U(SCH_1):PAGE211
 R2550    1      A Q_RES_0402LF-0,5%,1/16W,CHIP,CA    I19 @S9S_MB_2U_LIB.S9S_MB_2U(SCH_1):PAGE270

FM_PVCCFA_EHV_FIVRA_CPU1_R_EN @S9S_MB_2U_LIB.S9S_MB_2U(SCH_1):FM_PVCCFA_EHV_FIVRA_CPU1_R_EN
 R1412    1      A Q_RES_0402LF-2K,1%,1/16W,CHIP,A    I57 @S9S_MB_2U_LIB.S9S_MB_2U(SCH_1):PAGE208
  R988    1      A Q_RES_0402LF-33.2,1%,1/16W,CHIA    I23 @S9S_MB_2U_LIB.S9S_MB_2U(SCH_1):PAGE211
  U249  D21 PR3B||R_GPLLC_IN LCMXO3LF9400C5BG484C-LCMXO3LF-A     I1 @S9S_MB_2U_LIB.S9S_MB_2U(SCH_1):PAGE313

FM_PVCCINFAON_CPU0_EN @S9S_MB_2U_LIB.S9S_MB_2U(SCH_1):FM_PVCCINFAON_CPU0_EN
  R983    2      B Q_RES_0402LF-33.2,1%,1/16W,CHIA    I13 @S9S_MB_2U_LIB.S9S_MB_2U(SCH_1):PAGE211
 R2594    1      A Q_RES_0402LF-0,5%,1/16W,CHIP,CA    I55 @S9S_MB_2U_LIB.S9S_MB_2U(SCH_1):PAGE260

FM_PVCCINFAON_CPU0_R_EN @S9S_MB_2U_LIB.S9S_MB_2U(SCH_1):FM_PVCCINFAON_CPU0_R_EN
 R1407    1      A Q_RES_0402LF-2K,1%,1/16W,CHIP,A    I52 @S9S_MB_2U_LIB.S9S_MB_2U(SCH_1):PAGE208
  R983    1      A Q_RES_0402LF-33.2,1%,1/16W,CHIA    I13 @S9S_MB_2U_LIB.S9S_MB_2U(SCH_1):PAGE211
  U249  D19   PR3C LCMXO3LF9400C5BG484C-LCMXO3LF-A     I1 @S9S_MB_2U_LIB.S9S_MB_2U(SCH_1):PAGE313

FM_PVCCINFAON_CPU1_EN @S9S_MB_2U_LIB.S9S_MB_2U(SCH_1):FM_PVCCINFAON_CPU1_EN
  R987    2      B Q_RES_0402LF-33.2,1%,1/16W,CHIA    I24 @S9S_MB_2U_LIB.S9S_MB_2U(SCH_1):PAGE211
 R2558    1      A Q_RES_0402LF-0,5%,1/16W,CHIP,CA   I104 @S9S_MB_2U_LIB.S9S_MB_2U(SCH_1):PAGE278

FM_PVCCINFAON_CPU1_R_EN @S9S_MB_2U_LIB.S9S_MB_2U(SCH_1):FM_PVCCINFAON_CPU1_R_EN
 R1408    1      A Q_RES_0402LF-2K,1%,1/16W,CHIP,A    I53 @S9S_MB_2U_LIB.S9S_MB_2U(SCH_1):PAGE208
  R987    1      A Q_RES_0402LF-33.2,1%,1/16W,CHIA    I24 @S9S_MB_2U_LIB.S9S_MB_2U(SCH_1):PAGE211
  U249  D20   PR3D LCMXO3LF9400C5BG484C-LCMXO3LF-A     I1 @S9S_MB_2U_LIB.S9S_MB_2U(SCH_1):PAGE313

FM_PVCCIN_CPU0_EN @S9S_MB_2U_LIB.S9S_MB_2U(SCH_1):FM_PVCCIN_CPU0_EN
  R981    2      B Q_RES_0402LF-33.2,1%,1/16W,CHIA     I9 @S9S_MB_2U_LIB.S9S_MB_2U(SCH_1):PAGE211
 R2591    1      A Q_RES_0402LF-0,5%,1/16W,CHIP,CA    I48 @S9S_MB_2U_LIB.S9S_MB_2U(SCH_1):PAGE252

FM_PVCCIN_CPU0_R_EN @S9S_MB_2U_LIB.S9S_MB_2U(SCH_1):FM_PVCCIN_CPU0_R_EN
 R1405    1      A Q_RES_0402LF-2K,1%,1/16W,CHIP,A    I26 @S9S_MB_2U_LIB.S9S_MB_2U(SCH_1):PAGE208
  R981    1      A Q_RES_0402LF-33.2,1%,1/16W,CHIA     I9 @S9S_MB_2U_LIB.S9S_MB_2U(SCH_1):PAGE211
  U249  E19   PR4C LCMXO3LF9400C5BG484C-LCMXO3LF-A     I1 @S9S_MB_2U_LIB.S9S_MB_2U(SCH_1):PAGE313

FM_PVCCIN_CPU1_EN @S9S_MB_2U_LIB.S9S_MB_2U(SCH_1):FM_PVCCIN_CPU1_EN
  R985    2      B Q_RES_0402LF-33.2,1%,1/16W,CHIA    I21 @S9S_MB_2U_LIB.S9S_MB_2U(SCH_1):PAGE211
  R309    1      A Q_RES_0402LF-0,5%,1/16W,CHIP,CA    I59 @S9S_MB_2U_LIB.S9S_MB_2U(SCH_1):PAGE270

FM_PVCCIN_CPU1_R_EN @S9S_MB_2U_LIB.S9S_MB_2U(SCH_1):FM_PVCCIN_CPU1_R_EN
 R1406    1      A Q_RES_0402LF-2K,1%,1/16W,CHIP,A    I51 @S9S_MB_2U_LIB.S9S_MB_2U(SCH_1):PAGE208
  R985    1      A Q_RES_0402LF-33.2,1%,1/16W,CHIA    I21 @S9S_MB_2U_LIB.S9S_MB_2U(SCH_1):PAGE211
  U249  E20   PR4D LCMXO3LF9400C5BG484C-LCMXO3LF-A     I1 @S9S_MB_2U_LIB.S9S_MB_2U(SCH_1):PAGE313

FM_PVNN_MAIN_CPU0_EN @S9S_MB_2U_LIB.S9S_MB_2U(SCH_1):FM_PVNN_MAIN_CPU0_EN
  U249  E22   PR4A LCMXO3LF9400C5BG484C-LCMXO3LF-A     I1 @S9S_MB_2U_LIB.S9S_MB_2U(SCH_1):PAGE313
 R1445    1      A Q_RES_0402LF-2K,1%,1/16W,CHIP,A    I11 @S9S_MB_2U_LIB.S9S_MB_2U(SCH_1):PAGE268
 C1307    1      A Q_CAP_0402-1000PF,50V,5%,EMPTYA     I4 @S9S_MB_2U_LIB.S9S_MB_2U(SCH_1):PAGE268
 R2338    2      B Q_RES_0402LF-10K,1%,1/16W,EMPTA     I5 @S9S_MB_2U_LIB.S9S_MB_2U(SCH_1):PAGE268
  PU81    5     EN RS53317LR-RS53317LR,SMLF,IC,ALA    I22 @S9S_MB_2U_LIB.S9S_MB_2U(SCH_1):PAGE268

FM_PVNN_MAIN_CPU1_EN @S9S_MB_2U_LIB.S9S_MB_2U(SCH_1):FM_PVNN_MAIN_CPU1_EN
  U249  E21   PR4B LCMXO3LF9400C5BG484C-LCMXO3LF-A     I1 @S9S_MB_2U_LIB.S9S_MB_2U(SCH_1):PAGE313
 C1308    1      A Q_CAP_0402-1000PF,50V,5%,EMPTYA     I6 @S9S_MB_2U_LIB.S9S_MB_2U(SCH_1):PAGE286
  PU82    5     EN RS53317LR-RS53317LR,SMLF,IC,ALA    I20 @S9S_MB_2U_LIB.S9S_MB_2U(SCH_1):PAGE286
 R2384    2      B Q_RES_0402LF-10K,1%,1/16W,EMPTA     I5 @S9S_MB_2U_LIB.S9S_MB_2U(SCH_1):PAGE286
 R2385    1      A Q_RES_0402LF-2K,1%,1/16W,CHIP,A     I7 @S9S_MB_2U_LIB.S9S_MB_2U(SCH_1):PAGE286

FM_PVPP_HBM_CPU0_EN @S9S_MB_2U_LIB.S9S_MB_2U(SCH_1):FM_PVPP_HBM_CPU0_EN
 C1300    1      A Q_CAP_0402-1000PF,50V,5%,EMPTYA    I12 @S9S_MB_2U_LIB.S9S_MB_2U(SCH_1):PAGE267
  U249  G22   PR5B LCMXO3LF9400C5BG484C-LCMXO3LF-A     I1 @S9S_MB_2U_LIB.S9S_MB_2U(SCH_1):PAGE313
 R2406    2      B Q_RES_0402LF-10K,1%,1/16W,EMPTA     I9 @S9S_MB_2U_LIB.S9S_MB_2U(SCH_1):PAGE267
 R2332    1      A Q_RES_0402LF-2K,1%,1/16W,CHIP,A    I14 @S9S_MB_2U_LIB.S9S_MB_2U(SCH_1):PAGE267
  PU79    8     EN RS53318LR-RS53318LR,SMLF,IC,ALA    I19 @S9S_MB_2U_LIB.S9S_MB_2U(SCH_1):PAGE267

FM_PVPP_HBM_CPU1_EN @S9S_MB_2U_LIB.S9S_MB_2U(SCH_1):FM_PVPP_HBM_CPU1_EN
  U249  F22   PR5A LCMXO3LF9400C5BG484C-LCMXO3LF-A     I1 @S9S_MB_2U_LIB.S9S_MB_2U(SCH_1):PAGE313
 C2445    1      A Q_CAP_0402-1000PF,50V,5%,EMPTYA    I11 @S9S_MB_2U_LIB.S9S_MB_2U(SCH_1):PAGE285
 R2374    1      A Q_RES_0402LF-2K,1%,1/16W,CHIP,A    I13 @S9S_MB_2U_LIB.S9S_MB_2U(SCH_1):PAGE285
  PU80    8     EN RS53318LR-RS53318LR,SMLF,IC,ALA    I25 @S9S_MB_2U_LIB.S9S_MB_2U(SCH_1):PAGE285
 R2367    2      B Q_RES_0402LF-10K,1%,1/16W,EMPTA    I14 @S9S_MB_2U_LIB.S9S_MB_2U(SCH_1):PAGE285

FM_REMOTE_DEBUG_DET @S9S_MB_2U_LIB.S9S_MB_2U(SCH_1):FM_REMOTE_DEBUG_DET
  U249   V8  PB13C LCMXO3LF9400C5BG484C-LCMXO3LF-A     I1 @S9S_MB_2U_LIB.S9S_MB_2U(SCH_1):PAGE312
 R2347    2      B Q_RES_0402LF-0,5%,1/16W,CHIP,CA   I183 @S9S_MB_2U_LIB.S9S_MB_2U(SCH_1):PAGE312

FM_REMOTE_DEBUG_DET_R @S9S_MB_2U_LIB.S9S_MB_2U(SCH_1):FM_REMOTE_DEBUG_DET_R
   U87    G   GATE MOSFET_N_SMLF-BSS138K,BSS138K,A    I96 @S9S_MB_2U_LIB.S9S_MB_2U(SCH_1):PAGE137
 R1370    2      B Q_RES_0402LF-100,1%,1/16W,CHIPA    I98 @S9S_MB_2U_LIB.S9S_MB_2U(SCH_1):PAGE137
 R3025    1      A Q_RES_0402LF-1K,1%,1/16W,EMPTYA   I102 @S9S_MB_2U_LIB.S9S_MB_2U(SCH_1):PAGE137
 R2347    1      A Q_RES_0402LF-0,5%,1/16W,CHIP,CA   I183 @S9S_MB_2U_LIB.S9S_MB_2U(SCH_1):PAGE312

FM_RST_PERST_BIT0 @S9S_MB_2U_LIB.S9S_MB_2U(SCH_1):FM_RST_PERST_BIT0
  U249  P18  PR21D LCMXO3LF9400C5BG484C-LCMXO3LF-A     I1 @S9S_MB_2U_LIB.S9S_MB_2U(SCH_1):PAGE313
 R1742    1      A Q_RES_0402LF-10K,1%,1/16W,EMPTA    I24 @S9S_MB_2U_LIB.S9S_MB_2U(SCH_1):PAGE209
 R1741    1      A Q_RES_0402LF-1K,1%,1/16W,CHIP,A    I38 @S9S_MB_2U_LIB.S9S_MB_2U(SCH_1):PAGE209

FM_RST_PERST_BIT1 @S9S_MB_2U_LIB.S9S_MB_2U(SCH_1):FM_RST_PERST_BIT1
  U249  P17  PR24A LCMXO3LF9400C5BG484C-LCMXO3LF-A     I1 @S9S_MB_2U_LIB.S9S_MB_2U(SCH_1):PAGE313
 R1308    1      A Q_RES_0402LF-10K,1%,1/16W,EMPTA    I23 @S9S_MB_2U_LIB.S9S_MB_2U(SCH_1):PAGE209
 R1473    1      A Q_RES_0402LF-1K,1%,1/16W,CHIP,A    I37 @S9S_MB_2U_LIB.S9S_MB_2U(SCH_1):PAGE209

FM_RST_PERST_BIT2 @S9S_MB_2U_LIB.S9S_MB_2U(SCH_1):FM_RST_PERST_BIT2
  U249   W8  PB16D LCMXO3LF9400C5BG484C-LCMXO3LF-A     I1 @S9S_MB_2U_LIB.S9S_MB_2U(SCH_1):PAGE312
 R1312    1      A Q_RES_0402LF-10K,1%,1/16W,EMPTA    I22 @S9S_MB_2U_LIB.S9S_MB_2U(SCH_1):PAGE209
 R1474    1      A Q_RES_0402LF-1K,1%,1/16W,CHIP,A    I36 @S9S_MB_2U_LIB.S9S_MB_2U(SCH_1):PAGE209

FM_S3M_CPU0_CPLD_CONFIG_N @S9S_MB_2U_LIB.S9S_MB_2U(SCH_1):FM_S3M_CPU0_CPLD_CONFIG_N
    U2 CK65 TEST_2 SOCKET4677_AZIF0045P001C01CS-SA     I1 @S9S_MB_2U_LIB.S9S_MB_2U(SCH_1):PAGE15
  R321    2      B Q_RES_0402LF-10K,1%,1/16W,CHIPA     I2 @S9S_MB_2U_LIB.S9S_MB_2U(SCH_1):PAGE80

FM_S3M_CPU0_CPLD_CRC_ERROR @S9S_MB_2U_LIB.S9S_MB_2U(SCH_1):FM_S3M_CPU0_CPLD_CRC_ERROR
    U2 CY20 CD_INIT_ERROR SOCKET4677_AZIF0045P001C01CS-SA     I1 @S9S_MB_2U_LIB.S9S_MB_2U(SCH_1):PAGE15
 R1216    2      B Q_RES_0402LF-1.5K,1%,1/16W,CHIA     I1 @S9S_MB_2U_LIB.S9S_MB_2U(SCH_1):PAGE80
  U249   C6  PT14C LCMXO3LF9400C5BG484C-LCMXO3LF-A   I188 @S9S_MB_2U_LIB.S9S_MB_2U(SCH_1):PAGE314

FM_S3M_CPU0_LVC1_GPIO_0 @S9S_MB_2U_LIB.S9S_MB_2U(SCH_1):FM_S3M_CPU0_LVC1_GPIO_0
    U2 BA70 PARTITION_ID0 SOCKET4677_AZIF0045P001C01CS-SA     I1 @S9S_MB_2U_LIB.S9S_MB_2U(SCH_1):PAGE15
  R249    2      B Q_RES_0402LF-240,1%,1/16W,EMPTA    I27 @S9S_MB_2U_LIB.S9S_MB_2U(SCH_1):PAGE120

FM_S3M_CPU0_LVC1_GPIO_1 @S9S_MB_2U_LIB.S9S_MB_2U(SCH_1):FM_S3M_CPU0_LVC1_GPIO_1
    U2 AV71 PARTITION_ID1 SOCKET4677_AZIF0045P001C01CS-SA     I1 @S9S_MB_2U_LIB.S9S_MB_2U(SCH_1):PAGE15
  R250    2      B Q_RES_0402LF-240,1%,1/16W,EMPTA    I29 @S9S_MB_2U_LIB.S9S_MB_2U(SCH_1):PAGE120

FM_S3M_CPU0_LVC1_GPIO_2 @S9S_MB_2U_LIB.S9S_MB_2U(SCH_1):FM_S3M_CPU0_LVC1_GPIO_2
    U2 AV69 TEST_7 SOCKET4677_AZIF0045P001C01CS-SA     I1 @S9S_MB_2U_LIB.S9S_MB_2U(SCH_1):PAGE15
  R253    2      B Q_RES_0402LF-240,1%,1/16W,CHIPA    I31 @S9S_MB_2U_LIB.S9S_MB_2U(SCH_1):PAGE120
 R1391    2      B Q_RES_0402LF-240,1%,1/16W,EMPTA    I61 @S9S_MB_2U_LIB.S9S_MB_2U(SCH_1):PAGE120

FM_S3M_CPU0_LVC1_GPIO_3 @S9S_MB_2U_LIB.S9S_MB_2U(SCH_1):FM_S3M_CPU0_LVC1_GPIO_3
    U2 AY69 TEST_8 SOCKET4677_AZIF0045P001C01CS-SA     I1 @S9S_MB_2U_LIB.S9S_MB_2U(SCH_1):PAGE15
  R254    2      B Q_RES_0402LF-240,1%,1/16W,CHIPA    I32 @S9S_MB_2U_LIB.S9S_MB_2U(SCH_1):PAGE120
 R1392    2      B Q_RES_0402LF-240,1%,1/16W,EMPTA    I62 @S9S_MB_2U_LIB.S9S_MB_2U(SCH_1):PAGE120

FM_S3M_CPU0_LVC1_GPIO_4 @S9S_MB_2U_LIB.S9S_MB_2U(SCH_1):FM_S3M_CPU0_LVC1_GPIO_4
    U2 AW70 RSVD25 SOCKET4677_AZIF0045P001C01CS-SA     I1 @S9S_MB_2U_LIB.S9S_MB_2U(SCH_1):PAGE15
  R251    2      B Q_RES_0402LF-240,1%,1/16W,EMPTA    I28 @S9S_MB_2U_LIB.S9S_MB_2U(SCH_1):PAGE120

FM_S3M_CPU1_CPLD_CONFIG_N @S9S_MB_2U_LIB.S9S_MB_2U(SCH_1):FM_S3M_CPU1_CPLD_CONFIG_N
    U1 CK65 TEST_2 SOCKET4677_AZIF0045P001C01CS-SA     I5 @S9S_MB_2U_LIB.S9S_MB_2U(SCH_1):PAGE46
  R327    2      B Q_RES_0402LF-10K,1%,1/16W,CHIPA    I25 @S9S_MB_2U_LIB.S9S_MB_2U(SCH_1):PAGE80

FM_S3M_CPU1_CPLD_CRC_ERROR @S9S_MB_2U_LIB.S9S_MB_2U(SCH_1):FM_S3M_CPU1_CPLD_CRC_ERROR
    U1 CY20 CD_INIT_ERROR SOCKET4677_AZIF0045P001C01CS-SA     I5 @S9S_MB_2U_LIB.S9S_MB_2U(SCH_1):PAGE46
 R1217    2      B Q_RES_0402LF-1.5K,1%,1/16W,CHIA    I22 @S9S_MB_2U_LIB.S9S_MB_2U(SCH_1):PAGE80
  U249   D7  PT14D LCMXO3LF9400C5BG484C-LCMXO3LF-A   I188 @S9S_MB_2U_LIB.S9S_MB_2U(SCH_1):PAGE314

FM_S3M_CPU1_LVC1_GPIO_0 @S9S_MB_2U_LIB.S9S_MB_2U(SCH_1):FM_S3M_CPU1_LVC1_GPIO_0
    U1 BA70 PARTITION_ID0 SOCKET4677_AZIF0045P001C01CS-SA     I5 @S9S_MB_2U_LIB.S9S_MB_2U(SCH_1):PAGE46
  R255    2      B Q_RES_0402LF-240,1%,1/16W,EMPTA    I42 @S9S_MB_2U_LIB.S9S_MB_2U(SCH_1):PAGE120

FM_S3M_CPU1_LVC1_GPIO_1 @S9S_MB_2U_LIB.S9S_MB_2U(SCH_1):FM_S3M_CPU1_LVC1_GPIO_1
    U1 AV71 PARTITION_ID1 SOCKET4677_AZIF0045P001C01CS-SA     I5 @S9S_MB_2U_LIB.S9S_MB_2U(SCH_1):PAGE46
  R256    2      B Q_RES_0402LF-240,1%,1/16W,EMPTA    I48 @S9S_MB_2U_LIB.S9S_MB_2U(SCH_1):PAGE120

FM_S3M_CPU1_LVC1_GPIO_2 @S9S_MB_2U_LIB.S9S_MB_2U(SCH_1):FM_S3M_CPU1_LVC1_GPIO_2
    U1 AV69 TEST_7 SOCKET4677_AZIF0045P001C01CS-SA     I5 @S9S_MB_2U_LIB.S9S_MB_2U(SCH_1):PAGE46
  R259    2      B Q_RES_0402LF-240,1%,1/16W,CHIPA    I45 @S9S_MB_2U_LIB.S9S_MB_2U(SCH_1):PAGE120
 R1393    2      B Q_RES_0402LF-240,1%,1/16W,EMPTA    I66 @S9S_MB_2U_LIB.S9S_MB_2U(SCH_1):PAGE120

FM_S3M_CPU1_LVC1_GPIO_3 @S9S_MB_2U_LIB.S9S_MB_2U(SCH_1):FM_S3M_CPU1_LVC1_GPIO_3
    U1 AY69 TEST_8 SOCKET4677_AZIF0045P001C01CS-SA     I5 @S9S_MB_2U_LIB.S9S_MB_2U(SCH_1):PAGE46
  R260    2      B Q_RES_0402LF-240,1%,1/16W,CHIPA    I46 @S9S_MB_2U_LIB.S9S_MB_2U(SCH_1):PAGE120
 R1394    2      B Q_RES_0402LF-240,1%,1/16W,EMPTA    I67 @S9S_MB_2U_LIB.S9S_MB_2U(SCH_1):PAGE120

FM_S3M_CPU1_LVC1_GPIO_4 @S9S_MB_2U_LIB.S9S_MB_2U(SCH_1):FM_S3M_CPU1_LVC1_GPIO_4
    U1 AW70 RSVD25 SOCKET4677_AZIF0045P001C01CS-SA     I5 @S9S_MB_2U_LIB.S9S_MB_2U(SCH_1):PAGE46
  R257    2      B Q_RES_0402LF-240,1%,1/16W,EMPTA    I43 @S9S_MB_2U_LIB.S9S_MB_2U(SCH_1):PAGE120

FM_SCM_PRSNT1_N @S9S_MB_2U_LIB.S9S_MB_2U(SCH_1):FM_SCM_PRSNT1_N
 R1854    2      B Q_RES_0402LF-10K,1%,1/16W,CHIPA     I2 @S9S_MB_2U_LIB.S9S_MB_2U(SCH_1):PAGE229
 R1856    1      A Q_RES_0402LF-100,1%,1/16W,CHIPA     I3 @S9S_MB_2U_LIB.S9S_MB_2U(SCH_1):PAGE229
   J41  A57 PERP12 SCONN168_ME1016810202011-SCONNA   I173 @S9S_MB_2U_LIB.S9S_MB_2U(SCH_1):PAGE227

FM_SCM_PRSNT1_R_N @S9S_MB_2U_LIB.S9S_MB_2U(SCH_1):FM_SCM_PRSNT1_R_N
 R1856    2      B Q_RES_0402LF-100,1%,1/16W,CHIPA     I3 @S9S_MB_2U_LIB.S9S_MB_2U(SCH_1):PAGE229
   Q39    G      G MOSFET_NCH_GDS_ESD_PROTECTED-2A     I9 @S9S_MB_2U_LIB.S9S_MB_2U(SCH_1):PAGE229

FM_SLPS3_PLD_N @S9S_MB_2U_LIB.S9S_MB_2U(SCH_1):FM_SLPS3_PLD_N
 R1995    2      B Q_RES_0402LF-33.2,1%,1/16W,CHIA    I86 @S9S_MB_2U_LIB.S9S_MB_2U(SCH_1):PAGE212
  U249  U15  PB38D LCMXO3LF9400C5BG484C-LCMXO3LF-A     I1 @S9S_MB_2U_LIB.S9S_MB_2U(SCH_1):PAGE312

FM_SLPS4_PLD_N @S9S_MB_2U_LIB.S9S_MB_2U(SCH_1):FM_SLPS4_PLD_N
 R1996    2      B Q_RES_0402LF-33.2,1%,1/16W,CHIA    I87 @S9S_MB_2U_LIB.S9S_MB_2U(SCH_1):PAGE212
  U249  U21  PR24D LCMXO3LF9400C5BG484C-LCMXO3LF-A     I1 @S9S_MB_2U_LIB.S9S_MB_2U(SCH_1):PAGE313

FM_SLP_SUS_RSM_RST_N @S9S_MB_2U_LIB.S9S_MB_2U(SCH_1):FM_SLP_SUS_RSM_RST_N
 R1660    1      A Q_RES_0402LF-10K,1%,1/16W,EMPTA    I14 @S9S_MB_2U_LIB.S9S_MB_2U(SCH_1):PAGE209
  U249   C9  PT20C LCMXO3LF9400C5BG484C-LCMXO3LF-A   I188 @S9S_MB_2U_LIB.S9S_MB_2U(SCH_1):PAGE314
 R4674    1      A Q_RES_0402LF-10K,1%,1/16W,CHIPA    I46 @S9S_MB_2U_LIB.S9S_MB_2U(SCH_1):PAGE209
 R1736    2      B Q_RES_0402LF-33.2,1%,1/16W,CHIA    I99 @S9S_MB_2U_LIB.S9S_MB_2U(SCH_1):PAGE174

FM_SMB_1_ALERT_GPU @S9S_MB_2U_LIB.S9S_MB_2U(SCH_1):FM_SMB_1_ALERT_GPU
 R3029    2      B Q_RES_0402LF-4.7K,5%,1/16W,CHIA   I144 @S9S_MB_2U_LIB.S9S_MB_2U(SCH_1):PAGE145
   Q75    5     G2 MOSFET_NCH_DUAL-PJT138K,SMLF,IA   I151 @S9S_MB_2U_LIB.S9S_MB_2U(SCH_1):PAGE145
   Q75    6     D1 MOSFET_NCH_DUAL-PJT138K,SMLF,IA   I152 @S9S_MB_2U_LIB.S9S_MB_2U(SCH_1):PAGE145

FM_SMB_1_ALERT_GPU_ISO_N @S9S_MB_2U_LIB.S9S_MB_2U(SCH_1):FM_SMB_1_ALERT_GPU_ISO_N
 R3030    2      B Q_RES_0402LF-4.7K,5%,1/16W,CHIA   I146 @S9S_MB_2U_LIB.S9S_MB_2U(SCH_1):PAGE145
 C1802    1      A Q_CAP_0402-1000PF,50V,5%,EMPTYA   I148 @S9S_MB_2U_LIB.S9S_MB_2U(SCH_1):PAGE145
   Q75    3     D2 MOSFET_NCH_DUAL-PJT138K,SMLF,IA   I151 @S9S_MB_2U_LIB.S9S_MB_2U(SCH_1):PAGE145
 R3066    1      A Q_RES_0402LF-0,5%,1/16W,CHIP,CA   I175 @S9S_MB_2U_LIB.S9S_MB_2U(SCH_1):PAGE313

FM_SMB_1_ALERT_GPU_ISO_R_N @S9S_MB_2U_LIB.S9S_MB_2U(SCH_1):FM_SMB_1_ALERT_GPU_ISO_R_N
  U249  W21  PR28B LCMXO3LF9400C5BG484C-LCMXO3LF-A     I1 @S9S_MB_2U_LIB.S9S_MB_2U(SCH_1):PAGE313
 R3066    2      B Q_RES_0402LF-0,5%,1/16W,CHIP,CA   I175 @S9S_MB_2U_LIB.S9S_MB_2U(SCH_1):PAGE313

FM_SMB_1_ALERT_GPU_N @S9S_MB_2U_LIB.S9S_MB_2U(SCH_1):FM_SMB_1_ALERT_GPU_N
 R3028    1      A Q_RES_0402LF-100K,1%,1/16W,EMPA   I139 @S9S_MB_2U_LIB.S9S_MB_2U(SCH_1):PAGE145
   Q75    2     G1 MOSFET_NCH_DUAL-PJT138K,SMLF,IA   I152 @S9S_MB_2U_LIB.S9S_MB_2U(SCH_1):PAGE145
  J110   N4     N4 CONN112_10137002101LF-CONN112_A    I54 @S9S_MB_2U_LIB.S9S_MB_2U(SCH_1):PAGE318
 R3510    2      B Q_RES_0402LF-54.9K,1%,1/16W,CHA   I176 @S9S_MB_2U_LIB.S9S_MB_2U(SCH_1):PAGE145

FM_SMB_2_ALERT_GPU @S9S_MB_2U_LIB.S9S_MB_2U(SCH_1):FM_SMB_2_ALERT_GPU
   Q74    6     D1 MOSFET_NCH_DUAL-PJT138K,SMLF,IA   I121 @S9S_MB_2U_LIB.S9S_MB_2U(SCH_1):PAGE145
   Q74    5     G2 MOSFET_NCH_DUAL-PJT138K,SMLF,IA   I122 @S9S_MB_2U_LIB.S9S_MB_2U(SCH_1):PAGE145
 R3034    2      B Q_RES_0402LF-4.7K,5%,1/16W,CHIA   I129 @S9S_MB_2U_LIB.S9S_MB_2U(SCH_1):PAGE145

FM_SMB_2_ALERT_GPU_ISO_N @S9S_MB_2U_LIB.S9S_MB_2U(SCH_1):FM_SMB_2_ALERT_GPU_ISO_N
   Q74    3     D2 MOSFET_NCH_DUAL-PJT138K,SMLF,IA   I122 @S9S_MB_2U_LIB.S9S_MB_2U(SCH_1):PAGE145
 C1804    1      A Q_CAP_0402-1000PF,50V,5%,EMPTYA   I125 @S9S_MB_2U_LIB.S9S_MB_2U(SCH_1):PAGE145
 R3035    2      B Q_RES_0402LF-4.7K,5%,1/16W,CHIA   I127 @S9S_MB_2U_LIB.S9S_MB_2U(SCH_1):PAGE145
 R3067    1      A Q_RES_0402LF-0,5%,1/16W,CHIP,CA   I176 @S9S_MB_2U_LIB.S9S_MB_2U(SCH_1):PAGE313

FM_SMB_2_ALERT_GPU_ISO_R_N @S9S_MB_2U_LIB.S9S_MB_2U(SCH_1):FM_SMB_2_ALERT_GPU_ISO_R_N
  U249  U19  PR28C LCMXO3LF9400C5BG484C-LCMXO3LF-A     I1 @S9S_MB_2U_LIB.S9S_MB_2U(SCH_1):PAGE313
 R3067    2      B Q_RES_0402LF-0,5%,1/16W,CHIP,CA   I176 @S9S_MB_2U_LIB.S9S_MB_2U(SCH_1):PAGE313

FM_SMB_2_ALERT_GPU_N @S9S_MB_2U_LIB.S9S_MB_2U(SCH_1):FM_SMB_2_ALERT_GPU_N
   Q74    2     G1 MOSFET_NCH_DUAL-PJT138K,SMLF,IA   I121 @S9S_MB_2U_LIB.S9S_MB_2U(SCH_1):PAGE145
 R3032    1      A Q_RES_0402LF-100K,1%,1/16W,EMPA   I134 @S9S_MB_2U_LIB.S9S_MB_2U(SCH_1):PAGE145
  J110   N6     N6 CONN112_10137002101LF-CONN112_A    I16 @S9S_MB_2U_LIB.S9S_MB_2U(SCH_1):PAGE318
 R3514    2      B Q_RES_0402LF-54.9K,1%,1/16W,CHA   I175 @S9S_MB_2U_LIB.S9S_MB_2U(SCH_1):PAGE145

FM_SMB_CPU0_ALERT @S9S_MB_2U_LIB.S9S_MB_2U(SCH_1):FM_SMB_CPU0_ALERT
 R1921    1      A Q_RES_0402LF-33.2,1%,1/16W,CHIA   I132 @S9S_MB_2U_LIB.S9S_MB_2U(SCH_1):PAGE154
  U209    1   INT# PCA9555APW-PCA9555APW,SMLF,IC,A   I206 @S9S_MB_2U_LIB.S9S_MB_2U(SCH_1):PAGE154

FM_SMB_CPU0_ALERT_R1 @S9S_MB_2U_LIB.S9S_MB_2U(SCH_1):FM_SMB_CPU0_ALERT_R1
 R1002    2      B Q_RES_0402LF-4.7K,5%,1/16W,CHIA    I34 @S9S_MB_2U_LIB.S9S_MB_2U(SCH_1):PAGE223
   Q15    6     D1 MOSFET_NCH_DUAL-PJT138K,SMLF,IA   I104 @S9S_MB_2U_LIB.S9S_MB_2U(SCH_1):PAGE223
   Q15    5     G2 MOSFET_NCH_DUAL-PJT138K,SMLF,IA   I108 @S9S_MB_2U_LIB.S9S_MB_2U(SCH_1):PAGE223

FM_SMB_CPU1_ALERT @S9S_MB_2U_LIB.S9S_MB_2U(SCH_1):FM_SMB_CPU1_ALERT
 R3158    1      A Q_RES_0402LF-33.2,1%,1/16W,CHIA    I23 @S9S_MB_2U_LIB.S9S_MB_2U(SCH_1):PAGE132
   U51    1   INT# PCA9555APW-PCA9555APW,SMLF,IC,A    I66 @S9S_MB_2U_LIB.S9S_MB_2U(SCH_1):PAGE132

FM_SMB_CPU1_ALERT_R1 @S9S_MB_2U_LIB.S9S_MB_2U(SCH_1):FM_SMB_CPU1_ALERT_R1
 R1003    2      B Q_RES_0402LF-4.7K,5%,1/16W,CHIA    I38 @S9S_MB_2U_LIB.S9S_MB_2U(SCH_1):PAGE223
   Q16    6     D1 MOSFET_NCH_DUAL-PJT138K,SMLF,IA   I106 @S9S_MB_2U_LIB.S9S_MB_2U(SCH_1):PAGE223
   Q16    5     G2 MOSFET_NCH_DUAL-PJT138K,SMLF,IA   I109 @S9S_MB_2U_LIB.S9S_MB_2U(SCH_1):PAGE223

FM_SMB_PEHPCPU0_PCIE_ALERT_N @S9S_MB_2U_LIB.S9S_MB_2U(SCH_1):FM_SMB_PEHPCPU0_PCIE_ALERT_N
 R1921    2      B Q_RES_0402LF-33.2,1%,1/16W,CHIA   I132 @S9S_MB_2U_LIB.S9S_MB_2U(SCH_1):PAGE154
  R998    1      A Q_RES_0402LF-0,5%,1/16W,CHIP,CA    I53 @S9S_MB_2U_LIB.S9S_MB_2U(SCH_1):PAGE223
   JP7    1      1 CONN3_210HP1030BR1-CONN3_210-HB    I64 @S9S_MB_2U_LIB.S9S_MB_2U(SCH_1):PAGE223

FM_SMB_PEHPCPU0_PCIE_ALERT_R_N @S9S_MB_2U_LIB.S9S_MB_2U(SCH_1):FM_SMB_PEHPCPU0_PCIE_ALERT_R_N
 R1000    2      B Q_RES_0402LF-4.7K,5%,1/16W,CHIA    I52 @S9S_MB_2U_LIB.S9S_MB_2U(SCH_1):PAGE223
  R998    2      B Q_RES_0402LF-0,5%,1/16W,CHIP,CA    I53 @S9S_MB_2U_LIB.S9S_MB_2U(SCH_1):PAGE223
   Q15    2     G1 MOSFET_NCH_DUAL-PJT138K,SMLF,IA   I104 @S9S_MB_2U_LIB.S9S_MB_2U(SCH_1):PAGE223

FM_SMB_PEHPCPU1_PCIE_ALERT_N @S9S_MB_2U_LIB.S9S_MB_2U(SCH_1):FM_SMB_PEHPCPU1_PCIE_ALERT_N
   JP7    3      3 CONN3_210HP1030BR1-CONN3_210-HB    I64 @S9S_MB_2U_LIB.S9S_MB_2U(SCH_1):PAGE223
  R999    1      A Q_RES_0402LF-0,5%,1/16W,CHIP,CA    I69 @S9S_MB_2U_LIB.S9S_MB_2U(SCH_1):PAGE223
 R3158    2      B Q_RES_0402LF-33.2,1%,1/16W,CHIA    I23 @S9S_MB_2U_LIB.S9S_MB_2U(SCH_1):PAGE132

FM_SMB_PEHPCPU1_PCIE_ALERT_R_N @S9S_MB_2U_LIB.S9S_MB_2U(SCH_1):FM_SMB_PEHPCPU1_PCIE_ALERT_R_N
 R1001    2      B Q_RES_0402LF-4.7K,5%,1/16W,CHIA    I55 @S9S_MB_2U_LIB.S9S_MB_2U(SCH_1):PAGE223
  R999    2      B Q_RES_0402LF-0,5%,1/16W,CHIP,CA    I69 @S9S_MB_2U_LIB.S9S_MB_2U(SCH_1):PAGE223
   Q16    2     G1 MOSFET_NCH_DUAL-PJT138K,SMLF,IA   I106 @S9S_MB_2U_LIB.S9S_MB_2U(SCH_1):PAGE223

FM_SOL_UART_CH_SEL @S9S_MB_2U_LIB.S9S_MB_2U(SCH_1):FM_SOL_UART_CH_SEL
  U249  K22  PR16A LCMXO3LF9400C5BG484C-LCMXO3LF-A     I1 @S9S_MB_2U_LIB.S9S_MB_2U(SCH_1):PAGE313
 R3778    2      B Q_RES_0402LF-0,5%,1/16W,CHIP,CA   I159 @S9S_MB_2U_LIB.S9S_MB_2U(SCH_1):PAGE227

FM_SOL_UART_CH_SEL_R @S9S_MB_2U_LIB.S9S_MB_2U(SCH_1):FM_SOL_UART_CH_SEL_R
 R3778    1      A Q_RES_0402LF-0,5%,1/16W,CHIP,CA   I159 @S9S_MB_2U_LIB.S9S_MB_2U(SCH_1):PAGE227
   J41 OB14 RBT_CRS_DV SCONN168_ME1016810202011-SCONNA   I173 @S9S_MB_2U_LIB.S9S_MB_2U(SCH_1):PAGE227

FM_SPD_REMOTE_EN @S9S_MB_2U_LIB.S9S_MB_2U(SCH_1):FM_SPD_REMOTE_EN
   U15    1      S QS3VH257QG8_SMLF-QS3VH257QG8,IA    I19 @S9S_MB_2U_LIB.S9S_MB_2U(SCH_1):PAGE217
  R318    1      A Q_RES_0402LF-10K,1%,1/16W,CHIPA    I42 @S9S_MB_2U_LIB.S9S_MB_2U(SCH_1):PAGE217
   R87    2      B Q_RES_0402LF-1K,1%,1/16W,EMPTYA    I43 @S9S_MB_2U_LIB.S9S_MB_2U(SCH_1):PAGE217
   U14    1      S QS3VH257QG8_SMLF-QS3VH257QG8,IA    I12 @S9S_MB_2U_LIB.S9S_MB_2U(SCH_1):PAGE218
 R1821    2      B Q_RES_0402LF-200,1%,1/16W,CHIPA    I53 @S9S_MB_2U_LIB.S9S_MB_2U(SCH_1):PAGE217

FM_SPD_REMOTE_EN_R @S9S_MB_2U_LIB.S9S_MB_2U(SCH_1):FM_SPD_REMOTE_EN_R
  U249 AB15  PB35A LCMXO3LF9400C5BG484C-LCMXO3LF-A     I1 @S9S_MB_2U_LIB.S9S_MB_2U(SCH_1):PAGE312
 R1821    1      A Q_RES_0402LF-200,1%,1/16W,CHIPA    I53 @S9S_MB_2U_LIB.S9S_MB_2U(SCH_1):PAGE217

FM_SPI_3V3_1V8_VOLTAGE @S9S_MB_2U_LIB.S9S_MB_2U(SCH_1):FM_SPI_3V3_1V8_VOLTAGE
    U4 AU13 GPPC_S_4_CPU_GP_2 EMMITSBURG_REV0P9-GFNOCPU04302A    I27 @S9S_MB_2U_LIB.S9S_MB_2U(SCH_1):PAGE177
  R374    2      B Q_RES_0402LF-1K,1%,1/16W,EMPTYA    I60 @S9S_MB_2U_LIB.S9S_MB_2U(SCH_1):PAGE186
  R375    1      A Q_RES_0402LF-10K,1%,1/16W,CHIPA    I61 @S9S_MB_2U_LIB.S9S_MB_2U(SCH_1):PAGE186

FM_SUSACK_N @S9S_MB_2U_LIB.S9S_MB_2U(SCH_1):FM_SUSACK_N
    U4  BA7 GPPC_S_7_SUSACK_N EMMITSBURG_REV0P9-GFNOCPU04302A    I27 @S9S_MB_2U_LIB.S9S_MB_2U(SCH_1):PAGE177
 R1461    2      B Q_RES_0402LF-0,5%,1/16W,CHIP,CA    I80 @S9S_MB_2U_LIB.S9S_MB_2U(SCH_1):PAGE177
 R2071    2      B Q_RES_0402LF-0,5%,1/16W,EMPTY,A   I137 @S9S_MB_2U_LIB.S9S_MB_2U(SCH_1):PAGE314

FM_SWB_BIC_READY @S9S_MB_2U_LIB.S9S_MB_2U(SCH_1):FM_SWB_BIC_READY
 R2836    2      B Q_RES_0402LF-4.7K,5%,1/16W,CHIA    I19 @S9S_MB_2U_LIB.S9S_MB_2U(SCH_1):PAGE145
   Q70    6     D1 MOSFET_NCH_DUAL-PJT138K,SMLF,IA    I35 @S9S_MB_2U_LIB.S9S_MB_2U(SCH_1):PAGE145
   Q70    5     G2 MOSFET_NCH_DUAL-PJT138K,SMLF,IA   I120 @S9S_MB_2U_LIB.S9S_MB_2U(SCH_1):PAGE145

FM_SWB_BIC_READY_ISO_N @S9S_MB_2U_LIB.S9S_MB_2U(SCH_1):FM_SWB_BIC_READY_ISO_N
 C1754    1      A Q_CAP_0402-1000PF,50V,5%,EMPTYA    I92 @S9S_MB_2U_LIB.S9S_MB_2U(SCH_1):PAGE145
 R2933    2      B Q_RES_0402LF-4.7K,5%,1/16W,CHIA    I97 @S9S_MB_2U_LIB.S9S_MB_2U(SCH_1):PAGE145
   Q70    3     D2 MOSFET_NCH_DUAL-PJT138K,SMLF,IA   I120 @S9S_MB_2U_LIB.S9S_MB_2U(SCH_1):PAGE145
 R2844    1      A Q_RES_0402LF-33.2,1%,1/16W,CHIA   I112 @S9S_MB_2U_LIB.S9S_MB_2U(SCH_1):PAGE314

FM_SWB_BIC_READY_ISO_R_N @S9S_MB_2U_LIB.S9S_MB_2U(SCH_1):FM_SWB_BIC_READY_ISO_R_N
 R2844    2      B Q_RES_0402LF-33.2,1%,1/16W,CHIA   I112 @S9S_MB_2U_LIB.S9S_MB_2U(SCH_1):PAGE314
  U249   B3  PT11A LCMXO3LF9400C5BG484C-LCMXO3LF-A   I188 @S9S_MB_2U_LIB.S9S_MB_2U(SCH_1):PAGE314

FM_SWB_BIC_READY_N @S9S_MB_2U_LIB.S9S_MB_2U(SCH_1):FM_SWB_BIC_READY_N
  J105   N4     N4 CONN112_10137002101LF-CONN112_A    I65 @S9S_MB_2U_LIB.S9S_MB_2U(SCH_1):PAGE142
   Q70    2     G1 MOSFET_NCH_DUAL-PJT138K,SMLF,IA    I35 @S9S_MB_2U_LIB.S9S_MB_2U(SCH_1):PAGE145
 R2833    1      A Q_RES_0402LF-100K,1%,1/16W,EMPA    I60 @S9S_MB_2U_LIB.S9S_MB_2U(SCH_1):PAGE145
 R2832    2      B Q_RES_0402LF-100K,1%,1/16W,CHIA    I67 @S9S_MB_2U_LIB.S9S_MB_2U(SCH_1):PAGE145

FM_SWB_PWRGD @S9S_MB_2U_LIB.S9S_MB_2U(SCH_1):FM_SWB_PWRGD
  J106   A3     A3 CONN112_10137002101LF-CONN112_A    I65 @S9S_MB_2U_LIB.S9S_MB_2U(SCH_1):PAGE144
 R2838    1      A Q_RES_0402LF-100K,1%,1/16W,CHIA    I62 @S9S_MB_2U_LIB.S9S_MB_2U(SCH_1):PAGE145
 R2837    2      B Q_RES_0402LF-100K,1%,1/16W,EMPA    I80 @S9S_MB_2U_LIB.S9S_MB_2U(SCH_1):PAGE145
   Q71    2     G1 MOSFET_NCH_DUAL-PJT138K,SMLF,IA   I118 @S9S_MB_2U_LIB.S9S_MB_2U(SCH_1):PAGE145

FM_SWB_PWRGD_ISO @S9S_MB_2U_LIB.S9S_MB_2U(SCH_1):FM_SWB_PWRGD_ISO
   Q71    3     D2 MOSFET_NCH_DUAL-PJT138K,SMLF,IA   I100 @S9S_MB_2U_LIB.S9S_MB_2U(SCH_1):PAGE145
 R2934    2      B Q_RES_0402LF-4.7K,5%,1/16W,CHIA   I101 @S9S_MB_2U_LIB.S9S_MB_2U(SCH_1):PAGE145
 C1774    1      A Q_CAP_0402-1000PF,50V,5%,EMPTYA   I111 @S9S_MB_2U_LIB.S9S_MB_2U(SCH_1):PAGE145
 R2663    1      A Q_RES_0402LF-33.2,1%,1/16W,CHIA   I114 @S9S_MB_2U_LIB.S9S_MB_2U(SCH_1):PAGE314

FM_SWB_PWRGD_ISO_R @S9S_MB_2U_LIB.S9S_MB_2U(SCH_1):FM_SWB_PWRGD_ISO_R
 R2663    2      B Q_RES_0402LF-33.2,1%,1/16W,CHIA   I114 @S9S_MB_2U_LIB.S9S_MB_2U(SCH_1):PAGE314
  U249   E6   PT9C LCMXO3LF9400C5BG484C-LCMXO3LF-A   I188 @S9S_MB_2U_LIB.S9S_MB_2U(SCH_1):PAGE314

FM_SWB_PWRGD_N @S9S_MB_2U_LIB.S9S_MB_2U(SCH_1):FM_SWB_PWRGD_N
 R2841    2      B Q_RES_0402LF-4.7K,5%,1/16W,CHIA    I24 @S9S_MB_2U_LIB.S9S_MB_2U(SCH_1):PAGE145
   Q71    5     G2 MOSFET_NCH_DUAL-PJT138K,SMLF,IA   I100 @S9S_MB_2U_LIB.S9S_MB_2U(SCH_1):PAGE145
   Q71    6     D1 MOSFET_NCH_DUAL-PJT138K,SMLF,IA   I118 @S9S_MB_2U_LIB.S9S_MB_2U(SCH_1):PAGE145

FM_SWB_PWR_EN @S9S_MB_2U_LIB.S9S_MB_2U(SCH_1):FM_SWB_PWR_EN
 R2661    1      A Q_RES_0402LF-33.2,1%,1/16W,CHIA   I135 @S9S_MB_2U_LIB.S9S_MB_2U(SCH_1):PAGE314
  U249   B1 PT9A||L_GPLLT LCMXO3LF9400C5BG484C-LCMXO3LF-A   I188 @S9S_MB_2U_LIB.S9S_MB_2U(SCH_1):PAGE314

FM_SWB_PWR_EN_R @S9S_MB_2U_LIB.S9S_MB_2U(SCH_1):FM_SWB_PWR_EN_R
  U256    3     A1 74LVC2G17GW-74LVC2G17GW,SMLF,IA   I173 @S9S_MB_2U_LIB.S9S_MB_2U(SCH_1):PAGE160
 R2910    2      B Q_RES_0402LF-100K,1%,1/16W,EMPA   I187 @S9S_MB_2U_LIB.S9S_MB_2U(SCH_1):PAGE160
 R2918    1      A Q_RES_0402LF-4.7K,5%,1/16W,CHIA   I188 @S9S_MB_2U_LIB.S9S_MB_2U(SCH_1):PAGE160
 R2661    2      B Q_RES_0402LF-33.2,1%,1/16W,CHIA   I135 @S9S_MB_2U_LIB.S9S_MB_2U(SCH_1):PAGE314

FM_SWB_PWR_EN_R1_BUF @S9S_MB_2U_LIB.S9S_MB_2U(SCH_1):FM_SWB_PWR_EN_R1_BUF
  U256    4     B1 74LVC2G17GW-74LVC2G17GW,SMLF,IA   I173 @S9S_MB_2U_LIB.S9S_MB_2U(SCH_1):PAGE160
 R2914    2      B Q_RES_0402LF-4.7K,5%,1/16W,EMPA   I192 @S9S_MB_2U_LIB.S9S_MB_2U(SCH_1):PAGE160
 R2932    1      A Q_RES_0402LF-4.7K,5%,1/16W,CHIA   I195 @S9S_MB_2U_LIB.S9S_MB_2U(SCH_1):PAGE160
 R3515    1      A Q_RES_0402LF-49.9,1%,1/16W,CHIA   I198 @S9S_MB_2U_LIB.S9S_MB_2U(SCH_1):PAGE160

FM_SWB_PWR_EN_R_BUF @S9S_MB_2U_LIB.S9S_MB_2U(SCH_1):FM_SWB_PWR_EN_R_BUF
  J105   N2     N2 CONN112_10137002101LF-CONN112_A    I65 @S9S_MB_2U_LIB.S9S_MB_2U(SCH_1):PAGE142
 R3515    2      B Q_RES_0402LF-49.9,1%,1/16W,CHIA   I198 @S9S_MB_2U_LIB.S9S_MB_2U(SCH_1):PAGE160

FM_SYS_THROTTLE_R_N @S9S_MB_2U_LIB.S9S_MB_2U(SCH_1):FM_SYS_THROTTLE_R_N
  U104    2      A 74LVC1G07GV-74LVC1G07GV,SMLF,IA    I63 @S9S_MB_2U_LIB.S9S_MB_2U(SCH_1):PAGE152
  U218    2      A 74LVC1G07GV-74LVC1G07GV,SMLF,IA    I31 @S9S_MB_2U_LIB.S9S_MB_2U(SCH_1):PAGE156
  U249 AA14  PB33B LCMXO3LF9400C5BG484C-LCMXO3LF-A     I1 @S9S_MB_2U_LIB.S9S_MB_2U(SCH_1):PAGE312
 R1434    1      A Q_RES_0402LF-10K,1%,1/16W,CHIPA    I44 @S9S_MB_2U_LIB.S9S_MB_2U(SCH_1):PAGE209

FM_THERMAL_ALERT_N @S9S_MB_2U_LIB.S9S_MB_2U(SCH_1):FM_THERMAL_ALERT_N
 R4215    1      A Q_RES_0402LF-0,5%,1/16W,CHIP,CA    I79 @S9S_MB_2U_LIB.S9S_MB_2U(SCH_1):PAGE161
 R4214    1      A Q_RES_0402LF-0,5%,1/16W,CHIP,CA   I108 @S9S_MB_2U_LIB.S9S_MB_2U(SCH_1):PAGE161
 R4213    1      A Q_RES_0402LF-0,5%,1/16W,CHIP,CA   I115 @S9S_MB_2U_LIB.S9S_MB_2U(SCH_1):PAGE161
 R4212    1      A Q_RES_0402LF-0,5%,1/16W,CHIP,CA   I135 @S9S_MB_2U_LIB.S9S_MB_2U(SCH_1):PAGE161
 R4259    1      A Q_RES_0402LF-33.2,1%,1/16W,CHIA   I147 @S9S_MB_2U_LIB.S9S_MB_2U(SCH_1):PAGE313
 R4211    2      B Q_RES_0402LF-200K,1%,1/16W,CHIA   I168 @S9S_MB_2U_LIB.S9S_MB_2U(SCH_1):PAGE161
 R4209    2      B Q_RES_0402LF-200K,1%,1/16W,EMPA   I169 @S9S_MB_2U_LIB.S9S_MB_2U(SCH_1):PAGE161
 R4210    2      B Q_RES_0402LF-200K,1%,1/16W,EMPA   I170 @S9S_MB_2U_LIB.S9S_MB_2U(SCH_1):PAGE161
 R4208    2      B Q_RES_0402LF-200K,1%,1/16W,EMPA   I171 @S9S_MB_2U_LIB.S9S_MB_2U(SCH_1):PAGE161

FM_THERMAL_ALERT_R_N @S9S_MB_2U_LIB.S9S_MB_2U(SCH_1):FM_THERMAL_ALERT_R_N
  U249  L21  PR16B LCMXO3LF9400C5BG484C-LCMXO3LF-A     I1 @S9S_MB_2U_LIB.S9S_MB_2U(SCH_1):PAGE313
 R4259    2      B Q_RES_0402LF-33.2,1%,1/16W,CHIA   I147 @S9S_MB_2U_LIB.S9S_MB_2U(SCH_1):PAGE313

FM_THERMTRIP_DLY_LVC1_N @S9S_MB_2U_LIB.S9S_MB_2U(SCH_1):FM_THERMTRIP_DLY_LVC1_N
 R1249    1      A Q_RES_0402LF-0,5%,1/16W,CHIP,CA     I2 @S9S_MB_2U_LIB.S9S_MB_2U(SCH_1):PAGE191
 R1318    2      B Q_RES_0402LF-0,5%,1/16W,CHIP,CA   I130 @S9S_MB_2U_LIB.S9S_MB_2U(SCH_1):PAGE212

FM_THERMTRIP_DLY_LVC1_R_N @S9S_MB_2U_LIB.S9S_MB_2U(SCH_1):FM_THERMTRIP_DLY_LVC1_R_N
  U249   W3  PL29C LCMXO3LF9400C5BG484C-LCMXO3LF-A    I33 @S9S_MB_2U_LIB.S9S_MB_2U(SCH_1):PAGE311
 R1318    1      A Q_RES_0402LF-0,5%,1/16W,CHIP,CA   I130 @S9S_MB_2U_LIB.S9S_MB_2U(SCH_1):PAGE212

FM_THROTTLE_N @S9S_MB_2U_LIB.S9S_MB_2U(SCH_1):FM_THROTTLE_N
    U4  AW2 GPPC_C_14_ME_SML3ALERT_N EMMITSBURG_REV0P9-GFNOCPU04302A    I93 @S9S_MB_2U_LIB.S9S_MB_2U(SCH_1):PAGE175
 R1450    2      B Q_RES_0402LF-10K,1%,1/16W,CHIPA    I42 @S9S_MB_2U_LIB.S9S_MB_2U(SCH_1):PAGE192
 R1307    1      A Q_RES_0402LF-33.2,1%,1/16W,CHIA     I3 @S9S_MB_2U_LIB.S9S_MB_2U(SCH_1):PAGE193

FM_THROTTLE_R_N @S9S_MB_2U_LIB.S9S_MB_2U(SCH_1):FM_THROTTLE_R_N
 R1307    2      B Q_RES_0402LF-33.2,1%,1/16W,CHIA     I3 @S9S_MB_2U_LIB.S9S_MB_2U(SCH_1):PAGE193
  U249  Y15  PB35C LCMXO3LF9400C5BG484C-LCMXO3LF-A     I1 @S9S_MB_2U_LIB.S9S_MB_2U(SCH_1):PAGE312

FM_TPM_PRSNT_N @S9S_MB_2U_LIB.S9S_MB_2U(SCH_1):FM_TPM_PRSNT_N
    U4 BB31 GPP_E_19_ERR2_N EMMITSBURG_REV0P9-GFNOCPU04302A    I22 @S9S_MB_2U_LIB.S9S_MB_2U(SCH_1):PAGE176
 R1547    2      B Q_RES_0402LF-0,5%,1/16W,CHIP,CA   I139 @S9S_MB_2U_LIB.S9S_MB_2U(SCH_1):PAGE314

FM_TPM_PRSNT_R_N @S9S_MB_2U_LIB.S9S_MB_2U(SCH_1):FM_TPM_PRSNT_R_N
 R1547    1      A Q_RES_0402LF-0,5%,1/16W,CHIP,CA   I139 @S9S_MB_2U_LIB.S9S_MB_2U(SCH_1):PAGE314
  U249   A5  PT12B LCMXO3LF9400C5BG484C-LCMXO3LF-A   I188 @S9S_MB_2U_LIB.S9S_MB_2U(SCH_1):PAGE314

FM_UARTSW_LSB_N @S9S_MB_2U_LIB.S9S_MB_2U(SCH_1):FM_UARTSW_LSB_N
  U249  L19  PR14C LCMXO3LF9400C5BG484C-LCMXO3LF-A     I1 @S9S_MB_2U_LIB.S9S_MB_2U(SCH_1):PAGE313
 R3777    1      A Q_RES_0402LF-0,5%,1/16W,CHIP,CA    I19 @S9S_MB_2U_LIB.S9S_MB_2U(SCH_1):PAGE227

FM_UARTSW_LSB_R @S9S_MB_2U_LIB.S9S_MB_2U(SCH_1):FM_UARTSW_LSB_R
 R3777    2      B Q_RES_0402LF-0,5%,1/16W,CHIP,CA    I19 @S9S_MB_2U_LIB.S9S_MB_2U(SCH_1):PAGE227
   J41  A55 GND_A55 SCONN168_ME1016810202011-SCONNA   I173 @S9S_MB_2U_LIB.S9S_MB_2U(SCH_1):PAGE227

FM_UARTSW_MSB_N @S9S_MB_2U_LIB.S9S_MB_2U(SCH_1):FM_UARTSW_MSB_N
  U249  L20  PR14D LCMXO3LF9400C5BG484C-LCMXO3LF-A     I1 @S9S_MB_2U_LIB.S9S_MB_2U(SCH_1):PAGE313
 R3776    1      A Q_RES_0402LF-0,5%,1/16W,CHIP,CA    I21 @S9S_MB_2U_LIB.S9S_MB_2U(SCH_1):PAGE227

FM_UARTSW_MSB_R @S9S_MB_2U_LIB.S9S_MB_2U(SCH_1):FM_UARTSW_MSB_R
 R3776    2      B Q_RES_0402LF-0,5%,1/16W,CHIP,CA    I21 @S9S_MB_2U_LIB.S9S_MB_2U(SCH_1):PAGE227
   J41  A52 GND_A52 SCONN168_ME1016810202011-SCONNA   I173 @S9S_MB_2U_LIB.S9S_MB_2U(SCH_1):PAGE227

FM_UART_EN @S9S_MB_2U_LIB.S9S_MB_2U(SCH_1):FM_UART_EN
  U204    1     OE 74LVC1G126SE7-74LVC1G126SE-7,SA   I195 @S9S_MB_2U_LIB.S9S_MB_2U(SCH_1):PAGE140
 R3063    2      B Q_RES_0402LF-33.2,1%,1/16W,CHIA   I208 @S9S_MB_2U_LIB.S9S_MB_2U(SCH_1):PAGE140

FM_USB3_1_EN_N @S9S_MB_2U_LIB.S9S_MB_2U(SCH_1):FM_USB3_1_EN_N
 R4292    1      A Q_RES_0402LF-4.7K,1%,1/16W,EMPA    I63 @S9S_MB_2U_LIB.S9S_MB_2U(SCH_1):PAGE162
  U309    4     EN PI3EQX1002EZREX-PI3EQX1002EZREA    I43 @S9S_MB_2U_LIB.S9S_MB_2U(SCH_1):PAGE162
 R4291    2      B Q_RES_0402LF-4.7K,1%,1/16W,EMPA    I65 @S9S_MB_2U_LIB.S9S_MB_2U(SCH_1):PAGE162

FM_USB3_1_EQA @S9S_MB_2U_LIB.S9S_MB_2U(SCH_1):FM_USB3_1_EQA
 R4276    1      A Q_RES_0402LF-68K,1%,1/16W,CHIPA     I2 @S9S_MB_2U_LIB.S9S_MB_2U(SCH_1):PAGE162
 R4275    2      B Q_RES_0402LF-1K,1%,1/16W,EMPTYA     I3 @S9S_MB_2U_LIB.S9S_MB_2U(SCH_1):PAGE162
  U309    1    EQA PI3EQX1002EZREX-PI3EQX1002EZREA    I43 @S9S_MB_2U_LIB.S9S_MB_2U(SCH_1):PAGE162

FM_USB3_1_EQB @S9S_MB_2U_LIB.S9S_MB_2U(SCH_1):FM_USB3_1_EQB
 R4281    2      B Q_RES_0402LF-1K,1%,1/16W,EMPTYA     I7 @S9S_MB_2U_LIB.S9S_MB_2U(SCH_1):PAGE162
 R4282    1      A Q_RES_0402LF-68K,1%,1/16W,CHIPA     I6 @S9S_MB_2U_LIB.S9S_MB_2U(SCH_1):PAGE162
  U309   16    EQB PI3EQX1002EZREX-PI3EQX1002EZREA    I43 @S9S_MB_2U_LIB.S9S_MB_2U(SCH_1):PAGE162

FM_USB3_1_FGA @S9S_MB_2U_LIB.S9S_MB_2U(SCH_1):FM_USB3_1_FGA
 R4280    1      A Q_RES_0402LF-1K,1%,1/16W,EMPTYA    I17 @S9S_MB_2U_LIB.S9S_MB_2U(SCH_1):PAGE162
 R4279    2      B Q_RES_0402LF-1K,1%,1/16W,EMPTYA    I18 @S9S_MB_2U_LIB.S9S_MB_2U(SCH_1):PAGE162
  U309    2    FGA PI3EQX1002EZREX-PI3EQX1002EZREA    I43 @S9S_MB_2U_LIB.S9S_MB_2U(SCH_1):PAGE162

FM_USB3_1_FGB @S9S_MB_2U_LIB.S9S_MB_2U(SCH_1):FM_USB3_1_FGB
 R4274    1      A Q_RES_0402LF-1K,1%,1/16W,EMPTYA    I11 @S9S_MB_2U_LIB.S9S_MB_2U(SCH_1):PAGE162
 R4273    2      B Q_RES_0402LF-1K,1%,1/16W,EMPTYA    I12 @S9S_MB_2U_LIB.S9S_MB_2U(SCH_1):PAGE162
  U309   15    FGB PI3EQX1002EZREX-PI3EQX1002EZREA    I43 @S9S_MB_2U_LIB.S9S_MB_2U(SCH_1):PAGE162

FM_USB3_1_RXDET_EN @S9S_MB_2U_LIB.S9S_MB_2U(SCH_1):FM_USB3_1_RXDET_EN
 R4290    1      A Q_RES_0402LF-4.7K,1%,1/16W,EMPA    I68 @S9S_MB_2U_LIB.S9S_MB_2U(SCH_1):PAGE162
  U309   13 RXDET_EN PI3EQX1002EZREX-PI3EQX1002EZREA    I43 @S9S_MB_2U_LIB.S9S_MB_2U(SCH_1):PAGE162
 R4289    2      B Q_RES_0402LF-4.7K,1%,1/16W,EMPA    I69 @S9S_MB_2U_LIB.S9S_MB_2U(SCH_1):PAGE162

FM_USB3_1_SWA @S9S_MB_2U_LIB.S9S_MB_2U(SCH_1):FM_USB3_1_SWA
  U309    3    SWA PI3EQX1002EZREX-PI3EQX1002EZREA    I43 @S9S_MB_2U_LIB.S9S_MB_2U(SCH_1):PAGE162
 R4288    1      A Q_RES_0402LF-1K,1%,1/16W,EMPTYA    I48 @S9S_MB_2U_LIB.S9S_MB_2U(SCH_1):PAGE162
 R4287    2      B Q_RES_0402LF-1K,1%,1/16W,EMPTYA    I49 @S9S_MB_2U_LIB.S9S_MB_2U(SCH_1):PAGE162

FM_USB3_1_SWB @S9S_MB_2U_LIB.S9S_MB_2U(SCH_1):FM_USB3_1_SWB
 R4284    2      B Q_RES_0402LF-1K,1%,1/16W,EMPTYA    I41 @S9S_MB_2U_LIB.S9S_MB_2U(SCH_1):PAGE162
 R4285    1      A Q_RES_0402LF-1K,1%,1/16W,EMPTYA    I40 @S9S_MB_2U_LIB.S9S_MB_2U(SCH_1):PAGE162
  U309   14    SWB PI3EQX1002EZREX-PI3EQX1002EZREA    I43 @S9S_MB_2U_LIB.S9S_MB_2U(SCH_1):PAGE162

FM_UV_ADR_TRIGGER_N @S9S_MB_2U_LIB.S9S_MB_2U(SCH_1):FM_UV_ADR_TRIGGER_N
 R3046    1      A Q_RES_0402LF-0,5%,1/16W,CHIP,CA   I165 @S9S_MB_2U_LIB.S9S_MB_2U(SCH_1):PAGE312
 R2233    2      B Q_RES_0402LF-10K,1%,1/16W,CHIPA    I41 @S9S_MB_2U_LIB.S9S_MB_2U(SCH_1):PAGE326
 R4784    2      B Q_RES_0402LF-10K,1%,1/16W,EMPTA     I6 @S9S_MB_2U_LIB.S9S_MB_2U(SCH_1):PAGE329
 R4782    2      B Q_RES_0402LF-33.2,1%,1/16W,EMPA     I7 @S9S_MB_2U_LIB.S9S_MB_2U(SCH_1):PAGE329
  U206    1   OUTA LT6700CS61TRPBF-LT6700CS6-1#TRA   I102 @S9S_MB_2U_LIB.S9S_MB_2U(SCH_1):PAGE326

FM_UV_ADR_TRIGGER_N_R2 @S9S_MB_2U_LIB.S9S_MB_2U(SCH_1):FM_UV_ADR_TRIGGER_N_R2
 R4782    1      A Q_RES_0402LF-33.2,1%,1/16W,EMPA     I7 @S9S_MB_2U_LIB.S9S_MB_2U(SCH_1):PAGE329
 R4778    2      B Q_RES_0402LF-1M,1%,1/16W,CHIP,A     I9 @S9S_MB_2U_LIB.S9S_MB_2U(SCH_1):PAGE329
  U339    4 OUTPUT AP331AWG7-AP331AWG-7,SMLF,EMPTA    I12 @S9S_MB_2U_LIB.S9S_MB_2U(SCH_1):PAGE329

FM_UV_ADR_TRIGGER_R_N @S9S_MB_2U_LIB.S9S_MB_2U(SCH_1):FM_UV_ADR_TRIGGER_R_N
  U249  AB2   PB5B LCMXO3LF9400C5BG484C-LCMXO3LF-A     I1 @S9S_MB_2U_LIB.S9S_MB_2U(SCH_1):PAGE312
 R3046    2      B Q_RES_0402LF-0,5%,1/16W,CHIP,CA   I165 @S9S_MB_2U_LIB.S9S_MB_2U(SCH_1):PAGE312

FM_XTAL_INPUT_FREQUENCY_0_MGPIO @S9S_MB_2U_LIB.S9S_MB_2U(SCH_1):FM_XTAL_INPUT_FREQUENCY_0_MGPIO_TEST4
    U4 BB18 GPPC_S_0_TIME_SYNC_0 EMMITSBURG_REV0P9-GFNOCPU04302A    I27 @S9S_MB_2U_LIB.S9S_MB_2U(SCH_1):PAGE177
 R1311    1      A Q_RES_0402LF-10K,1%,1/16W,CHIPA    I31 @S9S_MB_2U_LIB.S9S_MB_2U(SCH_1):PAGE188

FM_XTAL_INPUT_FREQUENCY_1_MGPIO @S9S_MB_2U_LIB.S9S_MB_2U(SCH_1):FM_XTAL_INPUT_FREQUENCY_1_MGPIO_TEST5
    U4 AR16 GPPC_S_2_CPU_GP_0 EMMITSBURG_REV0P9-GFNOCPU04302A    I27 @S9S_MB_2U_LIB.S9S_MB_2U(SCH_1):PAGE177
 R1457    1      A Q_RES_0402LF-10K,1%,1/16W,CHIPA    I36 @S9S_MB_2U_LIB.S9S_MB_2U(SCH_1):PAGE188

GND @S9S_MB_2U_LIB.S9S_MB_2U(SCH_1):GND
    U2 EJ80 UPI3_RX_DN0 SOCKET4677_AZIF0045P001C01CS-SA   I102 @S9S_MB_2U_LIB.S9S_MB_2U(SCH_1):PAGE35
    U2 EP81 UPI3_RX_DN1 SOCKET4677_AZIF0045P001C01CS-SA   I102 @S9S_MB_2U_LIB.S9S_MB_2U(SCH_1):PAGE35
    U2 EL82 UPI3_RX_DN2 SOCKET4677_AZIF0045P001C01CS-SA   I102 @S9S_MB_2U_LIB.S9S_MB_2U(SCH_1):PAGE35
    U2 EK81 UPI3_RX_DN3 SOCKET4677_AZIF0045P001C01CS-SA   I102 @S9S_MB_2U_LIB.S9S_MB_2U(SCH_1):PAGE35
    U2 EF81 UPI3_RX_DN4 SOCKET4677_AZIF0045P001C01CS-SA   I102 @S9S_MB_2U_LIB.S9S_MB_2U(SCH_1):PAGE35
    U2 ED83 UPI3_RX_DN5 SOCKET4677_AZIF0045P001C01CS-SA   I102 @S9S_MB_2U_LIB.S9S_MB_2U(SCH_1):PAGE35
    U2 EC80 UPI3_RX_DN6 SOCKET4677_AZIF0045P001C01CS-SA   I102 @S9S_MB_2U_LIB.S9S_MB_2U(SCH_1):PAGE35
    U2 EA82 UPI3_RX_DN7 SOCKET4677_AZIF0045P001C01CS-SA   I102 @S9S_MB_2U_LIB.S9S_MB_2U(SCH_1):PAGE35
    U2 DY81 UPI3_RX_DN8 SOCKET4677_AZIF0045P001C01CS-SA   I102 @S9S_MB_2U_LIB.S9S_MB_2U(SCH_1):PAGE35
    U2 DJ78 UPI3_RX_DN9 SOCKET4677_AZIF0045P001C01CS-SA   I102 @S9S_MB_2U_LIB.S9S_MB_2U(SCH_1):PAGE35
    U2 DG78 UPI3_RX_DN10 SOCKET4677_AZIF0045P001C01CS-SA   I102 @S9S_MB_2U_LIB.S9S_MB_2U(SCH_1):PAGE35
    U2 DH81 UPI3_RX_DN11 SOCKET4677_AZIF0045P001C01CS-SA   I102 @S9S_MB_2U_LIB.S9S_MB_2U(SCH_1):PAGE35
    U2 DF83 UPI3_RX_DN12 SOCKET4677_AZIF0045P001C01CS-SA   I102 @S9S_MB_2U_LIB.S9S_MB_2U(SCH_1):PAGE35
    U2 DE80 UPI3_RX_DN13 SOCKET4677_AZIF0045P001C01CS-SA   I102 @S9S_MB_2U_LIB.S9S_MB_2U(SCH_1):PAGE35
    U2 DC82 UPI3_RX_DN14 SOCKET4677_AZIF0045P001C01CS-SA   I102 @S9S_MB_2U_LIB.S9S_MB_2U(SCH_1):PAGE35
    U2 DB81 UPI3_RX_DN15 SOCKET4677_AZIF0045P001C01CS-SA   I102 @S9S_MB_2U_LIB.S9S_MB_2U(SCH_1):PAGE35
    U2 DF77 UPI3_RX_DN16 SOCKET4677_AZIF0045P001C01CS-SA   I102 @S9S_MB_2U_LIB.S9S_MB_2U(SCH_1):PAGE35
    U2 CU82 UPI3_RX_DN17 SOCKET4677_AZIF0045P001C01CS-SA   I102 @S9S_MB_2U_LIB.S9S_MB_2U(SCH_1):PAGE35
    U2 CR82 UPI3_RX_DN18 SOCKET4677_AZIF0045P001C01CS-SA   I102 @S9S_MB_2U_LIB.S9S_MB_2U(SCH_1):PAGE35
    U2 CW80 UPI3_RX_DN19 SOCKET4677_AZIF0045P001C01CS-SA   I102 @S9S_MB_2U_LIB.S9S_MB_2U(SCH_1):PAGE35
    U2 CP81 UPI3_RX_DN20 SOCKET4677_AZIF0045P001C01CS-SA   I102 @S9S_MB_2U_LIB.S9S_MB_2U(SCH_1):PAGE35
    U2 CN80 UPI3_RX_DN21 SOCKET4677_AZIF0045P001C01CS-SA   I102 @S9S_MB_2U_LIB.S9S_MB_2U(SCH_1):PAGE35
    U2 CT79 UPI3_RX_DN22 SOCKET4677_AZIF0045P001C01CS-SA   I102 @S9S_MB_2U_LIB.S9S_MB_2U(SCH_1):PAGE35
    U2 DA78 UPI3_RX_DN23 SOCKET4677_AZIF0045P001C01CS-SA   I102 @S9S_MB_2U_LIB.S9S_MB_2U(SCH_1):PAGE35
    U2 EL80 UPI3_RX_DP0 SOCKET4677_AZIF0045P001C01CS-SA   I102 @S9S_MB_2U_LIB.S9S_MB_2U(SCH_1):PAGE35
    U2 ER82 UPI3_RX_DP1 SOCKET4677_AZIF0045P001C01CS-SA   I102 @S9S_MB_2U_LIB.S9S_MB_2U(SCH_1):PAGE35
    U2 EN82 UPI3_RX_DP2 SOCKET4677_AZIF0045P001C01CS-SA   I102 @S9S_MB_2U_LIB.S9S_MB_2U(SCH_1):PAGE35
    U2 EJ82 UPI3_RX_DP3 SOCKET4677_AZIF0045P001C01CS-SA   I102 @S9S_MB_2U_LIB.S9S_MB_2U(SCH_1):PAGE35
    U2 EE82 UPI3_RX_DP4 SOCKET4677_AZIF0045P001C01CS-SA   I102 @S9S_MB_2U_LIB.S9S_MB_2U(SCH_1):PAGE35
    U2 EF83 UPI3_RX_DP5 SOCKET4677_AZIF0045P001C01CS-SA   I102 @S9S_MB_2U_LIB.S9S_MB_2U(SCH_1):PAGE35
    U2 ED81 UPI3_RX_DP6 SOCKET4677_AZIF0045P001C01CS-SA   I102 @S9S_MB_2U_LIB.S9S_MB_2U(SCH_1):PAGE35
    U2 DY83 UPI3_RX_DP7 SOCKET4677_AZIF0045P001C01CS-SA   I102 @S9S_MB_2U_LIB.S9S_MB_2U(SCH_1):PAGE35
    U2 EB81 UPI3_RX_DP8 SOCKET4677_AZIF0045P001C01CS-SA   I102 @S9S_MB_2U_LIB.S9S_MB_2U(SCH_1):PAGE35
    U2 DL78 UPI3_RX_DP9 SOCKET4677_AZIF0045P001C01CS-SA   I102 @S9S_MB_2U_LIB.S9S_MB_2U(SCH_1):PAGE35
    U2 DH79 UPI3_RX_DP10 SOCKET4677_AZIF0045P001C01CS-SA   I102 @S9S_MB_2U_LIB.S9S_MB_2U(SCH_1):PAGE35
    U2 DG82 UPI3_RX_DP11 SOCKET4677_AZIF0045P001C01CS-SA   I102 @S9S_MB_2U_LIB.S9S_MB_2U(SCH_1):PAGE35
    U2 DH83 UPI3_RX_DP12 SOCKET4677_AZIF0045P001C01CS-SA   I102 @S9S_MB_2U_LIB.S9S_MB_2U(SCH_1):PAGE35
    U2 DF81 UPI3_RX_DP13 SOCKET4677_AZIF0045P001C01CS-SA   I102 @S9S_MB_2U_LIB.S9S_MB_2U(SCH_1):PAGE35
    U2 DB83 UPI3_RX_DP14 SOCKET4677_AZIF0045P001C01CS-SA   I102 @S9S_MB_2U_LIB.S9S_MB_2U(SCH_1):PAGE35
    U2 DD81 UPI3_RX_DP15 SOCKET4677_AZIF0045P001C01CS-SA   I102 @S9S_MB_2U_LIB.S9S_MB_2U(SCH_1):PAGE35
    U2 DE78 UPI3_RX_DP16 SOCKET4677_AZIF0045P001C01CS-SA   I102 @S9S_MB_2U_LIB.S9S_MB_2U(SCH_1):PAGE35
    U2 CW82 UPI3_RX_DP17 SOCKET4677_AZIF0045P001C01CS-SA   I102 @S9S_MB_2U_LIB.S9S_MB_2U(SCH_1):PAGE35
    U2 CT83 UPI3_RX_DP18 SOCKET4677_AZIF0045P001C01CS-SA   I102 @S9S_MB_2U_LIB.S9S_MB_2U(SCH_1):PAGE35
    U2 CV81 UPI3_RX_DP19 SOCKET4677_AZIF0045P001C01CS-SA   I102 @S9S_MB_2U_LIB.S9S_MB_2U(SCH_1):PAGE35
    U2 CN82 UPI3_RX_DP20 SOCKET4677_AZIF0045P001C01CS-SA   I102 @S9S_MB_2U_LIB.S9S_MB_2U(SCH_1):PAGE35
    U2 CR80 UPI3_RX_DP21 SOCKET4677_AZIF0045P001C01CS-SA   I102 @S9S_MB_2U_LIB.S9S_MB_2U(SCH_1):PAGE35
    U2 CU80 UPI3_RX_DP22 SOCKET4677_AZIF0045P001C01CS-SA   I102 @S9S_MB_2U_LIB.S9S_MB_2U(SCH_1):PAGE35
    U2 DB79 UPI3_RX_DP23 SOCKET4677_AZIF0045P001C01CS-SA   I102 @S9S_MB_2U_LIB.S9S_MB_2U(SCH_1):PAGE35
    C1    2      B Q_CAP_C0402-10UF,6.3V,20%,X6S,A    I15 @S9S_MB_2U_LIB.S9S_MB_2U(SCH_1):PAGE37
    U2 EH42 VSS1312 SOCKET4677_AZIF0045P001C01CS-SA     I1 @S9S_MB_2U_LIB.S9S_MB_2U(SCH_1):PAGE39
    U2 EH55 VSS1315 SOCKET4677_AZIF0045P001C01CS-SA     I1 @S9S_MB_2U_LIB.S9S_MB_2U(SCH_1):PAGE39
    U2 EH61 VSS1319 SOCKET4677_AZIF0045P001C01CS-SA     I1 @S9S_MB_2U_LIB.S9S_MB_2U(SCH_1):PAGE39
    U2 EH67 VSS1320 SOCKET4677_AZIF0045P001C01CS-SA     I1 @S9S_MB_2U_LIB.S9S_MB_2U(SCH_1):PAGE39
    U2 EH79 VSS1322 SOCKET4677_AZIF0045P001C01CS-SA     I1 @S9S_MB_2U_LIB.S9S_MB_2U(SCH_1):PAGE39
    U2 EJ11 VSS1325 SOCKET4677_AZIF0045P001C01CS-SA     I1 @S9S_MB_2U_LIB.S9S_MB_2U(SCH_1):PAGE39
    U2 EJ17 VSS1328 SOCKET4677_AZIF0045P001C01CS-SA     I1 @S9S_MB_2U_LIB.S9S_MB_2U(SCH_1):PAGE39
    U2 EJ25 VSS1331 SOCKET4677_AZIF0045P001C01CS-SA     I1 @S9S_MB_2U_LIB.S9S_MB_2U(SCH_1):PAGE39
    U2 EJ35 VSS1334 SOCKET4677_AZIF0045P001C01CS-SA     I1 @S9S_MB_2U_LIB.S9S_MB_2U(SCH_1):PAGE39
    U2 EJ54 VSS1340 SOCKET4677_AZIF0045P001C01CS-SA     I1 @S9S_MB_2U_LIB.S9S_MB_2U(SCH_1):PAGE39
    U2 EJ62 VSS1343 SOCKET4677_AZIF0045P001C01CS-SA     I1 @S9S_MB_2U_LIB.S9S_MB_2U(SCH_1):PAGE39
    U2 EJ68 VSS1345 SOCKET4677_AZIF0045P001C01CS-SA     I1 @S9S_MB_2U_LIB.S9S_MB_2U(SCH_1):PAGE39
    U2 EJ72 VSS1347 SOCKET4677_AZIF0045P001C01CS-SA     I1 @S9S_MB_2U_LIB.S9S_MB_2U(SCH_1):PAGE39
    U2 EK16 VSS1355 SOCKET4677_AZIF0045P001C01CS-SA     I1 @S9S_MB_2U_LIB.S9S_MB_2U(SCH_1):PAGE39
    U2 EK20 VSS1357 SOCKET4677_AZIF0045P001C01CS-SA     I1 @S9S_MB_2U_LIB.S9S_MB_2U(SCH_1):PAGE39
    U2 EK26 VSS1359 SOCKET4677_AZIF0045P001C01CS-SA     I1 @S9S_MB_2U_LIB.S9S_MB_2U(SCH_1):PAGE39
    U2 EK44 VSS1366 SOCKET4677_AZIF0045P001C01CS-SA     I1 @S9S_MB_2U_LIB.S9S_MB_2U(SCH_1):PAGE39
    U2 EK51 VSS1368 SOCKET4677_AZIF0045P001C01CS-SA     I1 @S9S_MB_2U_LIB.S9S_MB_2U(SCH_1):PAGE39
    U2 EK53 VSS1369 SOCKET4677_AZIF0045P001C01CS-SA     I1 @S9S_MB_2U_LIB.S9S_MB_2U(SCH_1):PAGE39
    U2 EK59 VSS1371 SOCKET4677_AZIF0045P001C01CS-SA     I1 @S9S_MB_2U_LIB.S9S_MB_2U(SCH_1):PAGE39
    U2 EK63 VSS1372 SOCKET4677_AZIF0045P001C01CS-SA     I1 @S9S_MB_2U_LIB.S9S_MB_2U(SCH_1):PAGE39
    U2 EK71 VSS1375 SOCKET4677_AZIF0045P001C01CS-SA     I1 @S9S_MB_2U_LIB.S9S_MB_2U(SCH_1):PAGE39
    U2 EK77 VSS1377 SOCKET4677_AZIF0045P001C01CS-SA     I1 @S9S_MB_2U_LIB.S9S_MB_2U(SCH_1):PAGE39
    U2 EK79 VSS1378 SOCKET4677_AZIF0045P001C01CS-SA     I1 @S9S_MB_2U_LIB.S9S_MB_2U(SCH_1):PAGE39
    U2 EK83 VSS1379 SOCKET4677_AZIF0045P001C01CS-SA     I1 @S9S_MB_2U_LIB.S9S_MB_2U(SCH_1):PAGE39
    U2 EK89 VSS1380 SOCKET4677_AZIF0045P001C01CS-SA     I1 @S9S_MB_2U_LIB.S9S_MB_2U(SCH_1):PAGE39
    U2 EL15 VSS1381 SOCKET4677_AZIF0045P001C01CS-SA     I1 @S9S_MB_2U_LIB.S9S_MB_2U(SCH_1):PAGE39
    U2 EL52 VSS1391 SOCKET4677_AZIF0045P001C01CS-SA     I1 @S9S_MB_2U_LIB.S9S_MB_2U(SCH_1):PAGE39
    U2 EL58 VSS1394 SOCKET4677_AZIF0045P001C01CS-SA     I1 @S9S_MB_2U_LIB.S9S_MB_2U(SCH_1):PAGE39
    U2  EL7 VSS1396 SOCKET4677_AZIF0045P001C01CS-SA     I1 @S9S_MB_2U_LIB.S9S_MB_2U(SCH_1):PAGE39
    U2 EL70 VSS1397 SOCKET4677_AZIF0045P001C01CS-SA     I1 @S9S_MB_2U_LIB.S9S_MB_2U(SCH_1):PAGE39
    U2 EL72 VSS1398 SOCKET4677_AZIF0045P001C01CS-SA     I1 @S9S_MB_2U_LIB.S9S_MB_2U(SCH_1):PAGE39
    U2 EL86 VSS1400 SOCKET4677_AZIF0045P001C01CS-SA     I1 @S9S_MB_2U_LIB.S9S_MB_2U(SCH_1):PAGE39
    U2  EL9 VSS1401 SOCKET4677_AZIF0045P001C01CS-SA     I1 @S9S_MB_2U_LIB.S9S_MB_2U(SCH_1):PAGE39
    U2 EM49 VSS1405 SOCKET4677_AZIF0045P001C01CS-SA     I1 @S9S_MB_2U_LIB.S9S_MB_2U(SCH_1):PAGE39
    U2 EM79 VSS1409 SOCKET4677_AZIF0045P001C01CS-SA     I1 @S9S_MB_2U_LIB.S9S_MB_2U(SCH_1):PAGE39
    U2 EH36 VSS1419 SOCKET4677_AZIF0045P001C01CS-SA     I1 @S9S_MB_2U_LIB.S9S_MB_2U(SCH_1):PAGE39
    U2 EH49 VSS1421 SOCKET4677_AZIF0045P001C01CS-SA     I1 @S9S_MB_2U_LIB.S9S_MB_2U(SCH_1):PAGE39
    U2 EH73 VSS1422 SOCKET4677_AZIF0045P001C01CS-SA     I1 @S9S_MB_2U_LIB.S9S_MB_2U(SCH_1):PAGE39
    U2 EH81 VSS1423 SOCKET4677_AZIF0045P001C01CS-SA     I1 @S9S_MB_2U_LIB.S9S_MB_2U(SCH_1):PAGE39
    U2 EH83 VSS1424 SOCKET4677_AZIF0045P001C01CS-SA     I1 @S9S_MB_2U_LIB.S9S_MB_2U(SCH_1):PAGE39
    U2 EJ13 VSS1425 SOCKET4677_AZIF0045P001C01CS-SA     I1 @S9S_MB_2U_LIB.S9S_MB_2U(SCH_1):PAGE39
    U2 EJ19 VSS1426 SOCKET4677_AZIF0045P001C01CS-SA     I1 @S9S_MB_2U_LIB.S9S_MB_2U(SCH_1):PAGE39
    U2 EN39 VSS1427 SOCKET4677_AZIF0045P001C01CS-SA     I1 @S9S_MB_2U_LIB.S9S_MB_2U(SCH_1):PAGE39
    U2 EJ23 VSS1428 SOCKET4677_AZIF0045P001C01CS-SA     I1 @S9S_MB_2U_LIB.S9S_MB_2U(SCH_1):PAGE39
    U2 EJ29 VSS1429 SOCKET4677_AZIF0045P001C01CS-SA     I1 @S9S_MB_2U_LIB.S9S_MB_2U(SCH_1):PAGE39
    U2 EJ31 VSS1430 SOCKET4677_AZIF0045P001C01CS-SA     I1 @S9S_MB_2U_LIB.S9S_MB_2U(SCH_1):PAGE39
    U2 EJ37 VSS1431 SOCKET4677_AZIF0045P001C01CS-SA     I1 @S9S_MB_2U_LIB.S9S_MB_2U(SCH_1):PAGE39
    U2 EJ41 VSS1432 SOCKET4677_AZIF0045P001C01CS-SA     I1 @S9S_MB_2U_LIB.S9S_MB_2U(SCH_1):PAGE39
    U2 EJ43 VSS1433 SOCKET4677_AZIF0045P001C01CS-SA     I1 @S9S_MB_2U_LIB.S9S_MB_2U(SCH_1):PAGE39
    U2 EJ48 VSS1434 SOCKET4677_AZIF0045P001C01CS-SA     I1 @S9S_MB_2U_LIB.S9S_MB_2U(SCH_1):PAGE39
    U2 EJ50 VSS1435 SOCKET4677_AZIF0045P001C01CS-SA     I1 @S9S_MB_2U_LIB.S9S_MB_2U(SCH_1):PAGE39
    U2 EN58 VSS1436 SOCKET4677_AZIF0045P001C01CS-SA     I1 @S9S_MB_2U_LIB.S9S_MB_2U(SCH_1):PAGE39
    U2 EN60 VSS1437 SOCKET4677_AZIF0045P001C01CS-SA     I1 @S9S_MB_2U_LIB.S9S_MB_2U(SCH_1):PAGE39
    U2 EN62 VSS1438 SOCKET4677_AZIF0045P001C01CS-SA     I1 @S9S_MB_2U_LIB.S9S_MB_2U(SCH_1):PAGE39
    U2 EJ56 VSS1439 SOCKET4677_AZIF0045P001C01CS-SA     I1 @S9S_MB_2U_LIB.S9S_MB_2U(SCH_1):PAGE39
    U2 EN66 VSS1440 SOCKET4677_AZIF0045P001C01CS-SA     I1 @S9S_MB_2U_LIB.S9S_MB_2U(SCH_1):PAGE39
    U2 EN72 VSS1441 SOCKET4677_AZIF0045P001C01CS-SA     I1 @S9S_MB_2U_LIB.S9S_MB_2U(SCH_1):PAGE39
    U2 EJ60 VSS1442 SOCKET4677_AZIF0045P001C01CS-SA     I1 @S9S_MB_2U_LIB.S9S_MB_2U(SCH_1):PAGE39
    U2 EJ66 VSS1443 SOCKET4677_AZIF0045P001C01CS-SA     I1 @S9S_MB_2U_LIB.S9S_MB_2U(SCH_1):PAGE39
    U2  EJ7 VSS1444 SOCKET4677_AZIF0045P001C01CS-SA     I1 @S9S_MB_2U_LIB.S9S_MB_2U(SCH_1):PAGE39
    U2 EN88 VSS1445 SOCKET4677_AZIF0045P001C01CS-SA     I1 @S9S_MB_2U_LIB.S9S_MB_2U(SCH_1):PAGE39
    U2  EN9 VSS1446 SOCKET4677_AZIF0045P001C01CS-SA     I1 @S9S_MB_2U_LIB.S9S_MB_2U(SCH_1):PAGE39
    U2 EJ74 VSS1447 SOCKET4677_AZIF0045P001C01CS-SA     I1 @S9S_MB_2U_LIB.S9S_MB_2U(SCH_1):PAGE39
    U2 EJ78 VSS1448 SOCKET4677_AZIF0045P001C01CS-SA     I1 @S9S_MB_2U_LIB.S9S_MB_2U(SCH_1):PAGE39
    U2 EJ88 VSS1449 SOCKET4677_AZIF0045P001C01CS-SA     I1 @S9S_MB_2U_LIB.S9S_MB_2U(SCH_1):PAGE39
    U2  EJ9 VSS1450 SOCKET4677_AZIF0045P001C01CS-SA     I1 @S9S_MB_2U_LIB.S9S_MB_2U(SCH_1):PAGE39
    U2 EK10 VSS1451 SOCKET4677_AZIF0045P001C01CS-SA     I1 @S9S_MB_2U_LIB.S9S_MB_2U(SCH_1):PAGE39
    U2 EP69 VSS1452 SOCKET4677_AZIF0045P001C01CS-SA     I1 @S9S_MB_2U_LIB.S9S_MB_2U(SCH_1):PAGE39
    U2 EP71 VSS1453 SOCKET4677_AZIF0045P001C01CS-SA     I1 @S9S_MB_2U_LIB.S9S_MB_2U(SCH_1):PAGE39
    U2 EP77 VSS1454 SOCKET4677_AZIF0045P001C01CS-SA     I1 @S9S_MB_2U_LIB.S9S_MB_2U(SCH_1):PAGE39
    U2 EK14 VSS1455 SOCKET4677_AZIF0045P001C01CS-SA     I1 @S9S_MB_2U_LIB.S9S_MB_2U(SCH_1):PAGE39
    U2 ER15 VSS1456 SOCKET4677_AZIF0045P001C01CS-SA     I1 @S9S_MB_2U_LIB.S9S_MB_2U(SCH_1):PAGE39
    U2 ER21 VSS1457 SOCKET4677_AZIF0045P001C01CS-SA     I1 @S9S_MB_2U_LIB.S9S_MB_2U(SCH_1):PAGE39
    U2  EK2 VSS1458 SOCKET4677_AZIF0045P001C01CS-SA     I1 @S9S_MB_2U_LIB.S9S_MB_2U(SCH_1):PAGE39
    U2 EK22 VSS1459 SOCKET4677_AZIF0045P001C01CS-SA     I1 @S9S_MB_2U_LIB.S9S_MB_2U(SCH_1):PAGE39
    U2 EK28 VSS1460 SOCKET4677_AZIF0045P001C01CS-SA     I1 @S9S_MB_2U_LIB.S9S_MB_2U(SCH_1):PAGE39
    U2 EK32 VSS1461 SOCKET4677_AZIF0045P001C01CS-SA     I1 @S9S_MB_2U_LIB.S9S_MB_2U(SCH_1):PAGE39
    U2 ER39 VSS1462 SOCKET4677_AZIF0045P001C01CS-SA     I1 @S9S_MB_2U_LIB.S9S_MB_2U(SCH_1):PAGE39
    U2 EK34 VSS1463 SOCKET4677_AZIF0045P001C01CS-SA     I1 @S9S_MB_2U_LIB.S9S_MB_2U(SCH_1):PAGE39
    U2 ER52 VSS1464 SOCKET4677_AZIF0045P001C01CS-SA     I1 @S9S_MB_2U_LIB.S9S_MB_2U(SCH_1):PAGE39
    U2 EK38 VSS1465 SOCKET4677_AZIF0045P001C01CS-SA     I1 @S9S_MB_2U_LIB.S9S_MB_2U(SCH_1):PAGE39
    U2  EK4 VSS1466 SOCKET4677_AZIF0045P001C01CS-SA     I1 @S9S_MB_2U_LIB.S9S_MB_2U(SCH_1):PAGE39
    U2 ER58 VSS1467 SOCKET4677_AZIF0045P001C01CS-SA     I1 @S9S_MB_2U_LIB.S9S_MB_2U(SCH_1):PAGE39
    U2 ER64 VSS1468 SOCKET4677_AZIF0045P001C01CS-SA     I1 @S9S_MB_2U_LIB.S9S_MB_2U(SCH_1):PAGE39
    U2 EK40 VSS1469 SOCKET4677_AZIF0045P001C01CS-SA     I1 @S9S_MB_2U_LIB.S9S_MB_2U(SCH_1):PAGE39
    U2 EK47 VSS1470 SOCKET4677_AZIF0045P001C01CS-SA     I1 @S9S_MB_2U_LIB.S9S_MB_2U(SCH_1):PAGE39
    U2 EK57 VSS1471 SOCKET4677_AZIF0045P001C01CS-SA     I1 @S9S_MB_2U_LIB.S9S_MB_2U(SCH_1):PAGE39
    U2 EK65 VSS1472 SOCKET4677_AZIF0045P001C01CS-SA     I1 @S9S_MB_2U_LIB.S9S_MB_2U(SCH_1):PAGE39
    U2 EK69 VSS1473 SOCKET4677_AZIF0045P001C01CS-SA     I1 @S9S_MB_2U_LIB.S9S_MB_2U(SCH_1):PAGE39
    U2 EK75 VSS1474 SOCKET4677_AZIF0045P001C01CS-SA     I1 @S9S_MB_2U_LIB.S9S_MB_2U(SCH_1):PAGE39
    U2 EL21 VSS1475 SOCKET4677_AZIF0045P001C01CS-SA     I1 @S9S_MB_2U_LIB.S9S_MB_2U(SCH_1):PAGE39
    U2  ER9 VSS1476 SOCKET4677_AZIF0045P001C01CS-SA     I1 @S9S_MB_2U_LIB.S9S_MB_2U(SCH_1):PAGE39
    U2 EL27 VSS1477 SOCKET4677_AZIF0045P001C01CS-SA     I1 @S9S_MB_2U_LIB.S9S_MB_2U(SCH_1):PAGE39
    U2 ET14 VSS1478 SOCKET4677_AZIF0045P001C01CS-SA     I1 @S9S_MB_2U_LIB.S9S_MB_2U(SCH_1):PAGE39
    U2  EL3 VSS1479 SOCKET4677_AZIF0045P001C01CS-SA     I1 @S9S_MB_2U_LIB.S9S_MB_2U(SCH_1):PAGE39
    U2 ET20 VSS1480 SOCKET4677_AZIF0045P001C01CS-SA     I1 @S9S_MB_2U_LIB.S9S_MB_2U(SCH_1):PAGE39
    U2 EL33 VSS1481 SOCKET4677_AZIF0045P001C01CS-SA     I1 @S9S_MB_2U_LIB.S9S_MB_2U(SCH_1):PAGE39
    U2 ET26 VSS1482 SOCKET4677_AZIF0045P001C01CS-SA     I1 @S9S_MB_2U_LIB.S9S_MB_2U(SCH_1):PAGE39
    U2 EL39 VSS1483 SOCKET4677_AZIF0045P001C01CS-SA     I1 @S9S_MB_2U_LIB.S9S_MB_2U(SCH_1):PAGE39
    U2 ET32 VSS1484 SOCKET4677_AZIF0045P001C01CS-SA     I1 @S9S_MB_2U_LIB.S9S_MB_2U(SCH_1):PAGE39
    U2 EL45 VSS1485 SOCKET4677_AZIF0045P001C01CS-SA     I1 @S9S_MB_2U_LIB.S9S_MB_2U(SCH_1):PAGE39
    U2  EL5 VSS1486 SOCKET4677_AZIF0045P001C01CS-SA     I1 @S9S_MB_2U_LIB.S9S_MB_2U(SCH_1):PAGE39
    U2 EL64 VSS1488 SOCKET4677_AZIF0045P001C01CS-SA     I1 @S9S_MB_2U_LIB.S9S_MB_2U(SCH_1):PAGE39
    U2 EL76 VSS1489 SOCKET4677_AZIF0045P001C01CS-SA     I1 @S9S_MB_2U_LIB.S9S_MB_2U(SCH_1):PAGE39
    U2 ET53 VSS1491 SOCKET4677_AZIF0045P001C01CS-SA     I1 @S9S_MB_2U_LIB.S9S_MB_2U(SCH_1):PAGE39
    U2 EM42 VSS1492 SOCKET4677_AZIF0045P001C01CS-SA     I1 @S9S_MB_2U_LIB.S9S_MB_2U(SCH_1):PAGE39
    U2 ET59 VSS1493 SOCKET4677_AZIF0045P001C01CS-SA     I1 @S9S_MB_2U_LIB.S9S_MB_2U(SCH_1):PAGE39
    U2 EM73 VSS1496 SOCKET4677_AZIF0045P001C01CS-SA     I1 @S9S_MB_2U_LIB.S9S_MB_2U(SCH_1):PAGE39
    U2  EM8 VSS1497 SOCKET4677_AZIF0045P001C01CS-SA     I1 @S9S_MB_2U_LIB.S9S_MB_2U(SCH_1):PAGE39
    U2 EM81 VSS1498 SOCKET4677_AZIF0045P001C01CS-SA     I1 @S9S_MB_2U_LIB.S9S_MB_2U(SCH_1):PAGE39
    U2 EM83 VSS1499 SOCKET4677_AZIF0045P001C01CS-SA     I1 @S9S_MB_2U_LIB.S9S_MB_2U(SCH_1):PAGE39
    U2 EN11 VSS1500 SOCKET4677_AZIF0045P001C01CS-SA     I1 @S9S_MB_2U_LIB.S9S_MB_2U(SCH_1):PAGE39
    U2 EN13 VSS1501 SOCKET4677_AZIF0045P001C01CS-SA     I1 @S9S_MB_2U_LIB.S9S_MB_2U(SCH_1):PAGE39
    U2 EN15 VSS1503 SOCKET4677_AZIF0045P001C01CS-SA     I1 @S9S_MB_2U_LIB.S9S_MB_2U(SCH_1):PAGE39
    U2 EN17 VSS1505 SOCKET4677_AZIF0045P001C01CS-SA     I1 @S9S_MB_2U_LIB.S9S_MB_2U(SCH_1):PAGE39
    U2 EN19 VSS1506 SOCKET4677_AZIF0045P001C01CS-SA     I1 @S9S_MB_2U_LIB.S9S_MB_2U(SCH_1):PAGE39
    U2 EN21 VSS1512 SOCKET4677_AZIF0045P001C01CS-SA     I1 @S9S_MB_2U_LIB.S9S_MB_2U(SCH_1):PAGE39
    U2 EN23 VSS1513 SOCKET4677_AZIF0045P001C01CS-SA     I1 @S9S_MB_2U_LIB.S9S_MB_2U(SCH_1):PAGE39
    U2 EN25 VSS1515 SOCKET4677_AZIF0045P001C01CS-SA     I1 @S9S_MB_2U_LIB.S9S_MB_2U(SCH_1):PAGE39
    U2 EN27 VSS1517 SOCKET4677_AZIF0045P001C01CS-SA     I1 @S9S_MB_2U_LIB.S9S_MB_2U(SCH_1):PAGE39
    U2 EN29 VSS1518 SOCKET4677_AZIF0045P001C01CS-SA     I1 @S9S_MB_2U_LIB.S9S_MB_2U(SCH_1):PAGE39
    U2 EN31 VSS1520 SOCKET4677_AZIF0045P001C01CS-SA     I1 @S9S_MB_2U_LIB.S9S_MB_2U(SCH_1):PAGE39
    U2 EN33 VSS1522 SOCKET4677_AZIF0045P001C01CS-SA     I1 @S9S_MB_2U_LIB.S9S_MB_2U(SCH_1):PAGE39
    U2 EN35 VSS1524 SOCKET4677_AZIF0045P001C01CS-SA     I1 @S9S_MB_2U_LIB.S9S_MB_2U(SCH_1):PAGE39
    U2 EN37 VSS1525 SOCKET4677_AZIF0045P001C01CS-SA     I1 @S9S_MB_2U_LIB.S9S_MB_2U(SCH_1):PAGE39
    U2 EN41 VSS1526 SOCKET4677_AZIF0045P001C01CS-SA     I1 @S9S_MB_2U_LIB.S9S_MB_2U(SCH_1):PAGE39
    U2 EN43 VSS1528 SOCKET4677_AZIF0045P001C01CS-SA     I1 @S9S_MB_2U_LIB.S9S_MB_2U(SCH_1):PAGE39
    U2 EN45 VSS1529 SOCKET4677_AZIF0045P001C01CS-SA     I1 @S9S_MB_2U_LIB.S9S_MB_2U(SCH_1):PAGE39
    U2 EN48 VSS1530 SOCKET4677_AZIF0045P001C01CS-SA     I1 @S9S_MB_2U_LIB.S9S_MB_2U(SCH_1):PAGE39
    U2 EN50 VSS1531 SOCKET4677_AZIF0045P001C01CS-SA     I1 @S9S_MB_2U_LIB.S9S_MB_2U(SCH_1):PAGE39
    U2 EN52 VSS1533 SOCKET4677_AZIF0045P001C01CS-SA     I1 @S9S_MB_2U_LIB.S9S_MB_2U(SCH_1):PAGE39
    U2 EN54 VSS1537 SOCKET4677_AZIF0045P001C01CS-SA     I1 @S9S_MB_2U_LIB.S9S_MB_2U(SCH_1):PAGE39
    U2 EN56 VSS1539 SOCKET4677_AZIF0045P001C01CS-SA     I1 @S9S_MB_2U_LIB.S9S_MB_2U(SCH_1):PAGE39
    U2 EN64 VSS1540 SOCKET4677_AZIF0045P001C01CS-SA     I1 @S9S_MB_2U_LIB.S9S_MB_2U(SCH_1):PAGE39
    U2 EN78 VSS1541 SOCKET4677_AZIF0045P001C01CS-SA     I1 @S9S_MB_2U_LIB.S9S_MB_2U(SCH_1):PAGE39
    U2 EN80 VSS1542 SOCKET4677_AZIF0045P001C01CS-SA     I1 @S9S_MB_2U_LIB.S9S_MB_2U(SCH_1):PAGE39
    U2 EP67 VSS1543 SOCKET4677_AZIF0045P001C01CS-SA     I1 @S9S_MB_2U_LIB.S9S_MB_2U(SCH_1):PAGE39
    U2 EP83 VSS1545 SOCKET4677_AZIF0045P001C01CS-SA     I1 @S9S_MB_2U_LIB.S9S_MB_2U(SCH_1):PAGE39
    U2 ER27 VSS1547 SOCKET4677_AZIF0045P001C01CS-SA     I1 @S9S_MB_2U_LIB.S9S_MB_2U(SCH_1):PAGE39
    U2 ER33 VSS1548 SOCKET4677_AZIF0045P001C01CS-SA     I1 @S9S_MB_2U_LIB.S9S_MB_2U(SCH_1):PAGE39
    U2  ER5 VSS1549 SOCKET4677_AZIF0045P001C01CS-SA     I1 @S9S_MB_2U_LIB.S9S_MB_2U(SCH_1):PAGE39
    U2  ER7 VSS1550 SOCKET4677_AZIF0045P001C01CS-SA     I1 @S9S_MB_2U_LIB.S9S_MB_2U(SCH_1):PAGE39
    U2 ER70 VSS1551 SOCKET4677_AZIF0045P001C01CS-SA     I1 @S9S_MB_2U_LIB.S9S_MB_2U(SCH_1):PAGE39
    U2 ER74 VSS1552 SOCKET4677_AZIF0045P001C01CS-SA     I1 @S9S_MB_2U_LIB.S9S_MB_2U(SCH_1):PAGE39
    U2 ER78 VSS1553 SOCKET4677_AZIF0045P001C01CS-SA     I1 @S9S_MB_2U_LIB.S9S_MB_2U(SCH_1):PAGE39
    U2 ER80 VSS1554 SOCKET4677_AZIF0045P001C01CS-SA     I1 @S9S_MB_2U_LIB.S9S_MB_2U(SCH_1):PAGE39
    U2 ER84 VSS1555 SOCKET4677_AZIF0045P001C01CS-SA     I1 @S9S_MB_2U_LIB.S9S_MB_2U(SCH_1):PAGE39
    U2 ER86 VSS1556 SOCKET4677_AZIF0045P001C01CS-SA     I1 @S9S_MB_2U_LIB.S9S_MB_2U(SCH_1):PAGE39
    U2 ET10 VSS1557 SOCKET4677_AZIF0045P001C01CS-SA     I1 @S9S_MB_2U_LIB.S9S_MB_2U(SCH_1):PAGE39
    U2 ET16 VSS1559 SOCKET4677_AZIF0045P001C01CS-SA     I1 @S9S_MB_2U_LIB.S9S_MB_2U(SCH_1):PAGE39
    U2 ET22 VSS1561 SOCKET4677_AZIF0045P001C01CS-SA     I1 @S9S_MB_2U_LIB.S9S_MB_2U(SCH_1):PAGE39
    U2 ET28 VSS1562 SOCKET4677_AZIF0045P001C01CS-SA     I1 @S9S_MB_2U_LIB.S9S_MB_2U(SCH_1):PAGE39
    U2 ET34 VSS1563 SOCKET4677_AZIF0045P001C01CS-SA     I1 @S9S_MB_2U_LIB.S9S_MB_2U(SCH_1):PAGE39
    U2 ET38 VSS1565 SOCKET4677_AZIF0045P001C01CS-SA     I1 @S9S_MB_2U_LIB.S9S_MB_2U(SCH_1):PAGE39
    U2 ET57 VSS1569 SOCKET4677_AZIF0045P001C01CS-SA     I1 @S9S_MB_2U_LIB.S9S_MB_2U(SCH_1):PAGE39
    U2 ER41 VSS1834 SOCKET4677_AZIF0045P001C01CS-SA     I1 @S9S_MB_2U_LIB.S9S_MB_2U(SCH_1):PAGE39
    U2 ER43 VSS1835 SOCKET4677_AZIF0045P001C01CS-SA     I1 @S9S_MB_2U_LIB.S9S_MB_2U(SCH_1):PAGE39
    U2 ER48 VSS1836 SOCKET4677_AZIF0045P001C01CS-SA     I1 @S9S_MB_2U_LIB.S9S_MB_2U(SCH_1):PAGE39
    U2 ER50 VSS1837 SOCKET4677_AZIF0045P001C01CS-SA     I1 @S9S_MB_2U_LIB.S9S_MB_2U(SCH_1):PAGE39
    U2 DY12 VSS1111 SOCKET4677_AZIF0045P001C01CS-SA     I9 @S9S_MB_2U_LIB.S9S_MB_2U(SCH_1):PAGE39
    U2 DY16 VSS1112 SOCKET4677_AZIF0045P001C01CS-SA     I9 @S9S_MB_2U_LIB.S9S_MB_2U(SCH_1):PAGE39
    U2  DY4 VSS1115 SOCKET4677_AZIF0045P001C01CS-SA     I9 @S9S_MB_2U_LIB.S9S_MB_2U(SCH_1):PAGE39
    U2 DY42 VSS1116 SOCKET4677_AZIF0045P001C01CS-SA     I9 @S9S_MB_2U_LIB.S9S_MB_2U(SCH_1):PAGE39
    U2 EA39 VSS1141 SOCKET4677_AZIF0045P001C01CS-SA     I9 @S9S_MB_2U_LIB.S9S_MB_2U(SCH_1):PAGE39
    U2 EA45 VSS1142 SOCKET4677_AZIF0045P001C01CS-SA     I9 @S9S_MB_2U_LIB.S9S_MB_2U(SCH_1):PAGE39
    U2 EA52 VSS1144 SOCKET4677_AZIF0045P001C01CS-SA     I9 @S9S_MB_2U_LIB.S9S_MB_2U(SCH_1):PAGE39
    U2 EA58 VSS1145 SOCKET4677_AZIF0045P001C01CS-SA     I9 @S9S_MB_2U_LIB.S9S_MB_2U(SCH_1):PAGE39
    U2 EA64 VSS1146 SOCKET4677_AZIF0045P001C01CS-SA     I9 @S9S_MB_2U_LIB.S9S_MB_2U(SCH_1):PAGE39
    U2 EB16 VSS1155 SOCKET4677_AZIF0045P001C01CS-SA     I9 @S9S_MB_2U_LIB.S9S_MB_2U(SCH_1):PAGE39
    U2 EB20 VSS1156 SOCKET4677_AZIF0045P001C01CS-SA     I9 @S9S_MB_2U_LIB.S9S_MB_2U(SCH_1):PAGE39
    U2 EB26 VSS1158 SOCKET4677_AZIF0045P001C01CS-SA     I9 @S9S_MB_2U_LIB.S9S_MB_2U(SCH_1):PAGE39
    U2 EB34 VSS1161 SOCKET4677_AZIF0045P001C01CS-SA     I9 @S9S_MB_2U_LIB.S9S_MB_2U(SCH_1):PAGE39
    U2  EB4 VSS1163 SOCKET4677_AZIF0045P001C01CS-SA     I9 @S9S_MB_2U_LIB.S9S_MB_2U(SCH_1):PAGE39
    U2 EB44 VSS1165 SOCKET4677_AZIF0045P001C01CS-SA     I9 @S9S_MB_2U_LIB.S9S_MB_2U(SCH_1):PAGE39
    U2 EB51 VSS1167 SOCKET4677_AZIF0045P001C01CS-SA     I9 @S9S_MB_2U_LIB.S9S_MB_2U(SCH_1):PAGE39
    U2 EB53 VSS1168 SOCKET4677_AZIF0045P001C01CS-SA     I9 @S9S_MB_2U_LIB.S9S_MB_2U(SCH_1):PAGE39
    U2 EB59 VSS1170 SOCKET4677_AZIF0045P001C01CS-SA     I9 @S9S_MB_2U_LIB.S9S_MB_2U(SCH_1):PAGE39
    U2 EB63 VSS1171 SOCKET4677_AZIF0045P001C01CS-SA     I9 @S9S_MB_2U_LIB.S9S_MB_2U(SCH_1):PAGE39
    U2 EB91 VSS1180 SOCKET4677_AZIF0045P001C01CS-SA     I9 @S9S_MB_2U_LIB.S9S_MB_2U(SCH_1):PAGE39
    U2 EC25 VSS1185 SOCKET4677_AZIF0045P001C01CS-SA     I9 @S9S_MB_2U_LIB.S9S_MB_2U(SCH_1):PAGE39
    U2 EC35 VSS1188 SOCKET4677_AZIF0045P001C01CS-SA     I9 @S9S_MB_2U_LIB.S9S_MB_2U(SCH_1):PAGE39
    U2  EC5 VSS1193 SOCKET4677_AZIF0045P001C01CS-SA     I9 @S9S_MB_2U_LIB.S9S_MB_2U(SCH_1):PAGE39
    U2 EC54 VSS1195 SOCKET4677_AZIF0045P001C01CS-SA     I9 @S9S_MB_2U_LIB.S9S_MB_2U(SCH_1):PAGE39
    U2 EC60 VSS1197 SOCKET4677_AZIF0045P001C01CS-SA     I9 @S9S_MB_2U_LIB.S9S_MB_2U(SCH_1):PAGE39
    U2 EC62 VSS1198 SOCKET4677_AZIF0045P001C01CS-SA     I9 @S9S_MB_2U_LIB.S9S_MB_2U(SCH_1):PAGE39
    U2 EC68 VSS1200 SOCKET4677_AZIF0045P001C01CS-SA     I9 @S9S_MB_2U_LIB.S9S_MB_2U(SCH_1):PAGE39
    U2 ED12 VSS1208 SOCKET4677_AZIF0045P001C01CS-SA     I9 @S9S_MB_2U_LIB.S9S_MB_2U(SCH_1):PAGE39
    U2 ED18 VSS1210 SOCKET4677_AZIF0045P001C01CS-SA     I9 @S9S_MB_2U_LIB.S9S_MB_2U(SCH_1):PAGE39
    U2 ED42 VSS1217 SOCKET4677_AZIF0045P001C01CS-SA     I9 @S9S_MB_2U_LIB.S9S_MB_2U(SCH_1):PAGE39
    U2 ED55 VSS1220 SOCKET4677_AZIF0045P001C01CS-SA     I9 @S9S_MB_2U_LIB.S9S_MB_2U(SCH_1):PAGE39
    U2 ED61 VSS1223 SOCKET4677_AZIF0045P001C01CS-SA     I9 @S9S_MB_2U_LIB.S9S_MB_2U(SCH_1):PAGE39
    U2 ED67 VSS1224 SOCKET4677_AZIF0045P001C01CS-SA     I9 @S9S_MB_2U_LIB.S9S_MB_2U(SCH_1):PAGE39
    U2 ED73 VSS1225 SOCKET4677_AZIF0045P001C01CS-SA     I9 @S9S_MB_2U_LIB.S9S_MB_2U(SCH_1):PAGE39
    U2 EE17 VSS1232 SOCKET4677_AZIF0045P001C01CS-SA     I9 @S9S_MB_2U_LIB.S9S_MB_2U(SCH_1):PAGE39
    U2 EE39 VSS1235 SOCKET4677_AZIF0045P001C01CS-SA     I9 @S9S_MB_2U_LIB.S9S_MB_2U(SCH_1):PAGE39
    U2 EE52 VSS1237 SOCKET4677_AZIF0045P001C01CS-SA     I9 @S9S_MB_2U_LIB.S9S_MB_2U(SCH_1):PAGE39
    U2 DW66 VSS1257 SOCKET4677_AZIF0045P001C01CS-SA     I9 @S9S_MB_2U_LIB.S9S_MB_2U(SCH_1):PAGE39
    U2 DW68 VSS1258 SOCKET4677_AZIF0045P001C01CS-SA     I9 @S9S_MB_2U_LIB.S9S_MB_2U(SCH_1):PAGE39
    U2 DW70 VSS1259 SOCKET4677_AZIF0045P001C01CS-SA     I9 @S9S_MB_2U_LIB.S9S_MB_2U(SCH_1):PAGE39
    U2 DW72 VSS1260 SOCKET4677_AZIF0045P001C01CS-SA     I9 @S9S_MB_2U_LIB.S9S_MB_2U(SCH_1):PAGE39
    U2 DW74 VSS1261 SOCKET4677_AZIF0045P001C01CS-SA     I9 @S9S_MB_2U_LIB.S9S_MB_2U(SCH_1):PAGE39
    U2 DW76 VSS1262 SOCKET4677_AZIF0045P001C01CS-SA     I9 @S9S_MB_2U_LIB.S9S_MB_2U(SCH_1):PAGE39
    U2 DW80 VSS1263 SOCKET4677_AZIF0045P001C01CS-SA     I9 @S9S_MB_2U_LIB.S9S_MB_2U(SCH_1):PAGE39
    U2 DW82 VSS1264 SOCKET4677_AZIF0045P001C01CS-SA     I9 @S9S_MB_2U_LIB.S9S_MB_2U(SCH_1):PAGE39
    U2 EF51 VSS1265 SOCKET4677_AZIF0045P001C01CS-SA     I9 @S9S_MB_2U_LIB.S9S_MB_2U(SCH_1):PAGE39
    U2 DW84 VSS1266 SOCKET4677_AZIF0045P001C01CS-SA     I9 @S9S_MB_2U_LIB.S9S_MB_2U(SCH_1):PAGE39
    U2 DW88 VSS1267 SOCKET4677_AZIF0045P001C01CS-SA     I9 @S9S_MB_2U_LIB.S9S_MB_2U(SCH_1):PAGE39
    U2 DY77 VSS1269 SOCKET4677_AZIF0045P001C01CS-SA     I9 @S9S_MB_2U_LIB.S9S_MB_2U(SCH_1):PAGE39
    U2  DY8 VSS1270 SOCKET4677_AZIF0045P001C01CS-SA     I9 @S9S_MB_2U_LIB.S9S_MB_2U(SCH_1):PAGE39
    U2 EA21 VSS1274 SOCKET4677_AZIF0045P001C01CS-SA     I9 @S9S_MB_2U_LIB.S9S_MB_2U(SCH_1):PAGE39
    U2 EA27 VSS1275 SOCKET4677_AZIF0045P001C01CS-SA     I9 @S9S_MB_2U_LIB.S9S_MB_2U(SCH_1):PAGE39
    U2 EF73 VSS1276 SOCKET4677_AZIF0045P001C01CS-SA     I9 @S9S_MB_2U_LIB.S9S_MB_2U(SCH_1):PAGE39
    U2 EF75 VSS1277 SOCKET4677_AZIF0045P001C01CS-SA     I9 @S9S_MB_2U_LIB.S9S_MB_2U(SCH_1):PAGE39
    U2 EA33 VSS1278 SOCKET4677_AZIF0045P001C01CS-SA     I9 @S9S_MB_2U_LIB.S9S_MB_2U(SCH_1):PAGE39
    U2 EA70 VSS1279 SOCKET4677_AZIF0045P001C01CS-SA     I9 @S9S_MB_2U_LIB.S9S_MB_2U(SCH_1):PAGE39
    U2 EA76 VSS1280 SOCKET4677_AZIF0045P001C01CS-SA     I9 @S9S_MB_2U_LIB.S9S_MB_2U(SCH_1):PAGE39
    U2 EA78 VSS1281 SOCKET4677_AZIF0045P001C01CS-SA     I9 @S9S_MB_2U_LIB.S9S_MB_2U(SCH_1):PAGE39
    U2 EA80 VSS1282 SOCKET4677_AZIF0045P001C01CS-SA     I9 @S9S_MB_2U_LIB.S9S_MB_2U(SCH_1):PAGE39
    U2 EF89 VSS1283 SOCKET4677_AZIF0045P001C01CS-SA     I9 @S9S_MB_2U_LIB.S9S_MB_2U(SCH_1):PAGE39
    U2 EG13 VSS1284 SOCKET4677_AZIF0045P001C01CS-SA     I9 @S9S_MB_2U_LIB.S9S_MB_2U(SCH_1):PAGE39
    U2 EA84 VSS1285 SOCKET4677_AZIF0045P001C01CS-SA     I9 @S9S_MB_2U_LIB.S9S_MB_2U(SCH_1):PAGE39
    U2 EA88 VSS1286 SOCKET4677_AZIF0045P001C01CS-SA     I9 @S9S_MB_2U_LIB.S9S_MB_2U(SCH_1):PAGE39
    U2 EB12 VSS1287 SOCKET4677_AZIF0045P001C01CS-SA     I9 @S9S_MB_2U_LIB.S9S_MB_2U(SCH_1):PAGE39
    U2 EB22 VSS1288 SOCKET4677_AZIF0045P001C01CS-SA     I9 @S9S_MB_2U_LIB.S9S_MB_2U(SCH_1):PAGE39
    U2 EB28 VSS1289 SOCKET4677_AZIF0045P001C01CS-SA     I9 @S9S_MB_2U_LIB.S9S_MB_2U(SCH_1):PAGE39
    U2  EG5 VSS1290 SOCKET4677_AZIF0045P001C01CS-SA     I9 @S9S_MB_2U_LIB.S9S_MB_2U(SCH_1):PAGE39
    U2 EG52 VSS1291 SOCKET4677_AZIF0045P001C01CS-SA     I9 @S9S_MB_2U_LIB.S9S_MB_2U(SCH_1):PAGE39
    U2 EB32 VSS1292 SOCKET4677_AZIF0045P001C01CS-SA     I9 @S9S_MB_2U_LIB.S9S_MB_2U(SCH_1):PAGE39
    U2 EB38 VSS1293 SOCKET4677_AZIF0045P001C01CS-SA     I9 @S9S_MB_2U_LIB.S9S_MB_2U(SCH_1):PAGE39
    U2  EG7 VSS1294 SOCKET4677_AZIF0045P001C01CS-SA     I9 @S9S_MB_2U_LIB.S9S_MB_2U(SCH_1):PAGE39
    U2 EB40 VSS1295 SOCKET4677_AZIF0045P001C01CS-SA     I9 @S9S_MB_2U_LIB.S9S_MB_2U(SCH_1):PAGE39
    U2 EB47 VSS1296 SOCKET4677_AZIF0045P001C01CS-SA     I9 @S9S_MB_2U_LIB.S9S_MB_2U(SCH_1):PAGE39
    U2 EB57 VSS1297 SOCKET4677_AZIF0045P001C01CS-SA     I9 @S9S_MB_2U_LIB.S9S_MB_2U(SCH_1):PAGE39
    U2 EB65 VSS1298 SOCKET4677_AZIF0045P001C01CS-SA     I9 @S9S_MB_2U_LIB.S9S_MB_2U(SCH_1):PAGE39
    U2 EB69 VSS1299 SOCKET4677_AZIF0045P001C01CS-SA     I9 @S9S_MB_2U_LIB.S9S_MB_2U(SCH_1):PAGE39
    U2 EB71 VSS1300 SOCKET4677_AZIF0045P001C01CS-SA     I9 @S9S_MB_2U_LIB.S9S_MB_2U(SCH_1):PAGE39
    U2 EB75 VSS1301 SOCKET4677_AZIF0045P001C01CS-SA     I9 @S9S_MB_2U_LIB.S9S_MB_2U(SCH_1):PAGE39
    U2 EH12 VSS1302 SOCKET4677_AZIF0045P001C01CS-SA     I9 @S9S_MB_2U_LIB.S9S_MB_2U(SCH_1):PAGE39
    U2 EH14 VSS1303 SOCKET4677_AZIF0045P001C01CS-SA     I9 @S9S_MB_2U_LIB.S9S_MB_2U(SCH_1):PAGE39
    U2 EB79 VSS1304 SOCKET4677_AZIF0045P001C01CS-SA     I9 @S9S_MB_2U_LIB.S9S_MB_2U(SCH_1):PAGE39
    U2 EH18 VSS1305 SOCKET4677_AZIF0045P001C01CS-SA     I9 @S9S_MB_2U_LIB.S9S_MB_2U(SCH_1):PAGE39
    U2  EB8 VSS1306 SOCKET4677_AZIF0045P001C01CS-SA     I9 @S9S_MB_2U_LIB.S9S_MB_2U(SCH_1):PAGE39
    U2 EB83 VSS1307 SOCKET4677_AZIF0045P001C01CS-SA     I9 @S9S_MB_2U_LIB.S9S_MB_2U(SCH_1):PAGE39
    U2 EB87 VSS1308 SOCKET4677_AZIF0045P001C01CS-SA     I9 @S9S_MB_2U_LIB.S9S_MB_2U(SCH_1):PAGE39
    U2  EC1 VSS1309 SOCKET4677_AZIF0045P001C01CS-SA     I9 @S9S_MB_2U_LIB.S9S_MB_2U(SCH_1):PAGE39
    U2 EC13 VSS1310 SOCKET4677_AZIF0045P001C01CS-SA     I9 @S9S_MB_2U_LIB.S9S_MB_2U(SCH_1):PAGE39
    U2 EC19 VSS1311 SOCKET4677_AZIF0045P001C01CS-SA     I9 @S9S_MB_2U_LIB.S9S_MB_2U(SCH_1):PAGE39
    U2 EC23 VSS1313 SOCKET4677_AZIF0045P001C01CS-SA     I9 @S9S_MB_2U_LIB.S9S_MB_2U(SCH_1):PAGE39
    U2 EC29 VSS1314 SOCKET4677_AZIF0045P001C01CS-SA     I9 @S9S_MB_2U_LIB.S9S_MB_2U(SCH_1):PAGE39
    U2 EC31 VSS1316 SOCKET4677_AZIF0045P001C01CS-SA     I9 @S9S_MB_2U_LIB.S9S_MB_2U(SCH_1):PAGE39
    U2 EC37 VSS1317 SOCKET4677_AZIF0045P001C01CS-SA     I9 @S9S_MB_2U_LIB.S9S_MB_2U(SCH_1):PAGE39
    U2  EH6 VSS1318 SOCKET4677_AZIF0045P001C01CS-SA     I9 @S9S_MB_2U_LIB.S9S_MB_2U(SCH_1):PAGE39
    U2 EC41 VSS1321 SOCKET4677_AZIF0045P001C01CS-SA     I9 @S9S_MB_2U_LIB.S9S_MB_2U(SCH_1):PAGE39
    U2 EC43 VSS1323 SOCKET4677_AZIF0045P001C01CS-SA     I9 @S9S_MB_2U_LIB.S9S_MB_2U(SCH_1):PAGE39
    U2 EC48 VSS1324 SOCKET4677_AZIF0045P001C01CS-SA     I9 @S9S_MB_2U_LIB.S9S_MB_2U(SCH_1):PAGE39
    U2 EC50 VSS1326 SOCKET4677_AZIF0045P001C01CS-SA     I9 @S9S_MB_2U_LIB.S9S_MB_2U(SCH_1):PAGE39
    U2 EC56 VSS1327 SOCKET4677_AZIF0045P001C01CS-SA     I9 @S9S_MB_2U_LIB.S9S_MB_2U(SCH_1):PAGE39
    U2 EC66 VSS1329 SOCKET4677_AZIF0045P001C01CS-SA     I9 @S9S_MB_2U_LIB.S9S_MB_2U(SCH_1):PAGE39
    U2 EC72 VSS1330 SOCKET4677_AZIF0045P001C01CS-SA     I9 @S9S_MB_2U_LIB.S9S_MB_2U(SCH_1):PAGE39
    U2 EC74 VSS1332 SOCKET4677_AZIF0045P001C01CS-SA     I9 @S9S_MB_2U_LIB.S9S_MB_2U(SCH_1):PAGE39
    U2 EC82 VSS1333 SOCKET4677_AZIF0045P001C01CS-SA     I9 @S9S_MB_2U_LIB.S9S_MB_2U(SCH_1):PAGE39
    U2 EC84 VSS1335 SOCKET4677_AZIF0045P001C01CS-SA     I9 @S9S_MB_2U_LIB.S9S_MB_2U(SCH_1):PAGE39
    U2 EC88 VSS1336 SOCKET4677_AZIF0045P001C01CS-SA     I9 @S9S_MB_2U_LIB.S9S_MB_2U(SCH_1):PAGE39
    U2  EC9 VSS1337 SOCKET4677_AZIF0045P001C01CS-SA     I9 @S9S_MB_2U_LIB.S9S_MB_2U(SCH_1):PAGE39
    U2 ED16 VSS1338 SOCKET4677_AZIF0045P001C01CS-SA     I9 @S9S_MB_2U_LIB.S9S_MB_2U(SCH_1):PAGE39
    U2 ED24 VSS1339 SOCKET4677_AZIF0045P001C01CS-SA     I9 @S9S_MB_2U_LIB.S9S_MB_2U(SCH_1):PAGE39
    U2 ED30 VSS1341 SOCKET4677_AZIF0045P001C01CS-SA     I9 @S9S_MB_2U_LIB.S9S_MB_2U(SCH_1):PAGE39
    U2 ED36 VSS1342 SOCKET4677_AZIF0045P001C01CS-SA     I9 @S9S_MB_2U_LIB.S9S_MB_2U(SCH_1):PAGE39
    U2  ED4 VSS1344 SOCKET4677_AZIF0045P001C01CS-SA     I9 @S9S_MB_2U_LIB.S9S_MB_2U(SCH_1):PAGE39
    U2 ED49 VSS1346 SOCKET4677_AZIF0045P001C01CS-SA     I9 @S9S_MB_2U_LIB.S9S_MB_2U(SCH_1):PAGE39
    U2  ED8 VSS1348 SOCKET4677_AZIF0045P001C01CS-SA     I9 @S9S_MB_2U_LIB.S9S_MB_2U(SCH_1):PAGE39
    U2 EE78 VSS1349 SOCKET4677_AZIF0045P001C01CS-SA     I9 @S9S_MB_2U_LIB.S9S_MB_2U(SCH_1):PAGE39
    U2 EE80 VSS1350 SOCKET4677_AZIF0045P001C01CS-SA     I9 @S9S_MB_2U_LIB.S9S_MB_2U(SCH_1):PAGE39
    U2 EE88 VSS1351 SOCKET4677_AZIF0045P001C01CS-SA     I9 @S9S_MB_2U_LIB.S9S_MB_2U(SCH_1):PAGE39
    U2 EF12 VSS1352 SOCKET4677_AZIF0045P001C01CS-SA     I9 @S9S_MB_2U_LIB.S9S_MB_2U(SCH_1):PAGE39
    U2 EF16 VSS1353 SOCKET4677_AZIF0045P001C01CS-SA     I9 @S9S_MB_2U_LIB.S9S_MB_2U(SCH_1):PAGE39
    U2 EF18 VSS1354 SOCKET4677_AZIF0045P001C01CS-SA     I9 @S9S_MB_2U_LIB.S9S_MB_2U(SCH_1):PAGE39
    U2  EF2 VSS1356 SOCKET4677_AZIF0045P001C01CS-SA     I9 @S9S_MB_2U_LIB.S9S_MB_2U(SCH_1):PAGE39
    U2 EF20 VSS1358 SOCKET4677_AZIF0045P001C01CS-SA     I9 @S9S_MB_2U_LIB.S9S_MB_2U(SCH_1):PAGE39
    U2 EF22 VSS1360 SOCKET4677_AZIF0045P001C01CS-SA     I9 @S9S_MB_2U_LIB.S9S_MB_2U(SCH_1):PAGE39
    U2 EF24 VSS1361 SOCKET4677_AZIF0045P001C01CS-SA     I9 @S9S_MB_2U_LIB.S9S_MB_2U(SCH_1):PAGE39
    U2 EF26 VSS1362 SOCKET4677_AZIF0045P001C01CS-SA     I9 @S9S_MB_2U_LIB.S9S_MB_2U(SCH_1):PAGE39
    U2 EF28 VSS1363 SOCKET4677_AZIF0045P001C01CS-SA     I9 @S9S_MB_2U_LIB.S9S_MB_2U(SCH_1):PAGE39
    U2 EF30 VSS1364 SOCKET4677_AZIF0045P001C01CS-SA     I9 @S9S_MB_2U_LIB.S9S_MB_2U(SCH_1):PAGE39
    U2 EF32 VSS1365 SOCKET4677_AZIF0045P001C01CS-SA     I9 @S9S_MB_2U_LIB.S9S_MB_2U(SCH_1):PAGE39
    U2 EF34 VSS1367 SOCKET4677_AZIF0045P001C01CS-SA     I9 @S9S_MB_2U_LIB.S9S_MB_2U(SCH_1):PAGE39
    U2 EF36 VSS1370 SOCKET4677_AZIF0045P001C01CS-SA     I9 @S9S_MB_2U_LIB.S9S_MB_2U(SCH_1):PAGE39
    U2 EF38 VSS1373 SOCKET4677_AZIF0045P001C01CS-SA     I9 @S9S_MB_2U_LIB.S9S_MB_2U(SCH_1):PAGE39
    U2  EF4 VSS1374 SOCKET4677_AZIF0045P001C01CS-SA     I9 @S9S_MB_2U_LIB.S9S_MB_2U(SCH_1):PAGE39
    U2 EF40 VSS1376 SOCKET4677_AZIF0045P001C01CS-SA     I9 @S9S_MB_2U_LIB.S9S_MB_2U(SCH_1):PAGE39
    U2 EF42 VSS1382 SOCKET4677_AZIF0045P001C01CS-SA     I9 @S9S_MB_2U_LIB.S9S_MB_2U(SCH_1):PAGE39
    U2 EF44 VSS1383 SOCKET4677_AZIF0045P001C01CS-SA     I9 @S9S_MB_2U_LIB.S9S_MB_2U(SCH_1):PAGE39
    U2 EF47 VSS1384 SOCKET4677_AZIF0045P001C01CS-SA     I9 @S9S_MB_2U_LIB.S9S_MB_2U(SCH_1):PAGE39
    U2 EF49 VSS1385 SOCKET4677_AZIF0045P001C01CS-SA     I9 @S9S_MB_2U_LIB.S9S_MB_2U(SCH_1):PAGE39
    U2 EF53 VSS1386 SOCKET4677_AZIF0045P001C01CS-SA     I9 @S9S_MB_2U_LIB.S9S_MB_2U(SCH_1):PAGE39
    U2 EF55 VSS1387 SOCKET4677_AZIF0045P001C01CS-SA     I9 @S9S_MB_2U_LIB.S9S_MB_2U(SCH_1):PAGE39
    U2 EF57 VSS1388 SOCKET4677_AZIF0045P001C01CS-SA     I9 @S9S_MB_2U_LIB.S9S_MB_2U(SCH_1):PAGE39
    U2 EF59 VSS1389 SOCKET4677_AZIF0045P001C01CS-SA     I9 @S9S_MB_2U_LIB.S9S_MB_2U(SCH_1):PAGE39
    U2 EF61 VSS1390 SOCKET4677_AZIF0045P001C01CS-SA     I9 @S9S_MB_2U_LIB.S9S_MB_2U(SCH_1):PAGE39
    U2 EF63 VSS1392 SOCKET4677_AZIF0045P001C01CS-SA     I9 @S9S_MB_2U_LIB.S9S_MB_2U(SCH_1):PAGE39
    U2 EF65 VSS1393 SOCKET4677_AZIF0045P001C01CS-SA     I9 @S9S_MB_2U_LIB.S9S_MB_2U(SCH_1):PAGE39
    U2 EF67 VSS1395 SOCKET4677_AZIF0045P001C01CS-SA     I9 @S9S_MB_2U_LIB.S9S_MB_2U(SCH_1):PAGE39
    U2 EF69 VSS1399 SOCKET4677_AZIF0045P001C01CS-SA     I9 @S9S_MB_2U_LIB.S9S_MB_2U(SCH_1):PAGE39
    U2 EF71 VSS1402 SOCKET4677_AZIF0045P001C01CS-SA     I9 @S9S_MB_2U_LIB.S9S_MB_2U(SCH_1):PAGE39
    U2 EF77 VSS1403 SOCKET4677_AZIF0045P001C01CS-SA     I9 @S9S_MB_2U_LIB.S9S_MB_2U(SCH_1):PAGE39
    U2  EF8 VSS1404 SOCKET4677_AZIF0045P001C01CS-SA     I9 @S9S_MB_2U_LIB.S9S_MB_2U(SCH_1):PAGE39
    U2 EF85 VSS1406 SOCKET4677_AZIF0045P001C01CS-SA     I9 @S9S_MB_2U_LIB.S9S_MB_2U(SCH_1):PAGE39
    U2 EF87 VSS1407 SOCKET4677_AZIF0045P001C01CS-SA     I9 @S9S_MB_2U_LIB.S9S_MB_2U(SCH_1):PAGE39
    U2 EG39 VSS1408 SOCKET4677_AZIF0045P001C01CS-SA     I9 @S9S_MB_2U_LIB.S9S_MB_2U(SCH_1):PAGE39
    U2 EG82 VSS1410 SOCKET4677_AZIF0045P001C01CS-SA     I9 @S9S_MB_2U_LIB.S9S_MB_2U(SCH_1):PAGE39
    U2 EG84 VSS1411 SOCKET4677_AZIF0045P001C01CS-SA     I9 @S9S_MB_2U_LIB.S9S_MB_2U(SCH_1):PAGE39
    U2 EG86 VSS1412 SOCKET4677_AZIF0045P001C01CS-SA     I9 @S9S_MB_2U_LIB.S9S_MB_2U(SCH_1):PAGE39
    U2 EG88 VSS1413 SOCKET4677_AZIF0045P001C01CS-SA     I9 @S9S_MB_2U_LIB.S9S_MB_2U(SCH_1):PAGE39
    U2  EG9 VSS1414 SOCKET4677_AZIF0045P001C01CS-SA     I9 @S9S_MB_2U_LIB.S9S_MB_2U(SCH_1):PAGE39
    U2 EG90 VSS1415 SOCKET4677_AZIF0045P001C01CS-SA     I9 @S9S_MB_2U_LIB.S9S_MB_2U(SCH_1):PAGE39
    U2 EH16 VSS1416 SOCKET4677_AZIF0045P001C01CS-SA     I9 @S9S_MB_2U_LIB.S9S_MB_2U(SCH_1):PAGE39
    U2 EH24 VSS1417 SOCKET4677_AZIF0045P001C01CS-SA     I9 @S9S_MB_2U_LIB.S9S_MB_2U(SCH_1):PAGE39
    U2 EH30 VSS1418 SOCKET4677_AZIF0045P001C01CS-SA     I9 @S9S_MB_2U_LIB.S9S_MB_2U(SCH_1):PAGE39
    U2  EH4 VSS1420 SOCKET4677_AZIF0045P001C01CS-SA     I9 @S9S_MB_2U_LIB.S9S_MB_2U(SCH_1):PAGE39
    U2 DM51 VSS934 SOCKET4677_AZIF0045P001C01CS-SA    I10 @S9S_MB_2U_LIB.S9S_MB_2U(SCH_1):PAGE39
    U2 DM73 VSS945 SOCKET4677_AZIF0045P001C01CS-SA    I10 @S9S_MB_2U_LIB.S9S_MB_2U(SCH_1):PAGE39
    U2 DN17 VSS955 SOCKET4677_AZIF0045P001C01CS-SA    I10 @S9S_MB_2U_LIB.S9S_MB_2U(SCH_1):PAGE39
    U2 DN39 VSS957 SOCKET4677_AZIF0045P001C01CS-SA    I10 @S9S_MB_2U_LIB.S9S_MB_2U(SCH_1):PAGE39
    U2 DN52 VSS959 SOCKET4677_AZIF0045P001C01CS-SA    I10 @S9S_MB_2U_LIB.S9S_MB_2U(SCH_1):PAGE39
    U2 DP12 VSS966 SOCKET4677_AZIF0045P001C01CS-SA    I10 @S9S_MB_2U_LIB.S9S_MB_2U(SCH_1):PAGE39
    U2 DP18 VSS968 SOCKET4677_AZIF0045P001C01CS-SA    I10 @S9S_MB_2U_LIB.S9S_MB_2U(SCH_1):PAGE39
    U2 DP24 VSS969 SOCKET4677_AZIF0045P001C01CS-SA    I10 @S9S_MB_2U_LIB.S9S_MB_2U(SCH_1):PAGE39
    U2 DP42 VSS973 SOCKET4677_AZIF0045P001C01CS-SA    I10 @S9S_MB_2U_LIB.S9S_MB_2U(SCH_1):PAGE39
    U2 DP55 VSS976 SOCKET4677_AZIF0045P001C01CS-SA    I10 @S9S_MB_2U_LIB.S9S_MB_2U(SCH_1):PAGE39
    U2 DP61 VSS979 SOCKET4677_AZIF0045P001C01CS-SA    I10 @S9S_MB_2U_LIB.S9S_MB_2U(SCH_1):PAGE39
    U2 DP67 VSS980 SOCKET4677_AZIF0045P001C01CS-SA    I10 @S9S_MB_2U_LIB.S9S_MB_2U(SCH_1):PAGE39
    U2 DP91 VSS985 SOCKET4677_AZIF0045P001C01CS-SA    I10 @S9S_MB_2U_LIB.S9S_MB_2U(SCH_1):PAGE39
    U2 DR25 VSS990 SOCKET4677_AZIF0045P001C01CS-SA    I10 @S9S_MB_2U_LIB.S9S_MB_2U(SCH_1):PAGE39
    U2 DR35 VSS993 SOCKET4677_AZIF0045P001C01CS-SA    I10 @S9S_MB_2U_LIB.S9S_MB_2U(SCH_1):PAGE39
    U2  DR5 VSS998 SOCKET4677_AZIF0045P001C01CS-SA    I10 @S9S_MB_2U_LIB.S9S_MB_2U(SCH_1):PAGE39
    U2 DR54 VSS1000 SOCKET4677_AZIF0045P001C01CS-SA    I10 @S9S_MB_2U_LIB.S9S_MB_2U(SCH_1):PAGE39
    U2 DR60 VSS1002 SOCKET4677_AZIF0045P001C01CS-SA    I10 @S9S_MB_2U_LIB.S9S_MB_2U(SCH_1):PAGE39
    U2 DR62 VSS1003 SOCKET4677_AZIF0045P001C01CS-SA    I10 @S9S_MB_2U_LIB.S9S_MB_2U(SCH_1):PAGE39
    U2 DR68 VSS1005 SOCKET4677_AZIF0045P001C01CS-SA    I10 @S9S_MB_2U_LIB.S9S_MB_2U(SCH_1):PAGE39
    U2 DR72 VSS1006 SOCKET4677_AZIF0045P001C01CS-SA    I10 @S9S_MB_2U_LIB.S9S_MB_2U(SCH_1):PAGE39
    U2 DT16 VSS1013 SOCKET4677_AZIF0045P001C01CS-SA    I10 @S9S_MB_2U_LIB.S9S_MB_2U(SCH_1):PAGE39
    U2 DT20 VSS1014 SOCKET4677_AZIF0045P001C01CS-SA    I10 @S9S_MB_2U_LIB.S9S_MB_2U(SCH_1):PAGE39
    U2 DT26 VSS1016 SOCKET4677_AZIF0045P001C01CS-SA    I10 @S9S_MB_2U_LIB.S9S_MB_2U(SCH_1):PAGE39
    U2  DT4 VSS1021 SOCKET4677_AZIF0045P001C01CS-SA    I10 @S9S_MB_2U_LIB.S9S_MB_2U(SCH_1):PAGE39
    U2 DT44 VSS1023 SOCKET4677_AZIF0045P001C01CS-SA    I10 @S9S_MB_2U_LIB.S9S_MB_2U(SCH_1):PAGE39
    U2 DT51 VSS1025 SOCKET4677_AZIF0045P001C01CS-SA    I10 @S9S_MB_2U_LIB.S9S_MB_2U(SCH_1):PAGE39
    U2 DT53 VSS1026 SOCKET4677_AZIF0045P001C01CS-SA    I10 @S9S_MB_2U_LIB.S9S_MB_2U(SCH_1):PAGE39
    U2 DT59 VSS1028 SOCKET4677_AZIF0045P001C01CS-SA    I10 @S9S_MB_2U_LIB.S9S_MB_2U(SCH_1):PAGE39
    U2 DT63 VSS1029 SOCKET4677_AZIF0045P001C01CS-SA    I10 @S9S_MB_2U_LIB.S9S_MB_2U(SCH_1):PAGE39
    U2 DT83 VSS1036 SOCKET4677_AZIF0045P001C01CS-SA    I10 @S9S_MB_2U_LIB.S9S_MB_2U(SCH_1):PAGE39
    U2 DU39 VSS1047 SOCKET4677_AZIF0045P001C01CS-SA    I10 @S9S_MB_2U_LIB.S9S_MB_2U(SCH_1):PAGE39
    U2 DU45 VSS1048 SOCKET4677_AZIF0045P001C01CS-SA    I10 @S9S_MB_2U_LIB.S9S_MB_2U(SCH_1):PAGE39
    U2 DU52 VSS1050 SOCKET4677_AZIF0045P001C01CS-SA    I10 @S9S_MB_2U_LIB.S9S_MB_2U(SCH_1):PAGE39
    U2 DU58 VSS1051 SOCKET4677_AZIF0045P001C01CS-SA    I10 @S9S_MB_2U_LIB.S9S_MB_2U(SCH_1):PAGE39
    U2 DU64 VSS1052 SOCKET4677_AZIF0045P001C01CS-SA    I10 @S9S_MB_2U_LIB.S9S_MB_2U(SCH_1):PAGE39
    U2 DU70 VSS1054 SOCKET4677_AZIF0045P001C01CS-SA    I10 @S9S_MB_2U_LIB.S9S_MB_2U(SCH_1):PAGE39
    U2 DV12 VSS1059 SOCKET4677_AZIF0045P001C01CS-SA    I10 @S9S_MB_2U_LIB.S9S_MB_2U(SCH_1):PAGE39
    U2 DV16 VSS1060 SOCKET4677_AZIF0045P001C01CS-SA    I10 @S9S_MB_2U_LIB.S9S_MB_2U(SCH_1):PAGE39
    U2  DV4 VSS1063 SOCKET4677_AZIF0045P001C01CS-SA    I10 @S9S_MB_2U_LIB.S9S_MB_2U(SCH_1):PAGE39
    U2 DV42 VSS1064 SOCKET4677_AZIF0045P001C01CS-SA    I10 @S9S_MB_2U_LIB.S9S_MB_2U(SCH_1):PAGE39
    U2 DW21 VSS1077 SOCKET4677_AZIF0045P001C01CS-SA    I10 @S9S_MB_2U_LIB.S9S_MB_2U(SCH_1):PAGE39
    U2 DW60 VSS1097 SOCKET4677_AZIF0045P001C01CS-SA    I10 @S9S_MB_2U_LIB.S9S_MB_2U(SCH_1):PAGE39
    U2 DM12 VSS1100 SOCKET4677_AZIF0045P001C01CS-SA    I10 @S9S_MB_2U_LIB.S9S_MB_2U(SCH_1):PAGE39
    U2 DM16 VSS1101 SOCKET4677_AZIF0045P001C01CS-SA    I10 @S9S_MB_2U_LIB.S9S_MB_2U(SCH_1):PAGE39
    U2 DM18 VSS1102 SOCKET4677_AZIF0045P001C01CS-SA    I10 @S9S_MB_2U_LIB.S9S_MB_2U(SCH_1):PAGE39
    U2 DM20 VSS1103 SOCKET4677_AZIF0045P001C01CS-SA    I10 @S9S_MB_2U_LIB.S9S_MB_2U(SCH_1):PAGE39
    U2 DM22 VSS1104 SOCKET4677_AZIF0045P001C01CS-SA    I10 @S9S_MB_2U_LIB.S9S_MB_2U(SCH_1):PAGE39
    U2 DM24 VSS1105 SOCKET4677_AZIF0045P001C01CS-SA    I10 @S9S_MB_2U_LIB.S9S_MB_2U(SCH_1):PAGE39
    U2 DM26 VSS1106 SOCKET4677_AZIF0045P001C01CS-SA    I10 @S9S_MB_2U_LIB.S9S_MB_2U(SCH_1):PAGE39
    U2 DM28 VSS1107 SOCKET4677_AZIF0045P001C01CS-SA    I10 @S9S_MB_2U_LIB.S9S_MB_2U(SCH_1):PAGE39
    U2 DM30 VSS1108 SOCKET4677_AZIF0045P001C01CS-SA    I10 @S9S_MB_2U_LIB.S9S_MB_2U(SCH_1):PAGE39
    U2 DM32 VSS1109 SOCKET4677_AZIF0045P001C01CS-SA    I10 @S9S_MB_2U_LIB.S9S_MB_2U(SCH_1):PAGE39
    U2 DM34 VSS1110 SOCKET4677_AZIF0045P001C01CS-SA    I10 @S9S_MB_2U_LIB.S9S_MB_2U(SCH_1):PAGE39
    U2 DM36 VSS1113 SOCKET4677_AZIF0045P001C01CS-SA    I10 @S9S_MB_2U_LIB.S9S_MB_2U(SCH_1):PAGE39
    U2 DM38 VSS1114 SOCKET4677_AZIF0045P001C01CS-SA    I10 @S9S_MB_2U_LIB.S9S_MB_2U(SCH_1):PAGE39
    U2  DM4 VSS1117 SOCKET4677_AZIF0045P001C01CS-SA    I10 @S9S_MB_2U_LIB.S9S_MB_2U(SCH_1):PAGE39
    U2 DM40 VSS1118 SOCKET4677_AZIF0045P001C01CS-SA    I10 @S9S_MB_2U_LIB.S9S_MB_2U(SCH_1):PAGE39
    U2 DM42 VSS1119 SOCKET4677_AZIF0045P001C01CS-SA    I10 @S9S_MB_2U_LIB.S9S_MB_2U(SCH_1):PAGE39
    U2 DM44 VSS1120 SOCKET4677_AZIF0045P001C01CS-SA    I10 @S9S_MB_2U_LIB.S9S_MB_2U(SCH_1):PAGE39
    U2 DM47 VSS1121 SOCKET4677_AZIF0045P001C01CS-SA    I10 @S9S_MB_2U_LIB.S9S_MB_2U(SCH_1):PAGE39
    U2 DM49 VSS1122 SOCKET4677_AZIF0045P001C01CS-SA    I10 @S9S_MB_2U_LIB.S9S_MB_2U(SCH_1):PAGE39
    U2 DM53 VSS1123 SOCKET4677_AZIF0045P001C01CS-SA    I10 @S9S_MB_2U_LIB.S9S_MB_2U(SCH_1):PAGE39
    U2 DM55 VSS1124 SOCKET4677_AZIF0045P001C01CS-SA    I10 @S9S_MB_2U_LIB.S9S_MB_2U(SCH_1):PAGE39
    U2 DM57 VSS1127 SOCKET4677_AZIF0045P001C01CS-SA    I10 @S9S_MB_2U_LIB.S9S_MB_2U(SCH_1):PAGE39
    U2 DM59 VSS1128 SOCKET4677_AZIF0045P001C01CS-SA    I10 @S9S_MB_2U_LIB.S9S_MB_2U(SCH_1):PAGE39
    U2 DM61 VSS1130 SOCKET4677_AZIF0045P001C01CS-SA    I10 @S9S_MB_2U_LIB.S9S_MB_2U(SCH_1):PAGE39
    U2 DM63 VSS1132 SOCKET4677_AZIF0045P001C01CS-SA    I10 @S9S_MB_2U_LIB.S9S_MB_2U(SCH_1):PAGE39
    U2 DM65 VSS1133 SOCKET4677_AZIF0045P001C01CS-SA    I10 @S9S_MB_2U_LIB.S9S_MB_2U(SCH_1):PAGE39
    U2 DM67 VSS1134 SOCKET4677_AZIF0045P001C01CS-SA    I10 @S9S_MB_2U_LIB.S9S_MB_2U(SCH_1):PAGE39
    U2 DM69 VSS1135 SOCKET4677_AZIF0045P001C01CS-SA    I10 @S9S_MB_2U_LIB.S9S_MB_2U(SCH_1):PAGE39
    U2 DM71 VSS1136 SOCKET4677_AZIF0045P001C01CS-SA    I10 @S9S_MB_2U_LIB.S9S_MB_2U(SCH_1):PAGE39
    U2 DM75 VSS1137 SOCKET4677_AZIF0045P001C01CS-SA    I10 @S9S_MB_2U_LIB.S9S_MB_2U(SCH_1):PAGE39
    U2 DM77 VSS1138 SOCKET4677_AZIF0045P001C01CS-SA    I10 @S9S_MB_2U_LIB.S9S_MB_2U(SCH_1):PAGE39
    U2 DM79 VSS1139 SOCKET4677_AZIF0045P001C01CS-SA    I10 @S9S_MB_2U_LIB.S9S_MB_2U(SCH_1):PAGE39
    U2  DM8 VSS1140 SOCKET4677_AZIF0045P001C01CS-SA    I10 @S9S_MB_2U_LIB.S9S_MB_2U(SCH_1):PAGE39
    U2 DN78 VSS1143 SOCKET4677_AZIF0045P001C01CS-SA    I10 @S9S_MB_2U_LIB.S9S_MB_2U(SCH_1):PAGE39
    U2 DN84 VSS1147 SOCKET4677_AZIF0045P001C01CS-SA    I10 @S9S_MB_2U_LIB.S9S_MB_2U(SCH_1):PAGE39
    U2 DN88 VSS1148 SOCKET4677_AZIF0045P001C01CS-SA    I10 @S9S_MB_2U_LIB.S9S_MB_2U(SCH_1):PAGE39
    U2 DP16 VSS1149 SOCKET4677_AZIF0045P001C01CS-SA    I10 @S9S_MB_2U_LIB.S9S_MB_2U(SCH_1):PAGE39
    U2 DP30 VSS1150 SOCKET4677_AZIF0045P001C01CS-SA    I10 @S9S_MB_2U_LIB.S9S_MB_2U(SCH_1):PAGE39
    U2 DP36 VSS1151 SOCKET4677_AZIF0045P001C01CS-SA    I10 @S9S_MB_2U_LIB.S9S_MB_2U(SCH_1):PAGE39
    U2  DP4 VSS1152 SOCKET4677_AZIF0045P001C01CS-SA    I10 @S9S_MB_2U_LIB.S9S_MB_2U(SCH_1):PAGE39
    U2 DP49 VSS1153 SOCKET4677_AZIF0045P001C01CS-SA    I10 @S9S_MB_2U_LIB.S9S_MB_2U(SCH_1):PAGE39
    U2 DP73 VSS1154 SOCKET4677_AZIF0045P001C01CS-SA    I10 @S9S_MB_2U_LIB.S9S_MB_2U(SCH_1):PAGE39
    U2  DP8 VSS1157 SOCKET4677_AZIF0045P001C01CS-SA    I10 @S9S_MB_2U_LIB.S9S_MB_2U(SCH_1):PAGE39
    U2 DP81 VSS1159 SOCKET4677_AZIF0045P001C01CS-SA    I10 @S9S_MB_2U_LIB.S9S_MB_2U(SCH_1):PAGE39
    U2 DP87 VSS1160 SOCKET4677_AZIF0045P001C01CS-SA    I10 @S9S_MB_2U_LIB.S9S_MB_2U(SCH_1):PAGE39
    U2  DR1 VSS1162 SOCKET4677_AZIF0045P001C01CS-SA    I10 @S9S_MB_2U_LIB.S9S_MB_2U(SCH_1):PAGE39
    U2 DR13 VSS1164 SOCKET4677_AZIF0045P001C01CS-SA    I10 @S9S_MB_2U_LIB.S9S_MB_2U(SCH_1):PAGE39
    U2 DR19 VSS1166 SOCKET4677_AZIF0045P001C01CS-SA    I10 @S9S_MB_2U_LIB.S9S_MB_2U(SCH_1):PAGE39
    U2 DR23 VSS1169 SOCKET4677_AZIF0045P001C01CS-SA    I10 @S9S_MB_2U_LIB.S9S_MB_2U(SCH_1):PAGE39
    U2 DR29 VSS1172 SOCKET4677_AZIF0045P001C01CS-SA    I10 @S9S_MB_2U_LIB.S9S_MB_2U(SCH_1):PAGE39
    U2 DR31 VSS1173 SOCKET4677_AZIF0045P001C01CS-SA    I10 @S9S_MB_2U_LIB.S9S_MB_2U(SCH_1):PAGE39
    U2 DR37 VSS1174 SOCKET4677_AZIF0045P001C01CS-SA    I10 @S9S_MB_2U_LIB.S9S_MB_2U(SCH_1):PAGE39
    U2 DR41 VSS1175 SOCKET4677_AZIF0045P001C01CS-SA    I10 @S9S_MB_2U_LIB.S9S_MB_2U(SCH_1):PAGE39
    U2 DR43 VSS1176 SOCKET4677_AZIF0045P001C01CS-SA    I10 @S9S_MB_2U_LIB.S9S_MB_2U(SCH_1):PAGE39
    U2 DR48 VSS1177 SOCKET4677_AZIF0045P001C01CS-SA    I10 @S9S_MB_2U_LIB.S9S_MB_2U(SCH_1):PAGE39
    U2 DR50 VSS1178 SOCKET4677_AZIF0045P001C01CS-SA    I10 @S9S_MB_2U_LIB.S9S_MB_2U(SCH_1):PAGE39
    U2 DR56 VSS1179 SOCKET4677_AZIF0045P001C01CS-SA    I10 @S9S_MB_2U_LIB.S9S_MB_2U(SCH_1):PAGE39
    U2 DR66 VSS1181 SOCKET4677_AZIF0045P001C01CS-SA    I10 @S9S_MB_2U_LIB.S9S_MB_2U(SCH_1):PAGE39
    U2 DR74 VSS1182 SOCKET4677_AZIF0045P001C01CS-SA    I10 @S9S_MB_2U_LIB.S9S_MB_2U(SCH_1):PAGE39
    U2 DR78 VSS1183 SOCKET4677_AZIF0045P001C01CS-SA    I10 @S9S_MB_2U_LIB.S9S_MB_2U(SCH_1):PAGE39
    U2 DR84 VSS1184 SOCKET4677_AZIF0045P001C01CS-SA    I10 @S9S_MB_2U_LIB.S9S_MB_2U(SCH_1):PAGE39
    U2 DR88 VSS1186 SOCKET4677_AZIF0045P001C01CS-SA    I10 @S9S_MB_2U_LIB.S9S_MB_2U(SCH_1):PAGE39
    U2  DR9 VSS1187 SOCKET4677_AZIF0045P001C01CS-SA    I10 @S9S_MB_2U_LIB.S9S_MB_2U(SCH_1):PAGE39
    U2 DT12 VSS1189 SOCKET4677_AZIF0045P001C01CS-SA    I10 @S9S_MB_2U_LIB.S9S_MB_2U(SCH_1):PAGE39
    U2 DT22 VSS1190 SOCKET4677_AZIF0045P001C01CS-SA    I10 @S9S_MB_2U_LIB.S9S_MB_2U(SCH_1):PAGE39
    U2 DT28 VSS1191 SOCKET4677_AZIF0045P001C01CS-SA    I10 @S9S_MB_2U_LIB.S9S_MB_2U(SCH_1):PAGE39
    U2 DT32 VSS1192 SOCKET4677_AZIF0045P001C01CS-SA    I10 @S9S_MB_2U_LIB.S9S_MB_2U(SCH_1):PAGE39
    U2 DT34 VSS1194 SOCKET4677_AZIF0045P001C01CS-SA    I10 @S9S_MB_2U_LIB.S9S_MB_2U(SCH_1):PAGE39
    U2 DT38 VSS1196 SOCKET4677_AZIF0045P001C01CS-SA    I10 @S9S_MB_2U_LIB.S9S_MB_2U(SCH_1):PAGE39
    U2 DT40 VSS1199 SOCKET4677_AZIF0045P001C01CS-SA    I10 @S9S_MB_2U_LIB.S9S_MB_2U(SCH_1):PAGE39
    U2 DT47 VSS1201 SOCKET4677_AZIF0045P001C01CS-SA    I10 @S9S_MB_2U_LIB.S9S_MB_2U(SCH_1):PAGE39
    U2 DT57 VSS1202 SOCKET4677_AZIF0045P001C01CS-SA    I10 @S9S_MB_2U_LIB.S9S_MB_2U(SCH_1):PAGE39
    U2 DT65 VSS1203 SOCKET4677_AZIF0045P001C01CS-SA    I10 @S9S_MB_2U_LIB.S9S_MB_2U(SCH_1):PAGE39
    U2 DT69 VSS1204 SOCKET4677_AZIF0045P001C01CS-SA    I10 @S9S_MB_2U_LIB.S9S_MB_2U(SCH_1):PAGE39
    U2 DT71 VSS1205 SOCKET4677_AZIF0045P001C01CS-SA    I10 @S9S_MB_2U_LIB.S9S_MB_2U(SCH_1):PAGE39
    U2 DT75 VSS1206 SOCKET4677_AZIF0045P001C01CS-SA    I10 @S9S_MB_2U_LIB.S9S_MB_2U(SCH_1):PAGE39
    U2  DT8 VSS1207 SOCKET4677_AZIF0045P001C01CS-SA    I10 @S9S_MB_2U_LIB.S9S_MB_2U(SCH_1):PAGE39
    U2 DU21 VSS1209 SOCKET4677_AZIF0045P001C01CS-SA    I10 @S9S_MB_2U_LIB.S9S_MB_2U(SCH_1):PAGE39
    U2 DU27 VSS1211 SOCKET4677_AZIF0045P001C01CS-SA    I10 @S9S_MB_2U_LIB.S9S_MB_2U(SCH_1):PAGE39
    U2 DU33 VSS1212 SOCKET4677_AZIF0045P001C01CS-SA    I10 @S9S_MB_2U_LIB.S9S_MB_2U(SCH_1):PAGE39
    U2 DU76 VSS1213 SOCKET4677_AZIF0045P001C01CS-SA    I10 @S9S_MB_2U_LIB.S9S_MB_2U(SCH_1):PAGE39
    U2 DU78 VSS1214 SOCKET4677_AZIF0045P001C01CS-SA    I10 @S9S_MB_2U_LIB.S9S_MB_2U(SCH_1):PAGE39
    U2 DU84 VSS1215 SOCKET4677_AZIF0045P001C01CS-SA    I10 @S9S_MB_2U_LIB.S9S_MB_2U(SCH_1):PAGE39
    U2 DU88 VSS1216 SOCKET4677_AZIF0045P001C01CS-SA    I10 @S9S_MB_2U_LIB.S9S_MB_2U(SCH_1):PAGE39
    U2 DV77 VSS1218 SOCKET4677_AZIF0045P001C01CS-SA    I10 @S9S_MB_2U_LIB.S9S_MB_2U(SCH_1):PAGE39
    U2 DV79 VSS1219 SOCKET4677_AZIF0045P001C01CS-SA    I10 @S9S_MB_2U_LIB.S9S_MB_2U(SCH_1):PAGE39
    U2  DV8 VSS1221 SOCKET4677_AZIF0045P001C01CS-SA    I10 @S9S_MB_2U_LIB.S9S_MB_2U(SCH_1):PAGE39
    U2 DV81 VSS1222 SOCKET4677_AZIF0045P001C01CS-SA    I10 @S9S_MB_2U_LIB.S9S_MB_2U(SCH_1):PAGE39
    U2 DV83 VSS1226 SOCKET4677_AZIF0045P001C01CS-SA    I10 @S9S_MB_2U_LIB.S9S_MB_2U(SCH_1):PAGE39
    U2 DV87 VSS1227 SOCKET4677_AZIF0045P001C01CS-SA    I10 @S9S_MB_2U_LIB.S9S_MB_2U(SCH_1):PAGE39
    U2 DV91 VSS1228 SOCKET4677_AZIF0045P001C01CS-SA    I10 @S9S_MB_2U_LIB.S9S_MB_2U(SCH_1):PAGE39
    U2  DW1 VSS1229 SOCKET4677_AZIF0045P001C01CS-SA    I10 @S9S_MB_2U_LIB.S9S_MB_2U(SCH_1):PAGE39
    U2 DW13 VSS1230 SOCKET4677_AZIF0045P001C01CS-SA    I10 @S9S_MB_2U_LIB.S9S_MB_2U(SCH_1):PAGE39
    U2 DW17 VSS1231 SOCKET4677_AZIF0045P001C01CS-SA    I10 @S9S_MB_2U_LIB.S9S_MB_2U(SCH_1):PAGE39
    U2 DW19 VSS1233 SOCKET4677_AZIF0045P001C01CS-SA    I10 @S9S_MB_2U_LIB.S9S_MB_2U(SCH_1):PAGE39
    U2 DW23 VSS1234 SOCKET4677_AZIF0045P001C01CS-SA    I10 @S9S_MB_2U_LIB.S9S_MB_2U(SCH_1):PAGE39
    U2 DW25 VSS1236 SOCKET4677_AZIF0045P001C01CS-SA    I10 @S9S_MB_2U_LIB.S9S_MB_2U(SCH_1):PAGE39
    U2 DW27 VSS1238 SOCKET4677_AZIF0045P001C01CS-SA    I10 @S9S_MB_2U_LIB.S9S_MB_2U(SCH_1):PAGE39
    U2 DW29 VSS1239 SOCKET4677_AZIF0045P001C01CS-SA    I10 @S9S_MB_2U_LIB.S9S_MB_2U(SCH_1):PAGE39
    U2 DW31 VSS1240 SOCKET4677_AZIF0045P001C01CS-SA    I10 @S9S_MB_2U_LIB.S9S_MB_2U(SCH_1):PAGE39
    U2 DW33 VSS1241 SOCKET4677_AZIF0045P001C01CS-SA    I10 @S9S_MB_2U_LIB.S9S_MB_2U(SCH_1):PAGE39
    U2 DW35 VSS1242 SOCKET4677_AZIF0045P001C01CS-SA    I10 @S9S_MB_2U_LIB.S9S_MB_2U(SCH_1):PAGE39
    U2 DW37 VSS1243 SOCKET4677_AZIF0045P001C01CS-SA    I10 @S9S_MB_2U_LIB.S9S_MB_2U(SCH_1):PAGE39
    U2 DW39 VSS1244 SOCKET4677_AZIF0045P001C01CS-SA    I10 @S9S_MB_2U_LIB.S9S_MB_2U(SCH_1):PAGE39
    U2 DW41 VSS1245 SOCKET4677_AZIF0045P001C01CS-SA    I10 @S9S_MB_2U_LIB.S9S_MB_2U(SCH_1):PAGE39
    U2 DW43 VSS1246 SOCKET4677_AZIF0045P001C01CS-SA    I10 @S9S_MB_2U_LIB.S9S_MB_2U(SCH_1):PAGE39
    U2 DW45 VSS1247 SOCKET4677_AZIF0045P001C01CS-SA    I10 @S9S_MB_2U_LIB.S9S_MB_2U(SCH_1):PAGE39
    U2 DW48 VSS1248 SOCKET4677_AZIF0045P001C01CS-SA    I10 @S9S_MB_2U_LIB.S9S_MB_2U(SCH_1):PAGE39
    U2  DW5 VSS1249 SOCKET4677_AZIF0045P001C01CS-SA    I10 @S9S_MB_2U_LIB.S9S_MB_2U(SCH_1):PAGE39
    U2 DW50 VSS1250 SOCKET4677_AZIF0045P001C01CS-SA    I10 @S9S_MB_2U_LIB.S9S_MB_2U(SCH_1):PAGE39
    U2 DW52 VSS1251 SOCKET4677_AZIF0045P001C01CS-SA    I10 @S9S_MB_2U_LIB.S9S_MB_2U(SCH_1):PAGE39
    U2 DW54 VSS1252 SOCKET4677_AZIF0045P001C01CS-SA    I10 @S9S_MB_2U_LIB.S9S_MB_2U(SCH_1):PAGE39
    U2 DW56 VSS1253 SOCKET4677_AZIF0045P001C01CS-SA    I10 @S9S_MB_2U_LIB.S9S_MB_2U(SCH_1):PAGE39
    U2 DW58 VSS1254 SOCKET4677_AZIF0045P001C01CS-SA    I10 @S9S_MB_2U_LIB.S9S_MB_2U(SCH_1):PAGE39
    U2 DW62 VSS1255 SOCKET4677_AZIF0045P001C01CS-SA    I10 @S9S_MB_2U_LIB.S9S_MB_2U(SCH_1):PAGE39
    U2 DW64 VSS1256 SOCKET4677_AZIF0045P001C01CS-SA    I10 @S9S_MB_2U_LIB.S9S_MB_2U(SCH_1):PAGE39
    U2  DW9 VSS1268 SOCKET4677_AZIF0045P001C01CS-SA    I10 @S9S_MB_2U_LIB.S9S_MB_2U(SCH_1):PAGE39
    U2 DB91 VSS723 SOCKET4677_AZIF0045P001C01CS-SA    I10 @S9S_MB_2U_LIB.S9S_MB_2U(SCH_1):PAGE40
    U2  DC1 VSS724 SOCKET4677_AZIF0045P001C01CS-SA    I10 @S9S_MB_2U_LIB.S9S_MB_2U(SCH_1):PAGE40
    U2 DC13 VSS725 SOCKET4677_AZIF0045P001C01CS-SA    I10 @S9S_MB_2U_LIB.S9S_MB_2U(SCH_1):PAGE40
    U2 DC21 VSS726 SOCKET4677_AZIF0045P001C01CS-SA    I10 @S9S_MB_2U_LIB.S9S_MB_2U(SCH_1):PAGE40
    U2 DC52 VSS735 SOCKET4677_AZIF0045P001C01CS-SA    I10 @S9S_MB_2U_LIB.S9S_MB_2U(SCH_1):PAGE40
    U2 DC58 VSS738 SOCKET4677_AZIF0045P001C01CS-SA    I10 @S9S_MB_2U_LIB.S9S_MB_2U(SCH_1):PAGE40
    U2 DC64 VSS739 SOCKET4677_AZIF0045P001C01CS-SA    I10 @S9S_MB_2U_LIB.S9S_MB_2U(SCH_1):PAGE40
    U2 DD12 VSS747 SOCKET4677_AZIF0045P001C01CS-SA    I10 @S9S_MB_2U_LIB.S9S_MB_2U(SCH_1):PAGE40
    U2 DD16 VSS748 SOCKET4677_AZIF0045P001C01CS-SA    I10 @S9S_MB_2U_LIB.S9S_MB_2U(SCH_1):PAGE40
    U2 DD49 VSS753 SOCKET4677_AZIF0045P001C01CS-SA    I10 @S9S_MB_2U_LIB.S9S_MB_2U(SCH_1):PAGE40
    U2 DE39 VSS776 SOCKET4677_AZIF0045P001C01CS-SA    I10 @S9S_MB_2U_LIB.S9S_MB_2U(SCH_1):PAGE40
    U2 DE70 VSS791 SOCKET4677_AZIF0045P001C01CS-SA    I10 @S9S_MB_2U_LIB.S9S_MB_2U(SCH_1):PAGE40
    U2 DF12 VSS798 SOCKET4677_AZIF0045P001C01CS-SA    I10 @S9S_MB_2U_LIB.S9S_MB_2U(SCH_1):PAGE40
    U2 DF16 VSS799 SOCKET4677_AZIF0045P001C01CS-SA    I10 @S9S_MB_2U_LIB.S9S_MB_2U(SCH_1):PAGE40
    U2 DF49 VSS802 SOCKET4677_AZIF0045P001C01CS-SA    I10 @S9S_MB_2U_LIB.S9S_MB_2U(SCH_1):PAGE40
    U2 DF91 VSS806 SOCKET4677_AZIF0045P001C01CS-SA    I10 @S9S_MB_2U_LIB.S9S_MB_2U(SCH_1):PAGE40
    U2  DG1 VSS807 SOCKET4677_AZIF0045P001C01CS-SA    I10 @S9S_MB_2U_LIB.S9S_MB_2U(SCH_1):PAGE40
    U2 DG13 VSS808 SOCKET4677_AZIF0045P001C01CS-SA    I10 @S9S_MB_2U_LIB.S9S_MB_2U(SCH_1):PAGE40
    U2 DG21 VSS809 SOCKET4677_AZIF0045P001C01CS-SA    I10 @S9S_MB_2U_LIB.S9S_MB_2U(SCH_1):PAGE40
    U2 DG52 VSS817 SOCKET4677_AZIF0045P001C01CS-SA    I10 @S9S_MB_2U_LIB.S9S_MB_2U(SCH_1):PAGE40
    U2 DG58 VSS820 SOCKET4677_AZIF0045P001C01CS-SA    I10 @S9S_MB_2U_LIB.S9S_MB_2U(SCH_1):PAGE40
    U2 DG64 VSS821 SOCKET4677_AZIF0045P001C01CS-SA    I10 @S9S_MB_2U_LIB.S9S_MB_2U(SCH_1):PAGE40
    U2 DH16 VSS829 SOCKET4677_AZIF0045P001C01CS-SA    I10 @S9S_MB_2U_LIB.S9S_MB_2U(SCH_1):PAGE40
    U2 DH20 VSS830 SOCKET4677_AZIF0045P001C01CS-SA    I10 @S9S_MB_2U_LIB.S9S_MB_2U(SCH_1):PAGE40
    U2 DH26 VSS832 SOCKET4677_AZIF0045P001C01CS-SA    I10 @S9S_MB_2U_LIB.S9S_MB_2U(SCH_1):PAGE40
    U2 DH34 VSS835 SOCKET4677_AZIF0045P001C01CS-SA    I10 @S9S_MB_2U_LIB.S9S_MB_2U(SCH_1):PAGE40
    U2 DH44 VSS839 SOCKET4677_AZIF0045P001C01CS-SA    I10 @S9S_MB_2U_LIB.S9S_MB_2U(SCH_1):PAGE40
    U2 DH51 VSS841 SOCKET4677_AZIF0045P001C01CS-SA    I10 @S9S_MB_2U_LIB.S9S_MB_2U(SCH_1):PAGE40
    U2 DH53 VSS842 SOCKET4677_AZIF0045P001C01CS-SA    I10 @S9S_MB_2U_LIB.S9S_MB_2U(SCH_1):PAGE40
    U2 DH59 VSS844 SOCKET4677_AZIF0045P001C01CS-SA    I10 @S9S_MB_2U_LIB.S9S_MB_2U(SCH_1):PAGE40
    U2 DH63 VSS845 SOCKET4677_AZIF0045P001C01CS-SA    I10 @S9S_MB_2U_LIB.S9S_MB_2U(SCH_1):PAGE40
    U2 DH69 VSS847 SOCKET4677_AZIF0045P001C01CS-SA    I10 @S9S_MB_2U_LIB.S9S_MB_2U(SCH_1):PAGE40
    U2 DH75 VSS849 SOCKET4677_AZIF0045P001C01CS-SA    I10 @S9S_MB_2U_LIB.S9S_MB_2U(SCH_1):PAGE40
    U2 DJ25 VSS857 SOCKET4677_AZIF0045P001C01CS-SA    I10 @S9S_MB_2U_LIB.S9S_MB_2U(SCH_1):PAGE40
    U2 DJ35 VSS861 SOCKET4677_AZIF0045P001C01CS-SA    I10 @S9S_MB_2U_LIB.S9S_MB_2U(SCH_1):PAGE40
    U2 DJ54 VSS867 SOCKET4677_AZIF0045P001C01CS-SA    I10 @S9S_MB_2U_LIB.S9S_MB_2U(SCH_1):PAGE40
    U2 DJ62 VSS870 SOCKET4677_AZIF0045P001C01CS-SA    I10 @S9S_MB_2U_LIB.S9S_MB_2U(SCH_1):PAGE40
    U2 DJ68 VSS872 SOCKET4677_AZIF0045P001C01CS-SA    I10 @S9S_MB_2U_LIB.S9S_MB_2U(SCH_1):PAGE40
    U2 DK12 VSS880 SOCKET4677_AZIF0045P001C01CS-SA    I10 @S9S_MB_2U_LIB.S9S_MB_2U(SCH_1):PAGE40
    U2 DK18 VSS882 SOCKET4677_AZIF0045P001C01CS-SA    I10 @S9S_MB_2U_LIB.S9S_MB_2U(SCH_1):PAGE40
    U2 DK24 VSS883 SOCKET4677_AZIF0045P001C01CS-SA    I10 @S9S_MB_2U_LIB.S9S_MB_2U(SCH_1):PAGE40
    U2 DK42 VSS887 SOCKET4677_AZIF0045P001C01CS-SA    I10 @S9S_MB_2U_LIB.S9S_MB_2U(SCH_1):PAGE40
    U2 DK55 VSS890 SOCKET4677_AZIF0045P001C01CS-SA    I10 @S9S_MB_2U_LIB.S9S_MB_2U(SCH_1):PAGE40
    U2 DK61 VSS893 SOCKET4677_AZIF0045P001C01CS-SA    I10 @S9S_MB_2U_LIB.S9S_MB_2U(SCH_1):PAGE40
    U2 DK67 VSS894 SOCKET4677_AZIF0045P001C01CS-SA    I10 @S9S_MB_2U_LIB.S9S_MB_2U(SCH_1):PAGE40
    U2  DL1 VSS903 SOCKET4677_AZIF0045P001C01CS-SA    I10 @S9S_MB_2U_LIB.S9S_MB_2U(SCH_1):PAGE40
    U2 DL13 VSS904 SOCKET4677_AZIF0045P001C01CS-SA    I10 @S9S_MB_2U_LIB.S9S_MB_2U(SCH_1):PAGE40
    U2 DL17 VSS905 SOCKET4677_AZIF0045P001C01CS-SA    I10 @S9S_MB_2U_LIB.S9S_MB_2U(SCH_1):PAGE40
    U2  DL5 VSS908 SOCKET4677_AZIF0045P001C01CS-SA    I10 @S9S_MB_2U_LIB.S9S_MB_2U(SCH_1):PAGE40
    U2 DL52 VSS909 SOCKET4677_AZIF0045P001C01CS-SA    I10 @S9S_MB_2U_LIB.S9S_MB_2U(SCH_1):PAGE40
    U2 DC27 VSS949 SOCKET4677_AZIF0045P001C01CS-SA    I10 @S9S_MB_2U_LIB.S9S_MB_2U(SCH_1):PAGE40
    U2 DC33 VSS950 SOCKET4677_AZIF0045P001C01CS-SA    I10 @S9S_MB_2U_LIB.S9S_MB_2U(SCH_1):PAGE40
    U2 DC39 VSS951 SOCKET4677_AZIF0045P001C01CS-SA    I10 @S9S_MB_2U_LIB.S9S_MB_2U(SCH_1):PAGE40
    U2 DC45 VSS952 SOCKET4677_AZIF0045P001C01CS-SA    I10 @S9S_MB_2U_LIB.S9S_MB_2U(SCH_1):PAGE40
    U2  DC5 VSS953 SOCKET4677_AZIF0045P001C01CS-SA    I10 @S9S_MB_2U_LIB.S9S_MB_2U(SCH_1):PAGE40
    U2 DC70 VSS954 SOCKET4677_AZIF0045P001C01CS-SA    I10 @S9S_MB_2U_LIB.S9S_MB_2U(SCH_1):PAGE40
    U2 DC76 VSS956 SOCKET4677_AZIF0045P001C01CS-SA    I10 @S9S_MB_2U_LIB.S9S_MB_2U(SCH_1):PAGE40
    U2 DC78 VSS958 SOCKET4677_AZIF0045P001C01CS-SA    I10 @S9S_MB_2U_LIB.S9S_MB_2U(SCH_1):PAGE40
    U2 DC80 VSS960 SOCKET4677_AZIF0045P001C01CS-SA    I10 @S9S_MB_2U_LIB.S9S_MB_2U(SCH_1):PAGE40
    U2 DC84 VSS961 SOCKET4677_AZIF0045P001C01CS-SA    I10 @S9S_MB_2U_LIB.S9S_MB_2U(SCH_1):PAGE40
    U2 DC88 VSS962 SOCKET4677_AZIF0045P001C01CS-SA    I10 @S9S_MB_2U_LIB.S9S_MB_2U(SCH_1):PAGE40
    U2  DC9 VSS963 SOCKET4677_AZIF0045P001C01CS-SA    I10 @S9S_MB_2U_LIB.S9S_MB_2U(SCH_1):PAGE40
    U2  DD4 VSS964 SOCKET4677_AZIF0045P001C01CS-SA    I10 @S9S_MB_2U_LIB.S9S_MB_2U(SCH_1):PAGE40
    U2 DD79 VSS965 SOCKET4677_AZIF0045P001C01CS-SA    I10 @S9S_MB_2U_LIB.S9S_MB_2U(SCH_1):PAGE40
    U2  DD8 VSS967 SOCKET4677_AZIF0045P001C01CS-SA    I10 @S9S_MB_2U_LIB.S9S_MB_2U(SCH_1):PAGE40
    U2 DE17 VSS970 SOCKET4677_AZIF0045P001C01CS-SA    I10 @S9S_MB_2U_LIB.S9S_MB_2U(SCH_1):PAGE40
    U2 DE19 VSS971 SOCKET4677_AZIF0045P001C01CS-SA    I10 @S9S_MB_2U_LIB.S9S_MB_2U(SCH_1):PAGE40
    U2 DE21 VSS972 SOCKET4677_AZIF0045P001C01CS-SA    I10 @S9S_MB_2U_LIB.S9S_MB_2U(SCH_1):PAGE40
    U2 DE23 VSS974 SOCKET4677_AZIF0045P001C01CS-SA    I10 @S9S_MB_2U_LIB.S9S_MB_2U(SCH_1):PAGE40
    U2 DE25 VSS975 SOCKET4677_AZIF0045P001C01CS-SA    I10 @S9S_MB_2U_LIB.S9S_MB_2U(SCH_1):PAGE40
    U2 DE27 VSS977 SOCKET4677_AZIF0045P001C01CS-SA    I10 @S9S_MB_2U_LIB.S9S_MB_2U(SCH_1):PAGE40
    U2 DE29 VSS978 SOCKET4677_AZIF0045P001C01CS-SA    I10 @S9S_MB_2U_LIB.S9S_MB_2U(SCH_1):PAGE40
    U2 DE31 VSS981 SOCKET4677_AZIF0045P001C01CS-SA    I10 @S9S_MB_2U_LIB.S9S_MB_2U(SCH_1):PAGE40
    U2 DE33 VSS982 SOCKET4677_AZIF0045P001C01CS-SA    I10 @S9S_MB_2U_LIB.S9S_MB_2U(SCH_1):PAGE40
    U2 DE35 VSS983 SOCKET4677_AZIF0045P001C01CS-SA    I10 @S9S_MB_2U_LIB.S9S_MB_2U(SCH_1):PAGE40
    U2 DE37 VSS984 SOCKET4677_AZIF0045P001C01CS-SA    I10 @S9S_MB_2U_LIB.S9S_MB_2U(SCH_1):PAGE40
    U2 DE41 VSS986 SOCKET4677_AZIF0045P001C01CS-SA    I10 @S9S_MB_2U_LIB.S9S_MB_2U(SCH_1):PAGE40
    U2 DE43 VSS987 SOCKET4677_AZIF0045P001C01CS-SA    I10 @S9S_MB_2U_LIB.S9S_MB_2U(SCH_1):PAGE40
    U2 DE45 VSS988 SOCKET4677_AZIF0045P001C01CS-SA    I10 @S9S_MB_2U_LIB.S9S_MB_2U(SCH_1):PAGE40
    U2 DE48 VSS989 SOCKET4677_AZIF0045P001C01CS-SA    I10 @S9S_MB_2U_LIB.S9S_MB_2U(SCH_1):PAGE40
    U2 DE50 VSS991 SOCKET4677_AZIF0045P001C01CS-SA    I10 @S9S_MB_2U_LIB.S9S_MB_2U(SCH_1):PAGE40
    U2 DE52 VSS992 SOCKET4677_AZIF0045P001C01CS-SA    I10 @S9S_MB_2U_LIB.S9S_MB_2U(SCH_1):PAGE40
    U2 DE54 VSS994 SOCKET4677_AZIF0045P001C01CS-SA    I10 @S9S_MB_2U_LIB.S9S_MB_2U(SCH_1):PAGE40
    U2 DE56 VSS995 SOCKET4677_AZIF0045P001C01CS-SA    I10 @S9S_MB_2U_LIB.S9S_MB_2U(SCH_1):PAGE40
    U2 DE58 VSS996 SOCKET4677_AZIF0045P001C01CS-SA    I10 @S9S_MB_2U_LIB.S9S_MB_2U(SCH_1):PAGE40
    U2 DE60 VSS997 SOCKET4677_AZIF0045P001C01CS-SA    I10 @S9S_MB_2U_LIB.S9S_MB_2U(SCH_1):PAGE40
    U2 DE62 VSS999 SOCKET4677_AZIF0045P001C01CS-SA    I10 @S9S_MB_2U_LIB.S9S_MB_2U(SCH_1):PAGE40
    U2 DE64 VSS1001 SOCKET4677_AZIF0045P001C01CS-SA    I10 @S9S_MB_2U_LIB.S9S_MB_2U(SCH_1):PAGE40
    U2 DE66 VSS1004 SOCKET4677_AZIF0045P001C01CS-SA    I10 @S9S_MB_2U_LIB.S9S_MB_2U(SCH_1):PAGE40
    U2 DE68 VSS1007 SOCKET4677_AZIF0045P001C01CS-SA    I10 @S9S_MB_2U_LIB.S9S_MB_2U(SCH_1):PAGE40
    U2 DE72 VSS1008 SOCKET4677_AZIF0045P001C01CS-SA    I10 @S9S_MB_2U_LIB.S9S_MB_2U(SCH_1):PAGE40
    U2 DE74 VSS1009 SOCKET4677_AZIF0045P001C01CS-SA    I10 @S9S_MB_2U_LIB.S9S_MB_2U(SCH_1):PAGE40
    U2 DE76 VSS1010 SOCKET4677_AZIF0045P001C01CS-SA    I10 @S9S_MB_2U_LIB.S9S_MB_2U(SCH_1):PAGE40
    U2 DE82 VSS1011 SOCKET4677_AZIF0045P001C01CS-SA    I10 @S9S_MB_2U_LIB.S9S_MB_2U(SCH_1):PAGE40
    U2 DE84 VSS1012 SOCKET4677_AZIF0045P001C01CS-SA    I10 @S9S_MB_2U_LIB.S9S_MB_2U(SCH_1):PAGE40
    U2 DE88 VSS1015 SOCKET4677_AZIF0045P001C01CS-SA    I10 @S9S_MB_2U_LIB.S9S_MB_2U(SCH_1):PAGE40
    U2  DF4 VSS1017 SOCKET4677_AZIF0045P001C01CS-SA    I10 @S9S_MB_2U_LIB.S9S_MB_2U(SCH_1):PAGE40
    U2 DF79 VSS1018 SOCKET4677_AZIF0045P001C01CS-SA    I10 @S9S_MB_2U_LIB.S9S_MB_2U(SCH_1):PAGE40
    U2  DF8 VSS1019 SOCKET4677_AZIF0045P001C01CS-SA    I10 @S9S_MB_2U_LIB.S9S_MB_2U(SCH_1):PAGE40
    U2 DF87 VSS1020 SOCKET4677_AZIF0045P001C01CS-SA    I10 @S9S_MB_2U_LIB.S9S_MB_2U(SCH_1):PAGE40
    U2 DG27 VSS1022 SOCKET4677_AZIF0045P001C01CS-SA    I10 @S9S_MB_2U_LIB.S9S_MB_2U(SCH_1):PAGE40
    U2 DG33 VSS1024 SOCKET4677_AZIF0045P001C01CS-SA    I10 @S9S_MB_2U_LIB.S9S_MB_2U(SCH_1):PAGE40
    U2 DG39 VSS1027 SOCKET4677_AZIF0045P001C01CS-SA    I10 @S9S_MB_2U_LIB.S9S_MB_2U(SCH_1):PAGE40
    U2 DG45 VSS1030 SOCKET4677_AZIF0045P001C01CS-SA    I10 @S9S_MB_2U_LIB.S9S_MB_2U(SCH_1):PAGE40
    U2  DG5 VSS1031 SOCKET4677_AZIF0045P001C01CS-SA    I10 @S9S_MB_2U_LIB.S9S_MB_2U(SCH_1):PAGE40
    U2 DG70 VSS1032 SOCKET4677_AZIF0045P001C01CS-SA    I10 @S9S_MB_2U_LIB.S9S_MB_2U(SCH_1):PAGE40
    U2 DG76 VSS1033 SOCKET4677_AZIF0045P001C01CS-SA    I10 @S9S_MB_2U_LIB.S9S_MB_2U(SCH_1):PAGE40
    U2 DG80 VSS1034 SOCKET4677_AZIF0045P001C01CS-SA    I10 @S9S_MB_2U_LIB.S9S_MB_2U(SCH_1):PAGE40
    U2 DG84 VSS1035 SOCKET4677_AZIF0045P001C01CS-SA    I10 @S9S_MB_2U_LIB.S9S_MB_2U(SCH_1):PAGE40
    U2 DG88 VSS1037 SOCKET4677_AZIF0045P001C01CS-SA    I10 @S9S_MB_2U_LIB.S9S_MB_2U(SCH_1):PAGE40
    U2  DG9 VSS1038 SOCKET4677_AZIF0045P001C01CS-SA    I10 @S9S_MB_2U_LIB.S9S_MB_2U(SCH_1):PAGE40
    U2 DH12 VSS1039 SOCKET4677_AZIF0045P001C01CS-SA    I10 @S9S_MB_2U_LIB.S9S_MB_2U(SCH_1):PAGE40
    U2 DH22 VSS1040 SOCKET4677_AZIF0045P001C01CS-SA    I10 @S9S_MB_2U_LIB.S9S_MB_2U(SCH_1):PAGE40
    U2 DH28 VSS1041 SOCKET4677_AZIF0045P001C01CS-SA    I10 @S9S_MB_2U_LIB.S9S_MB_2U(SCH_1):PAGE40
    U2 DH32 VSS1042 SOCKET4677_AZIF0045P001C01CS-SA    I10 @S9S_MB_2U_LIB.S9S_MB_2U(SCH_1):PAGE40
    U2 DH38 VSS1043 SOCKET4677_AZIF0045P001C01CS-SA    I10 @S9S_MB_2U_LIB.S9S_MB_2U(SCH_1):PAGE40
    U2  DH4 VSS1044 SOCKET4677_AZIF0045P001C01CS-SA    I10 @S9S_MB_2U_LIB.S9S_MB_2U(SCH_1):PAGE40
    U2 DH40 VSS1045 SOCKET4677_AZIF0045P001C01CS-SA    I10 @S9S_MB_2U_LIB.S9S_MB_2U(SCH_1):PAGE40
    U2 DH47 VSS1046 SOCKET4677_AZIF0045P001C01CS-SA    I10 @S9S_MB_2U_LIB.S9S_MB_2U(SCH_1):PAGE40
    U2 DH57 VSS1049 SOCKET4677_AZIF0045P001C01CS-SA    I10 @S9S_MB_2U_LIB.S9S_MB_2U(SCH_1):PAGE40
    U2 DH65 VSS1053 SOCKET4677_AZIF0045P001C01CS-SA    I10 @S9S_MB_2U_LIB.S9S_MB_2U(SCH_1):PAGE40
    U2 DH71 VSS1055 SOCKET4677_AZIF0045P001C01CS-SA    I10 @S9S_MB_2U_LIB.S9S_MB_2U(SCH_1):PAGE40
    U2 DH77 VSS1056 SOCKET4677_AZIF0045P001C01CS-SA    I10 @S9S_MB_2U_LIB.S9S_MB_2U(SCH_1):PAGE40
    U2  DH8 VSS1057 SOCKET4677_AZIF0045P001C01CS-SA    I10 @S9S_MB_2U_LIB.S9S_MB_2U(SCH_1):PAGE40
    U2 DH85 VSS1058 SOCKET4677_AZIF0045P001C01CS-SA    I10 @S9S_MB_2U_LIB.S9S_MB_2U(SCH_1):PAGE40
    U2 DJ19 VSS1061 SOCKET4677_AZIF0045P001C01CS-SA    I10 @S9S_MB_2U_LIB.S9S_MB_2U(SCH_1):PAGE40
    U2 DJ23 VSS1062 SOCKET4677_AZIF0045P001C01CS-SA    I10 @S9S_MB_2U_LIB.S9S_MB_2U(SCH_1):PAGE40
    U2 DJ29 VSS1065 SOCKET4677_AZIF0045P001C01CS-SA    I10 @S9S_MB_2U_LIB.S9S_MB_2U(SCH_1):PAGE40
    U2 DJ31 VSS1066 SOCKET4677_AZIF0045P001C01CS-SA    I10 @S9S_MB_2U_LIB.S9S_MB_2U(SCH_1):PAGE40
    U2 DJ37 VSS1067 SOCKET4677_AZIF0045P001C01CS-SA    I10 @S9S_MB_2U_LIB.S9S_MB_2U(SCH_1):PAGE40
    U2 DJ41 VSS1068 SOCKET4677_AZIF0045P001C01CS-SA    I10 @S9S_MB_2U_LIB.S9S_MB_2U(SCH_1):PAGE40
    U2 DJ43 VSS1069 SOCKET4677_AZIF0045P001C01CS-SA    I10 @S9S_MB_2U_LIB.S9S_MB_2U(SCH_1):PAGE40
    U2 DJ48 VSS1070 SOCKET4677_AZIF0045P001C01CS-SA    I10 @S9S_MB_2U_LIB.S9S_MB_2U(SCH_1):PAGE40
    U2 DJ50 VSS1071 SOCKET4677_AZIF0045P001C01CS-SA    I10 @S9S_MB_2U_LIB.S9S_MB_2U(SCH_1):PAGE40
    U2 DJ56 VSS1072 SOCKET4677_AZIF0045P001C01CS-SA    I10 @S9S_MB_2U_LIB.S9S_MB_2U(SCH_1):PAGE40
    U2 DJ60 VSS1073 SOCKET4677_AZIF0045P001C01CS-SA    I10 @S9S_MB_2U_LIB.S9S_MB_2U(SCH_1):PAGE40
    U2 DJ66 VSS1074 SOCKET4677_AZIF0045P001C01CS-SA    I10 @S9S_MB_2U_LIB.S9S_MB_2U(SCH_1):PAGE40
    U2 DJ72 VSS1075 SOCKET4677_AZIF0045P001C01CS-SA    I10 @S9S_MB_2U_LIB.S9S_MB_2U(SCH_1):PAGE40
    U2 DJ74 VSS1076 SOCKET4677_AZIF0045P001C01CS-SA    I10 @S9S_MB_2U_LIB.S9S_MB_2U(SCH_1):PAGE40
    U2 DJ80 VSS1078 SOCKET4677_AZIF0045P001C01CS-SA    I10 @S9S_MB_2U_LIB.S9S_MB_2U(SCH_1):PAGE40
    U2 DJ82 VSS1079 SOCKET4677_AZIF0045P001C01CS-SA    I10 @S9S_MB_2U_LIB.S9S_MB_2U(SCH_1):PAGE40
    U2 DJ84 VSS1080 SOCKET4677_AZIF0045P001C01CS-SA    I10 @S9S_MB_2U_LIB.S9S_MB_2U(SCH_1):PAGE40
    U2 DJ88 VSS1081 SOCKET4677_AZIF0045P001C01CS-SA    I10 @S9S_MB_2U_LIB.S9S_MB_2U(SCH_1):PAGE40
    U2 DK16 VSS1082 SOCKET4677_AZIF0045P001C01CS-SA    I10 @S9S_MB_2U_LIB.S9S_MB_2U(SCH_1):PAGE40
    U2 DK30 VSS1083 SOCKET4677_AZIF0045P001C01CS-SA    I10 @S9S_MB_2U_LIB.S9S_MB_2U(SCH_1):PAGE40
    U2 DK36 VSS1084 SOCKET4677_AZIF0045P001C01CS-SA    I10 @S9S_MB_2U_LIB.S9S_MB_2U(SCH_1):PAGE40
    U2  DK4 VSS1085 SOCKET4677_AZIF0045P001C01CS-SA    I10 @S9S_MB_2U_LIB.S9S_MB_2U(SCH_1):PAGE40
    U2 DK49 VSS1086 SOCKET4677_AZIF0045P001C01CS-SA    I10 @S9S_MB_2U_LIB.S9S_MB_2U(SCH_1):PAGE40
    U2 DK73 VSS1087 SOCKET4677_AZIF0045P001C01CS-SA    I10 @S9S_MB_2U_LIB.S9S_MB_2U(SCH_1):PAGE40
    U2 DK77 VSS1088 SOCKET4677_AZIF0045P001C01CS-SA    I10 @S9S_MB_2U_LIB.S9S_MB_2U(SCH_1):PAGE40
    U2 DK79 VSS1089 SOCKET4677_AZIF0045P001C01CS-SA    I10 @S9S_MB_2U_LIB.S9S_MB_2U(SCH_1):PAGE40
    U2  DK8 VSS1090 SOCKET4677_AZIF0045P001C01CS-SA    I10 @S9S_MB_2U_LIB.S9S_MB_2U(SCH_1):PAGE40
    U2 DK81 VSS1091 SOCKET4677_AZIF0045P001C01CS-SA    I10 @S9S_MB_2U_LIB.S9S_MB_2U(SCH_1):PAGE40
    U2 DK83 VSS1092 SOCKET4677_AZIF0045P001C01CS-SA    I10 @S9S_MB_2U_LIB.S9S_MB_2U(SCH_1):PAGE40
    U2 DK87 VSS1093 SOCKET4677_AZIF0045P001C01CS-SA    I10 @S9S_MB_2U_LIB.S9S_MB_2U(SCH_1):PAGE40
    U2 DK91 VSS1094 SOCKET4677_AZIF0045P001C01CS-SA    I10 @S9S_MB_2U_LIB.S9S_MB_2U(SCH_1):PAGE40
    U2 DL39 VSS1095 SOCKET4677_AZIF0045P001C01CS-SA    I10 @S9S_MB_2U_LIB.S9S_MB_2U(SCH_1):PAGE40
    U2 DL84 VSS1096 SOCKET4677_AZIF0045P001C01CS-SA    I10 @S9S_MB_2U_LIB.S9S_MB_2U(SCH_1):PAGE40
    U2 DL88 VSS1098 SOCKET4677_AZIF0045P001C01CS-SA    I10 @S9S_MB_2U_LIB.S9S_MB_2U(SCH_1):PAGE40
    U2  DL9 VSS1099 SOCKET4677_AZIF0045P001C01CS-SA    I10 @S9S_MB_2U_LIB.S9S_MB_2U(SCH_1):PAGE40
    U2 CM16 VSS436 SOCKET4677_AZIF0045P001C01CS-SA    I11 @S9S_MB_2U_LIB.S9S_MB_2U(SCH_1):PAGE40
    U2 CM22 VSS438 SOCKET4677_AZIF0045P001C01CS-SA    I11 @S9S_MB_2U_LIB.S9S_MB_2U(SCH_1):PAGE40
    U2 CN76 VSS471 SOCKET4677_AZIF0045P001C01CS-SA    I11 @S9S_MB_2U_LIB.S9S_MB_2U(SCH_1):PAGE40
    U2 CP16 VSS478 SOCKET4677_AZIF0045P001C01CS-SA    I11 @S9S_MB_2U_LIB.S9S_MB_2U(SCH_1):PAGE40
    U2 CP79 VSS493 SOCKET4677_AZIF0045P001C01CS-SA    I11 @S9S_MB_2U_LIB.S9S_MB_2U(SCH_1):PAGE40
    U2 CR78 VSS514 SOCKET4677_AZIF0045P001C01CS-SA    I11 @S9S_MB_2U_LIB.S9S_MB_2U(SCH_1):PAGE40
    U2 CT16 VSS521 SOCKET4677_AZIF0045P001C01CS-SA    I11 @S9S_MB_2U_LIB.S9S_MB_2U(SCH_1):PAGE40
    U2  CT4 VSS526 SOCKET4677_AZIF0045P001C01CS-SA    I11 @S9S_MB_2U_LIB.S9S_MB_2U(SCH_1):PAGE40
    U2  CT8 VSS534 SOCKET4677_AZIF0045P001C01CS-SA    I11 @S9S_MB_2U_LIB.S9S_MB_2U(SCH_1):PAGE40
    U2 CT89 VSS537 SOCKET4677_AZIF0045P001C01CS-SA    I11 @S9S_MB_2U_LIB.S9S_MB_2U(SCH_1):PAGE40
    U2 CU25 VSS544 SOCKET4677_AZIF0045P001C01CS-SA    I11 @S9S_MB_2U_LIB.S9S_MB_2U(SCH_1):PAGE40
    U2 CU72 VSS553 SOCKET4677_AZIF0045P001C01CS-SA    I11 @S9S_MB_2U_LIB.S9S_MB_2U(SCH_1):PAGE40
    U2 CU78 VSS554 SOCKET4677_AZIF0045P001C01CS-SA    I11 @S9S_MB_2U_LIB.S9S_MB_2U(SCH_1):PAGE40
    U2 CV16 VSS558 SOCKET4677_AZIF0045P001C01CS-SA    I11 @S9S_MB_2U_LIB.S9S_MB_2U(SCH_1):PAGE40
    U2 CV26 VSS562 SOCKET4677_AZIF0045P001C01CS-SA    I11 @S9S_MB_2U_LIB.S9S_MB_2U(SCH_1):PAGE40
    U2 CV79 VSS571 SOCKET4677_AZIF0045P001C01CS-SA    I11 @S9S_MB_2U_LIB.S9S_MB_2U(SCH_1):PAGE40
    U2 CW33 VSS583 SOCKET4677_AZIF0045P001C01CS-SA    I11 @S9S_MB_2U_LIB.S9S_MB_2U(SCH_1):PAGE40
    U2 CW70 VSS595 SOCKET4677_AZIF0045P001C01CS-SA    I11 @S9S_MB_2U_LIB.S9S_MB_2U(SCH_1):PAGE40
    U2  CY4 VSS611 SOCKET4677_AZIF0045P001C01CS-SA    I11 @S9S_MB_2U_LIB.S9S_MB_2U(SCH_1):PAGE40
    U2 DA43 VSS679 SOCKET4677_AZIF0045P001C01CS-SA    I11 @S9S_MB_2U_LIB.S9S_MB_2U(SCH_1):PAGE40
    U2 DA68 VSS690 SOCKET4677_AZIF0045P001C01CS-SA    I11 @S9S_MB_2U_LIB.S9S_MB_2U(SCH_1):PAGE40
    U2 DB16 VSS699 SOCKET4677_AZIF0045P001C01CS-SA    I11 @S9S_MB_2U_LIB.S9S_MB_2U(SCH_1):PAGE40
    U2 DB20 VSS700 SOCKET4677_AZIF0045P001C01CS-SA    I11 @S9S_MB_2U_LIB.S9S_MB_2U(SCH_1):PAGE40
    U2 DB26 VSS702 SOCKET4677_AZIF0045P001C01CS-SA    I11 @S9S_MB_2U_LIB.S9S_MB_2U(SCH_1):PAGE40
    U2 DB34 VSS705 SOCKET4677_AZIF0045P001C01CS-SA    I11 @S9S_MB_2U_LIB.S9S_MB_2U(SCH_1):PAGE40
    U2 DB44 VSS709 SOCKET4677_AZIF0045P001C01CS-SA    I11 @S9S_MB_2U_LIB.S9S_MB_2U(SCH_1):PAGE40
    U2 DB51 VSS711 SOCKET4677_AZIF0045P001C01CS-SA    I11 @S9S_MB_2U_LIB.S9S_MB_2U(SCH_1):PAGE40
    U2 DB53 VSS712 SOCKET4677_AZIF0045P001C01CS-SA    I11 @S9S_MB_2U_LIB.S9S_MB_2U(SCH_1):PAGE40
    U2 DB59 VSS714 SOCKET4677_AZIF0045P001C01CS-SA    I11 @S9S_MB_2U_LIB.S9S_MB_2U(SCH_1):PAGE40
    U2 DB63 VSS715 SOCKET4677_AZIF0045P001C01CS-SA    I11 @S9S_MB_2U_LIB.S9S_MB_2U(SCH_1):PAGE40
    U2 DB69 VSS717 SOCKET4677_AZIF0045P001C01CS-SA    I11 @S9S_MB_2U_LIB.S9S_MB_2U(SCH_1):PAGE40
    U2 DB75 VSS719 SOCKET4677_AZIF0045P001C01CS-SA    I11 @S9S_MB_2U_LIB.S9S_MB_2U(SCH_1):PAGE40
    U2 CK63 VSS744 SOCKET4677_AZIF0045P001C01CS-SA    I11 @S9S_MB_2U_LIB.S9S_MB_2U(SCH_1):PAGE40
    U2 CK69 VSS745 SOCKET4677_AZIF0045P001C01CS-SA    I11 @S9S_MB_2U_LIB.S9S_MB_2U(SCH_1):PAGE40
    U2 CK81 VSS749 SOCKET4677_AZIF0045P001C01CS-SA    I11 @S9S_MB_2U_LIB.S9S_MB_2U(SCH_1):PAGE40
    U2  CL1 VSS750 SOCKET4677_AZIF0045P001C01CS-SA    I11 @S9S_MB_2U_LIB.S9S_MB_2U(SCH_1):PAGE40
    U2 CL13 VSS751 SOCKET4677_AZIF0045P001C01CS-SA    I11 @S9S_MB_2U_LIB.S9S_MB_2U(SCH_1):PAGE40
    U2 CL17 VSS752 SOCKET4677_AZIF0045P001C01CS-SA    I11 @S9S_MB_2U_LIB.S9S_MB_2U(SCH_1):PAGE40
    U2  CL5 VSS754 SOCKET4677_AZIF0045P001C01CS-SA    I11 @S9S_MB_2U_LIB.S9S_MB_2U(SCH_1):PAGE40
    U2 CL62 VSS755 SOCKET4677_AZIF0045P001C01CS-SA    I11 @S9S_MB_2U_LIB.S9S_MB_2U(SCH_1):PAGE40
    U2 CL74 VSS756 SOCKET4677_AZIF0045P001C01CS-SA    I11 @S9S_MB_2U_LIB.S9S_MB_2U(SCH_1):PAGE40
    U2 CL78 VSS757 SOCKET4677_AZIF0045P001C01CS-SA    I11 @S9S_MB_2U_LIB.S9S_MB_2U(SCH_1):PAGE40
    U2 CL80 VSS758 SOCKET4677_AZIF0045P001C01CS-SA    I11 @S9S_MB_2U_LIB.S9S_MB_2U(SCH_1):PAGE40
    U2 CL82 VSS759 SOCKET4677_AZIF0045P001C01CS-SA    I11 @S9S_MB_2U_LIB.S9S_MB_2U(SCH_1):PAGE40
    U2  CL9 VSS760 SOCKET4677_AZIF0045P001C01CS-SA    I11 @S9S_MB_2U_LIB.S9S_MB_2U(SCH_1):PAGE40
    U2 CM12 VSS761 SOCKET4677_AZIF0045P001C01CS-SA    I11 @S9S_MB_2U_LIB.S9S_MB_2U(SCH_1):PAGE40
    U2 CM20 VSS762 SOCKET4677_AZIF0045P001C01CS-SA    I11 @S9S_MB_2U_LIB.S9S_MB_2U(SCH_1):PAGE40
    U2 CM24 VSS763 SOCKET4677_AZIF0045P001C01CS-SA    I11 @S9S_MB_2U_LIB.S9S_MB_2U(SCH_1):PAGE40
    U2  CM4 VSS764 SOCKET4677_AZIF0045P001C01CS-SA    I11 @S9S_MB_2U_LIB.S9S_MB_2U(SCH_1):PAGE40
    U2 CM61 VSS765 SOCKET4677_AZIF0045P001C01CS-SA    I11 @S9S_MB_2U_LIB.S9S_MB_2U(SCH_1):PAGE40
    U2 CM65 VSS766 SOCKET4677_AZIF0045P001C01CS-SA    I11 @S9S_MB_2U_LIB.S9S_MB_2U(SCH_1):PAGE40
    U2 CM67 VSS767 SOCKET4677_AZIF0045P001C01CS-SA    I11 @S9S_MB_2U_LIB.S9S_MB_2U(SCH_1):PAGE40
    U2 CM79 VSS768 SOCKET4677_AZIF0045P001C01CS-SA    I11 @S9S_MB_2U_LIB.S9S_MB_2U(SCH_1):PAGE40
    U2  CM8 VSS769 SOCKET4677_AZIF0045P001C01CS-SA    I11 @S9S_MB_2U_LIB.S9S_MB_2U(SCH_1):PAGE40
    U2 CM81 VSS770 SOCKET4677_AZIF0045P001C01CS-SA    I11 @S9S_MB_2U_LIB.S9S_MB_2U(SCH_1):PAGE40
    U2 CM83 VSS771 SOCKET4677_AZIF0045P001C01CS-SA    I11 @S9S_MB_2U_LIB.S9S_MB_2U(SCH_1):PAGE40
    U2 CM85 VSS772 SOCKET4677_AZIF0045P001C01CS-SA    I11 @S9S_MB_2U_LIB.S9S_MB_2U(SCH_1):PAGE40
    U2 CN68 VSS773 SOCKET4677_AZIF0045P001C01CS-SA    I11 @S9S_MB_2U_LIB.S9S_MB_2U(SCH_1):PAGE40
    U2 CN70 VSS774 SOCKET4677_AZIF0045P001C01CS-SA    I11 @S9S_MB_2U_LIB.S9S_MB_2U(SCH_1):PAGE40
    U2 CN72 VSS775 SOCKET4677_AZIF0045P001C01CS-SA    I11 @S9S_MB_2U_LIB.S9S_MB_2U(SCH_1):PAGE40
    U2 CN74 VSS777 SOCKET4677_AZIF0045P001C01CS-SA    I11 @S9S_MB_2U_LIB.S9S_MB_2U(SCH_1):PAGE40
    U2 CN84 VSS778 SOCKET4677_AZIF0045P001C01CS-SA    I11 @S9S_MB_2U_LIB.S9S_MB_2U(SCH_1):PAGE40
    U2 CN86 VSS779 SOCKET4677_AZIF0045P001C01CS-SA    I11 @S9S_MB_2U_LIB.S9S_MB_2U(SCH_1):PAGE40
    U2 CP12 VSS780 SOCKET4677_AZIF0045P001C01CS-SA    I11 @S9S_MB_2U_LIB.S9S_MB_2U(SCH_1):PAGE40
    U2 CP18 VSS781 SOCKET4677_AZIF0045P001C01CS-SA    I11 @S9S_MB_2U_LIB.S9S_MB_2U(SCH_1):PAGE40
    U2  CP4 VSS782 SOCKET4677_AZIF0045P001C01CS-SA    I11 @S9S_MB_2U_LIB.S9S_MB_2U(SCH_1):PAGE40
    U2 CP75 VSS783 SOCKET4677_AZIF0045P001C01CS-SA    I11 @S9S_MB_2U_LIB.S9S_MB_2U(SCH_1):PAGE40
    U2 CP77 VSS784 SOCKET4677_AZIF0045P001C01CS-SA    I11 @S9S_MB_2U_LIB.S9S_MB_2U(SCH_1):PAGE40
    U2  CP8 VSS785 SOCKET4677_AZIF0045P001C01CS-SA    I11 @S9S_MB_2U_LIB.S9S_MB_2U(SCH_1):PAGE40
    U2 CP83 VSS786 SOCKET4677_AZIF0045P001C01CS-SA    I11 @S9S_MB_2U_LIB.S9S_MB_2U(SCH_1):PAGE40
    U2 CP87 VSS787 SOCKET4677_AZIF0045P001C01CS-SA    I11 @S9S_MB_2U_LIB.S9S_MB_2U(SCH_1):PAGE40
    U2 CP91 VSS788 SOCKET4677_AZIF0045P001C01CS-SA    I11 @S9S_MB_2U_LIB.S9S_MB_2U(SCH_1):PAGE40
    U2  CR1 VSS789 SOCKET4677_AZIF0045P001C01CS-SA    I11 @S9S_MB_2U_LIB.S9S_MB_2U(SCH_1):PAGE40
    U2 CR11 VSS790 SOCKET4677_AZIF0045P001C01CS-SA    I11 @S9S_MB_2U_LIB.S9S_MB_2U(SCH_1):PAGE40
    U2 CR13 VSS792 SOCKET4677_AZIF0045P001C01CS-SA    I11 @S9S_MB_2U_LIB.S9S_MB_2U(SCH_1):PAGE40
    U2 CR17 VSS793 SOCKET4677_AZIF0045P001C01CS-SA    I11 @S9S_MB_2U_LIB.S9S_MB_2U(SCH_1):PAGE40
    U2  CR5 VSS794 SOCKET4677_AZIF0045P001C01CS-SA    I11 @S9S_MB_2U_LIB.S9S_MB_2U(SCH_1):PAGE40
    U2 CR62 VSS795 SOCKET4677_AZIF0045P001C01CS-SA    I11 @S9S_MB_2U_LIB.S9S_MB_2U(SCH_1):PAGE40
    U2 CR64 VSS796 SOCKET4677_AZIF0045P001C01CS-SA    I11 @S9S_MB_2U_LIB.S9S_MB_2U(SCH_1):PAGE40
    U2 CR84 VSS797 SOCKET4677_AZIF0045P001C01CS-SA    I11 @S9S_MB_2U_LIB.S9S_MB_2U(SCH_1):PAGE40
    U2 CR88 VSS800 SOCKET4677_AZIF0045P001C01CS-SA    I11 @S9S_MB_2U_LIB.S9S_MB_2U(SCH_1):PAGE40
    U2  CR9 VSS801 SOCKET4677_AZIF0045P001C01CS-SA    I11 @S9S_MB_2U_LIB.S9S_MB_2U(SCH_1):PAGE40
    U2 CR90 VSS803 SOCKET4677_AZIF0045P001C01CS-SA    I11 @S9S_MB_2U_LIB.S9S_MB_2U(SCH_1):PAGE40
    U2 CT10 VSS804 SOCKET4677_AZIF0045P001C01CS-SA    I11 @S9S_MB_2U_LIB.S9S_MB_2U(SCH_1):PAGE40
    U2 CT12 VSS805 SOCKET4677_AZIF0045P001C01CS-SA    I11 @S9S_MB_2U_LIB.S9S_MB_2U(SCH_1):PAGE40
    U2 CT69 VSS810 SOCKET4677_AZIF0045P001C01CS-SA    I11 @S9S_MB_2U_LIB.S9S_MB_2U(SCH_1):PAGE40
    U2 CT73 VSS811 SOCKET4677_AZIF0045P001C01CS-SA    I11 @S9S_MB_2U_LIB.S9S_MB_2U(SCH_1):PAGE40
    U2 CT81 VSS812 SOCKET4677_AZIF0045P001C01CS-SA    I11 @S9S_MB_2U_LIB.S9S_MB_2U(SCH_1):PAGE40
    U2 CU19 VSS813 SOCKET4677_AZIF0045P001C01CS-SA    I11 @S9S_MB_2U_LIB.S9S_MB_2U(SCH_1):PAGE40
    U2 CU21 VSS814 SOCKET4677_AZIF0045P001C01CS-SA    I11 @S9S_MB_2U_LIB.S9S_MB_2U(SCH_1):PAGE40
    U2 CU23 VSS815 SOCKET4677_AZIF0045P001C01CS-SA    I11 @S9S_MB_2U_LIB.S9S_MB_2U(SCH_1):PAGE40
    U2 CU60 VSS816 SOCKET4677_AZIF0045P001C01CS-SA    I11 @S9S_MB_2U_LIB.S9S_MB_2U(SCH_1):PAGE40
    U2 CU66 VSS818 SOCKET4677_AZIF0045P001C01CS-SA    I11 @S9S_MB_2U_LIB.S9S_MB_2U(SCH_1):PAGE40
    U2 CU68 VSS819 SOCKET4677_AZIF0045P001C01CS-SA    I11 @S9S_MB_2U_LIB.S9S_MB_2U(SCH_1):PAGE40
    U2 CU84 VSS822 SOCKET4677_AZIF0045P001C01CS-SA    I11 @S9S_MB_2U_LIB.S9S_MB_2U(SCH_1):PAGE40
    U2 CU88 VSS823 SOCKET4677_AZIF0045P001C01CS-SA    I11 @S9S_MB_2U_LIB.S9S_MB_2U(SCH_1):PAGE40
    U2 CV12 VSS824 SOCKET4677_AZIF0045P001C01CS-SA    I11 @S9S_MB_2U_LIB.S9S_MB_2U(SCH_1):PAGE40
    U2  CV4 VSS825 SOCKET4677_AZIF0045P001C01CS-SA    I11 @S9S_MB_2U_LIB.S9S_MB_2U(SCH_1):PAGE40
    U2 CV75 VSS826 SOCKET4677_AZIF0045P001C01CS-SA    I11 @S9S_MB_2U_LIB.S9S_MB_2U(SCH_1):PAGE40
    U2  CV8 VSS827 SOCKET4677_AZIF0045P001C01CS-SA    I11 @S9S_MB_2U_LIB.S9S_MB_2U(SCH_1):PAGE40
    U2 CV83 VSS828 SOCKET4677_AZIF0045P001C01CS-SA    I11 @S9S_MB_2U_LIB.S9S_MB_2U(SCH_1):PAGE40
    U2 CV87 VSS831 SOCKET4677_AZIF0045P001C01CS-SA    I11 @S9S_MB_2U_LIB.S9S_MB_2U(SCH_1):PAGE40
    U2 CV91 VSS833 SOCKET4677_AZIF0045P001C01CS-SA    I11 @S9S_MB_2U_LIB.S9S_MB_2U(SCH_1):PAGE40
    U2  CW1 VSS834 SOCKET4677_AZIF0045P001C01CS-SA    I11 @S9S_MB_2U_LIB.S9S_MB_2U(SCH_1):PAGE40
    U2 CW13 VSS836 SOCKET4677_AZIF0045P001C01CS-SA    I11 @S9S_MB_2U_LIB.S9S_MB_2U(SCH_1):PAGE40
    U2 CW17 VSS837 SOCKET4677_AZIF0045P001C01CS-SA    I11 @S9S_MB_2U_LIB.S9S_MB_2U(SCH_1):PAGE40
    U2  CW5 VSS838 SOCKET4677_AZIF0045P001C01CS-SA    I11 @S9S_MB_2U_LIB.S9S_MB_2U(SCH_1):PAGE40
    U2 CW72 VSS840 SOCKET4677_AZIF0045P001C01CS-SA    I11 @S9S_MB_2U_LIB.S9S_MB_2U(SCH_1):PAGE40
    U2 CW78 VSS843 SOCKET4677_AZIF0045P001C01CS-SA    I11 @S9S_MB_2U_LIB.S9S_MB_2U(SCH_1):PAGE40
    U2 CW84 VSS846 SOCKET4677_AZIF0045P001C01CS-SA    I11 @S9S_MB_2U_LIB.S9S_MB_2U(SCH_1):PAGE40
    U2 CW88 VSS848 SOCKET4677_AZIF0045P001C01CS-SA    I11 @S9S_MB_2U_LIB.S9S_MB_2U(SCH_1):PAGE40
    U2  CW9 VSS850 SOCKET4677_AZIF0045P001C01CS-SA    I11 @S9S_MB_2U_LIB.S9S_MB_2U(SCH_1):PAGE40
    U2 CY12 VSS851 SOCKET4677_AZIF0045P001C01CS-SA    I11 @S9S_MB_2U_LIB.S9S_MB_2U(SCH_1):PAGE40
    U2 CY16 VSS852 SOCKET4677_AZIF0045P001C01CS-SA    I11 @S9S_MB_2U_LIB.S9S_MB_2U(SCH_1):PAGE40
    U2 CY18 VSS853 SOCKET4677_AZIF0045P001C01CS-SA    I11 @S9S_MB_2U_LIB.S9S_MB_2U(SCH_1):PAGE40
    U2 CY26 VSS854 SOCKET4677_AZIF0045P001C01CS-SA    I11 @S9S_MB_2U_LIB.S9S_MB_2U(SCH_1):PAGE40
    U2 CY30 VSS855 SOCKET4677_AZIF0045P001C01CS-SA    I11 @S9S_MB_2U_LIB.S9S_MB_2U(SCH_1):PAGE40
    U2 CY63 VSS856 SOCKET4677_AZIF0045P001C01CS-SA    I11 @S9S_MB_2U_LIB.S9S_MB_2U(SCH_1):PAGE40
    U2 CY73 VSS858 SOCKET4677_AZIF0045P001C01CS-SA    I11 @S9S_MB_2U_LIB.S9S_MB_2U(SCH_1):PAGE40
    U2 CY77 VSS859 SOCKET4677_AZIF0045P001C01CS-SA    I11 @S9S_MB_2U_LIB.S9S_MB_2U(SCH_1):PAGE40
    U2  CY8 VSS860 SOCKET4677_AZIF0045P001C01CS-SA    I11 @S9S_MB_2U_LIB.S9S_MB_2U(SCH_1):PAGE40
    U2 CY81 VSS862 SOCKET4677_AZIF0045P001C01CS-SA    I11 @S9S_MB_2U_LIB.S9S_MB_2U(SCH_1):PAGE40
    U2 CY83 VSS863 SOCKET4677_AZIF0045P001C01CS-SA    I11 @S9S_MB_2U_LIB.S9S_MB_2U(SCH_1):PAGE40
    U2 DA19 VSS910 SOCKET4677_AZIF0045P001C01CS-SA    I11 @S9S_MB_2U_LIB.S9S_MB_2U(SCH_1):PAGE40
    U2 DA23 VSS911 SOCKET4677_AZIF0045P001C01CS-SA    I11 @S9S_MB_2U_LIB.S9S_MB_2U(SCH_1):PAGE40
    U2 DA25 VSS912 SOCKET4677_AZIF0045P001C01CS-SA    I11 @S9S_MB_2U_LIB.S9S_MB_2U(SCH_1):PAGE40
    U2 DA29 VSS913 SOCKET4677_AZIF0045P001C01CS-SA    I11 @S9S_MB_2U_LIB.S9S_MB_2U(SCH_1):PAGE40
    U2 DA31 VSS914 SOCKET4677_AZIF0045P001C01CS-SA    I11 @S9S_MB_2U_LIB.S9S_MB_2U(SCH_1):PAGE40
    U2 DA33 VSS915 SOCKET4677_AZIF0045P001C01CS-SA    I11 @S9S_MB_2U_LIB.S9S_MB_2U(SCH_1):PAGE40
    U2 DA35 VSS916 SOCKET4677_AZIF0045P001C01CS-SA    I11 @S9S_MB_2U_LIB.S9S_MB_2U(SCH_1):PAGE40
    U2 DA37 VSS917 SOCKET4677_AZIF0045P001C01CS-SA    I11 @S9S_MB_2U_LIB.S9S_MB_2U(SCH_1):PAGE40
    U2 DA41 VSS918 SOCKET4677_AZIF0045P001C01CS-SA    I11 @S9S_MB_2U_LIB.S9S_MB_2U(SCH_1):PAGE40
    U2 DA48 VSS919 SOCKET4677_AZIF0045P001C01CS-SA    I11 @S9S_MB_2U_LIB.S9S_MB_2U(SCH_1):PAGE40
    U2 DA50 VSS920 SOCKET4677_AZIF0045P001C01CS-SA    I11 @S9S_MB_2U_LIB.S9S_MB_2U(SCH_1):PAGE40
    U2 DA54 VSS921 SOCKET4677_AZIF0045P001C01CS-SA    I11 @S9S_MB_2U_LIB.S9S_MB_2U(SCH_1):PAGE40
    U2 DA56 VSS922 SOCKET4677_AZIF0045P001C01CS-SA    I11 @S9S_MB_2U_LIB.S9S_MB_2U(SCH_1):PAGE40
    U2 DA58 VSS923 SOCKET4677_AZIF0045P001C01CS-SA    I11 @S9S_MB_2U_LIB.S9S_MB_2U(SCH_1):PAGE40
    U2 DA60 VSS924 SOCKET4677_AZIF0045P001C01CS-SA    I11 @S9S_MB_2U_LIB.S9S_MB_2U(SCH_1):PAGE40
    U2 DA62 VSS925 SOCKET4677_AZIF0045P001C01CS-SA    I11 @S9S_MB_2U_LIB.S9S_MB_2U(SCH_1):PAGE40
    U2 DA66 VSS926 SOCKET4677_AZIF0045P001C01CS-SA    I11 @S9S_MB_2U_LIB.S9S_MB_2U(SCH_1):PAGE40
    U2 DA72 VSS927 SOCKET4677_AZIF0045P001C01CS-SA    I11 @S9S_MB_2U_LIB.S9S_MB_2U(SCH_1):PAGE40
    U2 DA74 VSS928 SOCKET4677_AZIF0045P001C01CS-SA    I11 @S9S_MB_2U_LIB.S9S_MB_2U(SCH_1):PAGE40
    U2 DA80 VSS929 SOCKET4677_AZIF0045P001C01CS-SA    I11 @S9S_MB_2U_LIB.S9S_MB_2U(SCH_1):PAGE40
    U2 DA82 VSS930 SOCKET4677_AZIF0045P001C01CS-SA    I11 @S9S_MB_2U_LIB.S9S_MB_2U(SCH_1):PAGE40
    U2 DA84 VSS931 SOCKET4677_AZIF0045P001C01CS-SA    I11 @S9S_MB_2U_LIB.S9S_MB_2U(SCH_1):PAGE40
    U2 DA88 VSS932 SOCKET4677_AZIF0045P001C01CS-SA    I11 @S9S_MB_2U_LIB.S9S_MB_2U(SCH_1):PAGE40
    U2 DB12 VSS933 SOCKET4677_AZIF0045P001C01CS-SA    I11 @S9S_MB_2U_LIB.S9S_MB_2U(SCH_1):PAGE40
    U2 DB22 VSS935 SOCKET4677_AZIF0045P001C01CS-SA    I11 @S9S_MB_2U_LIB.S9S_MB_2U(SCH_1):PAGE40
    U2 DB28 VSS936 SOCKET4677_AZIF0045P001C01CS-SA    I11 @S9S_MB_2U_LIB.S9S_MB_2U(SCH_1):PAGE40
    U2 DB32 VSS937 SOCKET4677_AZIF0045P001C01CS-SA    I11 @S9S_MB_2U_LIB.S9S_MB_2U(SCH_1):PAGE40
    U2 DB38 VSS938 SOCKET4677_AZIF0045P001C01CS-SA    I11 @S9S_MB_2U_LIB.S9S_MB_2U(SCH_1):PAGE40
    U2  DB4 VSS939 SOCKET4677_AZIF0045P001C01CS-SA    I11 @S9S_MB_2U_LIB.S9S_MB_2U(SCH_1):PAGE40
    U2 DB40 VSS940 SOCKET4677_AZIF0045P001C01CS-SA    I11 @S9S_MB_2U_LIB.S9S_MB_2U(SCH_1):PAGE40
    U2 DB47 VSS941 SOCKET4677_AZIF0045P001C01CS-SA    I11 @S9S_MB_2U_LIB.S9S_MB_2U(SCH_1):PAGE40
    U2 DB57 VSS942 SOCKET4677_AZIF0045P001C01CS-SA    I11 @S9S_MB_2U_LIB.S9S_MB_2U(SCH_1):PAGE40
    U2 DB65 VSS943 SOCKET4677_AZIF0045P001C01CS-SA    I11 @S9S_MB_2U_LIB.S9S_MB_2U(SCH_1):PAGE40
    U2 DB71 VSS944 SOCKET4677_AZIF0045P001C01CS-SA    I11 @S9S_MB_2U_LIB.S9S_MB_2U(SCH_1):PAGE40
    U2 DB77 VSS946 SOCKET4677_AZIF0045P001C01CS-SA    I11 @S9S_MB_2U_LIB.S9S_MB_2U(SCH_1):PAGE40
    U2  DB8 VSS947 SOCKET4677_AZIF0045P001C01CS-SA    I11 @S9S_MB_2U_LIB.S9S_MB_2U(SCH_1):PAGE40
    U2 DB87 VSS948 SOCKET4677_AZIF0045P001C01CS-SA    I11 @S9S_MB_2U_LIB.S9S_MB_2U(SCH_1):PAGE40
    U2 CJ76 VSS383 SOCKET4677_AZIF0045P001C01CS-SA    I12 @S9S_MB_2U_LIB.S9S_MB_2U(SCH_1):PAGE40
    U2  CK4 VSS396 SOCKET4677_AZIF0045P001C01CS-SA    I12 @S9S_MB_2U_LIB.S9S_MB_2U(SCH_1):PAGE40
    U2 BR35 VSS542 SOCKET4677_AZIF0045P001C01CS-SA    I12 @S9S_MB_2U_LIB.S9S_MB_2U(SCH_1):PAGE40
    U2 BR37 VSS543 SOCKET4677_AZIF0045P001C01CS-SA    I12 @S9S_MB_2U_LIB.S9S_MB_2U(SCH_1):PAGE40
    U2 BR39 VSS545 SOCKET4677_AZIF0045P001C01CS-SA    I12 @S9S_MB_2U_LIB.S9S_MB_2U(SCH_1):PAGE40
    U2 BR41 VSS546 SOCKET4677_AZIF0045P001C01CS-SA    I12 @S9S_MB_2U_LIB.S9S_MB_2U(SCH_1):PAGE40
    U2 BR43 VSS547 SOCKET4677_AZIF0045P001C01CS-SA    I12 @S9S_MB_2U_LIB.S9S_MB_2U(SCH_1):PAGE40
    U2 BR45 VSS548 SOCKET4677_AZIF0045P001C01CS-SA    I12 @S9S_MB_2U_LIB.S9S_MB_2U(SCH_1):PAGE40
    U2 BR48 VSS549 SOCKET4677_AZIF0045P001C01CS-SA    I12 @S9S_MB_2U_LIB.S9S_MB_2U(SCH_1):PAGE40
    U2 BR50 VSS550 SOCKET4677_AZIF0045P001C01CS-SA    I12 @S9S_MB_2U_LIB.S9S_MB_2U(SCH_1):PAGE40
    U2 BR52 VSS551 SOCKET4677_AZIF0045P001C01CS-SA    I12 @S9S_MB_2U_LIB.S9S_MB_2U(SCH_1):PAGE40
    U2 BR54 VSS552 SOCKET4677_AZIF0045P001C01CS-SA    I12 @S9S_MB_2U_LIB.S9S_MB_2U(SCH_1):PAGE40
    U2 BR56 VSS555 SOCKET4677_AZIF0045P001C01CS-SA    I12 @S9S_MB_2U_LIB.S9S_MB_2U(SCH_1):PAGE40
    U2 BR58 VSS556 SOCKET4677_AZIF0045P001C01CS-SA    I12 @S9S_MB_2U_LIB.S9S_MB_2U(SCH_1):PAGE40
    U2 BR64 VSS557 SOCKET4677_AZIF0045P001C01CS-SA    I12 @S9S_MB_2U_LIB.S9S_MB_2U(SCH_1):PAGE40
    U2 BR66 VSS559 SOCKET4677_AZIF0045P001C01CS-SA    I12 @S9S_MB_2U_LIB.S9S_MB_2U(SCH_1):PAGE40
    U2 BR68 VSS560 SOCKET4677_AZIF0045P001C01CS-SA    I12 @S9S_MB_2U_LIB.S9S_MB_2U(SCH_1):PAGE40
    U2 BR70 VSS561 SOCKET4677_AZIF0045P001C01CS-SA    I12 @S9S_MB_2U_LIB.S9S_MB_2U(SCH_1):PAGE40
    U2 BR72 VSS563 SOCKET4677_AZIF0045P001C01CS-SA    I12 @S9S_MB_2U_LIB.S9S_MB_2U(SCH_1):PAGE40
    U2 BR74 VSS564 SOCKET4677_AZIF0045P001C01CS-SA    I12 @S9S_MB_2U_LIB.S9S_MB_2U(SCH_1):PAGE40
    U2 BR76 VSS565 SOCKET4677_AZIF0045P001C01CS-SA    I12 @S9S_MB_2U_LIB.S9S_MB_2U(SCH_1):PAGE40
    U2 BR80 VSS566 SOCKET4677_AZIF0045P001C01CS-SA    I12 @S9S_MB_2U_LIB.S9S_MB_2U(SCH_1):PAGE40
    U2 BR82 VSS567 SOCKET4677_AZIF0045P001C01CS-SA    I12 @S9S_MB_2U_LIB.S9S_MB_2U(SCH_1):PAGE40
    U2 BR84 VSS568 SOCKET4677_AZIF0045P001C01CS-SA    I12 @S9S_MB_2U_LIB.S9S_MB_2U(SCH_1):PAGE40
    U2 BR86 VSS569 SOCKET4677_AZIF0045P001C01CS-SA    I12 @S9S_MB_2U_LIB.S9S_MB_2U(SCH_1):PAGE40
    U2 BR88 VSS570 SOCKET4677_AZIF0045P001C01CS-SA    I12 @S9S_MB_2U_LIB.S9S_MB_2U(SCH_1):PAGE40
    U2 BR90 VSS573 SOCKET4677_AZIF0045P001C01CS-SA    I12 @S9S_MB_2U_LIB.S9S_MB_2U(SCH_1):PAGE40
    U2 BT12 VSS574 SOCKET4677_AZIF0045P001C01CS-SA    I12 @S9S_MB_2U_LIB.S9S_MB_2U(SCH_1):PAGE40
    U2 BT16 VSS575 SOCKET4677_AZIF0045P001C01CS-SA    I12 @S9S_MB_2U_LIB.S9S_MB_2U(SCH_1):PAGE40
    U2 BT20 VSS576 SOCKET4677_AZIF0045P001C01CS-SA    I12 @S9S_MB_2U_LIB.S9S_MB_2U(SCH_1):PAGE40
    U2  BT4 VSS577 SOCKET4677_AZIF0045P001C01CS-SA    I12 @S9S_MB_2U_LIB.S9S_MB_2U(SCH_1):PAGE40
    U2  BT8 VSS578 SOCKET4677_AZIF0045P001C01CS-SA    I12 @S9S_MB_2U_LIB.S9S_MB_2U(SCH_1):PAGE40
    U2 BU15 VSS579 SOCKET4677_AZIF0045P001C01CS-SA    I12 @S9S_MB_2U_LIB.S9S_MB_2U(SCH_1):PAGE40
    U2 BU19 VSS580 SOCKET4677_AZIF0045P001C01CS-SA    I12 @S9S_MB_2U_LIB.S9S_MB_2U(SCH_1):PAGE40
    U2 BU21 VSS581 SOCKET4677_AZIF0045P001C01CS-SA    I12 @S9S_MB_2U_LIB.S9S_MB_2U(SCH_1):PAGE40
    U2 BU23 VSS582 SOCKET4677_AZIF0045P001C01CS-SA    I12 @S9S_MB_2U_LIB.S9S_MB_2U(SCH_1):PAGE40
    U2 BU25 VSS584 SOCKET4677_AZIF0045P001C01CS-SA    I12 @S9S_MB_2U_LIB.S9S_MB_2U(SCH_1):PAGE40
    U2 BU31 VSS585 SOCKET4677_AZIF0045P001C01CS-SA    I12 @S9S_MB_2U_LIB.S9S_MB_2U(SCH_1):PAGE40
    U2  BU7 VSS586 SOCKET4677_AZIF0045P001C01CS-SA    I12 @S9S_MB_2U_LIB.S9S_MB_2U(SCH_1):PAGE40
    U2 BV12 VSS587 SOCKET4677_AZIF0045P001C01CS-SA    I12 @S9S_MB_2U_LIB.S9S_MB_2U(SCH_1):PAGE40
    U2 BV16 VSS588 SOCKET4677_AZIF0045P001C01CS-SA    I12 @S9S_MB_2U_LIB.S9S_MB_2U(SCH_1):PAGE40
    U2 BV18 VSS589 SOCKET4677_AZIF0045P001C01CS-SA    I12 @S9S_MB_2U_LIB.S9S_MB_2U(SCH_1):PAGE40
    U2  BV2 VSS590 SOCKET4677_AZIF0045P001C01CS-SA    I12 @S9S_MB_2U_LIB.S9S_MB_2U(SCH_1):PAGE40
    U2 BV20 VSS591 SOCKET4677_AZIF0045P001C01CS-SA    I12 @S9S_MB_2U_LIB.S9S_MB_2U(SCH_1):PAGE40
    U2  BV4 VSS592 SOCKET4677_AZIF0045P001C01CS-SA    I12 @S9S_MB_2U_LIB.S9S_MB_2U(SCH_1):PAGE40
    U2  BV6 VSS593 SOCKET4677_AZIF0045P001C01CS-SA    I12 @S9S_MB_2U_LIB.S9S_MB_2U(SCH_1):PAGE40
    U2  BV8 VSS594 SOCKET4677_AZIF0045P001C01CS-SA    I12 @S9S_MB_2U_LIB.S9S_MB_2U(SCH_1):PAGE40
    U2 BW13 VSS596 SOCKET4677_AZIF0045P001C01CS-SA    I12 @S9S_MB_2U_LIB.S9S_MB_2U(SCH_1):PAGE40
    U2 BW17 VSS597 SOCKET4677_AZIF0045P001C01CS-SA    I12 @S9S_MB_2U_LIB.S9S_MB_2U(SCH_1):PAGE40
    U2 BW27 VSS598 SOCKET4677_AZIF0045P001C01CS-SA    I12 @S9S_MB_2U_LIB.S9S_MB_2U(SCH_1):PAGE40
    U2 BW29 VSS599 SOCKET4677_AZIF0045P001C01CS-SA    I12 @S9S_MB_2U_LIB.S9S_MB_2U(SCH_1):PAGE40
    U2  BW3 VSS600 SOCKET4677_AZIF0045P001C01CS-SA    I12 @S9S_MB_2U_LIB.S9S_MB_2U(SCH_1):PAGE40
    U2 BW31 VSS601 SOCKET4677_AZIF0045P001C01CS-SA    I12 @S9S_MB_2U_LIB.S9S_MB_2U(SCH_1):PAGE40
    U2  BW5 VSS602 SOCKET4677_AZIF0045P001C01CS-SA    I12 @S9S_MB_2U_LIB.S9S_MB_2U(SCH_1):PAGE40
    U2  BW9 VSS603 SOCKET4677_AZIF0045P001C01CS-SA    I12 @S9S_MB_2U_LIB.S9S_MB_2U(SCH_1):PAGE40
    U2 BY12 VSS604 SOCKET4677_AZIF0045P001C01CS-SA    I12 @S9S_MB_2U_LIB.S9S_MB_2U(SCH_1):PAGE40
    U2 BY16 VSS605 SOCKET4677_AZIF0045P001C01CS-SA    I12 @S9S_MB_2U_LIB.S9S_MB_2U(SCH_1):PAGE40
    U2 BY20 VSS606 SOCKET4677_AZIF0045P001C01CS-SA    I12 @S9S_MB_2U_LIB.S9S_MB_2U(SCH_1):PAGE40
    U2  BY4 VSS607 SOCKET4677_AZIF0045P001C01CS-SA    I12 @S9S_MB_2U_LIB.S9S_MB_2U(SCH_1):PAGE40
    U2  BY8 VSS608 SOCKET4677_AZIF0045P001C01CS-SA    I12 @S9S_MB_2U_LIB.S9S_MB_2U(SCH_1):PAGE40
    U2  CA3 VSS620 SOCKET4677_AZIF0045P001C01CS-SA    I12 @S9S_MB_2U_LIB.S9S_MB_2U(SCH_1):PAGE40
    U2 CA31 VSS621 SOCKET4677_AZIF0045P001C01CS-SA    I12 @S9S_MB_2U_LIB.S9S_MB_2U(SCH_1):PAGE40
    U2 CB12 VSS622 SOCKET4677_AZIF0045P001C01CS-SA    I12 @S9S_MB_2U_LIB.S9S_MB_2U(SCH_1):PAGE40
    U2 CB16 VSS623 SOCKET4677_AZIF0045P001C01CS-SA    I12 @S9S_MB_2U_LIB.S9S_MB_2U(SCH_1):PAGE40
    U2 CB20 VSS624 SOCKET4677_AZIF0045P001C01CS-SA    I12 @S9S_MB_2U_LIB.S9S_MB_2U(SCH_1):PAGE40
    U2 CB22 VSS625 SOCKET4677_AZIF0045P001C01CS-SA    I12 @S9S_MB_2U_LIB.S9S_MB_2U(SCH_1):PAGE40
    U2 CB24 VSS626 SOCKET4677_AZIF0045P001C01CS-SA    I12 @S9S_MB_2U_LIB.S9S_MB_2U(SCH_1):PAGE40
    U2 CB26 VSS627 SOCKET4677_AZIF0045P001C01CS-SA    I12 @S9S_MB_2U_LIB.S9S_MB_2U(SCH_1):PAGE40
    U2 CB28 VSS628 SOCKET4677_AZIF0045P001C01CS-SA    I12 @S9S_MB_2U_LIB.S9S_MB_2U(SCH_1):PAGE40
    U2 CB32 VSS629 SOCKET4677_AZIF0045P001C01CS-SA    I12 @S9S_MB_2U_LIB.S9S_MB_2U(SCH_1):PAGE40
    U2 CB34 VSS630 SOCKET4677_AZIF0045P001C01CS-SA    I12 @S9S_MB_2U_LIB.S9S_MB_2U(SCH_1):PAGE40
    U2 CB36 VSS631 SOCKET4677_AZIF0045P001C01CS-SA    I12 @S9S_MB_2U_LIB.S9S_MB_2U(SCH_1):PAGE40
    U2 CB38 VSS632 SOCKET4677_AZIF0045P001C01CS-SA    I12 @S9S_MB_2U_LIB.S9S_MB_2U(SCH_1):PAGE40
    U2  CB4 VSS633 SOCKET4677_AZIF0045P001C01CS-SA    I12 @S9S_MB_2U_LIB.S9S_MB_2U(SCH_1):PAGE40
    U2 CB40 VSS634 SOCKET4677_AZIF0045P001C01CS-SA    I12 @S9S_MB_2U_LIB.S9S_MB_2U(SCH_1):PAGE40
    U2 CB42 VSS635 SOCKET4677_AZIF0045P001C01CS-SA    I12 @S9S_MB_2U_LIB.S9S_MB_2U(SCH_1):PAGE40
    U2 CB44 VSS636 SOCKET4677_AZIF0045P001C01CS-SA    I12 @S9S_MB_2U_LIB.S9S_MB_2U(SCH_1):PAGE40
    U2 CB47 VSS637 SOCKET4677_AZIF0045P001C01CS-SA    I12 @S9S_MB_2U_LIB.S9S_MB_2U(SCH_1):PAGE40
    U2 CB49 VSS638 SOCKET4677_AZIF0045P001C01CS-SA    I12 @S9S_MB_2U_LIB.S9S_MB_2U(SCH_1):PAGE40
    U2 CB51 VSS639 SOCKET4677_AZIF0045P001C01CS-SA    I12 @S9S_MB_2U_LIB.S9S_MB_2U(SCH_1):PAGE40
    U2 CB53 VSS640 SOCKET4677_AZIF0045P001C01CS-SA    I12 @S9S_MB_2U_LIB.S9S_MB_2U(SCH_1):PAGE40
    U2 CB55 VSS641 SOCKET4677_AZIF0045P001C01CS-SA    I12 @S9S_MB_2U_LIB.S9S_MB_2U(SCH_1):PAGE40
    U2 CB57 VSS642 SOCKET4677_AZIF0045P001C01CS-SA    I12 @S9S_MB_2U_LIB.S9S_MB_2U(SCH_1):PAGE40
    U2 CB59 VSS643 SOCKET4677_AZIF0045P001C01CS-SA    I12 @S9S_MB_2U_LIB.S9S_MB_2U(SCH_1):PAGE40
    U2 CB63 VSS644 SOCKET4677_AZIF0045P001C01CS-SA    I12 @S9S_MB_2U_LIB.S9S_MB_2U(SCH_1):PAGE40
    U2 CB65 VSS645 SOCKET4677_AZIF0045P001C01CS-SA    I12 @S9S_MB_2U_LIB.S9S_MB_2U(SCH_1):PAGE40
    U2 CB67 VSS646 SOCKET4677_AZIF0045P001C01CS-SA    I12 @S9S_MB_2U_LIB.S9S_MB_2U(SCH_1):PAGE40
    U2 CB69 VSS647 SOCKET4677_AZIF0045P001C01CS-SA    I12 @S9S_MB_2U_LIB.S9S_MB_2U(SCH_1):PAGE40
    U2 CB71 VSS648 SOCKET4677_AZIF0045P001C01CS-SA    I12 @S9S_MB_2U_LIB.S9S_MB_2U(SCH_1):PAGE40
    U2 CB73 VSS649 SOCKET4677_AZIF0045P001C01CS-SA    I12 @S9S_MB_2U_LIB.S9S_MB_2U(SCH_1):PAGE40
    U2 CB79 VSS650 SOCKET4677_AZIF0045P001C01CS-SA    I12 @S9S_MB_2U_LIB.S9S_MB_2U(SCH_1):PAGE40
    U2  CB8 VSS651 SOCKET4677_AZIF0045P001C01CS-SA    I12 @S9S_MB_2U_LIB.S9S_MB_2U(SCH_1):PAGE40
    U2 CB81 VSS652 SOCKET4677_AZIF0045P001C01CS-SA    I12 @S9S_MB_2U_LIB.S9S_MB_2U(SCH_1):PAGE40
    U2 CB83 VSS653 SOCKET4677_AZIF0045P001C01CS-SA    I12 @S9S_MB_2U_LIB.S9S_MB_2U(SCH_1):PAGE40
    U2 CB85 VSS654 SOCKET4677_AZIF0045P001C01CS-SA    I12 @S9S_MB_2U_LIB.S9S_MB_2U(SCH_1):PAGE40
    U2 CB87 VSS655 SOCKET4677_AZIF0045P001C01CS-SA    I12 @S9S_MB_2U_LIB.S9S_MB_2U(SCH_1):PAGE40
    U2 CB89 VSS656 SOCKET4677_AZIF0045P001C01CS-SA    I12 @S9S_MB_2U_LIB.S9S_MB_2U(SCH_1):PAGE40
    U2 CC13 VSS660 SOCKET4677_AZIF0045P001C01CS-SA    I12 @S9S_MB_2U_LIB.S9S_MB_2U(SCH_1):PAGE40
    U2 CC17 VSS661 SOCKET4677_AZIF0045P001C01CS-SA    I12 @S9S_MB_2U_LIB.S9S_MB_2U(SCH_1):PAGE40
    U2 CC31 VSS664 SOCKET4677_AZIF0045P001C01CS-SA    I12 @S9S_MB_2U_LIB.S9S_MB_2U(SCH_1):PAGE40
    U2  CC5 VSS665 SOCKET4677_AZIF0045P001C01CS-SA    I12 @S9S_MB_2U_LIB.S9S_MB_2U(SCH_1):PAGE40
    U2 CC62 VSS666 SOCKET4677_AZIF0045P001C01CS-SA    I12 @S9S_MB_2U_LIB.S9S_MB_2U(SCH_1):PAGE40
    U2 CC70 VSS667 SOCKET4677_AZIF0045P001C01CS-SA    I12 @S9S_MB_2U_LIB.S9S_MB_2U(SCH_1):PAGE40
    U2 CC72 VSS668 SOCKET4677_AZIF0045P001C01CS-SA    I12 @S9S_MB_2U_LIB.S9S_MB_2U(SCH_1):PAGE40
    U2 CC74 VSS669 SOCKET4677_AZIF0045P001C01CS-SA    I12 @S9S_MB_2U_LIB.S9S_MB_2U(SCH_1):PAGE40
    U2  CC9 VSS670 SOCKET4677_AZIF0045P001C01CS-SA    I12 @S9S_MB_2U_LIB.S9S_MB_2U(SCH_1):PAGE40
    U2 CD12 VSS671 SOCKET4677_AZIF0045P001C01CS-SA    I12 @S9S_MB_2U_LIB.S9S_MB_2U(SCH_1):PAGE40
    U2 CD16 VSS672 SOCKET4677_AZIF0045P001C01CS-SA    I12 @S9S_MB_2U_LIB.S9S_MB_2U(SCH_1):PAGE40
    U2 CD20 VSS673 SOCKET4677_AZIF0045P001C01CS-SA    I12 @S9S_MB_2U_LIB.S9S_MB_2U(SCH_1):PAGE40
    U2  CD4 VSS674 SOCKET4677_AZIF0045P001C01CS-SA    I12 @S9S_MB_2U_LIB.S9S_MB_2U(SCH_1):PAGE40
    U2 CD61 VSS675 SOCKET4677_AZIF0045P001C01CS-SA    I12 @S9S_MB_2U_LIB.S9S_MB_2U(SCH_1):PAGE40
    U2 CD75 VSS676 SOCKET4677_AZIF0045P001C01CS-SA    I12 @S9S_MB_2U_LIB.S9S_MB_2U(SCH_1):PAGE40
    U2 CD77 VSS677 SOCKET4677_AZIF0045P001C01CS-SA    I12 @S9S_MB_2U_LIB.S9S_MB_2U(SCH_1):PAGE40
    U2  CD8 VSS678 SOCKET4677_AZIF0045P001C01CS-SA    I12 @S9S_MB_2U_LIB.S9S_MB_2U(SCH_1):PAGE40
    U2  CE3 VSS680 SOCKET4677_AZIF0045P001C01CS-SA    I12 @S9S_MB_2U_LIB.S9S_MB_2U(SCH_1):PAGE40
    U2 CE60 VSS681 SOCKET4677_AZIF0045P001C01CS-SA    I12 @S9S_MB_2U_LIB.S9S_MB_2U(SCH_1):PAGE40
    U2 CE66 VSS682 SOCKET4677_AZIF0045P001C01CS-SA    I12 @S9S_MB_2U_LIB.S9S_MB_2U(SCH_1):PAGE40
    U2 CE72 VSS683 SOCKET4677_AZIF0045P001C01CS-SA    I12 @S9S_MB_2U_LIB.S9S_MB_2U(SCH_1):PAGE40
    U2 CE76 VSS684 SOCKET4677_AZIF0045P001C01CS-SA    I12 @S9S_MB_2U_LIB.S9S_MB_2U(SCH_1):PAGE40
    U2 CE78 VSS685 SOCKET4677_AZIF0045P001C01CS-SA    I12 @S9S_MB_2U_LIB.S9S_MB_2U(SCH_1):PAGE40
    U2 CF12 VSS686 SOCKET4677_AZIF0045P001C01CS-SA    I12 @S9S_MB_2U_LIB.S9S_MB_2U(SCH_1):PAGE40
    U2 CF16 VSS687 SOCKET4677_AZIF0045P001C01CS-SA    I12 @S9S_MB_2U_LIB.S9S_MB_2U(SCH_1):PAGE40
    U2 CF20 VSS688 SOCKET4677_AZIF0045P001C01CS-SA    I12 @S9S_MB_2U_LIB.S9S_MB_2U(SCH_1):PAGE40
    U2  CF4 VSS689 SOCKET4677_AZIF0045P001C01CS-SA    I12 @S9S_MB_2U_LIB.S9S_MB_2U(SCH_1):PAGE40
    U2 CF69 VSS691 SOCKET4677_AZIF0045P001C01CS-SA    I12 @S9S_MB_2U_LIB.S9S_MB_2U(SCH_1):PAGE40
    U2 CF71 VSS692 SOCKET4677_AZIF0045P001C01CS-SA    I12 @S9S_MB_2U_LIB.S9S_MB_2U(SCH_1):PAGE40
    U2  CF8 VSS693 SOCKET4677_AZIF0045P001C01CS-SA    I12 @S9S_MB_2U_LIB.S9S_MB_2U(SCH_1):PAGE40
    U2  CG1 VSS694 SOCKET4677_AZIF0045P001C01CS-SA    I12 @S9S_MB_2U_LIB.S9S_MB_2U(SCH_1):PAGE40
    U2 CG13 VSS695 SOCKET4677_AZIF0045P001C01CS-SA    I12 @S9S_MB_2U_LIB.S9S_MB_2U(SCH_1):PAGE40
    U2 CG17 VSS696 SOCKET4677_AZIF0045P001C01CS-SA    I12 @S9S_MB_2U_LIB.S9S_MB_2U(SCH_1):PAGE40
    U2 CG21 VSS697 SOCKET4677_AZIF0045P001C01CS-SA    I12 @S9S_MB_2U_LIB.S9S_MB_2U(SCH_1):PAGE40
    U2 CG23 VSS698 SOCKET4677_AZIF0045P001C01CS-SA    I12 @S9S_MB_2U_LIB.S9S_MB_2U(SCH_1):PAGE40
    U2 CG25 VSS701 SOCKET4677_AZIF0045P001C01CS-SA    I12 @S9S_MB_2U_LIB.S9S_MB_2U(SCH_1):PAGE40
    U2  CG5 VSS703 SOCKET4677_AZIF0045P001C01CS-SA    I12 @S9S_MB_2U_LIB.S9S_MB_2U(SCH_1):PAGE40
    U2 CG62 VSS704 SOCKET4677_AZIF0045P001C01CS-SA    I12 @S9S_MB_2U_LIB.S9S_MB_2U(SCH_1):PAGE40
    U2 CG64 VSS706 SOCKET4677_AZIF0045P001C01CS-SA    I12 @S9S_MB_2U_LIB.S9S_MB_2U(SCH_1):PAGE40
    U2 CG70 VSS707 SOCKET4677_AZIF0045P001C01CS-SA    I12 @S9S_MB_2U_LIB.S9S_MB_2U(SCH_1):PAGE40
    U2 CG72 VSS708 SOCKET4677_AZIF0045P001C01CS-SA    I12 @S9S_MB_2U_LIB.S9S_MB_2U(SCH_1):PAGE40
    U2 CG74 VSS710 SOCKET4677_AZIF0045P001C01CS-SA    I12 @S9S_MB_2U_LIB.S9S_MB_2U(SCH_1):PAGE40
    U2 CG78 VSS713 SOCKET4677_AZIF0045P001C01CS-SA    I12 @S9S_MB_2U_LIB.S9S_MB_2U(SCH_1):PAGE40
    U2  CG9 VSS716 SOCKET4677_AZIF0045P001C01CS-SA    I12 @S9S_MB_2U_LIB.S9S_MB_2U(SCH_1):PAGE40
    U2 CH12 VSS718 SOCKET4677_AZIF0045P001C01CS-SA    I12 @S9S_MB_2U_LIB.S9S_MB_2U(SCH_1):PAGE40
    U2 CH16 VSS720 SOCKET4677_AZIF0045P001C01CS-SA    I12 @S9S_MB_2U_LIB.S9S_MB_2U(SCH_1):PAGE40
    U2 CH20 VSS721 SOCKET4677_AZIF0045P001C01CS-SA    I12 @S9S_MB_2U_LIB.S9S_MB_2U(SCH_1):PAGE40
    U2  CH4 VSS722 SOCKET4677_AZIF0045P001C01CS-SA    I12 @S9S_MB_2U_LIB.S9S_MB_2U(SCH_1):PAGE40
    U2 CH67 VSS727 SOCKET4677_AZIF0045P001C01CS-SA    I12 @S9S_MB_2U_LIB.S9S_MB_2U(SCH_1):PAGE40
    U2 CH73 VSS728 SOCKET4677_AZIF0045P001C01CS-SA    I12 @S9S_MB_2U_LIB.S9S_MB_2U(SCH_1):PAGE40
    U2 CH79 VSS729 SOCKET4677_AZIF0045P001C01CS-SA    I12 @S9S_MB_2U_LIB.S9S_MB_2U(SCH_1):PAGE40
    U2  CH8 VSS730 SOCKET4677_AZIF0045P001C01CS-SA    I12 @S9S_MB_2U_LIB.S9S_MB_2U(SCH_1):PAGE40
    U2 CH83 VSS731 SOCKET4677_AZIF0045P001C01CS-SA    I12 @S9S_MB_2U_LIB.S9S_MB_2U(SCH_1):PAGE40
    U2 CH85 VSS732 SOCKET4677_AZIF0045P001C01CS-SA    I12 @S9S_MB_2U_LIB.S9S_MB_2U(SCH_1):PAGE40
    U2 CH87 VSS733 SOCKET4677_AZIF0045P001C01CS-SA    I12 @S9S_MB_2U_LIB.S9S_MB_2U(SCH_1):PAGE40
    U2 CH89 VSS734 SOCKET4677_AZIF0045P001C01CS-SA    I12 @S9S_MB_2U_LIB.S9S_MB_2U(SCH_1):PAGE40
    U2 CJ60 VSS736 SOCKET4677_AZIF0045P001C01CS-SA    I12 @S9S_MB_2U_LIB.S9S_MB_2U(SCH_1):PAGE40
    U2 CJ80 VSS737 SOCKET4677_AZIF0045P001C01CS-SA    I12 @S9S_MB_2U_LIB.S9S_MB_2U(SCH_1):PAGE40
    U2 CK12 VSS740 SOCKET4677_AZIF0045P001C01CS-SA    I12 @S9S_MB_2U_LIB.S9S_MB_2U(SCH_1):PAGE40
    U2 CK16 VSS741 SOCKET4677_AZIF0045P001C01CS-SA    I12 @S9S_MB_2U_LIB.S9S_MB_2U(SCH_1):PAGE40
    U2 CK20 VSS742 SOCKET4677_AZIF0045P001C01CS-SA    I12 @S9S_MB_2U_LIB.S9S_MB_2U(SCH_1):PAGE40
    U2 CK26 VSS743 SOCKET4677_AZIF0045P001C01CS-SA    I12 @S9S_MB_2U_LIB.S9S_MB_2U(SCH_1):PAGE40
    U2  CK8 VSS746 SOCKET4677_AZIF0045P001C01CS-SA    I12 @S9S_MB_2U_LIB.S9S_MB_2U(SCH_1):PAGE40
    U2  BR5   VSS0 SOCKET4677_AZIF0045P001C01CS-SA     I9 @S9S_MB_2U_LIB.S9S_MB_2U(SCH_1):PAGE41
    U2 AW21 VSS356 SOCKET4677_AZIF0045P001C01CS-SA     I9 @S9S_MB_2U_LIB.S9S_MB_2U(SCH_1):PAGE41
    U2 AW23 VSS357 SOCKET4677_AZIF0045P001C01CS-SA     I9 @S9S_MB_2U_LIB.S9S_MB_2U(SCH_1):PAGE41
    U2 AW25 VSS358 SOCKET4677_AZIF0045P001C01CS-SA     I9 @S9S_MB_2U_LIB.S9S_MB_2U(SCH_1):PAGE41
    U2 AW62 VSS360 SOCKET4677_AZIF0045P001C01CS-SA     I9 @S9S_MB_2U_LIB.S9S_MB_2U(SCH_1):PAGE41
    U2 AW66 VSS361 SOCKET4677_AZIF0045P001C01CS-SA     I9 @S9S_MB_2U_LIB.S9S_MB_2U(SCH_1):PAGE41
    U2 AW68 VSS362 SOCKET4677_AZIF0045P001C01CS-SA     I9 @S9S_MB_2U_LIB.S9S_MB_2U(SCH_1):PAGE41
    U2 AW72 VSS363 SOCKET4677_AZIF0045P001C01CS-SA     I9 @S9S_MB_2U_LIB.S9S_MB_2U(SCH_1):PAGE41
    U2 AW80 VSS364 SOCKET4677_AZIF0045P001C01CS-SA     I9 @S9S_MB_2U_LIB.S9S_MB_2U(SCH_1):PAGE41
    U2 AW82 VSS365 SOCKET4677_AZIF0045P001C01CS-SA     I9 @S9S_MB_2U_LIB.S9S_MB_2U(SCH_1):PAGE41
    U2 AW84 VSS366 SOCKET4677_AZIF0045P001C01CS-SA     I9 @S9S_MB_2U_LIB.S9S_MB_2U(SCH_1):PAGE41
    U2 AW88 VSS367 SOCKET4677_AZIF0045P001C01CS-SA     I9 @S9S_MB_2U_LIB.S9S_MB_2U(SCH_1):PAGE41
    U2 AY12 VSS369 SOCKET4677_AZIF0045P001C01CS-SA     I9 @S9S_MB_2U_LIB.S9S_MB_2U(SCH_1):PAGE41
    U2 AY16 VSS370 SOCKET4677_AZIF0045P001C01CS-SA     I9 @S9S_MB_2U_LIB.S9S_MB_2U(SCH_1):PAGE41
    U2  AY4 VSS371 SOCKET4677_AZIF0045P001C01CS-SA     I9 @S9S_MB_2U_LIB.S9S_MB_2U(SCH_1):PAGE41
    U2 AY71 VSS372 SOCKET4677_AZIF0045P001C01CS-SA     I9 @S9S_MB_2U_LIB.S9S_MB_2U(SCH_1):PAGE41
    U2 AY77 VSS373 SOCKET4677_AZIF0045P001C01CS-SA     I9 @S9S_MB_2U_LIB.S9S_MB_2U(SCH_1):PAGE41
    U2 AY79 VSS374 SOCKET4677_AZIF0045P001C01CS-SA     I9 @S9S_MB_2U_LIB.S9S_MB_2U(SCH_1):PAGE41
    U2  AY8 VSS375 SOCKET4677_AZIF0045P001C01CS-SA     I9 @S9S_MB_2U_LIB.S9S_MB_2U(SCH_1):PAGE41
    U2 AY81 VSS376 SOCKET4677_AZIF0045P001C01CS-SA     I9 @S9S_MB_2U_LIB.S9S_MB_2U(SCH_1):PAGE41
    U2 AY83 VSS377 SOCKET4677_AZIF0045P001C01CS-SA     I9 @S9S_MB_2U_LIB.S9S_MB_2U(SCH_1):PAGE41
    U2 BA17 VSS393 SOCKET4677_AZIF0045P001C01CS-SA     I9 @S9S_MB_2U_LIB.S9S_MB_2U(SCH_1):PAGE41
    U2 BA60 VSS394 SOCKET4677_AZIF0045P001C01CS-SA     I9 @S9S_MB_2U_LIB.S9S_MB_2U(SCH_1):PAGE41
    U2 BA64 VSS395 SOCKET4677_AZIF0045P001C01CS-SA     I9 @S9S_MB_2U_LIB.S9S_MB_2U(SCH_1):PAGE41
    U2 BA74 VSS397 SOCKET4677_AZIF0045P001C01CS-SA     I9 @S9S_MB_2U_LIB.S9S_MB_2U(SCH_1):PAGE41
    U2 BA84 VSS398 SOCKET4677_AZIF0045P001C01CS-SA     I9 @S9S_MB_2U_LIB.S9S_MB_2U(SCH_1):PAGE41
    U2 BA88 VSS399 SOCKET4677_AZIF0045P001C01CS-SA     I9 @S9S_MB_2U_LIB.S9S_MB_2U(SCH_1):PAGE41
    U2 BB10 VSS400 SOCKET4677_AZIF0045P001C01CS-SA     I9 @S9S_MB_2U_LIB.S9S_MB_2U(SCH_1):PAGE41
    U2 BB12 VSS401 SOCKET4677_AZIF0045P001C01CS-SA     I9 @S9S_MB_2U_LIB.S9S_MB_2U(SCH_1):PAGE41
    U2 BB16 VSS402 SOCKET4677_AZIF0045P001C01CS-SA     I9 @S9S_MB_2U_LIB.S9S_MB_2U(SCH_1):PAGE41
    U2 BB20 VSS403 SOCKET4677_AZIF0045P001C01CS-SA     I9 @S9S_MB_2U_LIB.S9S_MB_2U(SCH_1):PAGE41
    U2 BB22 VSS404 SOCKET4677_AZIF0045P001C01CS-SA     I9 @S9S_MB_2U_LIB.S9S_MB_2U(SCH_1):PAGE41
    U2 BB24 VSS405 SOCKET4677_AZIF0045P001C01CS-SA     I9 @S9S_MB_2U_LIB.S9S_MB_2U(SCH_1):PAGE41
    U2 BB26 VSS406 SOCKET4677_AZIF0045P001C01CS-SA     I9 @S9S_MB_2U_LIB.S9S_MB_2U(SCH_1):PAGE41
    U2  BB4 VSS407 SOCKET4677_AZIF0045P001C01CS-SA     I9 @S9S_MB_2U_LIB.S9S_MB_2U(SCH_1):PAGE41
    U2 BB63 VSS408 SOCKET4677_AZIF0045P001C01CS-SA     I9 @S9S_MB_2U_LIB.S9S_MB_2U(SCH_1):PAGE41
    U2 BB69 VSS409 SOCKET4677_AZIF0045P001C01CS-SA     I9 @S9S_MB_2U_LIB.S9S_MB_2U(SCH_1):PAGE41
    U2 BB71 VSS410 SOCKET4677_AZIF0045P001C01CS-SA     I9 @S9S_MB_2U_LIB.S9S_MB_2U(SCH_1):PAGE41
    U2 BB77 VSS411 SOCKET4677_AZIF0045P001C01CS-SA     I9 @S9S_MB_2U_LIB.S9S_MB_2U(SCH_1):PAGE41
    U2 BB79 VSS412 SOCKET4677_AZIF0045P001C01CS-SA     I9 @S9S_MB_2U_LIB.S9S_MB_2U(SCH_1):PAGE41
    U2  BB8 VSS413 SOCKET4677_AZIF0045P001C01CS-SA     I9 @S9S_MB_2U_LIB.S9S_MB_2U(SCH_1):PAGE41
    U2 BB83 VSS414 SOCKET4677_AZIF0045P001C01CS-SA     I9 @S9S_MB_2U_LIB.S9S_MB_2U(SCH_1):PAGE41
    U2 BB87 VSS415 SOCKET4677_AZIF0045P001C01CS-SA     I9 @S9S_MB_2U_LIB.S9S_MB_2U(SCH_1):PAGE41
    U2 BB91 VSS416 SOCKET4677_AZIF0045P001C01CS-SA     I9 @S9S_MB_2U_LIB.S9S_MB_2U(SCH_1):PAGE41
    U2  BC1 VSS417 SOCKET4677_AZIF0045P001C01CS-SA     I9 @S9S_MB_2U_LIB.S9S_MB_2U(SCH_1):PAGE41
    U2 BC13 VSS418 SOCKET4677_AZIF0045P001C01CS-SA     I9 @S9S_MB_2U_LIB.S9S_MB_2U(SCH_1):PAGE41
    U2 BC17 VSS419 SOCKET4677_AZIF0045P001C01CS-SA     I9 @S9S_MB_2U_LIB.S9S_MB_2U(SCH_1):PAGE41
    U2  BC5 VSS420 SOCKET4677_AZIF0045P001C01CS-SA     I9 @S9S_MB_2U_LIB.S9S_MB_2U(SCH_1):PAGE41
    U2 BC62 VSS421 SOCKET4677_AZIF0045P001C01CS-SA     I9 @S9S_MB_2U_LIB.S9S_MB_2U(SCH_1):PAGE41
    U2 BC66 VSS422 SOCKET4677_AZIF0045P001C01CS-SA     I9 @S9S_MB_2U_LIB.S9S_MB_2U(SCH_1):PAGE41
    U2 BC72 VSS423 SOCKET4677_AZIF0045P001C01CS-SA     I9 @S9S_MB_2U_LIB.S9S_MB_2U(SCH_1):PAGE41
    U2 BC76 VSS424 SOCKET4677_AZIF0045P001C01CS-SA     I9 @S9S_MB_2U_LIB.S9S_MB_2U(SCH_1):PAGE41
    U2 BC78 VSS425 SOCKET4677_AZIF0045P001C01CS-SA     I9 @S9S_MB_2U_LIB.S9S_MB_2U(SCH_1):PAGE41
    U2 BC84 VSS426 SOCKET4677_AZIF0045P001C01CS-SA     I9 @S9S_MB_2U_LIB.S9S_MB_2U(SCH_1):PAGE41
    U2 BC86 VSS427 SOCKET4677_AZIF0045P001C01CS-SA     I9 @S9S_MB_2U_LIB.S9S_MB_2U(SCH_1):PAGE41
    U2 BC88 VSS428 SOCKET4677_AZIF0045P001C01CS-SA     I9 @S9S_MB_2U_LIB.S9S_MB_2U(SCH_1):PAGE41
    U2  BC9 VSS429 SOCKET4677_AZIF0045P001C01CS-SA     I9 @S9S_MB_2U_LIB.S9S_MB_2U(SCH_1):PAGE41
    U2 BD12 VSS430 SOCKET4677_AZIF0045P001C01CS-SA     I9 @S9S_MB_2U_LIB.S9S_MB_2U(SCH_1):PAGE41
    U2 BD16 VSS431 SOCKET4677_AZIF0045P001C01CS-SA     I9 @S9S_MB_2U_LIB.S9S_MB_2U(SCH_1):PAGE41
    U2 BD20 VSS432 SOCKET4677_AZIF0045P001C01CS-SA     I9 @S9S_MB_2U_LIB.S9S_MB_2U(SCH_1):PAGE41
    U2  BD4 VSS433 SOCKET4677_AZIF0045P001C01CS-SA     I9 @S9S_MB_2U_LIB.S9S_MB_2U(SCH_1):PAGE41
    U2  BD8 VSS434 SOCKET4677_AZIF0045P001C01CS-SA     I9 @S9S_MB_2U_LIB.S9S_MB_2U(SCH_1):PAGE41
    U2 BD81 VSS435 SOCKET4677_AZIF0045P001C01CS-SA     I9 @S9S_MB_2U_LIB.S9S_MB_2U(SCH_1):PAGE41
    U2 BD85 VSS437 SOCKET4677_AZIF0045P001C01CS-SA     I9 @S9S_MB_2U_LIB.S9S_MB_2U(SCH_1):PAGE41
    U2 BD89 VSS439 SOCKET4677_AZIF0045P001C01CS-SA     I9 @S9S_MB_2U_LIB.S9S_MB_2U(SCH_1):PAGE41
    U2 BE64 VSS440 SOCKET4677_AZIF0045P001C01CS-SA     I9 @S9S_MB_2U_LIB.S9S_MB_2U(SCH_1):PAGE41
    U2 BE66 VSS441 SOCKET4677_AZIF0045P001C01CS-SA     I9 @S9S_MB_2U_LIB.S9S_MB_2U(SCH_1):PAGE41
    U2 BE68 VSS442 SOCKET4677_AZIF0045P001C01CS-SA     I9 @S9S_MB_2U_LIB.S9S_MB_2U(SCH_1):PAGE41
    U2 BE74 VSS443 SOCKET4677_AZIF0045P001C01CS-SA     I9 @S9S_MB_2U_LIB.S9S_MB_2U(SCH_1):PAGE41
    U2 BE76 VSS444 SOCKET4677_AZIF0045P001C01CS-SA     I9 @S9S_MB_2U_LIB.S9S_MB_2U(SCH_1):PAGE41
    U2 BE78 VSS445 SOCKET4677_AZIF0045P001C01CS-SA     I9 @S9S_MB_2U_LIB.S9S_MB_2U(SCH_1):PAGE41
    U2 BE84 VSS446 SOCKET4677_AZIF0045P001C01CS-SA     I9 @S9S_MB_2U_LIB.S9S_MB_2U(SCH_1):PAGE41
    U2 BF12 VSS447 SOCKET4677_AZIF0045P001C01CS-SA     I9 @S9S_MB_2U_LIB.S9S_MB_2U(SCH_1):PAGE41
    U2 BF16 VSS448 SOCKET4677_AZIF0045P001C01CS-SA     I9 @S9S_MB_2U_LIB.S9S_MB_2U(SCH_1):PAGE41
    U2 BF20 VSS449 SOCKET4677_AZIF0045P001C01CS-SA     I9 @S9S_MB_2U_LIB.S9S_MB_2U(SCH_1):PAGE41
    U2  BF4 VSS450 SOCKET4677_AZIF0045P001C01CS-SA     I9 @S9S_MB_2U_LIB.S9S_MB_2U(SCH_1):PAGE41
    U2 BF61 VSS451 SOCKET4677_AZIF0045P001C01CS-SA     I9 @S9S_MB_2U_LIB.S9S_MB_2U(SCH_1):PAGE41
    U2 BF63 VSS452 SOCKET4677_AZIF0045P001C01CS-SA     I9 @S9S_MB_2U_LIB.S9S_MB_2U(SCH_1):PAGE41
    U2 BF73 VSS453 SOCKET4677_AZIF0045P001C01CS-SA     I9 @S9S_MB_2U_LIB.S9S_MB_2U(SCH_1):PAGE41
    U2 BF75 VSS454 SOCKET4677_AZIF0045P001C01CS-SA     I9 @S9S_MB_2U_LIB.S9S_MB_2U(SCH_1):PAGE41
    U2 BF79 VSS455 SOCKET4677_AZIF0045P001C01CS-SA     I9 @S9S_MB_2U_LIB.S9S_MB_2U(SCH_1):PAGE41
    U2  BF8 VSS456 SOCKET4677_AZIF0045P001C01CS-SA     I9 @S9S_MB_2U_LIB.S9S_MB_2U(SCH_1):PAGE41
    U2 BF83 VSS457 SOCKET4677_AZIF0045P001C01CS-SA     I9 @S9S_MB_2U_LIB.S9S_MB_2U(SCH_1):PAGE41
    U2  BG1 VSS458 SOCKET4677_AZIF0045P001C01CS-SA     I9 @S9S_MB_2U_LIB.S9S_MB_2U(SCH_1):PAGE41
    U2 BG13 VSS459 SOCKET4677_AZIF0045P001C01CS-SA     I9 @S9S_MB_2U_LIB.S9S_MB_2U(SCH_1):PAGE41
    U2 BG17 VSS460 SOCKET4677_AZIF0045P001C01CS-SA     I9 @S9S_MB_2U_LIB.S9S_MB_2U(SCH_1):PAGE41
    U2 BG21 VSS461 SOCKET4677_AZIF0045P001C01CS-SA     I9 @S9S_MB_2U_LIB.S9S_MB_2U(SCH_1):PAGE41
    U2 BG23 VSS462 SOCKET4677_AZIF0045P001C01CS-SA     I9 @S9S_MB_2U_LIB.S9S_MB_2U(SCH_1):PAGE41
    U2 BG25 VSS463 SOCKET4677_AZIF0045P001C01CS-SA     I9 @S9S_MB_2U_LIB.S9S_MB_2U(SCH_1):PAGE41
    U2  BG5 VSS464 SOCKET4677_AZIF0045P001C01CS-SA     I9 @S9S_MB_2U_LIB.S9S_MB_2U(SCH_1):PAGE41
    U2 BG70 VSS465 SOCKET4677_AZIF0045P001C01CS-SA     I9 @S9S_MB_2U_LIB.S9S_MB_2U(SCH_1):PAGE41
    U2  BG9 VSS466 SOCKET4677_AZIF0045P001C01CS-SA     I9 @S9S_MB_2U_LIB.S9S_MB_2U(SCH_1):PAGE41
    U2 BH12 VSS467 SOCKET4677_AZIF0045P001C01CS-SA     I9 @S9S_MB_2U_LIB.S9S_MB_2U(SCH_1):PAGE41
    U2 BH16 VSS468 SOCKET4677_AZIF0045P001C01CS-SA     I9 @S9S_MB_2U_LIB.S9S_MB_2U(SCH_1):PAGE41
    U2 BH20 VSS469 SOCKET4677_AZIF0045P001C01CS-SA     I9 @S9S_MB_2U_LIB.S9S_MB_2U(SCH_1):PAGE41
    U2  BH4 VSS470 SOCKET4677_AZIF0045P001C01CS-SA     I9 @S9S_MB_2U_LIB.S9S_MB_2U(SCH_1):PAGE41
    U2 BH67 VSS472 SOCKET4677_AZIF0045P001C01CS-SA     I9 @S9S_MB_2U_LIB.S9S_MB_2U(SCH_1):PAGE41
    U2 BH73 VSS473 SOCKET4677_AZIF0045P001C01CS-SA     I9 @S9S_MB_2U_LIB.S9S_MB_2U(SCH_1):PAGE41
    U2 BH77 VSS474 SOCKET4677_AZIF0045P001C01CS-SA     I9 @S9S_MB_2U_LIB.S9S_MB_2U(SCH_1):PAGE41
    U2  BH8 VSS475 SOCKET4677_AZIF0045P001C01CS-SA     I9 @S9S_MB_2U_LIB.S9S_MB_2U(SCH_1):PAGE41
    U2 BH81 VSS476 SOCKET4677_AZIF0045P001C01CS-SA     I9 @S9S_MB_2U_LIB.S9S_MB_2U(SCH_1):PAGE41
    U2 BH83 VSS477 SOCKET4677_AZIF0045P001C01CS-SA     I9 @S9S_MB_2U_LIB.S9S_MB_2U(SCH_1):PAGE41
    U2 BJ62 VSS479 SOCKET4677_AZIF0045P001C01CS-SA     I9 @S9S_MB_2U_LIB.S9S_MB_2U(SCH_1):PAGE41
    U2 BJ68 VSS480 SOCKET4677_AZIF0045P001C01CS-SA     I9 @S9S_MB_2U_LIB.S9S_MB_2U(SCH_1):PAGE41
    U2 BJ80 VSS481 SOCKET4677_AZIF0045P001C01CS-SA     I9 @S9S_MB_2U_LIB.S9S_MB_2U(SCH_1):PAGE41
    U2 BJ82 VSS482 SOCKET4677_AZIF0045P001C01CS-SA     I9 @S9S_MB_2U_LIB.S9S_MB_2U(SCH_1):PAGE41
    U2 BJ84 VSS483 SOCKET4677_AZIF0045P001C01CS-SA     I9 @S9S_MB_2U_LIB.S9S_MB_2U(SCH_1):PAGE41
    U2 BJ86 VSS484 SOCKET4677_AZIF0045P001C01CS-SA     I9 @S9S_MB_2U_LIB.S9S_MB_2U(SCH_1):PAGE41
    U2 BJ88 VSS485 SOCKET4677_AZIF0045P001C01CS-SA     I9 @S9S_MB_2U_LIB.S9S_MB_2U(SCH_1):PAGE41
    U2 BJ90 VSS486 SOCKET4677_AZIF0045P001C01CS-SA     I9 @S9S_MB_2U_LIB.S9S_MB_2U(SCH_1):PAGE41
    U2 BK12 VSS487 SOCKET4677_AZIF0045P001C01CS-SA     I9 @S9S_MB_2U_LIB.S9S_MB_2U(SCH_1):PAGE41
    U2 BK16 VSS488 SOCKET4677_AZIF0045P001C01CS-SA     I9 @S9S_MB_2U_LIB.S9S_MB_2U(SCH_1):PAGE41
    U2 BK20 VSS489 SOCKET4677_AZIF0045P001C01CS-SA     I9 @S9S_MB_2U_LIB.S9S_MB_2U(SCH_1):PAGE41
    U2  BK4 VSS490 SOCKET4677_AZIF0045P001C01CS-SA     I9 @S9S_MB_2U_LIB.S9S_MB_2U(SCH_1):PAGE41
    U2 BK65 VSS491 SOCKET4677_AZIF0045P001C01CS-SA     I9 @S9S_MB_2U_LIB.S9S_MB_2U(SCH_1):PAGE41
    U2 BK71 VSS492 SOCKET4677_AZIF0045P001C01CS-SA     I9 @S9S_MB_2U_LIB.S9S_MB_2U(SCH_1):PAGE41
    U2 BK75 VSS494 SOCKET4677_AZIF0045P001C01CS-SA     I9 @S9S_MB_2U_LIB.S9S_MB_2U(SCH_1):PAGE41
    U2 BK79 VSS495 SOCKET4677_AZIF0045P001C01CS-SA     I9 @S9S_MB_2U_LIB.S9S_MB_2U(SCH_1):PAGE41
    U2  BK8 VSS496 SOCKET4677_AZIF0045P001C01CS-SA     I9 @S9S_MB_2U_LIB.S9S_MB_2U(SCH_1):PAGE41
    U2  BL1 VSS497 SOCKET4677_AZIF0045P001C01CS-SA     I9 @S9S_MB_2U_LIB.S9S_MB_2U(SCH_1):PAGE41
    U2 BL13 VSS498 SOCKET4677_AZIF0045P001C01CS-SA     I9 @S9S_MB_2U_LIB.S9S_MB_2U(SCH_1):PAGE41
    U2 BL17 VSS499 SOCKET4677_AZIF0045P001C01CS-SA     I9 @S9S_MB_2U_LIB.S9S_MB_2U(SCH_1):PAGE41
    U2  BL5 VSS500 SOCKET4677_AZIF0045P001C01CS-SA     I9 @S9S_MB_2U_LIB.S9S_MB_2U(SCH_1):PAGE41
    U2 BL68 VSS501 SOCKET4677_AZIF0045P001C01CS-SA     I9 @S9S_MB_2U_LIB.S9S_MB_2U(SCH_1):PAGE41
    U2 BL70 VSS502 SOCKET4677_AZIF0045P001C01CS-SA     I9 @S9S_MB_2U_LIB.S9S_MB_2U(SCH_1):PAGE41
    U2 BL72 VSS503 SOCKET4677_AZIF0045P001C01CS-SA     I9 @S9S_MB_2U_LIB.S9S_MB_2U(SCH_1):PAGE41
    U2 BL78 VSS504 SOCKET4677_AZIF0045P001C01CS-SA     I9 @S9S_MB_2U_LIB.S9S_MB_2U(SCH_1):PAGE41
    U2  BL9 VSS505 SOCKET4677_AZIF0045P001C01CS-SA     I9 @S9S_MB_2U_LIB.S9S_MB_2U(SCH_1):PAGE41
    U2 BM12 VSS506 SOCKET4677_AZIF0045P001C01CS-SA     I9 @S9S_MB_2U_LIB.S9S_MB_2U(SCH_1):PAGE41
    U2 BM16 VSS507 SOCKET4677_AZIF0045P001C01CS-SA     I9 @S9S_MB_2U_LIB.S9S_MB_2U(SCH_1):PAGE41
    U2 BM20 VSS508 SOCKET4677_AZIF0045P001C01CS-SA     I9 @S9S_MB_2U_LIB.S9S_MB_2U(SCH_1):PAGE41
    U2 BM22 VSS509 SOCKET4677_AZIF0045P001C01CS-SA     I9 @S9S_MB_2U_LIB.S9S_MB_2U(SCH_1):PAGE41
    U2 BM24 VSS510 SOCKET4677_AZIF0045P001C01CS-SA     I9 @S9S_MB_2U_LIB.S9S_MB_2U(SCH_1):PAGE41
    U2 BM26 VSS511 SOCKET4677_AZIF0045P001C01CS-SA     I9 @S9S_MB_2U_LIB.S9S_MB_2U(SCH_1):PAGE41
    U2  BM4 VSS512 SOCKET4677_AZIF0045P001C01CS-SA     I9 @S9S_MB_2U_LIB.S9S_MB_2U(SCH_1):PAGE41
    U2 BM61 VSS513 SOCKET4677_AZIF0045P001C01CS-SA     I9 @S9S_MB_2U_LIB.S9S_MB_2U(SCH_1):PAGE41
    U2 BM73 VSS515 SOCKET4677_AZIF0045P001C01CS-SA     I9 @S9S_MB_2U_LIB.S9S_MB_2U(SCH_1):PAGE41
    U2 BM77 VSS516 SOCKET4677_AZIF0045P001C01CS-SA     I9 @S9S_MB_2U_LIB.S9S_MB_2U(SCH_1):PAGE41
    U2  BM8 VSS517 SOCKET4677_AZIF0045P001C01CS-SA     I9 @S9S_MB_2U_LIB.S9S_MB_2U(SCH_1):PAGE41
    U2 BN31 VSS518 SOCKET4677_AZIF0045P001C01CS-SA     I9 @S9S_MB_2U_LIB.S9S_MB_2U(SCH_1):PAGE41
    U2 BN62 VSS519 SOCKET4677_AZIF0045P001C01CS-SA     I9 @S9S_MB_2U_LIB.S9S_MB_2U(SCH_1):PAGE41
    U2 BN70 VSS520 SOCKET4677_AZIF0045P001C01CS-SA     I9 @S9S_MB_2U_LIB.S9S_MB_2U(SCH_1):PAGE41
    U2 BP12 VSS522 SOCKET4677_AZIF0045P001C01CS-SA     I9 @S9S_MB_2U_LIB.S9S_MB_2U(SCH_1):PAGE41
    U2 BP16 VSS523 SOCKET4677_AZIF0045P001C01CS-SA     I9 @S9S_MB_2U_LIB.S9S_MB_2U(SCH_1):PAGE41
    U2  BP2 VSS524 SOCKET4677_AZIF0045P001C01CS-SA     I9 @S9S_MB_2U_LIB.S9S_MB_2U(SCH_1):PAGE41
    U2 BP20 VSS525 SOCKET4677_AZIF0045P001C01CS-SA     I9 @S9S_MB_2U_LIB.S9S_MB_2U(SCH_1):PAGE41
    U2  BP4 VSS527 SOCKET4677_AZIF0045P001C01CS-SA     I9 @S9S_MB_2U_LIB.S9S_MB_2U(SCH_1):PAGE41
    U2 BP63 VSS528 SOCKET4677_AZIF0045P001C01CS-SA     I9 @S9S_MB_2U_LIB.S9S_MB_2U(SCH_1):PAGE41
    U2 BP71 VSS529 SOCKET4677_AZIF0045P001C01CS-SA     I9 @S9S_MB_2U_LIB.S9S_MB_2U(SCH_1):PAGE41
    U2 BP73 VSS530 SOCKET4677_AZIF0045P001C01CS-SA     I9 @S9S_MB_2U_LIB.S9S_MB_2U(SCH_1):PAGE41
    U2 BP75 VSS531 SOCKET4677_AZIF0045P001C01CS-SA     I9 @S9S_MB_2U_LIB.S9S_MB_2U(SCH_1):PAGE41
    U2 BP77 VSS532 SOCKET4677_AZIF0045P001C01CS-SA     I9 @S9S_MB_2U_LIB.S9S_MB_2U(SCH_1):PAGE41
    U2  BP8 VSS533 SOCKET4677_AZIF0045P001C01CS-SA     I9 @S9S_MB_2U_LIB.S9S_MB_2U(SCH_1):PAGE41
    U2 BR13 VSS535 SOCKET4677_AZIF0045P001C01CS-SA     I9 @S9S_MB_2U_LIB.S9S_MB_2U(SCH_1):PAGE41
    U2 BR17 VSS536 SOCKET4677_AZIF0045P001C01CS-SA     I9 @S9S_MB_2U_LIB.S9S_MB_2U(SCH_1):PAGE41
    U2 BR27 VSS538 SOCKET4677_AZIF0045P001C01CS-SA     I9 @S9S_MB_2U_LIB.S9S_MB_2U(SCH_1):PAGE41
    U2 BR29 VSS539 SOCKET4677_AZIF0045P001C01CS-SA     I9 @S9S_MB_2U_LIB.S9S_MB_2U(SCH_1):PAGE41
    U2 BR31 VSS540 SOCKET4677_AZIF0045P001C01CS-SA     I9 @S9S_MB_2U_LIB.S9S_MB_2U(SCH_1):PAGE41
    U2 BR33 VSS541 SOCKET4677_AZIF0045P001C01CS-SA     I9 @S9S_MB_2U_LIB.S9S_MB_2U(SCH_1):PAGE41
    U2  BR9 VSS572 SOCKET4677_AZIF0045P001C01CS-SA     I9 @S9S_MB_2U_LIB.S9S_MB_2U(SCH_1):PAGE41
    U2 AK12 VSS198 SOCKET4677_AZIF0045P001C01CS-SA    I10 @S9S_MB_2U_LIB.S9S_MB_2U(SCH_1):PAGE41
    U2 AK16 VSS199 SOCKET4677_AZIF0045P001C01CS-SA    I10 @S9S_MB_2U_LIB.S9S_MB_2U(SCH_1):PAGE41
    U2 AK18 VSS200 SOCKET4677_AZIF0045P001C01CS-SA    I10 @S9S_MB_2U_LIB.S9S_MB_2U(SCH_1):PAGE41
    U2 AK24 VSS201 SOCKET4677_AZIF0045P001C01CS-SA    I10 @S9S_MB_2U_LIB.S9S_MB_2U(SCH_1):PAGE41
    U2 AK30 VSS202 SOCKET4677_AZIF0045P001C01CS-SA    I10 @S9S_MB_2U_LIB.S9S_MB_2U(SCH_1):PAGE41
    U2 AK36 VSS203 SOCKET4677_AZIF0045P001C01CS-SA    I10 @S9S_MB_2U_LIB.S9S_MB_2U(SCH_1):PAGE41
    U2  AK4 VSS204 SOCKET4677_AZIF0045P001C01CS-SA    I10 @S9S_MB_2U_LIB.S9S_MB_2U(SCH_1):PAGE41
    U2 AK42 VSS205 SOCKET4677_AZIF0045P001C01CS-SA    I10 @S9S_MB_2U_LIB.S9S_MB_2U(SCH_1):PAGE41
    U2 AK49 VSS206 SOCKET4677_AZIF0045P001C01CS-SA    I10 @S9S_MB_2U_LIB.S9S_MB_2U(SCH_1):PAGE41
    U2 AK55 VSS207 SOCKET4677_AZIF0045P001C01CS-SA    I10 @S9S_MB_2U_LIB.S9S_MB_2U(SCH_1):PAGE41
    U2 AK61 VSS208 SOCKET4677_AZIF0045P001C01CS-SA    I10 @S9S_MB_2U_LIB.S9S_MB_2U(SCH_1):PAGE41
    U2 AK67 VSS209 SOCKET4677_AZIF0045P001C01CS-SA    I10 @S9S_MB_2U_LIB.S9S_MB_2U(SCH_1):PAGE41
    U2 AK73 VSS210 SOCKET4677_AZIF0045P001C01CS-SA    I10 @S9S_MB_2U_LIB.S9S_MB_2U(SCH_1):PAGE41
    U2 AK79 VSS211 SOCKET4677_AZIF0045P001C01CS-SA    I10 @S9S_MB_2U_LIB.S9S_MB_2U(SCH_1):PAGE41
    U2  AK8 VSS212 SOCKET4677_AZIF0045P001C01CS-SA    I10 @S9S_MB_2U_LIB.S9S_MB_2U(SCH_1):PAGE41
    U2 AK81 VSS213 SOCKET4677_AZIF0045P001C01CS-SA    I10 @S9S_MB_2U_LIB.S9S_MB_2U(SCH_1):PAGE41
    U2 AK83 VSS214 SOCKET4677_AZIF0045P001C01CS-SA    I10 @S9S_MB_2U_LIB.S9S_MB_2U(SCH_1):PAGE41
    U2 AK87 VSS215 SOCKET4677_AZIF0045P001C01CS-SA    I10 @S9S_MB_2U_LIB.S9S_MB_2U(SCH_1):PAGE41
    U2 AK91 VSS216 SOCKET4677_AZIF0045P001C01CS-SA    I10 @S9S_MB_2U_LIB.S9S_MB_2U(SCH_1):PAGE41
    U2  AL1 VSS217 SOCKET4677_AZIF0045P001C01CS-SA    I10 @S9S_MB_2U_LIB.S9S_MB_2U(SCH_1):PAGE41
    U2 AL13 VSS218 SOCKET4677_AZIF0045P001C01CS-SA    I10 @S9S_MB_2U_LIB.S9S_MB_2U(SCH_1):PAGE41
    U2 AL17 VSS219 SOCKET4677_AZIF0045P001C01CS-SA    I10 @S9S_MB_2U_LIB.S9S_MB_2U(SCH_1):PAGE41
    U2  AL5 VSS220 SOCKET4677_AZIF0045P001C01CS-SA    I10 @S9S_MB_2U_LIB.S9S_MB_2U(SCH_1):PAGE41
    U2 AL52 VSS221 SOCKET4677_AZIF0045P001C01CS-SA    I10 @S9S_MB_2U_LIB.S9S_MB_2U(SCH_1):PAGE41
    U2 AL80 VSS222 SOCKET4677_AZIF0045P001C01CS-SA    I10 @S9S_MB_2U_LIB.S9S_MB_2U(SCH_1):PAGE41
    U2 AL82 VSS223 SOCKET4677_AZIF0045P001C01CS-SA    I10 @S9S_MB_2U_LIB.S9S_MB_2U(SCH_1):PAGE41
    U2 AL84 VSS224 SOCKET4677_AZIF0045P001C01CS-SA    I10 @S9S_MB_2U_LIB.S9S_MB_2U(SCH_1):PAGE41
    U2 AL88 VSS225 SOCKET4677_AZIF0045P001C01CS-SA    I10 @S9S_MB_2U_LIB.S9S_MB_2U(SCH_1):PAGE41
    U2  AL9 VSS226 SOCKET4677_AZIF0045P001C01CS-SA    I10 @S9S_MB_2U_LIB.S9S_MB_2U(SCH_1):PAGE41
    U2 AM12 VSS227 SOCKET4677_AZIF0045P001C01CS-SA    I10 @S9S_MB_2U_LIB.S9S_MB_2U(SCH_1):PAGE41
    U2 AM16 VSS228 SOCKET4677_AZIF0045P001C01CS-SA    I10 @S9S_MB_2U_LIB.S9S_MB_2U(SCH_1):PAGE41
    U2 AM18 VSS229 SOCKET4677_AZIF0045P001C01CS-SA    I10 @S9S_MB_2U_LIB.S9S_MB_2U(SCH_1):PAGE41
    U2 AM20 VSS230 SOCKET4677_AZIF0045P001C01CS-SA    I10 @S9S_MB_2U_LIB.S9S_MB_2U(SCH_1):PAGE41
    U2 AM22 VSS231 SOCKET4677_AZIF0045P001C01CS-SA    I10 @S9S_MB_2U_LIB.S9S_MB_2U(SCH_1):PAGE41
    U2 AM24 VSS232 SOCKET4677_AZIF0045P001C01CS-SA    I10 @S9S_MB_2U_LIB.S9S_MB_2U(SCH_1):PAGE41
    U2 AM26 VSS233 SOCKET4677_AZIF0045P001C01CS-SA    I10 @S9S_MB_2U_LIB.S9S_MB_2U(SCH_1):PAGE41
    U2 AM28 VSS234 SOCKET4677_AZIF0045P001C01CS-SA    I10 @S9S_MB_2U_LIB.S9S_MB_2U(SCH_1):PAGE41
    U2 AM30 VSS235 SOCKET4677_AZIF0045P001C01CS-SA    I10 @S9S_MB_2U_LIB.S9S_MB_2U(SCH_1):PAGE41
    U2 AM32 VSS236 SOCKET4677_AZIF0045P001C01CS-SA    I10 @S9S_MB_2U_LIB.S9S_MB_2U(SCH_1):PAGE41
    U2 AM34 VSS237 SOCKET4677_AZIF0045P001C01CS-SA    I10 @S9S_MB_2U_LIB.S9S_MB_2U(SCH_1):PAGE41
    U2 AM36 VSS238 SOCKET4677_AZIF0045P001C01CS-SA    I10 @S9S_MB_2U_LIB.S9S_MB_2U(SCH_1):PAGE41
    U2 AM38 VSS239 SOCKET4677_AZIF0045P001C01CS-SA    I10 @S9S_MB_2U_LIB.S9S_MB_2U(SCH_1):PAGE41
    U2  AM4 VSS240 SOCKET4677_AZIF0045P001C01CS-SA    I10 @S9S_MB_2U_LIB.S9S_MB_2U(SCH_1):PAGE41
    U2 AM40 VSS241 SOCKET4677_AZIF0045P001C01CS-SA    I10 @S9S_MB_2U_LIB.S9S_MB_2U(SCH_1):PAGE41
    U2 AM42 VSS242 SOCKET4677_AZIF0045P001C01CS-SA    I10 @S9S_MB_2U_LIB.S9S_MB_2U(SCH_1):PAGE41
    U2 AM44 VSS243 SOCKET4677_AZIF0045P001C01CS-SA    I10 @S9S_MB_2U_LIB.S9S_MB_2U(SCH_1):PAGE41
    U2 AM47 VSS244 SOCKET4677_AZIF0045P001C01CS-SA    I10 @S9S_MB_2U_LIB.S9S_MB_2U(SCH_1):PAGE41
    U2 AM49 VSS245 SOCKET4677_AZIF0045P001C01CS-SA    I10 @S9S_MB_2U_LIB.S9S_MB_2U(SCH_1):PAGE41
    U2 AM51 VSS246 SOCKET4677_AZIF0045P001C01CS-SA    I10 @S9S_MB_2U_LIB.S9S_MB_2U(SCH_1):PAGE41
    U2 AM53 VSS247 SOCKET4677_AZIF0045P001C01CS-SA    I10 @S9S_MB_2U_LIB.S9S_MB_2U(SCH_1):PAGE41
    U2 AM55 VSS248 SOCKET4677_AZIF0045P001C01CS-SA    I10 @S9S_MB_2U_LIB.S9S_MB_2U(SCH_1):PAGE41
    U2 AM57 VSS249 SOCKET4677_AZIF0045P001C01CS-SA    I10 @S9S_MB_2U_LIB.S9S_MB_2U(SCH_1):PAGE41
    U2 AM59 VSS250 SOCKET4677_AZIF0045P001C01CS-SA    I10 @S9S_MB_2U_LIB.S9S_MB_2U(SCH_1):PAGE41
    U2 AM61 VSS251 SOCKET4677_AZIF0045P001C01CS-SA    I10 @S9S_MB_2U_LIB.S9S_MB_2U(SCH_1):PAGE41
    U2 AM63 VSS252 SOCKET4677_AZIF0045P001C01CS-SA    I10 @S9S_MB_2U_LIB.S9S_MB_2U(SCH_1):PAGE41
    U2 AM65 VSS253 SOCKET4677_AZIF0045P001C01CS-SA    I10 @S9S_MB_2U_LIB.S9S_MB_2U(SCH_1):PAGE41
    U2 AM67 VSS254 SOCKET4677_AZIF0045P001C01CS-SA    I10 @S9S_MB_2U_LIB.S9S_MB_2U(SCH_1):PAGE41
    U2 AM69 VSS255 SOCKET4677_AZIF0045P001C01CS-SA    I10 @S9S_MB_2U_LIB.S9S_MB_2U(SCH_1):PAGE41
    U2 AM71 VSS256 SOCKET4677_AZIF0045P001C01CS-SA    I10 @S9S_MB_2U_LIB.S9S_MB_2U(SCH_1):PAGE41
    U2 AM73 VSS257 SOCKET4677_AZIF0045P001C01CS-SA    I10 @S9S_MB_2U_LIB.S9S_MB_2U(SCH_1):PAGE41
    U2 AM75 VSS258 SOCKET4677_AZIF0045P001C01CS-SA    I10 @S9S_MB_2U_LIB.S9S_MB_2U(SCH_1):PAGE41
    U2 AM77 VSS259 SOCKET4677_AZIF0045P001C01CS-SA    I10 @S9S_MB_2U_LIB.S9S_MB_2U(SCH_1):PAGE41
    U2  AM8 VSS260 SOCKET4677_AZIF0045P001C01CS-SA    I10 @S9S_MB_2U_LIB.S9S_MB_2U(SCH_1):PAGE41
    U2 AN52 VSS261 SOCKET4677_AZIF0045P001C01CS-SA    I10 @S9S_MB_2U_LIB.S9S_MB_2U(SCH_1):PAGE41
    U2 AN84 VSS262 SOCKET4677_AZIF0045P001C01CS-SA    I10 @S9S_MB_2U_LIB.S9S_MB_2U(SCH_1):PAGE41
    U2 AN88 VSS263 SOCKET4677_AZIF0045P001C01CS-SA    I10 @S9S_MB_2U_LIB.S9S_MB_2U(SCH_1):PAGE41
    U2 AP12 VSS264 SOCKET4677_AZIF0045P001C01CS-SA    I10 @S9S_MB_2U_LIB.S9S_MB_2U(SCH_1):PAGE41
    U2 AP16 VSS265 SOCKET4677_AZIF0045P001C01CS-SA    I10 @S9S_MB_2U_LIB.S9S_MB_2U(SCH_1):PAGE41
    U2 AP18 VSS266 SOCKET4677_AZIF0045P001C01CS-SA    I10 @S9S_MB_2U_LIB.S9S_MB_2U(SCH_1):PAGE41
    U2 AP24 VSS267 SOCKET4677_AZIF0045P001C01CS-SA    I10 @S9S_MB_2U_LIB.S9S_MB_2U(SCH_1):PAGE41
    U2 AP30 VSS268 SOCKET4677_AZIF0045P001C01CS-SA    I10 @S9S_MB_2U_LIB.S9S_MB_2U(SCH_1):PAGE41
    U2 AP36 VSS269 SOCKET4677_AZIF0045P001C01CS-SA    I10 @S9S_MB_2U_LIB.S9S_MB_2U(SCH_1):PAGE41
    U2  AP4 VSS270 SOCKET4677_AZIF0045P001C01CS-SA    I10 @S9S_MB_2U_LIB.S9S_MB_2U(SCH_1):PAGE41
    U2 AP42 VSS271 SOCKET4677_AZIF0045P001C01CS-SA    I10 @S9S_MB_2U_LIB.S9S_MB_2U(SCH_1):PAGE41
    U2 AP49 VSS272 SOCKET4677_AZIF0045P001C01CS-SA    I10 @S9S_MB_2U_LIB.S9S_MB_2U(SCH_1):PAGE41
    U2 AP55 VSS273 SOCKET4677_AZIF0045P001C01CS-SA    I10 @S9S_MB_2U_LIB.S9S_MB_2U(SCH_1):PAGE41
    U2 AP61 VSS274 SOCKET4677_AZIF0045P001C01CS-SA    I10 @S9S_MB_2U_LIB.S9S_MB_2U(SCH_1):PAGE41
    U2 AP67 VSS275 SOCKET4677_AZIF0045P001C01CS-SA    I10 @S9S_MB_2U_LIB.S9S_MB_2U(SCH_1):PAGE41
    U2 AP73 VSS276 SOCKET4677_AZIF0045P001C01CS-SA    I10 @S9S_MB_2U_LIB.S9S_MB_2U(SCH_1):PAGE41
    U2 AP79 VSS277 SOCKET4677_AZIF0045P001C01CS-SA    I10 @S9S_MB_2U_LIB.S9S_MB_2U(SCH_1):PAGE41
    U2  AP8 VSS278 SOCKET4677_AZIF0045P001C01CS-SA    I10 @S9S_MB_2U_LIB.S9S_MB_2U(SCH_1):PAGE41
    U2 AP83 VSS279 SOCKET4677_AZIF0045P001C01CS-SA    I10 @S9S_MB_2U_LIB.S9S_MB_2U(SCH_1):PAGE41
    U2 AP87 VSS280 SOCKET4677_AZIF0045P001C01CS-SA    I10 @S9S_MB_2U_LIB.S9S_MB_2U(SCH_1):PAGE41
    U2 AP91 VSS281 SOCKET4677_AZIF0045P001C01CS-SA    I10 @S9S_MB_2U_LIB.S9S_MB_2U(SCH_1):PAGE41
    U2  AR1 VSS282 SOCKET4677_AZIF0045P001C01CS-SA    I10 @S9S_MB_2U_LIB.S9S_MB_2U(SCH_1):PAGE41
    U2 AR13 VSS283 SOCKET4677_AZIF0045P001C01CS-SA    I10 @S9S_MB_2U_LIB.S9S_MB_2U(SCH_1):PAGE41
    U2 AR19 VSS284 SOCKET4677_AZIF0045P001C01CS-SA    I10 @S9S_MB_2U_LIB.S9S_MB_2U(SCH_1):PAGE41
    U2 AR23 VSS285 SOCKET4677_AZIF0045P001C01CS-SA    I10 @S9S_MB_2U_LIB.S9S_MB_2U(SCH_1):PAGE41
    U2 AR25 VSS286 SOCKET4677_AZIF0045P001C01CS-SA    I10 @S9S_MB_2U_LIB.S9S_MB_2U(SCH_1):PAGE41
    U2 AR29 VSS287 SOCKET4677_AZIF0045P001C01CS-SA    I10 @S9S_MB_2U_LIB.S9S_MB_2U(SCH_1):PAGE41
    U2 AR31 VSS288 SOCKET4677_AZIF0045P001C01CS-SA    I10 @S9S_MB_2U_LIB.S9S_MB_2U(SCH_1):PAGE41
    U2 AR35 VSS289 SOCKET4677_AZIF0045P001C01CS-SA    I10 @S9S_MB_2U_LIB.S9S_MB_2U(SCH_1):PAGE41
    U2 AR37 VSS290 SOCKET4677_AZIF0045P001C01CS-SA    I10 @S9S_MB_2U_LIB.S9S_MB_2U(SCH_1):PAGE41
    U2 AR41 VSS291 SOCKET4677_AZIF0045P001C01CS-SA    I10 @S9S_MB_2U_LIB.S9S_MB_2U(SCH_1):PAGE41
    U2 AR43 VSS292 SOCKET4677_AZIF0045P001C01CS-SA    I10 @S9S_MB_2U_LIB.S9S_MB_2U(SCH_1):PAGE41
    U2 AR48 VSS293 SOCKET4677_AZIF0045P001C01CS-SA    I10 @S9S_MB_2U_LIB.S9S_MB_2U(SCH_1):PAGE41
    U2  AR5 VSS294 SOCKET4677_AZIF0045P001C01CS-SA    I10 @S9S_MB_2U_LIB.S9S_MB_2U(SCH_1):PAGE41
    U2 AR50 VSS295 SOCKET4677_AZIF0045P001C01CS-SA    I10 @S9S_MB_2U_LIB.S9S_MB_2U(SCH_1):PAGE41
    U2 AR54 VSS296 SOCKET4677_AZIF0045P001C01CS-SA    I10 @S9S_MB_2U_LIB.S9S_MB_2U(SCH_1):PAGE41
    U2 AR56 VSS297 SOCKET4677_AZIF0045P001C01CS-SA    I10 @S9S_MB_2U_LIB.S9S_MB_2U(SCH_1):PAGE41
    U2 AR60 VSS298 SOCKET4677_AZIF0045P001C01CS-SA    I10 @S9S_MB_2U_LIB.S9S_MB_2U(SCH_1):PAGE41
    U2 AR62 VSS299 SOCKET4677_AZIF0045P001C01CS-SA    I10 @S9S_MB_2U_LIB.S9S_MB_2U(SCH_1):PAGE41
    U2 AR66 VSS300 SOCKET4677_AZIF0045P001C01CS-SA    I10 @S9S_MB_2U_LIB.S9S_MB_2U(SCH_1):PAGE41
    U2 AR68 VSS301 SOCKET4677_AZIF0045P001C01CS-SA    I10 @S9S_MB_2U_LIB.S9S_MB_2U(SCH_1):PAGE41
    U2 AR72 VSS302 SOCKET4677_AZIF0045P001C01CS-SA    I10 @S9S_MB_2U_LIB.S9S_MB_2U(SCH_1):PAGE41
    U2 AR74 VSS303 SOCKET4677_AZIF0045P001C01CS-SA    I10 @S9S_MB_2U_LIB.S9S_MB_2U(SCH_1):PAGE41
    U2 AR78 VSS304 SOCKET4677_AZIF0045P001C01CS-SA    I10 @S9S_MB_2U_LIB.S9S_MB_2U(SCH_1):PAGE41
    U2 AR82 VSS305 SOCKET4677_AZIF0045P001C01CS-SA    I10 @S9S_MB_2U_LIB.S9S_MB_2U(SCH_1):PAGE41
    U2 AR84 VSS306 SOCKET4677_AZIF0045P001C01CS-SA    I10 @S9S_MB_2U_LIB.S9S_MB_2U(SCH_1):PAGE41
    U2 AR88 VSS307 SOCKET4677_AZIF0045P001C01CS-SA    I10 @S9S_MB_2U_LIB.S9S_MB_2U(SCH_1):PAGE41
    U2  AR9 VSS308 SOCKET4677_AZIF0045P001C01CS-SA    I10 @S9S_MB_2U_LIB.S9S_MB_2U(SCH_1):PAGE41
    U2 AT12 VSS309 SOCKET4677_AZIF0045P001C01CS-SA    I10 @S9S_MB_2U_LIB.S9S_MB_2U(SCH_1):PAGE41
    U2 AT16 VSS310 SOCKET4677_AZIF0045P001C01CS-SA    I10 @S9S_MB_2U_LIB.S9S_MB_2U(SCH_1):PAGE41
    U2 AT20 VSS311 SOCKET4677_AZIF0045P001C01CS-SA    I10 @S9S_MB_2U_LIB.S9S_MB_2U(SCH_1):PAGE41
    U2 AT22 VSS312 SOCKET4677_AZIF0045P001C01CS-SA    I10 @S9S_MB_2U_LIB.S9S_MB_2U(SCH_1):PAGE41
    U2 AT26 VSS313 SOCKET4677_AZIF0045P001C01CS-SA    I10 @S9S_MB_2U_LIB.S9S_MB_2U(SCH_1):PAGE41
    U2 AT28 VSS314 SOCKET4677_AZIF0045P001C01CS-SA    I10 @S9S_MB_2U_LIB.S9S_MB_2U(SCH_1):PAGE41
    U2 AT32 VSS315 SOCKET4677_AZIF0045P001C01CS-SA    I10 @S9S_MB_2U_LIB.S9S_MB_2U(SCH_1):PAGE41
    U2 AT34 VSS316 SOCKET4677_AZIF0045P001C01CS-SA    I10 @S9S_MB_2U_LIB.S9S_MB_2U(SCH_1):PAGE41
    U2 AT38 VSS317 SOCKET4677_AZIF0045P001C01CS-SA    I10 @S9S_MB_2U_LIB.S9S_MB_2U(SCH_1):PAGE41
    U2  AT4 VSS318 SOCKET4677_AZIF0045P001C01CS-SA    I10 @S9S_MB_2U_LIB.S9S_MB_2U(SCH_1):PAGE41
    U2 AT40 VSS319 SOCKET4677_AZIF0045P001C01CS-SA    I10 @S9S_MB_2U_LIB.S9S_MB_2U(SCH_1):PAGE41
    U2 AT44 VSS320 SOCKET4677_AZIF0045P001C01CS-SA    I10 @S9S_MB_2U_LIB.S9S_MB_2U(SCH_1):PAGE41
    U2 AT51 VSS321 SOCKET4677_AZIF0045P001C01CS-SA    I10 @S9S_MB_2U_LIB.S9S_MB_2U(SCH_1):PAGE41
    U2 AT53 VSS322 SOCKET4677_AZIF0045P001C01CS-SA    I10 @S9S_MB_2U_LIB.S9S_MB_2U(SCH_1):PAGE41
    U2 AT57 VSS323 SOCKET4677_AZIF0045P001C01CS-SA    I10 @S9S_MB_2U_LIB.S9S_MB_2U(SCH_1):PAGE41
    U2 AT59 VSS324 SOCKET4677_AZIF0045P001C01CS-SA    I10 @S9S_MB_2U_LIB.S9S_MB_2U(SCH_1):PAGE41
    U2 AT63 VSS325 SOCKET4677_AZIF0045P001C01CS-SA    I10 @S9S_MB_2U_LIB.S9S_MB_2U(SCH_1):PAGE41
    U2 AT65 VSS326 SOCKET4677_AZIF0045P001C01CS-SA    I10 @S9S_MB_2U_LIB.S9S_MB_2U(SCH_1):PAGE41
    U2 AT69 VSS327 SOCKET4677_AZIF0045P001C01CS-SA    I10 @S9S_MB_2U_LIB.S9S_MB_2U(SCH_1):PAGE41
    U2 AT71 VSS328 SOCKET4677_AZIF0045P001C01CS-SA    I10 @S9S_MB_2U_LIB.S9S_MB_2U(SCH_1):PAGE41
    U2 AT75 VSS329 SOCKET4677_AZIF0045P001C01CS-SA    I10 @S9S_MB_2U_LIB.S9S_MB_2U(SCH_1):PAGE41
    U2 AT77 VSS330 SOCKET4677_AZIF0045P001C01CS-SA    I10 @S9S_MB_2U_LIB.S9S_MB_2U(SCH_1):PAGE41
    U2 AT79 VSS331 SOCKET4677_AZIF0045P001C01CS-SA    I10 @S9S_MB_2U_LIB.S9S_MB_2U(SCH_1):PAGE41
    U2  AT8 VSS332 SOCKET4677_AZIF0045P001C01CS-SA    I10 @S9S_MB_2U_LIB.S9S_MB_2U(SCH_1):PAGE41
    U2 AU27 VSS333 SOCKET4677_AZIF0045P001C01CS-SA    I10 @S9S_MB_2U_LIB.S9S_MB_2U(SCH_1):PAGE41
    U2 AU31 VSS334 SOCKET4677_AZIF0045P001C01CS-SA    I10 @S9S_MB_2U_LIB.S9S_MB_2U(SCH_1):PAGE41
    U2 AU37 VSS335 SOCKET4677_AZIF0045P001C01CS-SA    I10 @S9S_MB_2U_LIB.S9S_MB_2U(SCH_1):PAGE41
    U2 AU39 VSS336 SOCKET4677_AZIF0045P001C01CS-SA    I10 @S9S_MB_2U_LIB.S9S_MB_2U(SCH_1):PAGE41
    U2 AU41 VSS337 SOCKET4677_AZIF0045P001C01CS-SA    I10 @S9S_MB_2U_LIB.S9S_MB_2U(SCH_1):PAGE41
    U2 AU45 VSS338 SOCKET4677_AZIF0045P001C01CS-SA    I10 @S9S_MB_2U_LIB.S9S_MB_2U(SCH_1):PAGE41
    U2 AU48 VSS339 SOCKET4677_AZIF0045P001C01CS-SA    I10 @S9S_MB_2U_LIB.S9S_MB_2U(SCH_1):PAGE41
    U2 AU70 VSS340 SOCKET4677_AZIF0045P001C01CS-SA    I10 @S9S_MB_2U_LIB.S9S_MB_2U(SCH_1):PAGE41
    U2 AU72 VSS341 SOCKET4677_AZIF0045P001C01CS-SA    I10 @S9S_MB_2U_LIB.S9S_MB_2U(SCH_1):PAGE41
    U2 AU74 VSS342 SOCKET4677_AZIF0045P001C01CS-SA    I10 @S9S_MB_2U_LIB.S9S_MB_2U(SCH_1):PAGE41
    U2 AU76 VSS343 SOCKET4677_AZIF0045P001C01CS-SA    I10 @S9S_MB_2U_LIB.S9S_MB_2U(SCH_1):PAGE41
    U2 AU80 VSS344 SOCKET4677_AZIF0045P001C01CS-SA    I10 @S9S_MB_2U_LIB.S9S_MB_2U(SCH_1):PAGE41
    U2 AU84 VSS345 SOCKET4677_AZIF0045P001C01CS-SA    I10 @S9S_MB_2U_LIB.S9S_MB_2U(SCH_1):PAGE41
    U2 AU88 VSS346 SOCKET4677_AZIF0045P001C01CS-SA    I10 @S9S_MB_2U_LIB.S9S_MB_2U(SCH_1):PAGE41
    U2 AV12 VSS347 SOCKET4677_AZIF0045P001C01CS-SA    I10 @S9S_MB_2U_LIB.S9S_MB_2U(SCH_1):PAGE41
    U2 AV16 VSS348 SOCKET4677_AZIF0045P001C01CS-SA    I10 @S9S_MB_2U_LIB.S9S_MB_2U(SCH_1):PAGE41
    U2  AV4 VSS349 SOCKET4677_AZIF0045P001C01CS-SA    I10 @S9S_MB_2U_LIB.S9S_MB_2U(SCH_1):PAGE41
    U2 AV77 VSS350 SOCKET4677_AZIF0045P001C01CS-SA    I10 @S9S_MB_2U_LIB.S9S_MB_2U(SCH_1):PAGE41
    U2  AV8 VSS351 SOCKET4677_AZIF0045P001C01CS-SA    I10 @S9S_MB_2U_LIB.S9S_MB_2U(SCH_1):PAGE41
    U2 AV87 VSS352 SOCKET4677_AZIF0045P001C01CS-SA    I10 @S9S_MB_2U_LIB.S9S_MB_2U(SCH_1):PAGE41
    U2 AV91 VSS353 SOCKET4677_AZIF0045P001C01CS-SA    I10 @S9S_MB_2U_LIB.S9S_MB_2U(SCH_1):PAGE41
    U2  AW1 VSS354 SOCKET4677_AZIF0045P001C01CS-SA    I10 @S9S_MB_2U_LIB.S9S_MB_2U(SCH_1):PAGE41
    U2 AW13 VSS355 SOCKET4677_AZIF0045P001C01CS-SA    I10 @S9S_MB_2U_LIB.S9S_MB_2U(SCH_1):PAGE41
    U2  AW5 VSS359 SOCKET4677_AZIF0045P001C01CS-SA    I10 @S9S_MB_2U_LIB.S9S_MB_2U(SCH_1):PAGE41
    U2  AW9 VSS368 SOCKET4677_AZIF0045P001C01CS-SA    I10 @S9S_MB_2U_LIB.S9S_MB_2U(SCH_1):PAGE41
    U2 AA82  VSS38 SOCKET4677_AZIF0045P001C01CS-SA    I11 @S9S_MB_2U_LIB.S9S_MB_2U(SCH_1):PAGE41
    U2 AA84  VSS39 SOCKET4677_AZIF0045P001C01CS-SA    I11 @S9S_MB_2U_LIB.S9S_MB_2U(SCH_1):PAGE41
    U2 AA88  VSS40 SOCKET4677_AZIF0045P001C01CS-SA    I11 @S9S_MB_2U_LIB.S9S_MB_2U(SCH_1):PAGE41
    U2 AB12  VSS41 SOCKET4677_AZIF0045P001C01CS-SA    I11 @S9S_MB_2U_LIB.S9S_MB_2U(SCH_1):PAGE41
    U2 AB16  VSS42 SOCKET4677_AZIF0045P001C01CS-SA    I11 @S9S_MB_2U_LIB.S9S_MB_2U(SCH_1):PAGE41
    U2 AB20  VSS43 SOCKET4677_AZIF0045P001C01CS-SA    I11 @S9S_MB_2U_LIB.S9S_MB_2U(SCH_1):PAGE41
    U2 AB22  VSS44 SOCKET4677_AZIF0045P001C01CS-SA    I11 @S9S_MB_2U_LIB.S9S_MB_2U(SCH_1):PAGE41
    U2 AB26  VSS45 SOCKET4677_AZIF0045P001C01CS-SA    I11 @S9S_MB_2U_LIB.S9S_MB_2U(SCH_1):PAGE41
    U2 AB28  VSS46 SOCKET4677_AZIF0045P001C01CS-SA    I11 @S9S_MB_2U_LIB.S9S_MB_2U(SCH_1):PAGE41
    U2 AB32  VSS47 SOCKET4677_AZIF0045P001C01CS-SA    I11 @S9S_MB_2U_LIB.S9S_MB_2U(SCH_1):PAGE41
    U2 AB34  VSS48 SOCKET4677_AZIF0045P001C01CS-SA    I11 @S9S_MB_2U_LIB.S9S_MB_2U(SCH_1):PAGE41
    U2 AB38  VSS49 SOCKET4677_AZIF0045P001C01CS-SA    I11 @S9S_MB_2U_LIB.S9S_MB_2U(SCH_1):PAGE41
    U2  AB4  VSS50 SOCKET4677_AZIF0045P001C01CS-SA    I11 @S9S_MB_2U_LIB.S9S_MB_2U(SCH_1):PAGE41
    U2 AB40  VSS51 SOCKET4677_AZIF0045P001C01CS-SA    I11 @S9S_MB_2U_LIB.S9S_MB_2U(SCH_1):PAGE41
    U2 AB44  VSS52 SOCKET4677_AZIF0045P001C01CS-SA    I11 @S9S_MB_2U_LIB.S9S_MB_2U(SCH_1):PAGE41
    U2 AB47  VSS53 SOCKET4677_AZIF0045P001C01CS-SA    I11 @S9S_MB_2U_LIB.S9S_MB_2U(SCH_1):PAGE41
    U2 AB51  VSS54 SOCKET4677_AZIF0045P001C01CS-SA    I11 @S9S_MB_2U_LIB.S9S_MB_2U(SCH_1):PAGE41
    U2 AB53  VSS55 SOCKET4677_AZIF0045P001C01CS-SA    I11 @S9S_MB_2U_LIB.S9S_MB_2U(SCH_1):PAGE41
    U2 AB57  VSS56 SOCKET4677_AZIF0045P001C01CS-SA    I11 @S9S_MB_2U_LIB.S9S_MB_2U(SCH_1):PAGE41
    U2 AB59  VSS57 SOCKET4677_AZIF0045P001C01CS-SA    I11 @S9S_MB_2U_LIB.S9S_MB_2U(SCH_1):PAGE41
    U2 AB63  VSS58 SOCKET4677_AZIF0045P001C01CS-SA    I11 @S9S_MB_2U_LIB.S9S_MB_2U(SCH_1):PAGE41
    U2 AB65  VSS59 SOCKET4677_AZIF0045P001C01CS-SA    I11 @S9S_MB_2U_LIB.S9S_MB_2U(SCH_1):PAGE41
    U2 AB69  VSS60 SOCKET4677_AZIF0045P001C01CS-SA    I11 @S9S_MB_2U_LIB.S9S_MB_2U(SCH_1):PAGE41
    U2 AB71  VSS61 SOCKET4677_AZIF0045P001C01CS-SA    I11 @S9S_MB_2U_LIB.S9S_MB_2U(SCH_1):PAGE41
    U2 AB75  VSS62 SOCKET4677_AZIF0045P001C01CS-SA    I11 @S9S_MB_2U_LIB.S9S_MB_2U(SCH_1):PAGE41
    U2 AB77  VSS63 SOCKET4677_AZIF0045P001C01CS-SA    I11 @S9S_MB_2U_LIB.S9S_MB_2U(SCH_1):PAGE41
    U2 AB79  VSS64 SOCKET4677_AZIF0045P001C01CS-SA    I11 @S9S_MB_2U_LIB.S9S_MB_2U(SCH_1):PAGE41
    U2  AB8  VSS65 SOCKET4677_AZIF0045P001C01CS-SA    I11 @S9S_MB_2U_LIB.S9S_MB_2U(SCH_1):PAGE41
    U2 AB81  VSS66 SOCKET4677_AZIF0045P001C01CS-SA    I11 @S9S_MB_2U_LIB.S9S_MB_2U(SCH_1):PAGE41
    U2 AB83  VSS67 SOCKET4677_AZIF0045P001C01CS-SA    I11 @S9S_MB_2U_LIB.S9S_MB_2U(SCH_1):PAGE41
    U2 AB87  VSS68 SOCKET4677_AZIF0045P001C01CS-SA    I11 @S9S_MB_2U_LIB.S9S_MB_2U(SCH_1):PAGE41
    U2 AB91  VSS69 SOCKET4677_AZIF0045P001C01CS-SA    I11 @S9S_MB_2U_LIB.S9S_MB_2U(SCH_1):PAGE41
    U2  AC1  VSS70 SOCKET4677_AZIF0045P001C01CS-SA    I11 @S9S_MB_2U_LIB.S9S_MB_2U(SCH_1):PAGE41
    U2 AC13  VSS71 SOCKET4677_AZIF0045P001C01CS-SA    I11 @S9S_MB_2U_LIB.S9S_MB_2U(SCH_1):PAGE41
    U2 AC21  VSS72 SOCKET4677_AZIF0045P001C01CS-SA    I11 @S9S_MB_2U_LIB.S9S_MB_2U(SCH_1):PAGE41
    U2 AC27  VSS73 SOCKET4677_AZIF0045P001C01CS-SA    I11 @S9S_MB_2U_LIB.S9S_MB_2U(SCH_1):PAGE41
    U2 AC33  VSS74 SOCKET4677_AZIF0045P001C01CS-SA    I11 @S9S_MB_2U_LIB.S9S_MB_2U(SCH_1):PAGE41
    U2 AC39  VSS75 SOCKET4677_AZIF0045P001C01CS-SA    I11 @S9S_MB_2U_LIB.S9S_MB_2U(SCH_1):PAGE41
    U2 AC45  VSS76 SOCKET4677_AZIF0045P001C01CS-SA    I11 @S9S_MB_2U_LIB.S9S_MB_2U(SCH_1):PAGE41
    U2  AC5  VSS77 SOCKET4677_AZIF0045P001C01CS-SA    I11 @S9S_MB_2U_LIB.S9S_MB_2U(SCH_1):PAGE41
    U2 AC52  VSS78 SOCKET4677_AZIF0045P001C01CS-SA    I11 @S9S_MB_2U_LIB.S9S_MB_2U(SCH_1):PAGE41
    U2 AC58  VSS79 SOCKET4677_AZIF0045P001C01CS-SA    I11 @S9S_MB_2U_LIB.S9S_MB_2U(SCH_1):PAGE41
    U2 AC64  VSS80 SOCKET4677_AZIF0045P001C01CS-SA    I11 @S9S_MB_2U_LIB.S9S_MB_2U(SCH_1):PAGE41
    U2 AC70  VSS81 SOCKET4677_AZIF0045P001C01CS-SA    I11 @S9S_MB_2U_LIB.S9S_MB_2U(SCH_1):PAGE41
    U2 AC76  VSS82 SOCKET4677_AZIF0045P001C01CS-SA    I11 @S9S_MB_2U_LIB.S9S_MB_2U(SCH_1):PAGE41
    U2 AC84  VSS83 SOCKET4677_AZIF0045P001C01CS-SA    I11 @S9S_MB_2U_LIB.S9S_MB_2U(SCH_1):PAGE41
    U2 AC88  VSS84 SOCKET4677_AZIF0045P001C01CS-SA    I11 @S9S_MB_2U_LIB.S9S_MB_2U(SCH_1):PAGE41
    U2  AC9  VSS85 SOCKET4677_AZIF0045P001C01CS-SA    I11 @S9S_MB_2U_LIB.S9S_MB_2U(SCH_1):PAGE41
    U2 AD12  VSS86 SOCKET4677_AZIF0045P001C01CS-SA    I11 @S9S_MB_2U_LIB.S9S_MB_2U(SCH_1):PAGE41
    U2 AD16  VSS87 SOCKET4677_AZIF0045P001C01CS-SA    I11 @S9S_MB_2U_LIB.S9S_MB_2U(SCH_1):PAGE41
    U2  AD4  VSS88 SOCKET4677_AZIF0045P001C01CS-SA    I11 @S9S_MB_2U_LIB.S9S_MB_2U(SCH_1):PAGE41
    U2 AD42  VSS89 SOCKET4677_AZIF0045P001C01CS-SA    I11 @S9S_MB_2U_LIB.S9S_MB_2U(SCH_1):PAGE41
    U2 AD79  VSS90 SOCKET4677_AZIF0045P001C01CS-SA    I11 @S9S_MB_2U_LIB.S9S_MB_2U(SCH_1):PAGE41
    U2  AD8  VSS91 SOCKET4677_AZIF0045P001C01CS-SA    I11 @S9S_MB_2U_LIB.S9S_MB_2U(SCH_1):PAGE41
    U2 AD83  VSS92 SOCKET4677_AZIF0045P001C01CS-SA    I11 @S9S_MB_2U_LIB.S9S_MB_2U(SCH_1):PAGE41
    U2 AE17  VSS93 SOCKET4677_AZIF0045P001C01CS-SA    I11 @S9S_MB_2U_LIB.S9S_MB_2U(SCH_1):PAGE41
    U2 AE19  VSS94 SOCKET4677_AZIF0045P001C01CS-SA    I11 @S9S_MB_2U_LIB.S9S_MB_2U(SCH_1):PAGE41
    U2 AE21  VSS95 SOCKET4677_AZIF0045P001C01CS-SA    I11 @S9S_MB_2U_LIB.S9S_MB_2U(SCH_1):PAGE41
    U2 AE23  VSS96 SOCKET4677_AZIF0045P001C01CS-SA    I11 @S9S_MB_2U_LIB.S9S_MB_2U(SCH_1):PAGE41
    U2 AE25  VSS97 SOCKET4677_AZIF0045P001C01CS-SA    I11 @S9S_MB_2U_LIB.S9S_MB_2U(SCH_1):PAGE41
    U2 AE27  VSS98 SOCKET4677_AZIF0045P001C01CS-SA    I11 @S9S_MB_2U_LIB.S9S_MB_2U(SCH_1):PAGE41
    U2 AE29  VSS99 SOCKET4677_AZIF0045P001C01CS-SA    I11 @S9S_MB_2U_LIB.S9S_MB_2U(SCH_1):PAGE41
    U2 AE31 VSS100 SOCKET4677_AZIF0045P001C01CS-SA    I11 @S9S_MB_2U_LIB.S9S_MB_2U(SCH_1):PAGE41
    U2 AE33 VSS101 SOCKET4677_AZIF0045P001C01CS-SA    I11 @S9S_MB_2U_LIB.S9S_MB_2U(SCH_1):PAGE41
    U2 AE35 VSS102 SOCKET4677_AZIF0045P001C01CS-SA    I11 @S9S_MB_2U_LIB.S9S_MB_2U(SCH_1):PAGE41
    U2 AE37 VSS103 SOCKET4677_AZIF0045P001C01CS-SA    I11 @S9S_MB_2U_LIB.S9S_MB_2U(SCH_1):PAGE41
    U2 AE39 VSS104 SOCKET4677_AZIF0045P001C01CS-SA    I11 @S9S_MB_2U_LIB.S9S_MB_2U(SCH_1):PAGE41
    U2 AE41 VSS105 SOCKET4677_AZIF0045P001C01CS-SA    I11 @S9S_MB_2U_LIB.S9S_MB_2U(SCH_1):PAGE41
    U2 AE43 VSS106 SOCKET4677_AZIF0045P001C01CS-SA    I11 @S9S_MB_2U_LIB.S9S_MB_2U(SCH_1):PAGE41
    U2 AE45 VSS107 SOCKET4677_AZIF0045P001C01CS-SA    I11 @S9S_MB_2U_LIB.S9S_MB_2U(SCH_1):PAGE41
    U2 AE48 VSS108 SOCKET4677_AZIF0045P001C01CS-SA    I11 @S9S_MB_2U_LIB.S9S_MB_2U(SCH_1):PAGE41
    U2 AE50 VSS109 SOCKET4677_AZIF0045P001C01CS-SA    I11 @S9S_MB_2U_LIB.S9S_MB_2U(SCH_1):PAGE41
    U2 AE52 VSS110 SOCKET4677_AZIF0045P001C01CS-SA    I11 @S9S_MB_2U_LIB.S9S_MB_2U(SCH_1):PAGE41
    U2 AE54 VSS111 SOCKET4677_AZIF0045P001C01CS-SA    I11 @S9S_MB_2U_LIB.S9S_MB_2U(SCH_1):PAGE41
    U2 AE56 VSS112 SOCKET4677_AZIF0045P001C01CS-SA    I11 @S9S_MB_2U_LIB.S9S_MB_2U(SCH_1):PAGE41
    U2 AE58 VSS113 SOCKET4677_AZIF0045P001C01CS-SA    I11 @S9S_MB_2U_LIB.S9S_MB_2U(SCH_1):PAGE41
    U2 AE60 VSS114 SOCKET4677_AZIF0045P001C01CS-SA    I11 @S9S_MB_2U_LIB.S9S_MB_2U(SCH_1):PAGE41
    U2 AE62 VSS115 SOCKET4677_AZIF0045P001C01CS-SA    I11 @S9S_MB_2U_LIB.S9S_MB_2U(SCH_1):PAGE41
    U2 AE64 VSS116 SOCKET4677_AZIF0045P001C01CS-SA    I11 @S9S_MB_2U_LIB.S9S_MB_2U(SCH_1):PAGE41
    U2 AE66 VSS117 SOCKET4677_AZIF0045P001C01CS-SA    I11 @S9S_MB_2U_LIB.S9S_MB_2U(SCH_1):PAGE41
    U2 AE68 VSS118 SOCKET4677_AZIF0045P001C01CS-SA    I11 @S9S_MB_2U_LIB.S9S_MB_2U(SCH_1):PAGE41
    U2 AE70 VSS119 SOCKET4677_AZIF0045P001C01CS-SA    I11 @S9S_MB_2U_LIB.S9S_MB_2U(SCH_1):PAGE41
    U2 AE72 VSS120 SOCKET4677_AZIF0045P001C01CS-SA    I11 @S9S_MB_2U_LIB.S9S_MB_2U(SCH_1):PAGE41
    U2 AE74 VSS121 SOCKET4677_AZIF0045P001C01CS-SA    I11 @S9S_MB_2U_LIB.S9S_MB_2U(SCH_1):PAGE41
    U2 AE76 VSS122 SOCKET4677_AZIF0045P001C01CS-SA    I11 @S9S_MB_2U_LIB.S9S_MB_2U(SCH_1):PAGE41
    U2 AE78 VSS123 SOCKET4677_AZIF0045P001C01CS-SA    I11 @S9S_MB_2U_LIB.S9S_MB_2U(SCH_1):PAGE41
    U2 AE84 VSS124 SOCKET4677_AZIF0045P001C01CS-SA    I11 @S9S_MB_2U_LIB.S9S_MB_2U(SCH_1):PAGE41
    U2 AE88 VSS125 SOCKET4677_AZIF0045P001C01CS-SA    I11 @S9S_MB_2U_LIB.S9S_MB_2U(SCH_1):PAGE41
    U2 AF12 VSS126 SOCKET4677_AZIF0045P001C01CS-SA    I11 @S9S_MB_2U_LIB.S9S_MB_2U(SCH_1):PAGE41
    U2 AF16 VSS127 SOCKET4677_AZIF0045P001C01CS-SA    I11 @S9S_MB_2U_LIB.S9S_MB_2U(SCH_1):PAGE41
    U2  AF4 VSS128 SOCKET4677_AZIF0045P001C01CS-SA    I11 @S9S_MB_2U_LIB.S9S_MB_2U(SCH_1):PAGE41
    U2 AF42 VSS129 SOCKET4677_AZIF0045P001C01CS-SA    I11 @S9S_MB_2U_LIB.S9S_MB_2U(SCH_1):PAGE41
    U2  AF8 VSS130 SOCKET4677_AZIF0045P001C01CS-SA    I11 @S9S_MB_2U_LIB.S9S_MB_2U(SCH_1):PAGE41
    U2 AF81 VSS131 SOCKET4677_AZIF0045P001C01CS-SA    I11 @S9S_MB_2U_LIB.S9S_MB_2U(SCH_1):PAGE41
    U2 AF87 VSS132 SOCKET4677_AZIF0045P001C01CS-SA    I11 @S9S_MB_2U_LIB.S9S_MB_2U(SCH_1):PAGE41
    U2 AF91 VSS133 SOCKET4677_AZIF0045P001C01CS-SA    I11 @S9S_MB_2U_LIB.S9S_MB_2U(SCH_1):PAGE41
    U2  AG1 VSS134 SOCKET4677_AZIF0045P001C01CS-SA    I11 @S9S_MB_2U_LIB.S9S_MB_2U(SCH_1):PAGE41
    U2 AG13 VSS135 SOCKET4677_AZIF0045P001C01CS-SA    I11 @S9S_MB_2U_LIB.S9S_MB_2U(SCH_1):PAGE41
    U2 AG21 VSS136 SOCKET4677_AZIF0045P001C01CS-SA    I11 @S9S_MB_2U_LIB.S9S_MB_2U(SCH_1):PAGE41
    U2 AG27 VSS137 SOCKET4677_AZIF0045P001C01CS-SA    I11 @S9S_MB_2U_LIB.S9S_MB_2U(SCH_1):PAGE41
    U2 AG33 VSS138 SOCKET4677_AZIF0045P001C01CS-SA    I11 @S9S_MB_2U_LIB.S9S_MB_2U(SCH_1):PAGE41
    U2 AG39 VSS139 SOCKET4677_AZIF0045P001C01CS-SA    I11 @S9S_MB_2U_LIB.S9S_MB_2U(SCH_1):PAGE41
    U2 AG45 VSS140 SOCKET4677_AZIF0045P001C01CS-SA    I11 @S9S_MB_2U_LIB.S9S_MB_2U(SCH_1):PAGE41
    U2  AG5 VSS141 SOCKET4677_AZIF0045P001C01CS-SA    I11 @S9S_MB_2U_LIB.S9S_MB_2U(SCH_1):PAGE41
    U2 AG52 VSS142 SOCKET4677_AZIF0045P001C01CS-SA    I11 @S9S_MB_2U_LIB.S9S_MB_2U(SCH_1):PAGE41
    U2 AG58 VSS143 SOCKET4677_AZIF0045P001C01CS-SA    I11 @S9S_MB_2U_LIB.S9S_MB_2U(SCH_1):PAGE41
    U2 AG64 VSS144 SOCKET4677_AZIF0045P001C01CS-SA    I11 @S9S_MB_2U_LIB.S9S_MB_2U(SCH_1):PAGE41
    U2 AG70 VSS145 SOCKET4677_AZIF0045P001C01CS-SA    I11 @S9S_MB_2U_LIB.S9S_MB_2U(SCH_1):PAGE41
    U2 AG76 VSS146 SOCKET4677_AZIF0045P001C01CS-SA    I11 @S9S_MB_2U_LIB.S9S_MB_2U(SCH_1):PAGE41
    U2 AG84 VSS147 SOCKET4677_AZIF0045P001C01CS-SA    I11 @S9S_MB_2U_LIB.S9S_MB_2U(SCH_1):PAGE41
    U2 AG88 VSS148 SOCKET4677_AZIF0045P001C01CS-SA    I11 @S9S_MB_2U_LIB.S9S_MB_2U(SCH_1):PAGE41
    U2  AG9 VSS149 SOCKET4677_AZIF0045P001C01CS-SA    I11 @S9S_MB_2U_LIB.S9S_MB_2U(SCH_1):PAGE41
    U2 AH12 VSS150 SOCKET4677_AZIF0045P001C01CS-SA    I11 @S9S_MB_2U_LIB.S9S_MB_2U(SCH_1):PAGE41
    U2 AH16 VSS151 SOCKET4677_AZIF0045P001C01CS-SA    I11 @S9S_MB_2U_LIB.S9S_MB_2U(SCH_1):PAGE41
    U2 AH20 VSS152 SOCKET4677_AZIF0045P001C01CS-SA    I11 @S9S_MB_2U_LIB.S9S_MB_2U(SCH_1):PAGE41
    U2 AH22 VSS153 SOCKET4677_AZIF0045P001C01CS-SA    I11 @S9S_MB_2U_LIB.S9S_MB_2U(SCH_1):PAGE41
    U2 AH26 VSS154 SOCKET4677_AZIF0045P001C01CS-SA    I11 @S9S_MB_2U_LIB.S9S_MB_2U(SCH_1):PAGE41
    U2 AH28 VSS155 SOCKET4677_AZIF0045P001C01CS-SA    I11 @S9S_MB_2U_LIB.S9S_MB_2U(SCH_1):PAGE41
    U2 AH32 VSS156 SOCKET4677_AZIF0045P001C01CS-SA    I11 @S9S_MB_2U_LIB.S9S_MB_2U(SCH_1):PAGE41
    U2 AH34 VSS157 SOCKET4677_AZIF0045P001C01CS-SA    I11 @S9S_MB_2U_LIB.S9S_MB_2U(SCH_1):PAGE41
    U2 AH38 VSS158 SOCKET4677_AZIF0045P001C01CS-SA    I11 @S9S_MB_2U_LIB.S9S_MB_2U(SCH_1):PAGE41
    U2  AH4 VSS159 SOCKET4677_AZIF0045P001C01CS-SA    I11 @S9S_MB_2U_LIB.S9S_MB_2U(SCH_1):PAGE41
    U2 AH40 VSS160 SOCKET4677_AZIF0045P001C01CS-SA    I11 @S9S_MB_2U_LIB.S9S_MB_2U(SCH_1):PAGE41
    U2 AH44 VSS161 SOCKET4677_AZIF0045P001C01CS-SA    I11 @S9S_MB_2U_LIB.S9S_MB_2U(SCH_1):PAGE41
    U2 AH47 VSS162 SOCKET4677_AZIF0045P001C01CS-SA    I11 @S9S_MB_2U_LIB.S9S_MB_2U(SCH_1):PAGE41
    U2 AH51 VSS163 SOCKET4677_AZIF0045P001C01CS-SA    I11 @S9S_MB_2U_LIB.S9S_MB_2U(SCH_1):PAGE41
    U2 AH53 VSS164 SOCKET4677_AZIF0045P001C01CS-SA    I11 @S9S_MB_2U_LIB.S9S_MB_2U(SCH_1):PAGE41
    U2 AH57 VSS165 SOCKET4677_AZIF0045P001C01CS-SA    I11 @S9S_MB_2U_LIB.S9S_MB_2U(SCH_1):PAGE41
    U2 AH59 VSS166 SOCKET4677_AZIF0045P001C01CS-SA    I11 @S9S_MB_2U_LIB.S9S_MB_2U(SCH_1):PAGE41
    U2 AH63 VSS167 SOCKET4677_AZIF0045P001C01CS-SA    I11 @S9S_MB_2U_LIB.S9S_MB_2U(SCH_1):PAGE41
    U2 AH65 VSS168 SOCKET4677_AZIF0045P001C01CS-SA    I11 @S9S_MB_2U_LIB.S9S_MB_2U(SCH_1):PAGE41
    U2 AH69 VSS169 SOCKET4677_AZIF0045P001C01CS-SA    I11 @S9S_MB_2U_LIB.S9S_MB_2U(SCH_1):PAGE41
    U2 AH71 VSS170 SOCKET4677_AZIF0045P001C01CS-SA    I11 @S9S_MB_2U_LIB.S9S_MB_2U(SCH_1):PAGE41
    U2 AH75 VSS171 SOCKET4677_AZIF0045P001C01CS-SA    I11 @S9S_MB_2U_LIB.S9S_MB_2U(SCH_1):PAGE41
    U2 AH77 VSS172 SOCKET4677_AZIF0045P001C01CS-SA    I11 @S9S_MB_2U_LIB.S9S_MB_2U(SCH_1):PAGE41
    U2 AH79 VSS173 SOCKET4677_AZIF0045P001C01CS-SA    I11 @S9S_MB_2U_LIB.S9S_MB_2U(SCH_1):PAGE41
    U2  AH8 VSS174 SOCKET4677_AZIF0045P001C01CS-SA    I11 @S9S_MB_2U_LIB.S9S_MB_2U(SCH_1):PAGE41
    U2 AH83 VSS175 SOCKET4677_AZIF0045P001C01CS-SA    I11 @S9S_MB_2U_LIB.S9S_MB_2U(SCH_1):PAGE41
    U2 AJ19 VSS176 SOCKET4677_AZIF0045P001C01CS-SA    I11 @S9S_MB_2U_LIB.S9S_MB_2U(SCH_1):PAGE41
    U2 AJ23 VSS177 SOCKET4677_AZIF0045P001C01CS-SA    I11 @S9S_MB_2U_LIB.S9S_MB_2U(SCH_1):PAGE41
    U2 AJ25 VSS178 SOCKET4677_AZIF0045P001C01CS-SA    I11 @S9S_MB_2U_LIB.S9S_MB_2U(SCH_1):PAGE41
    U2 AJ29 VSS179 SOCKET4677_AZIF0045P001C01CS-SA    I11 @S9S_MB_2U_LIB.S9S_MB_2U(SCH_1):PAGE41
    U2 AJ31 VSS180 SOCKET4677_AZIF0045P001C01CS-SA    I11 @S9S_MB_2U_LIB.S9S_MB_2U(SCH_1):PAGE41
    U2 AJ35 VSS181 SOCKET4677_AZIF0045P001C01CS-SA    I11 @S9S_MB_2U_LIB.S9S_MB_2U(SCH_1):PAGE41
    U2 AJ37 VSS182 SOCKET4677_AZIF0045P001C01CS-SA    I11 @S9S_MB_2U_LIB.S9S_MB_2U(SCH_1):PAGE41
    U2 AJ41 VSS183 SOCKET4677_AZIF0045P001C01CS-SA    I11 @S9S_MB_2U_LIB.S9S_MB_2U(SCH_1):PAGE41
    U2 AJ43 VSS184 SOCKET4677_AZIF0045P001C01CS-SA    I11 @S9S_MB_2U_LIB.S9S_MB_2U(SCH_1):PAGE41
    U2 AJ48 VSS185 SOCKET4677_AZIF0045P001C01CS-SA    I11 @S9S_MB_2U_LIB.S9S_MB_2U(SCH_1):PAGE41
    U2 AJ50 VSS186 SOCKET4677_AZIF0045P001C01CS-SA    I11 @S9S_MB_2U_LIB.S9S_MB_2U(SCH_1):PAGE41
    U2 AJ54 VSS187 SOCKET4677_AZIF0045P001C01CS-SA    I11 @S9S_MB_2U_LIB.S9S_MB_2U(SCH_1):PAGE41
    U2 AJ56 VSS188 SOCKET4677_AZIF0045P001C01CS-SA    I11 @S9S_MB_2U_LIB.S9S_MB_2U(SCH_1):PAGE41
    U2 AJ60 VSS189 SOCKET4677_AZIF0045P001C01CS-SA    I11 @S9S_MB_2U_LIB.S9S_MB_2U(SCH_1):PAGE41
    U2 AJ62 VSS190 SOCKET4677_AZIF0045P001C01CS-SA    I11 @S9S_MB_2U_LIB.S9S_MB_2U(SCH_1):PAGE41
    U2 AJ66 VSS191 SOCKET4677_AZIF0045P001C01CS-SA    I11 @S9S_MB_2U_LIB.S9S_MB_2U(SCH_1):PAGE41
    U2 AJ68 VSS192 SOCKET4677_AZIF0045P001C01CS-SA    I11 @S9S_MB_2U_LIB.S9S_MB_2U(SCH_1):PAGE41
    U2 AJ72 VSS193 SOCKET4677_AZIF0045P001C01CS-SA    I11 @S9S_MB_2U_LIB.S9S_MB_2U(SCH_1):PAGE41
    U2 AJ74 VSS194 SOCKET4677_AZIF0045P001C01CS-SA    I11 @S9S_MB_2U_LIB.S9S_MB_2U(SCH_1):PAGE41
    U2 AJ78 VSS195 SOCKET4677_AZIF0045P001C01CS-SA    I11 @S9S_MB_2U_LIB.S9S_MB_2U(SCH_1):PAGE41
    U2 AJ84 VSS196 SOCKET4677_AZIF0045P001C01CS-SA    I11 @S9S_MB_2U_LIB.S9S_MB_2U(SCH_1):PAGE41
    U2 AJ88 VSS197 SOCKET4677_AZIF0045P001C01CS-SA    I11 @S9S_MB_2U_LIB.S9S_MB_2U(SCH_1):PAGE41
    U2 AA19  VSS17 SOCKET4677_AZIF0045P001C01CS-SA    I10 @S9S_MB_2U_LIB.S9S_MB_2U(SCH_1):PAGE42
    U2 AA23  VSS18 SOCKET4677_AZIF0045P001C01CS-SA    I10 @S9S_MB_2U_LIB.S9S_MB_2U(SCH_1):PAGE42
    U2 AA25  VSS19 SOCKET4677_AZIF0045P001C01CS-SA    I10 @S9S_MB_2U_LIB.S9S_MB_2U(SCH_1):PAGE42
    U2 AA29  VSS20 SOCKET4677_AZIF0045P001C01CS-SA    I10 @S9S_MB_2U_LIB.S9S_MB_2U(SCH_1):PAGE42
    U2 AA31  VSS21 SOCKET4677_AZIF0045P001C01CS-SA    I10 @S9S_MB_2U_LIB.S9S_MB_2U(SCH_1):PAGE42
    U2 AA35  VSS22 SOCKET4677_AZIF0045P001C01CS-SA    I10 @S9S_MB_2U_LIB.S9S_MB_2U(SCH_1):PAGE42
    U2 AA37  VSS23 SOCKET4677_AZIF0045P001C01CS-SA    I10 @S9S_MB_2U_LIB.S9S_MB_2U(SCH_1):PAGE42
    U2 AA41  VSS24 SOCKET4677_AZIF0045P001C01CS-SA    I10 @S9S_MB_2U_LIB.S9S_MB_2U(SCH_1):PAGE42
    U2 AA43  VSS25 SOCKET4677_AZIF0045P001C01CS-SA    I10 @S9S_MB_2U_LIB.S9S_MB_2U(SCH_1):PAGE42
    U2 AA48  VSS26 SOCKET4677_AZIF0045P001C01CS-SA    I10 @S9S_MB_2U_LIB.S9S_MB_2U(SCH_1):PAGE42
    U2 AA50  VSS27 SOCKET4677_AZIF0045P001C01CS-SA    I10 @S9S_MB_2U_LIB.S9S_MB_2U(SCH_1):PAGE42
    U2 AA54  VSS28 SOCKET4677_AZIF0045P001C01CS-SA    I10 @S9S_MB_2U_LIB.S9S_MB_2U(SCH_1):PAGE42
    U2 AA56  VSS29 SOCKET4677_AZIF0045P001C01CS-SA    I10 @S9S_MB_2U_LIB.S9S_MB_2U(SCH_1):PAGE42
    U2 AA60  VSS30 SOCKET4677_AZIF0045P001C01CS-SA    I10 @S9S_MB_2U_LIB.S9S_MB_2U(SCH_1):PAGE42
    U2 AA62  VSS31 SOCKET4677_AZIF0045P001C01CS-SA    I10 @S9S_MB_2U_LIB.S9S_MB_2U(SCH_1):PAGE42
    U2 AA66  VSS32 SOCKET4677_AZIF0045P001C01CS-SA    I10 @S9S_MB_2U_LIB.S9S_MB_2U(SCH_1):PAGE42
    U2 AA68  VSS33 SOCKET4677_AZIF0045P001C01CS-SA    I10 @S9S_MB_2U_LIB.S9S_MB_2U(SCH_1):PAGE42
    U2 AA72  VSS34 SOCKET4677_AZIF0045P001C01CS-SA    I10 @S9S_MB_2U_LIB.S9S_MB_2U(SCH_1):PAGE42
    U2 AA74  VSS35 SOCKET4677_AZIF0045P001C01CS-SA    I10 @S9S_MB_2U_LIB.S9S_MB_2U(SCH_1):PAGE42
    U2 AA78  VSS36 SOCKET4677_AZIF0045P001C01CS-SA    I10 @S9S_MB_2U_LIB.S9S_MB_2U(SCH_1):PAGE42
    U2 AA80  VSS37 SOCKET4677_AZIF0045P001C01CS-SA    I10 @S9S_MB_2U_LIB.S9S_MB_2U(SCH_1):PAGE42
    U2  P32 VSS1690 SOCKET4677_AZIF0045P001C01CS-SA    I10 @S9S_MB_2U_LIB.S9S_MB_2U(SCH_1):PAGE42
    U2  N76 VSS1696 SOCKET4677_AZIF0045P001C01CS-SA    I10 @S9S_MB_2U_LIB.S9S_MB_2U(SCH_1):PAGE42
    U2  P51 VSS1697 SOCKET4677_AZIF0045P001C01CS-SA    I10 @S9S_MB_2U_LIB.S9S_MB_2U(SCH_1):PAGE42
    U2  N78 VSS1698 SOCKET4677_AZIF0045P001C01CS-SA    I10 @S9S_MB_2U_LIB.S9S_MB_2U(SCH_1):PAGE42
    U2  P57 VSS1699 SOCKET4677_AZIF0045P001C01CS-SA    I10 @S9S_MB_2U_LIB.S9S_MB_2U(SCH_1):PAGE42
    U2  N80 VSS1700 SOCKET4677_AZIF0045P001C01CS-SA    I10 @S9S_MB_2U_LIB.S9S_MB_2U(SCH_1):PAGE42
    U2  N82 VSS1701 SOCKET4677_AZIF0045P001C01CS-SA    I10 @S9S_MB_2U_LIB.S9S_MB_2U(SCH_1):PAGE42
    U2  N84 VSS1702 SOCKET4677_AZIF0045P001C01CS-SA    I10 @S9S_MB_2U_LIB.S9S_MB_2U(SCH_1):PAGE42
    U2  N88 VSS1703 SOCKET4677_AZIF0045P001C01CS-SA    I10 @S9S_MB_2U_LIB.S9S_MB_2U(SCH_1):PAGE42
    U2  P71 VSS1704 SOCKET4677_AZIF0045P001C01CS-SA    I10 @S9S_MB_2U_LIB.S9S_MB_2U(SCH_1):PAGE42
    U2  P12 VSS1705 SOCKET4677_AZIF0045P001C01CS-SA    I10 @S9S_MB_2U_LIB.S9S_MB_2U(SCH_1):PAGE42
    U2  P16 VSS1706 SOCKET4677_AZIF0045P001C01CS-SA    I10 @S9S_MB_2U_LIB.S9S_MB_2U(SCH_1):PAGE42
    U2  P20 VSS1707 SOCKET4677_AZIF0045P001C01CS-SA    I10 @S9S_MB_2U_LIB.S9S_MB_2U(SCH_1):PAGE42
    U2  P22 VSS1708 SOCKET4677_AZIF0045P001C01CS-SA    I10 @S9S_MB_2U_LIB.S9S_MB_2U(SCH_1):PAGE42
    U2  P26 VSS1709 SOCKET4677_AZIF0045P001C01CS-SA    I10 @S9S_MB_2U_LIB.S9S_MB_2U(SCH_1):PAGE42
    U2  P28 VSS1710 SOCKET4677_AZIF0045P001C01CS-SA    I10 @S9S_MB_2U_LIB.S9S_MB_2U(SCH_1):PAGE42
    U2   R1 VSS1711 SOCKET4677_AZIF0045P001C01CS-SA    I10 @S9S_MB_2U_LIB.S9S_MB_2U(SCH_1):PAGE42
    U2  P34 VSS1712 SOCKET4677_AZIF0045P001C01CS-SA    I10 @S9S_MB_2U_LIB.S9S_MB_2U(SCH_1):PAGE42
    U2  P38 VSS1713 SOCKET4677_AZIF0045P001C01CS-SA    I10 @S9S_MB_2U_LIB.S9S_MB_2U(SCH_1):PAGE42
    U2  R19 VSS1714 SOCKET4677_AZIF0045P001C01CS-SA    I10 @S9S_MB_2U_LIB.S9S_MB_2U(SCH_1):PAGE42
    U2  R23 VSS1715 SOCKET4677_AZIF0045P001C01CS-SA    I10 @S9S_MB_2U_LIB.S9S_MB_2U(SCH_1):PAGE42
    U2   P4 VSS1716 SOCKET4677_AZIF0045P001C01CS-SA    I10 @S9S_MB_2U_LIB.S9S_MB_2U(SCH_1):PAGE42
    U2  P40 VSS1717 SOCKET4677_AZIF0045P001C01CS-SA    I10 @S9S_MB_2U_LIB.S9S_MB_2U(SCH_1):PAGE42
    U2  P44 VSS1718 SOCKET4677_AZIF0045P001C01CS-SA    I10 @S9S_MB_2U_LIB.S9S_MB_2U(SCH_1):PAGE42
    U2  P47 VSS1719 SOCKET4677_AZIF0045P001C01CS-SA    I10 @S9S_MB_2U_LIB.S9S_MB_2U(SCH_1):PAGE42
    U2  P53 VSS1720 SOCKET4677_AZIF0045P001C01CS-SA    I10 @S9S_MB_2U_LIB.S9S_MB_2U(SCH_1):PAGE42
    U2  P59 VSS1721 SOCKET4677_AZIF0045P001C01CS-SA    I10 @S9S_MB_2U_LIB.S9S_MB_2U(SCH_1):PAGE42
    U2  P63 VSS1722 SOCKET4677_AZIF0045P001C01CS-SA    I10 @S9S_MB_2U_LIB.S9S_MB_2U(SCH_1):PAGE42
    U2  R48 VSS1723 SOCKET4677_AZIF0045P001C01CS-SA    I10 @S9S_MB_2U_LIB.S9S_MB_2U(SCH_1):PAGE42
    U2  P65 VSS1724 SOCKET4677_AZIF0045P001C01CS-SA    I10 @S9S_MB_2U_LIB.S9S_MB_2U(SCH_1):PAGE42
    U2  P69 VSS1725 SOCKET4677_AZIF0045P001C01CS-SA    I10 @S9S_MB_2U_LIB.S9S_MB_2U(SCH_1):PAGE42
    U2  P75 VSS1726 SOCKET4677_AZIF0045P001C01CS-SA    I10 @S9S_MB_2U_LIB.S9S_MB_2U(SCH_1):PAGE42
    U2  P77 VSS1727 SOCKET4677_AZIF0045P001C01CS-SA    I10 @S9S_MB_2U_LIB.S9S_MB_2U(SCH_1):PAGE42
    U2  R60 VSS1728 SOCKET4677_AZIF0045P001C01CS-SA    I10 @S9S_MB_2U_LIB.S9S_MB_2U(SCH_1):PAGE42
    U2   P8 VSS1729 SOCKET4677_AZIF0045P001C01CS-SA    I10 @S9S_MB_2U_LIB.S9S_MB_2U(SCH_1):PAGE42
    U2  R66 VSS1730 SOCKET4677_AZIF0045P001C01CS-SA    I10 @S9S_MB_2U_LIB.S9S_MB_2U(SCH_1):PAGE42
    U2  P87 VSS1731 SOCKET4677_AZIF0045P001C01CS-SA    I10 @S9S_MB_2U_LIB.S9S_MB_2U(SCH_1):PAGE42
    U2  P91 VSS1732 SOCKET4677_AZIF0045P001C01CS-SA    I10 @S9S_MB_2U_LIB.S9S_MB_2U(SCH_1):PAGE42
    U2  R13 VSS1733 SOCKET4677_AZIF0045P001C01CS-SA    I10 @S9S_MB_2U_LIB.S9S_MB_2U(SCH_1):PAGE42
    U2  R17 VSS1734 SOCKET4677_AZIF0045P001C01CS-SA    I10 @S9S_MB_2U_LIB.S9S_MB_2U(SCH_1):PAGE42
    U2  R25 VSS1735 SOCKET4677_AZIF0045P001C01CS-SA    I10 @S9S_MB_2U_LIB.S9S_MB_2U(SCH_1):PAGE42
    U2  R29 VSS1736 SOCKET4677_AZIF0045P001C01CS-SA    I10 @S9S_MB_2U_LIB.S9S_MB_2U(SCH_1):PAGE42
    U2  R31 VSS1737 SOCKET4677_AZIF0045P001C01CS-SA    I10 @S9S_MB_2U_LIB.S9S_MB_2U(SCH_1):PAGE42
    U2  R35 VSS1738 SOCKET4677_AZIF0045P001C01CS-SA    I10 @S9S_MB_2U_LIB.S9S_MB_2U(SCH_1):PAGE42
    U2  T12 VSS1739 SOCKET4677_AZIF0045P001C01CS-SA    I10 @S9S_MB_2U_LIB.S9S_MB_2U(SCH_1):PAGE42
    U2  T16 VSS1740 SOCKET4677_AZIF0045P001C01CS-SA    I10 @S9S_MB_2U_LIB.S9S_MB_2U(SCH_1):PAGE42
    U2  T18 VSS1741 SOCKET4677_AZIF0045P001C01CS-SA    I10 @S9S_MB_2U_LIB.S9S_MB_2U(SCH_1):PAGE42
    U2  R37 VSS1742 SOCKET4677_AZIF0045P001C01CS-SA    I10 @S9S_MB_2U_LIB.S9S_MB_2U(SCH_1):PAGE42
    U2  R41 VSS1743 SOCKET4677_AZIF0045P001C01CS-SA    I10 @S9S_MB_2U_LIB.S9S_MB_2U(SCH_1):PAGE42
    U2  R43 VSS1744 SOCKET4677_AZIF0045P001C01CS-SA    I10 @S9S_MB_2U_LIB.S9S_MB_2U(SCH_1):PAGE42
    U2   R5 VSS1745 SOCKET4677_AZIF0045P001C01CS-SA    I10 @S9S_MB_2U_LIB.S9S_MB_2U(SCH_1):PAGE42
    U2  T36 VSS1746 SOCKET4677_AZIF0045P001C01CS-SA    I10 @S9S_MB_2U_LIB.S9S_MB_2U(SCH_1):PAGE42
    U2  R50 VSS1747 SOCKET4677_AZIF0045P001C01CS-SA    I10 @S9S_MB_2U_LIB.S9S_MB_2U(SCH_1):PAGE42
    U2  R54 VSS1748 SOCKET4677_AZIF0045P001C01CS-SA    I10 @S9S_MB_2U_LIB.S9S_MB_2U(SCH_1):PAGE42
    U2  T49 VSS1749 SOCKET4677_AZIF0045P001C01CS-SA    I10 @S9S_MB_2U_LIB.S9S_MB_2U(SCH_1):PAGE42
    U2  T55 VSS1750 SOCKET4677_AZIF0045P001C01CS-SA    I10 @S9S_MB_2U_LIB.S9S_MB_2U(SCH_1):PAGE42
    U2  R56 VSS1751 SOCKET4677_AZIF0045P001C01CS-SA    I10 @S9S_MB_2U_LIB.S9S_MB_2U(SCH_1):PAGE42
    U2  R62 VSS1752 SOCKET4677_AZIF0045P001C01CS-SA    I10 @S9S_MB_2U_LIB.S9S_MB_2U(SCH_1):PAGE42
    U2  R68 VSS1753 SOCKET4677_AZIF0045P001C01CS-SA    I10 @S9S_MB_2U_LIB.S9S_MB_2U(SCH_1):PAGE42
    U2  R72 VSS1754 SOCKET4677_AZIF0045P001C01CS-SA    I10 @S9S_MB_2U_LIB.S9S_MB_2U(SCH_1):PAGE42
    U2  R74 VSS1755 SOCKET4677_AZIF0045P001C01CS-SA    I10 @S9S_MB_2U_LIB.S9S_MB_2U(SCH_1):PAGE42
    U2  R78 VSS1756 SOCKET4677_AZIF0045P001C01CS-SA    I10 @S9S_MB_2U_LIB.S9S_MB_2U(SCH_1):PAGE42
    U2  R84 VSS1757 SOCKET4677_AZIF0045P001C01CS-SA    I10 @S9S_MB_2U_LIB.S9S_MB_2U(SCH_1):PAGE42
    U2  R88 VSS1758 SOCKET4677_AZIF0045P001C01CS-SA    I10 @S9S_MB_2U_LIB.S9S_MB_2U(SCH_1):PAGE42
    U2   R9 VSS1759 SOCKET4677_AZIF0045P001C01CS-SA    I10 @S9S_MB_2U_LIB.S9S_MB_2U(SCH_1):PAGE42
    U2  T24 VSS1760 SOCKET4677_AZIF0045P001C01CS-SA    I10 @S9S_MB_2U_LIB.S9S_MB_2U(SCH_1):PAGE42
    U2  T30 VSS1761 SOCKET4677_AZIF0045P001C01CS-SA    I10 @S9S_MB_2U_LIB.S9S_MB_2U(SCH_1):PAGE42
    U2   T4 VSS1762 SOCKET4677_AZIF0045P001C01CS-SA    I10 @S9S_MB_2U_LIB.S9S_MB_2U(SCH_1):PAGE42
    U2  T42 VSS1763 SOCKET4677_AZIF0045P001C01CS-SA    I10 @S9S_MB_2U_LIB.S9S_MB_2U(SCH_1):PAGE42
    U2  T61 VSS1764 SOCKET4677_AZIF0045P001C01CS-SA    I10 @S9S_MB_2U_LIB.S9S_MB_2U(SCH_1):PAGE42
    U2  T67 VSS1765 SOCKET4677_AZIF0045P001C01CS-SA    I10 @S9S_MB_2U_LIB.S9S_MB_2U(SCH_1):PAGE42
    U2  U52 VSS1766 SOCKET4677_AZIF0045P001C01CS-SA    I10 @S9S_MB_2U_LIB.S9S_MB_2U(SCH_1):PAGE42
    U2  T73 VSS1767 SOCKET4677_AZIF0045P001C01CS-SA    I10 @S9S_MB_2U_LIB.S9S_MB_2U(SCH_1):PAGE42
    U2  T79 VSS1768 SOCKET4677_AZIF0045P001C01CS-SA    I10 @S9S_MB_2U_LIB.S9S_MB_2U(SCH_1):PAGE42
    U2   T8 VSS1769 SOCKET4677_AZIF0045P001C01CS-SA    I10 @S9S_MB_2U_LIB.S9S_MB_2U(SCH_1):PAGE42
    U2  T83 VSS1770 SOCKET4677_AZIF0045P001C01CS-SA    I10 @S9S_MB_2U_LIB.S9S_MB_2U(SCH_1):PAGE42
    U2  U39 VSS1771 SOCKET4677_AZIF0045P001C01CS-SA    I10 @S9S_MB_2U_LIB.S9S_MB_2U(SCH_1):PAGE42
    U2  U82 VSS1772 SOCKET4677_AZIF0045P001C01CS-SA    I10 @S9S_MB_2U_LIB.S9S_MB_2U(SCH_1):PAGE42
    U2  U84 VSS1773 SOCKET4677_AZIF0045P001C01CS-SA    I10 @S9S_MB_2U_LIB.S9S_MB_2U(SCH_1):PAGE42
    U2  U88 VSS1774 SOCKET4677_AZIF0045P001C01CS-SA    I10 @S9S_MB_2U_LIB.S9S_MB_2U(SCH_1):PAGE42
    U2  V12 VSS1775 SOCKET4677_AZIF0045P001C01CS-SA    I10 @S9S_MB_2U_LIB.S9S_MB_2U(SCH_1):PAGE42
    U2  V16 VSS1776 SOCKET4677_AZIF0045P001C01CS-SA    I10 @S9S_MB_2U_LIB.S9S_MB_2U(SCH_1):PAGE42
    U2  V18 VSS1777 SOCKET4677_AZIF0045P001C01CS-SA    I10 @S9S_MB_2U_LIB.S9S_MB_2U(SCH_1):PAGE42
    U2  V20 VSS1778 SOCKET4677_AZIF0045P001C01CS-SA    I10 @S9S_MB_2U_LIB.S9S_MB_2U(SCH_1):PAGE42
    U2  V22 VSS1779 SOCKET4677_AZIF0045P001C01CS-SA    I10 @S9S_MB_2U_LIB.S9S_MB_2U(SCH_1):PAGE42
    U2  V24 VSS1780 SOCKET4677_AZIF0045P001C01CS-SA    I10 @S9S_MB_2U_LIB.S9S_MB_2U(SCH_1):PAGE42
    U2  V26 VSS1781 SOCKET4677_AZIF0045P001C01CS-SA    I10 @S9S_MB_2U_LIB.S9S_MB_2U(SCH_1):PAGE42
    U2  V28 VSS1782 SOCKET4677_AZIF0045P001C01CS-SA    I10 @S9S_MB_2U_LIB.S9S_MB_2U(SCH_1):PAGE42
    U2  V30 VSS1783 SOCKET4677_AZIF0045P001C01CS-SA    I10 @S9S_MB_2U_LIB.S9S_MB_2U(SCH_1):PAGE42
    U2  V32 VSS1784 SOCKET4677_AZIF0045P001C01CS-SA    I10 @S9S_MB_2U_LIB.S9S_MB_2U(SCH_1):PAGE42
    U2  V34 VSS1785 SOCKET4677_AZIF0045P001C01CS-SA    I10 @S9S_MB_2U_LIB.S9S_MB_2U(SCH_1):PAGE42
    U2  V36 VSS1786 SOCKET4677_AZIF0045P001C01CS-SA    I10 @S9S_MB_2U_LIB.S9S_MB_2U(SCH_1):PAGE42
    U2  V38 VSS1787 SOCKET4677_AZIF0045P001C01CS-SA    I10 @S9S_MB_2U_LIB.S9S_MB_2U(SCH_1):PAGE42
    U2   V4 VSS1788 SOCKET4677_AZIF0045P001C01CS-SA    I10 @S9S_MB_2U_LIB.S9S_MB_2U(SCH_1):PAGE42
    U2  V49 VSS1789 SOCKET4677_AZIF0045P001C01CS-SA    I10 @S9S_MB_2U_LIB.S9S_MB_2U(SCH_1):PAGE42
    U2  V40 VSS1790 SOCKET4677_AZIF0045P001C01CS-SA    I10 @S9S_MB_2U_LIB.S9S_MB_2U(SCH_1):PAGE42
    U2  V42 VSS1791 SOCKET4677_AZIF0045P001C01CS-SA    I10 @S9S_MB_2U_LIB.S9S_MB_2U(SCH_1):PAGE42
    U2  V44 VSS1792 SOCKET4677_AZIF0045P001C01CS-SA    I10 @S9S_MB_2U_LIB.S9S_MB_2U(SCH_1):PAGE42
    U2  V47 VSS1793 SOCKET4677_AZIF0045P001C01CS-SA    I10 @S9S_MB_2U_LIB.S9S_MB_2U(SCH_1):PAGE42
    U2  V51 VSS1794 SOCKET4677_AZIF0045P001C01CS-SA    I10 @S9S_MB_2U_LIB.S9S_MB_2U(SCH_1):PAGE42
    U2  V53 VSS1795 SOCKET4677_AZIF0045P001C01CS-SA    I10 @S9S_MB_2U_LIB.S9S_MB_2U(SCH_1):PAGE42
    U2  V55 VSS1796 SOCKET4677_AZIF0045P001C01CS-SA    I10 @S9S_MB_2U_LIB.S9S_MB_2U(SCH_1):PAGE42
    U2  V57 VSS1797 SOCKET4677_AZIF0045P001C01CS-SA    I10 @S9S_MB_2U_LIB.S9S_MB_2U(SCH_1):PAGE42
    U2  V59 VSS1798 SOCKET4677_AZIF0045P001C01CS-SA    I10 @S9S_MB_2U_LIB.S9S_MB_2U(SCH_1):PAGE42
    U2  V61 VSS1799 SOCKET4677_AZIF0045P001C01CS-SA    I10 @S9S_MB_2U_LIB.S9S_MB_2U(SCH_1):PAGE42
    U2  V71 VSS1800 SOCKET4677_AZIF0045P001C01CS-SA    I10 @S9S_MB_2U_LIB.S9S_MB_2U(SCH_1):PAGE42
    U2  V73 VSS1801 SOCKET4677_AZIF0045P001C01CS-SA    I10 @S9S_MB_2U_LIB.S9S_MB_2U(SCH_1):PAGE42
    U2  V63 VSS1802 SOCKET4677_AZIF0045P001C01CS-SA    I10 @S9S_MB_2U_LIB.S9S_MB_2U(SCH_1):PAGE42
    U2  V65 VSS1803 SOCKET4677_AZIF0045P001C01CS-SA    I10 @S9S_MB_2U_LIB.S9S_MB_2U(SCH_1):PAGE42
    U2  V67 VSS1804 SOCKET4677_AZIF0045P001C01CS-SA    I10 @S9S_MB_2U_LIB.S9S_MB_2U(SCH_1):PAGE42
    U2  V69 VSS1805 SOCKET4677_AZIF0045P001C01CS-SA    I10 @S9S_MB_2U_LIB.S9S_MB_2U(SCH_1):PAGE42
    U2  V75 VSS1806 SOCKET4677_AZIF0045P001C01CS-SA    I10 @S9S_MB_2U_LIB.S9S_MB_2U(SCH_1):PAGE42
    U2  V91 VSS1807 SOCKET4677_AZIF0045P001C01CS-SA    I10 @S9S_MB_2U_LIB.S9S_MB_2U(SCH_1):PAGE42
    U2   W1 VSS1808 SOCKET4677_AZIF0045P001C01CS-SA    I10 @S9S_MB_2U_LIB.S9S_MB_2U(SCH_1):PAGE42
    U2  W13 VSS1809 SOCKET4677_AZIF0045P001C01CS-SA    I10 @S9S_MB_2U_LIB.S9S_MB_2U(SCH_1):PAGE42
    U2  V77 VSS1810 SOCKET4677_AZIF0045P001C01CS-SA    I10 @S9S_MB_2U_LIB.S9S_MB_2U(SCH_1):PAGE42
    U2  V79 VSS1811 SOCKET4677_AZIF0045P001C01CS-SA    I10 @S9S_MB_2U_LIB.S9S_MB_2U(SCH_1):PAGE42
    U2   V8 VSS1812 SOCKET4677_AZIF0045P001C01CS-SA    I10 @S9S_MB_2U_LIB.S9S_MB_2U(SCH_1):PAGE42
    U2  V87 VSS1813 SOCKET4677_AZIF0045P001C01CS-SA    I10 @S9S_MB_2U_LIB.S9S_MB_2U(SCH_1):PAGE42
    U2   W5 VSS1814 SOCKET4677_AZIF0045P001C01CS-SA    I10 @S9S_MB_2U_LIB.S9S_MB_2U(SCH_1):PAGE42
    U2  W52 VSS1815 SOCKET4677_AZIF0045P001C01CS-SA    I10 @S9S_MB_2U_LIB.S9S_MB_2U(SCH_1):PAGE42
    U2  W39 VSS1816 SOCKET4677_AZIF0045P001C01CS-SA    I10 @S9S_MB_2U_LIB.S9S_MB_2U(SCH_1):PAGE42
    U2  W84 VSS1817 SOCKET4677_AZIF0045P001C01CS-SA    I10 @S9S_MB_2U_LIB.S9S_MB_2U(SCH_1):PAGE42
    U2  W88 VSS1818 SOCKET4677_AZIF0045P001C01CS-SA    I10 @S9S_MB_2U_LIB.S9S_MB_2U(SCH_1):PAGE42
    U2   W9 VSS1819 SOCKET4677_AZIF0045P001C01CS-SA    I10 @S9S_MB_2U_LIB.S9S_MB_2U(SCH_1):PAGE42
    U2  Y12 VSS1820 SOCKET4677_AZIF0045P001C01CS-SA    I10 @S9S_MB_2U_LIB.S9S_MB_2U(SCH_1):PAGE42
    U2  Y16 VSS1821 SOCKET4677_AZIF0045P001C01CS-SA    I10 @S9S_MB_2U_LIB.S9S_MB_2U(SCH_1):PAGE42
    U2  Y18 VSS1822 SOCKET4677_AZIF0045P001C01CS-SA    I10 @S9S_MB_2U_LIB.S9S_MB_2U(SCH_1):PAGE42
    U2  Y24 VSS1823 SOCKET4677_AZIF0045P001C01CS-SA    I10 @S9S_MB_2U_LIB.S9S_MB_2U(SCH_1):PAGE42
    U2  Y30 VSS1824 SOCKET4677_AZIF0045P001C01CS-SA    I10 @S9S_MB_2U_LIB.S9S_MB_2U(SCH_1):PAGE42
    U2  Y36 VSS1825 SOCKET4677_AZIF0045P001C01CS-SA    I10 @S9S_MB_2U_LIB.S9S_MB_2U(SCH_1):PAGE42
    U2   Y4 VSS1826 SOCKET4677_AZIF0045P001C01CS-SA    I10 @S9S_MB_2U_LIB.S9S_MB_2U(SCH_1):PAGE42
    U2  Y42 VSS1827 SOCKET4677_AZIF0045P001C01CS-SA    I10 @S9S_MB_2U_LIB.S9S_MB_2U(SCH_1):PAGE42
    U2  Y61 VSS1828 SOCKET4677_AZIF0045P001C01CS-SA    I10 @S9S_MB_2U_LIB.S9S_MB_2U(SCH_1):PAGE42
    U2  Y67 VSS1829 SOCKET4677_AZIF0045P001C01CS-SA    I10 @S9S_MB_2U_LIB.S9S_MB_2U(SCH_1):PAGE42
    U2  Y49 VSS1830 SOCKET4677_AZIF0045P001C01CS-SA    I10 @S9S_MB_2U_LIB.S9S_MB_2U(SCH_1):PAGE42
    U2  Y55 VSS1831 SOCKET4677_AZIF0045P001C01CS-SA    I10 @S9S_MB_2U_LIB.S9S_MB_2U(SCH_1):PAGE42
    U2   Y8 VSS1832 SOCKET4677_AZIF0045P001C01CS-SA    I10 @S9S_MB_2U_LIB.S9S_MB_2U(SCH_1):PAGE42
    U2  Y73 VSS1833 SOCKET4677_AZIF0045P001C01CS-SA    I10 @S9S_MB_2U_LIB.S9S_MB_2U(SCH_1):PAGE42
    U2  E52 VSS1126 SOCKET4677_AZIF0045P001C01CS-SA    I11 @S9S_MB_2U_LIB.S9S_MB_2U(SCH_1):PAGE42
    U2  E74 VSS1129 SOCKET4677_AZIF0045P001C01CS-SA    I11 @S9S_MB_2U_LIB.S9S_MB_2U(SCH_1):PAGE42
    U2  E78 VSS1131 SOCKET4677_AZIF0045P001C01CS-SA    I11 @S9S_MB_2U_LIB.S9S_MB_2U(SCH_1):PAGE42
    U2  E76 VSS1272 SOCKET4677_AZIF0045P001C01CS-SA    I11 @S9S_MB_2U_LIB.S9S_MB_2U(SCH_1):PAGE42
    U2  E86 VSS1273 SOCKET4677_AZIF0045P001C01CS-SA    I11 @S9S_MB_2U_LIB.S9S_MB_2U(SCH_1):PAGE42
    U2  F12 VSS1494 SOCKET4677_AZIF0045P001C01CS-SA    I11 @S9S_MB_2U_LIB.S9S_MB_2U(SCH_1):PAGE42
    U2  F18 VSS1495 SOCKET4677_AZIF0045P001C01CS-SA    I11 @S9S_MB_2U_LIB.S9S_MB_2U(SCH_1):PAGE42
    U2  F42 VSS1502 SOCKET4677_AZIF0045P001C01CS-SA    I11 @S9S_MB_2U_LIB.S9S_MB_2U(SCH_1):PAGE42
    U2  F55 VSS1504 SOCKET4677_AZIF0045P001C01CS-SA    I11 @S9S_MB_2U_LIB.S9S_MB_2U(SCH_1):PAGE42
    U2   F6 VSS1507 SOCKET4677_AZIF0045P001C01CS-SA    I11 @S9S_MB_2U_LIB.S9S_MB_2U(SCH_1):PAGE42
    U2  F61 VSS1508 SOCKET4677_AZIF0045P001C01CS-SA    I11 @S9S_MB_2U_LIB.S9S_MB_2U(SCH_1):PAGE42
    U2  F67 VSS1509 SOCKET4677_AZIF0045P001C01CS-SA    I11 @S9S_MB_2U_LIB.S9S_MB_2U(SCH_1):PAGE42
    U2  F73 VSS1510 SOCKET4677_AZIF0045P001C01CS-SA    I11 @S9S_MB_2U_LIB.S9S_MB_2U(SCH_1):PAGE42
    U2  F79 VSS1511 SOCKET4677_AZIF0045P001C01CS-SA    I11 @S9S_MB_2U_LIB.S9S_MB_2U(SCH_1):PAGE42
    U2  G11 VSS1514 SOCKET4677_AZIF0045P001C01CS-SA    I11 @S9S_MB_2U_LIB.S9S_MB_2U(SCH_1):PAGE42
    U2  G17 VSS1516 SOCKET4677_AZIF0045P001C01CS-SA    I11 @S9S_MB_2U_LIB.S9S_MB_2U(SCH_1):PAGE42
    U2  G25 VSS1519 SOCKET4677_AZIF0045P001C01CS-SA    I11 @S9S_MB_2U_LIB.S9S_MB_2U(SCH_1):PAGE42
    U2   G3 VSS1521 SOCKET4677_AZIF0045P001C01CS-SA    I11 @S9S_MB_2U_LIB.S9S_MB_2U(SCH_1):PAGE42
    U2  G35 VSS1523 SOCKET4677_AZIF0045P001C01CS-SA    I11 @S9S_MB_2U_LIB.S9S_MB_2U(SCH_1):PAGE42
    U2  G48 VSS1527 SOCKET4677_AZIF0045P001C01CS-SA    I11 @S9S_MB_2U_LIB.S9S_MB_2U(SCH_1):PAGE42
    U2  G60 VSS1532 SOCKET4677_AZIF0045P001C01CS-SA    I11 @S9S_MB_2U_LIB.S9S_MB_2U(SCH_1):PAGE42
    U2  G66 VSS1534 SOCKET4677_AZIF0045P001C01CS-SA    I11 @S9S_MB_2U_LIB.S9S_MB_2U(SCH_1):PAGE42
    U2  G68 VSS1535 SOCKET4677_AZIF0045P001C01CS-SA    I11 @S9S_MB_2U_LIB.S9S_MB_2U(SCH_1):PAGE42
    U2   G7 VSS1536 SOCKET4677_AZIF0045P001C01CS-SA    I11 @S9S_MB_2U_LIB.S9S_MB_2U(SCH_1):PAGE42
    U2  G74 VSS1538 SOCKET4677_AZIF0045P001C01CS-SA    I11 @S9S_MB_2U_LIB.S9S_MB_2U(SCH_1):PAGE42
    U2  H14 VSS1544 SOCKET4677_AZIF0045P001C01CS-SA    I11 @S9S_MB_2U_LIB.S9S_MB_2U(SCH_1):PAGE42
    U2   H2 VSS1546 SOCKET4677_AZIF0045P001C01CS-SA    I11 @S9S_MB_2U_LIB.S9S_MB_2U(SCH_1):PAGE42
    U2  H51 VSS1558 SOCKET4677_AZIF0045P001C01CS-SA    I11 @S9S_MB_2U_LIB.S9S_MB_2U(SCH_1):PAGE42
    U2  H57 VSS1560 SOCKET4677_AZIF0045P001C01CS-SA    I11 @S9S_MB_2U_LIB.S9S_MB_2U(SCH_1):PAGE42
    U2  H65 VSS1564 SOCKET4677_AZIF0045P001C01CS-SA    I11 @S9S_MB_2U_LIB.S9S_MB_2U(SCH_1):PAGE42
    U2  H75 VSS1567 SOCKET4677_AZIF0045P001C01CS-SA    I11 @S9S_MB_2U_LIB.S9S_MB_2U(SCH_1):PAGE42
    U2  F24 VSS1570 SOCKET4677_AZIF0045P001C01CS-SA    I11 @S9S_MB_2U_LIB.S9S_MB_2U(SCH_1):PAGE42
    U2  F30 VSS1571 SOCKET4677_AZIF0045P001C01CS-SA    I11 @S9S_MB_2U_LIB.S9S_MB_2U(SCH_1):PAGE42
    U2  F36 VSS1572 SOCKET4677_AZIF0045P001C01CS-SA    I11 @S9S_MB_2U_LIB.S9S_MB_2U(SCH_1):PAGE42
    U2   F4 VSS1573 SOCKET4677_AZIF0045P001C01CS-SA    I11 @S9S_MB_2U_LIB.S9S_MB_2U(SCH_1):PAGE42
    U2  F49 VSS1574 SOCKET4677_AZIF0045P001C01CS-SA    I11 @S9S_MB_2U_LIB.S9S_MB_2U(SCH_1):PAGE42
    U2  J21 VSS1575 SOCKET4677_AZIF0045P001C01CS-SA    I11 @S9S_MB_2U_LIB.S9S_MB_2U(SCH_1):PAGE42
    U2  F83 VSS1576 SOCKET4677_AZIF0045P001C01CS-SA    I11 @S9S_MB_2U_LIB.S9S_MB_2U(SCH_1):PAGE42
    U2  F89 VSS1577 SOCKET4677_AZIF0045P001C01CS-SA    I11 @S9S_MB_2U_LIB.S9S_MB_2U(SCH_1):PAGE42
    U2  G13 VSS1578 SOCKET4677_AZIF0045P001C01CS-SA    I11 @S9S_MB_2U_LIB.S9S_MB_2U(SCH_1):PAGE42
    U2  G19 VSS1579 SOCKET4677_AZIF0045P001C01CS-SA    I11 @S9S_MB_2U_LIB.S9S_MB_2U(SCH_1):PAGE42
    U2  J39 VSS1580 SOCKET4677_AZIF0045P001C01CS-SA    I11 @S9S_MB_2U_LIB.S9S_MB_2U(SCH_1):PAGE42
    U2  G23 VSS1581 SOCKET4677_AZIF0045P001C01CS-SA    I11 @S9S_MB_2U_LIB.S9S_MB_2U(SCH_1):PAGE42
    U2   J5 VSS1582 SOCKET4677_AZIF0045P001C01CS-SA    I11 @S9S_MB_2U_LIB.S9S_MB_2U(SCH_1):PAGE42
    U2  G29 VSS1583 SOCKET4677_AZIF0045P001C01CS-SA    I11 @S9S_MB_2U_LIB.S9S_MB_2U(SCH_1):PAGE42
    U2  G31 VSS1584 SOCKET4677_AZIF0045P001C01CS-SA    I11 @S9S_MB_2U_LIB.S9S_MB_2U(SCH_1):PAGE42
    U2  G37 VSS1585 SOCKET4677_AZIF0045P001C01CS-SA    I11 @S9S_MB_2U_LIB.S9S_MB_2U(SCH_1):PAGE42
    U2  G41 VSS1586 SOCKET4677_AZIF0045P001C01CS-SA    I11 @S9S_MB_2U_LIB.S9S_MB_2U(SCH_1):PAGE42
    U2  J64 VSS1587 SOCKET4677_AZIF0045P001C01CS-SA    I11 @S9S_MB_2U_LIB.S9S_MB_2U(SCH_1):PAGE42
    U2  G43 VSS1588 SOCKET4677_AZIF0045P001C01CS-SA    I11 @S9S_MB_2U_LIB.S9S_MB_2U(SCH_1):PAGE42
    U2  J70 VSS1589 SOCKET4677_AZIF0045P001C01CS-SA    I11 @S9S_MB_2U_LIB.S9S_MB_2U(SCH_1):PAGE42
    U2  G50 VSS1590 SOCKET4677_AZIF0045P001C01CS-SA    I11 @S9S_MB_2U_LIB.S9S_MB_2U(SCH_1):PAGE42
    U2  G54 VSS1591 SOCKET4677_AZIF0045P001C01CS-SA    I11 @S9S_MB_2U_LIB.S9S_MB_2U(SCH_1):PAGE42
    U2  G56 VSS1592 SOCKET4677_AZIF0045P001C01CS-SA    I11 @S9S_MB_2U_LIB.S9S_MB_2U(SCH_1):PAGE42
    U2  G62 VSS1593 SOCKET4677_AZIF0045P001C01CS-SA    I11 @S9S_MB_2U_LIB.S9S_MB_2U(SCH_1):PAGE42
    U2  G72 VSS1594 SOCKET4677_AZIF0045P001C01CS-SA    I11 @S9S_MB_2U_LIB.S9S_MB_2U(SCH_1):PAGE42
    U2  J88 VSS1595 SOCKET4677_AZIF0045P001C01CS-SA    I11 @S9S_MB_2U_LIB.S9S_MB_2U(SCH_1):PAGE42
    U2   J9 VSS1596 SOCKET4677_AZIF0045P001C01CS-SA    I11 @S9S_MB_2U_LIB.S9S_MB_2U(SCH_1):PAGE42
    U2  K12 VSS1597 SOCKET4677_AZIF0045P001C01CS-SA    I11 @S9S_MB_2U_LIB.S9S_MB_2U(SCH_1):PAGE42
    U2  K14 VSS1598 SOCKET4677_AZIF0045P001C01CS-SA    I11 @S9S_MB_2U_LIB.S9S_MB_2U(SCH_1):PAGE42
    U2   K2 VSS1599 SOCKET4677_AZIF0045P001C01CS-SA    I11 @S9S_MB_2U_LIB.S9S_MB_2U(SCH_1):PAGE42
    U2  G84 VSS1600 SOCKET4677_AZIF0045P001C01CS-SA    I11 @S9S_MB_2U_LIB.S9S_MB_2U(SCH_1):PAGE42
    U2  G88 VSS1601 SOCKET4677_AZIF0045P001C01CS-SA    I11 @S9S_MB_2U_LIB.S9S_MB_2U(SCH_1):PAGE42
    U2  K42 VSS1602 SOCKET4677_AZIF0045P001C01CS-SA    I11 @S9S_MB_2U_LIB.S9S_MB_2U(SCH_1):PAGE42
    U2  K49 VSS1603 SOCKET4677_AZIF0045P001C01CS-SA    I11 @S9S_MB_2U_LIB.S9S_MB_2U(SCH_1):PAGE42
    U2  G90 VSS1604 SOCKET4677_AZIF0045P001C01CS-SA    I11 @S9S_MB_2U_LIB.S9S_MB_2U(SCH_1):PAGE42
    U2  H10 VSS1605 SOCKET4677_AZIF0045P001C01CS-SA    I11 @S9S_MB_2U_LIB.S9S_MB_2U(SCH_1):PAGE42
    U2  H16 VSS1606 SOCKET4677_AZIF0045P001C01CS-SA    I11 @S9S_MB_2U_LIB.S9S_MB_2U(SCH_1):PAGE42
    U2  H20 VSS1607 SOCKET4677_AZIF0045P001C01CS-SA    I11 @S9S_MB_2U_LIB.S9S_MB_2U(SCH_1):PAGE42
    U2  H22 VSS1608 SOCKET4677_AZIF0045P001C01CS-SA    I11 @S9S_MB_2U_LIB.S9S_MB_2U(SCH_1):PAGE42
    U2  H26 VSS1609 SOCKET4677_AZIF0045P001C01CS-SA    I11 @S9S_MB_2U_LIB.S9S_MB_2U(SCH_1):PAGE42
    U2  H28 VSS1610 SOCKET4677_AZIF0045P001C01CS-SA    I11 @S9S_MB_2U_LIB.S9S_MB_2U(SCH_1):PAGE42
    U2  H32 VSS1611 SOCKET4677_AZIF0045P001C01CS-SA    I11 @S9S_MB_2U_LIB.S9S_MB_2U(SCH_1):PAGE42
    U2  H34 VSS1612 SOCKET4677_AZIF0045P001C01CS-SA    I11 @S9S_MB_2U_LIB.S9S_MB_2U(SCH_1):PAGE42
    U2  H38 VSS1613 SOCKET4677_AZIF0045P001C01CS-SA    I11 @S9S_MB_2U_LIB.S9S_MB_2U(SCH_1):PAGE42
    U2  L19 VSS1614 SOCKET4677_AZIF0045P001C01CS-SA    I11 @S9S_MB_2U_LIB.S9S_MB_2U(SCH_1):PAGE42
    U2   H4 VSS1615 SOCKET4677_AZIF0045P001C01CS-SA    I11 @S9S_MB_2U_LIB.S9S_MB_2U(SCH_1):PAGE42
    U2  H40 VSS1616 SOCKET4677_AZIF0045P001C01CS-SA    I11 @S9S_MB_2U_LIB.S9S_MB_2U(SCH_1):PAGE42
    U2  H44 VSS1617 SOCKET4677_AZIF0045P001C01CS-SA    I11 @S9S_MB_2U_LIB.S9S_MB_2U(SCH_1):PAGE42
    U2  H47 VSS1618 SOCKET4677_AZIF0045P001C01CS-SA    I11 @S9S_MB_2U_LIB.S9S_MB_2U(SCH_1):PAGE42
    U2  H53 VSS1619 SOCKET4677_AZIF0045P001C01CS-SA    I11 @S9S_MB_2U_LIB.S9S_MB_2U(SCH_1):PAGE42
    U2  H59 VSS1620 SOCKET4677_AZIF0045P001C01CS-SA    I11 @S9S_MB_2U_LIB.S9S_MB_2U(SCH_1):PAGE42
    U2   H6 VSS1621 SOCKET4677_AZIF0045P001C01CS-SA    I11 @S9S_MB_2U_LIB.S9S_MB_2U(SCH_1):PAGE42
    U2  H63 VSS1622 SOCKET4677_AZIF0045P001C01CS-SA    I11 @S9S_MB_2U_LIB.S9S_MB_2U(SCH_1):PAGE42
    U2  H69 VSS1623 SOCKET4677_AZIF0045P001C01CS-SA    I11 @S9S_MB_2U_LIB.S9S_MB_2U(SCH_1):PAGE42
    U2  H71 VSS1624 SOCKET4677_AZIF0045P001C01CS-SA    I11 @S9S_MB_2U_LIB.S9S_MB_2U(SCH_1):PAGE42
    U2  H79 VSS1625 SOCKET4677_AZIF0045P001C01CS-SA    I11 @S9S_MB_2U_LIB.S9S_MB_2U(SCH_1):PAGE42
    U2   H8 VSS1626 SOCKET4677_AZIF0045P001C01CS-SA    I11 @S9S_MB_2U_LIB.S9S_MB_2U(SCH_1):PAGE42
    U2  H81 VSS1627 SOCKET4677_AZIF0045P001C01CS-SA    I11 @S9S_MB_2U_LIB.S9S_MB_2U(SCH_1):PAGE42
    U2  J15 VSS1628 SOCKET4677_AZIF0045P001C01CS-SA    I11 @S9S_MB_2U_LIB.S9S_MB_2U(SCH_1):PAGE42
    U2  J27 VSS1629 SOCKET4677_AZIF0045P001C01CS-SA    I11 @S9S_MB_2U_LIB.S9S_MB_2U(SCH_1):PAGE42
    U2  J33 VSS1630 SOCKET4677_AZIF0045P001C01CS-SA    I11 @S9S_MB_2U_LIB.S9S_MB_2U(SCH_1):PAGE42
    U2  J45 VSS1631 SOCKET4677_AZIF0045P001C01CS-SA    I11 @S9S_MB_2U_LIB.S9S_MB_2U(SCH_1):PAGE42
    U2  J52 VSS1632 SOCKET4677_AZIF0045P001C01CS-SA    I11 @S9S_MB_2U_LIB.S9S_MB_2U(SCH_1):PAGE42
    U2  J58 VSS1633 SOCKET4677_AZIF0045P001C01CS-SA    I11 @S9S_MB_2U_LIB.S9S_MB_2U(SCH_1):PAGE42
    U2  L58 VSS1634 SOCKET4677_AZIF0045P001C01CS-SA    I11 @S9S_MB_2U_LIB.S9S_MB_2U(SCH_1):PAGE42
    U2  J76 VSS1635 SOCKET4677_AZIF0045P001C01CS-SA    I11 @S9S_MB_2U_LIB.S9S_MB_2U(SCH_1):PAGE42
    U2  J78 VSS1636 SOCKET4677_AZIF0045P001C01CS-SA    I11 @S9S_MB_2U_LIB.S9S_MB_2U(SCH_1):PAGE42
    U2  J84 VSS1637 SOCKET4677_AZIF0045P001C01CS-SA    I11 @S9S_MB_2U_LIB.S9S_MB_2U(SCH_1):PAGE42
    U2  J86 VSS1638 SOCKET4677_AZIF0045P001C01CS-SA    I11 @S9S_MB_2U_LIB.S9S_MB_2U(SCH_1):PAGE42
    U2  K77 VSS1639 SOCKET4677_AZIF0045P001C01CS-SA    I11 @S9S_MB_2U_LIB.S9S_MB_2U(SCH_1):PAGE42
    U2  L70 VSS1640 SOCKET4677_AZIF0045P001C01CS-SA    I11 @S9S_MB_2U_LIB.S9S_MB_2U(SCH_1):PAGE42
    U2   K8 VSS1641 SOCKET4677_AZIF0045P001C01CS-SA    I11 @S9S_MB_2U_LIB.S9S_MB_2U(SCH_1):PAGE42
    U2  K83 VSS1642 SOCKET4677_AZIF0045P001C01CS-SA    I11 @S9S_MB_2U_LIB.S9S_MB_2U(SCH_1):PAGE42
    U2  K85 VSS1643 SOCKET4677_AZIF0045P001C01CS-SA    I11 @S9S_MB_2U_LIB.S9S_MB_2U(SCH_1):PAGE42
    U2  L13 VSS1644 SOCKET4677_AZIF0045P001C01CS-SA    I11 @S9S_MB_2U_LIB.S9S_MB_2U(SCH_1):PAGE42
    U2  L15 VSS1645 SOCKET4677_AZIF0045P001C01CS-SA    I11 @S9S_MB_2U_LIB.S9S_MB_2U(SCH_1):PAGE42
    U2  L88 VSS1646 SOCKET4677_AZIF0045P001C01CS-SA    I11 @S9S_MB_2U_LIB.S9S_MB_2U(SCH_1):PAGE42
    U2   L9 VSS1647 SOCKET4677_AZIF0045P001C01CS-SA    I11 @S9S_MB_2U_LIB.S9S_MB_2U(SCH_1):PAGE42
    U2  L90 VSS1648 SOCKET4677_AZIF0045P001C01CS-SA    I11 @S9S_MB_2U_LIB.S9S_MB_2U(SCH_1):PAGE42
    U2  M12 VSS1649 SOCKET4677_AZIF0045P001C01CS-SA    I11 @S9S_MB_2U_LIB.S9S_MB_2U(SCH_1):PAGE42
    U2  L17 VSS1650 SOCKET4677_AZIF0045P001C01CS-SA    I11 @S9S_MB_2U_LIB.S9S_MB_2U(SCH_1):PAGE42
    U2  L21 VSS1651 SOCKET4677_AZIF0045P001C01CS-SA    I11 @S9S_MB_2U_LIB.S9S_MB_2U(SCH_1):PAGE42
    U2   M4 VSS1652 SOCKET4677_AZIF0045P001C01CS-SA    I11 @S9S_MB_2U_LIB.S9S_MB_2U(SCH_1):PAGE42
    U2  M42 VSS1653 SOCKET4677_AZIF0045P001C01CS-SA    I11 @S9S_MB_2U_LIB.S9S_MB_2U(SCH_1):PAGE42
    U2  M49 VSS1654 SOCKET4677_AZIF0045P001C01CS-SA    I11 @S9S_MB_2U_LIB.S9S_MB_2U(SCH_1):PAGE42
    U2  L23 VSS1655 SOCKET4677_AZIF0045P001C01CS-SA    I11 @S9S_MB_2U_LIB.S9S_MB_2U(SCH_1):PAGE42
    U2  L25 VSS1656 SOCKET4677_AZIF0045P001C01CS-SA    I11 @S9S_MB_2U_LIB.S9S_MB_2U(SCH_1):PAGE42
    U2   M8 VSS1657 SOCKET4677_AZIF0045P001C01CS-SA    I11 @S9S_MB_2U_LIB.S9S_MB_2U(SCH_1):PAGE42
    U2  L27 VSS1658 SOCKET4677_AZIF0045P001C01CS-SA    I11 @S9S_MB_2U_LIB.S9S_MB_2U(SCH_1):PAGE42
    U2  L29 VSS1659 SOCKET4677_AZIF0045P001C01CS-SA    I11 @S9S_MB_2U_LIB.S9S_MB_2U(SCH_1):PAGE42
    U2  L31 VSS1660 SOCKET4677_AZIF0045P001C01CS-SA    I11 @S9S_MB_2U_LIB.S9S_MB_2U(SCH_1):PAGE42
    U2  L33 VSS1661 SOCKET4677_AZIF0045P001C01CS-SA    I11 @S9S_MB_2U_LIB.S9S_MB_2U(SCH_1):PAGE42
    U2  L35 VSS1662 SOCKET4677_AZIF0045P001C01CS-SA    I11 @S9S_MB_2U_LIB.S9S_MB_2U(SCH_1):PAGE42
    U2  L37 VSS1663 SOCKET4677_AZIF0045P001C01CS-SA    I11 @S9S_MB_2U_LIB.S9S_MB_2U(SCH_1):PAGE42
    U2  N21 VSS1664 SOCKET4677_AZIF0045P001C01CS-SA    I11 @S9S_MB_2U_LIB.S9S_MB_2U(SCH_1):PAGE42
    U2  L39 VSS1665 SOCKET4677_AZIF0045P001C01CS-SA    I11 @S9S_MB_2U_LIB.S9S_MB_2U(SCH_1):PAGE42
    U2  L41 VSS1666 SOCKET4677_AZIF0045P001C01CS-SA    I11 @S9S_MB_2U_LIB.S9S_MB_2U(SCH_1):PAGE42
    U2  L43 VSS1667 SOCKET4677_AZIF0045P001C01CS-SA    I11 @S9S_MB_2U_LIB.S9S_MB_2U(SCH_1):PAGE42
    U2  L45 VSS1668 SOCKET4677_AZIF0045P001C01CS-SA    I11 @S9S_MB_2U_LIB.S9S_MB_2U(SCH_1):PAGE42
    U2  N39 VSS1669 SOCKET4677_AZIF0045P001C01CS-SA    I11 @S9S_MB_2U_LIB.S9S_MB_2U(SCH_1):PAGE42
    U2  L48 VSS1670 SOCKET4677_AZIF0045P001C01CS-SA    I11 @S9S_MB_2U_LIB.S9S_MB_2U(SCH_1):PAGE42
    U2   L5 VSS1671 SOCKET4677_AZIF0045P001C01CS-SA    I11 @S9S_MB_2U_LIB.S9S_MB_2U(SCH_1):PAGE42
    U2  L50 VSS1672 SOCKET4677_AZIF0045P001C01CS-SA    I11 @S9S_MB_2U_LIB.S9S_MB_2U(SCH_1):PAGE42
    U2  L52 VSS1673 SOCKET4677_AZIF0045P001C01CS-SA    I11 @S9S_MB_2U_LIB.S9S_MB_2U(SCH_1):PAGE42
    U2  L54 VSS1674 SOCKET4677_AZIF0045P001C01CS-SA    I11 @S9S_MB_2U_LIB.S9S_MB_2U(SCH_1):PAGE42
    U2  N64 VSS1675 SOCKET4677_AZIF0045P001C01CS-SA    I11 @S9S_MB_2U_LIB.S9S_MB_2U(SCH_1):PAGE42
    U2  L56 VSS1676 SOCKET4677_AZIF0045P001C01CS-SA    I11 @S9S_MB_2U_LIB.S9S_MB_2U(SCH_1):PAGE42
    U2  L60 VSS1677 SOCKET4677_AZIF0045P001C01CS-SA    I11 @S9S_MB_2U_LIB.S9S_MB_2U(SCH_1):PAGE42
    U2  L62 VSS1678 SOCKET4677_AZIF0045P001C01CS-SA    I11 @S9S_MB_2U_LIB.S9S_MB_2U(SCH_1):PAGE42
    U2  L64 VSS1679 SOCKET4677_AZIF0045P001C01CS-SA    I11 @S9S_MB_2U_LIB.S9S_MB_2U(SCH_1):PAGE42
    U2  L66 VSS1680 SOCKET4677_AZIF0045P001C01CS-SA    I11 @S9S_MB_2U_LIB.S9S_MB_2U(SCH_1):PAGE42
    U2  L68 VSS1681 SOCKET4677_AZIF0045P001C01CS-SA    I11 @S9S_MB_2U_LIB.S9S_MB_2U(SCH_1):PAGE42
    U2  L72 VSS1682 SOCKET4677_AZIF0045P001C01CS-SA    I11 @S9S_MB_2U_LIB.S9S_MB_2U(SCH_1):PAGE42
    U2  L74 VSS1683 SOCKET4677_AZIF0045P001C01CS-SA    I11 @S9S_MB_2U_LIB.S9S_MB_2U(SCH_1):PAGE42
    U2  L76 VSS1684 SOCKET4677_AZIF0045P001C01CS-SA    I11 @S9S_MB_2U_LIB.S9S_MB_2U(SCH_1):PAGE42
    U2  L78 VSS1685 SOCKET4677_AZIF0045P001C01CS-SA    I11 @S9S_MB_2U_LIB.S9S_MB_2U(SCH_1):PAGE42
    U2  M81 VSS1686 SOCKET4677_AZIF0045P001C01CS-SA    I11 @S9S_MB_2U_LIB.S9S_MB_2U(SCH_1):PAGE42
    U2  M83 VSS1687 SOCKET4677_AZIF0045P001C01CS-SA    I11 @S9S_MB_2U_LIB.S9S_MB_2U(SCH_1):PAGE42
    U2  N15 VSS1688 SOCKET4677_AZIF0045P001C01CS-SA    I11 @S9S_MB_2U_LIB.S9S_MB_2U(SCH_1):PAGE42
    U2  N27 VSS1689 SOCKET4677_AZIF0045P001C01CS-SA    I11 @S9S_MB_2U_LIB.S9S_MB_2U(SCH_1):PAGE42
    U2  N33 VSS1691 SOCKET4677_AZIF0045P001C01CS-SA    I11 @S9S_MB_2U_LIB.S9S_MB_2U(SCH_1):PAGE42
    U2  N45 VSS1692 SOCKET4677_AZIF0045P001C01CS-SA    I11 @S9S_MB_2U_LIB.S9S_MB_2U(SCH_1):PAGE42
    U2  N52 VSS1693 SOCKET4677_AZIF0045P001C01CS-SA    I11 @S9S_MB_2U_LIB.S9S_MB_2U(SCH_1):PAGE42
    U2  N58 VSS1694 SOCKET4677_AZIF0045P001C01CS-SA    I11 @S9S_MB_2U_LIB.S9S_MB_2U(SCH_1):PAGE42
    U2  N70 VSS1695 SOCKET4677_AZIF0045P001C01CS-SA    I11 @S9S_MB_2U_LIB.S9S_MB_2U(SCH_1):PAGE42
    U2  A11   VSS1 SOCKET4677_AZIF0045P001C01CS-SA    I12 @S9S_MB_2U_LIB.S9S_MB_2U(SCH_1):PAGE42
    U2  A13   VSS2 SOCKET4677_AZIF0045P001C01CS-SA    I12 @S9S_MB_2U_LIB.S9S_MB_2U(SCH_1):PAGE42
    U2  A17   VSS3 SOCKET4677_AZIF0045P001C01CS-SA    I12 @S9S_MB_2U_LIB.S9S_MB_2U(SCH_1):PAGE42
    U2  A19   VSS4 SOCKET4677_AZIF0045P001C01CS-SA    I12 @S9S_MB_2U_LIB.S9S_MB_2U(SCH_1):PAGE42
    U2  A23   VSS5 SOCKET4677_AZIF0045P001C01CS-SA    I12 @S9S_MB_2U_LIB.S9S_MB_2U(SCH_1):PAGE42
    U2  A25   VSS6 SOCKET4677_AZIF0045P001C01CS-SA    I12 @S9S_MB_2U_LIB.S9S_MB_2U(SCH_1):PAGE42
    U2  A29   VSS7 SOCKET4677_AZIF0045P001C01CS-SA    I12 @S9S_MB_2U_LIB.S9S_MB_2U(SCH_1):PAGE42
    U2  A31   VSS8 SOCKET4677_AZIF0045P001C01CS-SA    I12 @S9S_MB_2U_LIB.S9S_MB_2U(SCH_1):PAGE42
    U2  A35   VSS9 SOCKET4677_AZIF0045P001C01CS-SA    I12 @S9S_MB_2U_LIB.S9S_MB_2U(SCH_1):PAGE42
    U2  A37  VSS10 SOCKET4677_AZIF0045P001C01CS-SA    I12 @S9S_MB_2U_LIB.S9S_MB_2U(SCH_1):PAGE42
    U2  A41  VSS11 SOCKET4677_AZIF0045P001C01CS-SA    I12 @S9S_MB_2U_LIB.S9S_MB_2U(SCH_1):PAGE42
    U2  A50  VSS12 SOCKET4677_AZIF0045P001C01CS-SA    I12 @S9S_MB_2U_LIB.S9S_MB_2U(SCH_1):PAGE42
    U2  A54  VSS13 SOCKET4677_AZIF0045P001C01CS-SA    I12 @S9S_MB_2U_LIB.S9S_MB_2U(SCH_1):PAGE42
    U2  A56  VSS14 SOCKET4677_AZIF0045P001C01CS-SA    I12 @S9S_MB_2U_LIB.S9S_MB_2U(SCH_1):PAGE42
    U2  A60  VSS15 SOCKET4677_AZIF0045P001C01CS-SA    I12 @S9S_MB_2U_LIB.S9S_MB_2U(SCH_1):PAGE42
    U2  A62  VSS16 SOCKET4677_AZIF0045P001C01CS-SA    I12 @S9S_MB_2U_LIB.S9S_MB_2U(SCH_1):PAGE42
    U2  B12 VSS378 SOCKET4677_AZIF0045P001C01CS-SA    I12 @S9S_MB_2U_LIB.S9S_MB_2U(SCH_1):PAGE42
    U2  B18 VSS379 SOCKET4677_AZIF0045P001C01CS-SA    I12 @S9S_MB_2U_LIB.S9S_MB_2U(SCH_1):PAGE42
    U2  B24 VSS380 SOCKET4677_AZIF0045P001C01CS-SA    I12 @S9S_MB_2U_LIB.S9S_MB_2U(SCH_1):PAGE42
    U2  B30 VSS381 SOCKET4677_AZIF0045P001C01CS-SA    I12 @S9S_MB_2U_LIB.S9S_MB_2U(SCH_1):PAGE42
    U2  B36 VSS382 SOCKET4677_AZIF0045P001C01CS-SA    I12 @S9S_MB_2U_LIB.S9S_MB_2U(SCH_1):PAGE42
    U2  B42 VSS384 SOCKET4677_AZIF0045P001C01CS-SA    I12 @S9S_MB_2U_LIB.S9S_MB_2U(SCH_1):PAGE42
    U2  B49 VSS385 SOCKET4677_AZIF0045P001C01CS-SA    I12 @S9S_MB_2U_LIB.S9S_MB_2U(SCH_1):PAGE42
    U2  B55 VSS386 SOCKET4677_AZIF0045P001C01CS-SA    I12 @S9S_MB_2U_LIB.S9S_MB_2U(SCH_1):PAGE42
    U2   B6 VSS387 SOCKET4677_AZIF0045P001C01CS-SA    I12 @S9S_MB_2U_LIB.S9S_MB_2U(SCH_1):PAGE42
    U2  B61 VSS388 SOCKET4677_AZIF0045P001C01CS-SA    I12 @S9S_MB_2U_LIB.S9S_MB_2U(SCH_1):PAGE42
    U2  B67 VSS389 SOCKET4677_AZIF0045P001C01CS-SA    I12 @S9S_MB_2U_LIB.S9S_MB_2U(SCH_1):PAGE42
    U2  B75 VSS390 SOCKET4677_AZIF0045P001C01CS-SA    I12 @S9S_MB_2U_LIB.S9S_MB_2U(SCH_1):PAGE42
    U2  B83 VSS391 SOCKET4677_AZIF0045P001C01CS-SA    I12 @S9S_MB_2U_LIB.S9S_MB_2U(SCH_1):PAGE42
    U2  B87 VSS392 SOCKET4677_AZIF0045P001C01CS-SA    I12 @S9S_MB_2U_LIB.S9S_MB_2U(SCH_1):PAGE42
    U2  C39 VSS609 SOCKET4677_AZIF0045P001C01CS-SA    I12 @S9S_MB_2U_LIB.S9S_MB_2U(SCH_1):PAGE42
    U2  C45 VSS610 SOCKET4677_AZIF0045P001C01CS-SA    I12 @S9S_MB_2U_LIB.S9S_MB_2U(SCH_1):PAGE42
    U2   C5 VSS612 SOCKET4677_AZIF0045P001C01CS-SA    I12 @S9S_MB_2U_LIB.S9S_MB_2U(SCH_1):PAGE42
    U2  C52 VSS613 SOCKET4677_AZIF0045P001C01CS-SA    I12 @S9S_MB_2U_LIB.S9S_MB_2U(SCH_1):PAGE42
    U2  C72 VSS614 SOCKET4677_AZIF0045P001C01CS-SA    I12 @S9S_MB_2U_LIB.S9S_MB_2U(SCH_1):PAGE42
    U2  C74 VSS615 SOCKET4677_AZIF0045P001C01CS-SA    I12 @S9S_MB_2U_LIB.S9S_MB_2U(SCH_1):PAGE42
    U2  C78 VSS616 SOCKET4677_AZIF0045P001C01CS-SA    I12 @S9S_MB_2U_LIB.S9S_MB_2U(SCH_1):PAGE42
    U2  C80 VSS617 SOCKET4677_AZIF0045P001C01CS-SA    I12 @S9S_MB_2U_LIB.S9S_MB_2U(SCH_1):PAGE42
    U2  C82 VSS618 SOCKET4677_AZIF0045P001C01CS-SA    I12 @S9S_MB_2U_LIB.S9S_MB_2U(SCH_1):PAGE42
    U2  C86 VSS619 SOCKET4677_AZIF0045P001C01CS-SA    I12 @S9S_MB_2U_LIB.S9S_MB_2U(SCH_1):PAGE42
    U2  D63 VSS657 SOCKET4677_AZIF0045P001C01CS-SA    I12 @S9S_MB_2U_LIB.S9S_MB_2U(SCH_1):PAGE42
    U2  D65 VSS658 SOCKET4677_AZIF0045P001C01CS-SA    I12 @S9S_MB_2U_LIB.S9S_MB_2U(SCH_1):PAGE42
    U2  D67 VSS659 SOCKET4677_AZIF0045P001C01CS-SA    I12 @S9S_MB_2U_LIB.S9S_MB_2U(SCH_1):PAGE42
    U2  D79 VSS662 SOCKET4677_AZIF0045P001C01CS-SA    I12 @S9S_MB_2U_LIB.S9S_MB_2U(SCH_1):PAGE42
    U2   D8 VSS663 SOCKET4677_AZIF0045P001C01CS-SA    I12 @S9S_MB_2U_LIB.S9S_MB_2U(SCH_1):PAGE42
    U2  D10 VSS864 SOCKET4677_AZIF0045P001C01CS-SA    I12 @S9S_MB_2U_LIB.S9S_MB_2U(SCH_1):PAGE42
    U2  D12 VSS865 SOCKET4677_AZIF0045P001C01CS-SA    I12 @S9S_MB_2U_LIB.S9S_MB_2U(SCH_1):PAGE42
    U2  D14 VSS866 SOCKET4677_AZIF0045P001C01CS-SA    I12 @S9S_MB_2U_LIB.S9S_MB_2U(SCH_1):PAGE42
    U2  D16 VSS868 SOCKET4677_AZIF0045P001C01CS-SA    I12 @S9S_MB_2U_LIB.S9S_MB_2U(SCH_1):PAGE42
    U2  D18 VSS869 SOCKET4677_AZIF0045P001C01CS-SA    I12 @S9S_MB_2U_LIB.S9S_MB_2U(SCH_1):PAGE42
    U2  D20 VSS871 SOCKET4677_AZIF0045P001C01CS-SA    I12 @S9S_MB_2U_LIB.S9S_MB_2U(SCH_1):PAGE42
    U2  D22 VSS873 SOCKET4677_AZIF0045P001C01CS-SA    I12 @S9S_MB_2U_LIB.S9S_MB_2U(SCH_1):PAGE42
    U2  D24 VSS874 SOCKET4677_AZIF0045P001C01CS-SA    I12 @S9S_MB_2U_LIB.S9S_MB_2U(SCH_1):PAGE42
    U2  D26 VSS875 SOCKET4677_AZIF0045P001C01CS-SA    I12 @S9S_MB_2U_LIB.S9S_MB_2U(SCH_1):PAGE42
    U2  D28 VSS876 SOCKET4677_AZIF0045P001C01CS-SA    I12 @S9S_MB_2U_LIB.S9S_MB_2U(SCH_1):PAGE42
    U2  D30 VSS877 SOCKET4677_AZIF0045P001C01CS-SA    I12 @S9S_MB_2U_LIB.S9S_MB_2U(SCH_1):PAGE42
    U2  D32 VSS878 SOCKET4677_AZIF0045P001C01CS-SA    I12 @S9S_MB_2U_LIB.S9S_MB_2U(SCH_1):PAGE42
    U2  D34 VSS879 SOCKET4677_AZIF0045P001C01CS-SA    I12 @S9S_MB_2U_LIB.S9S_MB_2U(SCH_1):PAGE42
    U2  D36 VSS881 SOCKET4677_AZIF0045P001C01CS-SA    I12 @S9S_MB_2U_LIB.S9S_MB_2U(SCH_1):PAGE42
    U2  D38 VSS884 SOCKET4677_AZIF0045P001C01CS-SA    I12 @S9S_MB_2U_LIB.S9S_MB_2U(SCH_1):PAGE42
    U2  D40 VSS885 SOCKET4677_AZIF0045P001C01CS-SA    I12 @S9S_MB_2U_LIB.S9S_MB_2U(SCH_1):PAGE42
    U2  D42 VSS886 SOCKET4677_AZIF0045P001C01CS-SA    I12 @S9S_MB_2U_LIB.S9S_MB_2U(SCH_1):PAGE42
    U2  D44 VSS888 SOCKET4677_AZIF0045P001C01CS-SA    I12 @S9S_MB_2U_LIB.S9S_MB_2U(SCH_1):PAGE42
    U2  D47 VSS889 SOCKET4677_AZIF0045P001C01CS-SA    I12 @S9S_MB_2U_LIB.S9S_MB_2U(SCH_1):PAGE42
    U2  D49 VSS891 SOCKET4677_AZIF0045P001C01CS-SA    I12 @S9S_MB_2U_LIB.S9S_MB_2U(SCH_1):PAGE42
    U2  D51 VSS892 SOCKET4677_AZIF0045P001C01CS-SA    I12 @S9S_MB_2U_LIB.S9S_MB_2U(SCH_1):PAGE42
    U2  D53 VSS895 SOCKET4677_AZIF0045P001C01CS-SA    I12 @S9S_MB_2U_LIB.S9S_MB_2U(SCH_1):PAGE42
    U2  D55 VSS896 SOCKET4677_AZIF0045P001C01CS-SA    I12 @S9S_MB_2U_LIB.S9S_MB_2U(SCH_1):PAGE42
    U2  D57 VSS897 SOCKET4677_AZIF0045P001C01CS-SA    I12 @S9S_MB_2U_LIB.S9S_MB_2U(SCH_1):PAGE42
    U2  D59 VSS898 SOCKET4677_AZIF0045P001C01CS-SA    I12 @S9S_MB_2U_LIB.S9S_MB_2U(SCH_1):PAGE42
    U2   D6 VSS899 SOCKET4677_AZIF0045P001C01CS-SA    I12 @S9S_MB_2U_LIB.S9S_MB_2U(SCH_1):PAGE42
    U2  D61 VSS900 SOCKET4677_AZIF0045P001C01CS-SA    I12 @S9S_MB_2U_LIB.S9S_MB_2U(SCH_1):PAGE42
    U2  D69 VSS901 SOCKET4677_AZIF0045P001C01CS-SA    I12 @S9S_MB_2U_LIB.S9S_MB_2U(SCH_1):PAGE42
    U2  D71 VSS902 SOCKET4677_AZIF0045P001C01CS-SA    I12 @S9S_MB_2U_LIB.S9S_MB_2U(SCH_1):PAGE42
    U2  D81 VSS906 SOCKET4677_AZIF0045P001C01CS-SA    I12 @S9S_MB_2U_LIB.S9S_MB_2U(SCH_1):PAGE42
    U2  D83 VSS907 SOCKET4677_AZIF0045P001C01CS-SA    I12 @S9S_MB_2U_LIB.S9S_MB_2U(SCH_1):PAGE42
    U2   E5 VSS1125 SOCKET4677_AZIF0045P001C01CS-SA    I12 @S9S_MB_2U_LIB.S9S_MB_2U(SCH_1):PAGE42
    U2  E39 VSS1271 SOCKET4677_AZIF0045P001C01CS-SA    I12 @S9S_MB_2U_LIB.S9S_MB_2U(SCH_1):PAGE42
   R69    2      B Q_RES_0402LF-10K,1%,1/16W,CHIPA    I16 @S9S_MB_2U_LIB.S9S_MB_2U(SCH_1):PAGE43
   R70    2      B Q_RES_0402LF-10K,1%,1/16W,CHIPA    I17 @S9S_MB_2U_LIB.S9S_MB_2U(SCH_1):PAGE43
 R1226    2      B Q_RES_0402LF-10K,1%,1/16W,CHIPA    I52 @S9S_MB_2U_LIB.S9S_MB_2U(SCH_1):PAGE43
 R1227    2      B Q_RES_0402LF-10K,1%,1/16W,CHIPA    I56 @S9S_MB_2U_LIB.S9S_MB_2U(SCH_1):PAGE43
 R1270    2      B Q_RES_0402LF-240,1%,1/16W,EMPTA    I55 @S9S_MB_2U_LIB.S9S_MB_2U(SCH_1):PAGE44
    U1 EJ80 UPI3_RX_DN0 SOCKET4677_AZIF0045P001C01CS-SA    I16 @S9S_MB_2U_LIB.S9S_MB_2U(SCH_1):PAGE66
    U1 EP81 UPI3_RX_DN1 SOCKET4677_AZIF0045P001C01CS-SA    I16 @S9S_MB_2U_LIB.S9S_MB_2U(SCH_1):PAGE66
    U1 EL82 UPI3_RX_DN2 SOCKET4677_AZIF0045P001C01CS-SA    I16 @S9S_MB_2U_LIB.S9S_MB_2U(SCH_1):PAGE66
    U1 EK81 UPI3_RX_DN3 SOCKET4677_AZIF0045P001C01CS-SA    I16 @S9S_MB_2U_LIB.S9S_MB_2U(SCH_1):PAGE66
    U1 EF81 UPI3_RX_DN4 SOCKET4677_AZIF0045P001C01CS-SA    I16 @S9S_MB_2U_LIB.S9S_MB_2U(SCH_1):PAGE66
    U1 ED83 UPI3_RX_DN5 SOCKET4677_AZIF0045P001C01CS-SA    I16 @S9S_MB_2U_LIB.S9S_MB_2U(SCH_1):PAGE66
    U1 EC80 UPI3_RX_DN6 SOCKET4677_AZIF0045P001C01CS-SA    I16 @S9S_MB_2U_LIB.S9S_MB_2U(SCH_1):PAGE66
    U1 EA82 UPI3_RX_DN7 SOCKET4677_AZIF0045P001C01CS-SA    I16 @S9S_MB_2U_LIB.S9S_MB_2U(SCH_1):PAGE66
    U1 DY81 UPI3_RX_DN8 SOCKET4677_AZIF0045P001C01CS-SA    I16 @S9S_MB_2U_LIB.S9S_MB_2U(SCH_1):PAGE66
    U1 DJ78 UPI3_RX_DN9 SOCKET4677_AZIF0045P001C01CS-SA    I16 @S9S_MB_2U_LIB.S9S_MB_2U(SCH_1):PAGE66
    U1 DG78 UPI3_RX_DN10 SOCKET4677_AZIF0045P001C01CS-SA    I16 @S9S_MB_2U_LIB.S9S_MB_2U(SCH_1):PAGE66
    U1 DH81 UPI3_RX_DN11 SOCKET4677_AZIF0045P001C01CS-SA    I16 @S9S_MB_2U_LIB.S9S_MB_2U(SCH_1):PAGE66
    U1 DF83 UPI3_RX_DN12 SOCKET4677_AZIF0045P001C01CS-SA    I16 @S9S_MB_2U_LIB.S9S_MB_2U(SCH_1):PAGE66
    U1 DE80 UPI3_RX_DN13 SOCKET4677_AZIF0045P001C01CS-SA    I16 @S9S_MB_2U_LIB.S9S_MB_2U(SCH_1):PAGE66
    U1 DC82 UPI3_RX_DN14 SOCKET4677_AZIF0045P001C01CS-SA    I16 @S9S_MB_2U_LIB.S9S_MB_2U(SCH_1):PAGE66
    U1 DB81 UPI3_RX_DN15 SOCKET4677_AZIF0045P001C01CS-SA    I16 @S9S_MB_2U_LIB.S9S_MB_2U(SCH_1):PAGE66
    U1 DF77 UPI3_RX_DN16 SOCKET4677_AZIF0045P001C01CS-SA    I16 @S9S_MB_2U_LIB.S9S_MB_2U(SCH_1):PAGE66
    U1 CU82 UPI3_RX_DN17 SOCKET4677_AZIF0045P001C01CS-SA    I16 @S9S_MB_2U_LIB.S9S_MB_2U(SCH_1):PAGE66
    U1 CR82 UPI3_RX_DN18 SOCKET4677_AZIF0045P001C01CS-SA    I16 @S9S_MB_2U_LIB.S9S_MB_2U(SCH_1):PAGE66
    U1 CW80 UPI3_RX_DN19 SOCKET4677_AZIF0045P001C01CS-SA    I16 @S9S_MB_2U_LIB.S9S_MB_2U(SCH_1):PAGE66
    U1 CP81 UPI3_RX_DN20 SOCKET4677_AZIF0045P001C01CS-SA    I16 @S9S_MB_2U_LIB.S9S_MB_2U(SCH_1):PAGE66
    U1 CN80 UPI3_RX_DN21 SOCKET4677_AZIF0045P001C01CS-SA    I16 @S9S_MB_2U_LIB.S9S_MB_2U(SCH_1):PAGE66
    U1 CT79 UPI3_RX_DN22 SOCKET4677_AZIF0045P001C01CS-SA    I16 @S9S_MB_2U_LIB.S9S_MB_2U(SCH_1):PAGE66
    U1 DA78 UPI3_RX_DN23 SOCKET4677_AZIF0045P001C01CS-SA    I16 @S9S_MB_2U_LIB.S9S_MB_2U(SCH_1):PAGE66
    U1 EL80 UPI3_RX_DP0 SOCKET4677_AZIF0045P001C01CS-SA    I16 @S9S_MB_2U_LIB.S9S_MB_2U(SCH_1):PAGE66
    U1 ER82 UPI3_RX_DP1 SOCKET4677_AZIF0045P001C01CS-SA    I16 @S9S_MB_2U_LIB.S9S_MB_2U(SCH_1):PAGE66
    U1 EN82 UPI3_RX_DP2 SOCKET4677_AZIF0045P001C01CS-SA    I16 @S9S_MB_2U_LIB.S9S_MB_2U(SCH_1):PAGE66
    U1 EJ82 UPI3_RX_DP3 SOCKET4677_AZIF0045P001C01CS-SA    I16 @S9S_MB_2U_LIB.S9S_MB_2U(SCH_1):PAGE66
    U1 EE82 UPI3_RX_DP4 SOCKET4677_AZIF0045P001C01CS-SA    I16 @S9S_MB_2U_LIB.S9S_MB_2U(SCH_1):PAGE66
    U1 EF83 UPI3_RX_DP5 SOCKET4677_AZIF0045P001C01CS-SA    I16 @S9S_MB_2U_LIB.S9S_MB_2U(SCH_1):PAGE66
    U1 ED81 UPI3_RX_DP6 SOCKET4677_AZIF0045P001C01CS-SA    I16 @S9S_MB_2U_LIB.S9S_MB_2U(SCH_1):PAGE66
    U1 DY83 UPI3_RX_DP7 SOCKET4677_AZIF0045P001C01CS-SA    I16 @S9S_MB_2U_LIB.S9S_MB_2U(SCH_1):PAGE66
    U1 EB81 UPI3_RX_DP8 SOCKET4677_AZIF0045P001C01CS-SA    I16 @S9S_MB_2U_LIB.S9S_MB_2U(SCH_1):PAGE66
    U1 DL78 UPI3_RX_DP9 SOCKET4677_AZIF0045P001C01CS-SA    I16 @S9S_MB_2U_LIB.S9S_MB_2U(SCH_1):PAGE66
    U1 DH79 UPI3_RX_DP10 SOCKET4677_AZIF0045P001C01CS-SA    I16 @S9S_MB_2U_LIB.S9S_MB_2U(SCH_1):PAGE66
    U1 DG82 UPI3_RX_DP11 SOCKET4677_AZIF0045P001C01CS-SA    I16 @S9S_MB_2U_LIB.S9S_MB_2U(SCH_1):PAGE66
    U1 DH83 UPI3_RX_DP12 SOCKET4677_AZIF0045P001C01CS-SA    I16 @S9S_MB_2U_LIB.S9S_MB_2U(SCH_1):PAGE66
    U1 DF81 UPI3_RX_DP13 SOCKET4677_AZIF0045P001C01CS-SA    I16 @S9S_MB_2U_LIB.S9S_MB_2U(SCH_1):PAGE66
    U1 DB83 UPI3_RX_DP14 SOCKET4677_AZIF0045P001C01CS-SA    I16 @S9S_MB_2U_LIB.S9S_MB_2U(SCH_1):PAGE66
    U1 DD81 UPI3_RX_DP15 SOCKET4677_AZIF0045P001C01CS-SA    I16 @S9S_MB_2U_LIB.S9S_MB_2U(SCH_1):PAGE66
    U1 DE78 UPI3_RX_DP16 SOCKET4677_AZIF0045P001C01CS-SA    I16 @S9S_MB_2U_LIB.S9S_MB_2U(SCH_1):PAGE66
    U1 CW82 UPI3_RX_DP17 SOCKET4677_AZIF0045P001C01CS-SA    I16 @S9S_MB_2U_LIB.S9S_MB_2U(SCH_1):PAGE66
    U1 CT83 UPI3_RX_DP18 SOCKET4677_AZIF0045P001C01CS-SA    I16 @S9S_MB_2U_LIB.S9S_MB_2U(SCH_1):PAGE66
    U1 CV81 UPI3_RX_DP19 SOCKET4677_AZIF0045P001C01CS-SA    I16 @S9S_MB_2U_LIB.S9S_MB_2U(SCH_1):PAGE66
    U1 CN82 UPI3_RX_DP20 SOCKET4677_AZIF0045P001C01CS-SA    I16 @S9S_MB_2U_LIB.S9S_MB_2U(SCH_1):PAGE66
    U1 CR80 UPI3_RX_DP21 SOCKET4677_AZIF0045P001C01CS-SA    I16 @S9S_MB_2U_LIB.S9S_MB_2U(SCH_1):PAGE66
    U1 CU80 UPI3_RX_DP22 SOCKET4677_AZIF0045P001C01CS-SA    I16 @S9S_MB_2U_LIB.S9S_MB_2U(SCH_1):PAGE66
    U1 DB79 UPI3_RX_DP23 SOCKET4677_AZIF0045P001C01CS-SA    I16 @S9S_MB_2U_LIB.S9S_MB_2U(SCH_1):PAGE66
   C71    2      B Q_CAP_C0402-10UF,6.3V,20%,X6S,A     I4 @S9S_MB_2U_LIB.S9S_MB_2U(SCH_1):PAGE68
    U1 EH42 VSS1312 SOCKET4677_AZIF0045P001C01CS-SA     I2 @S9S_MB_2U_LIB.S9S_MB_2U(SCH_1):PAGE70
    U1 EH55 VSS1315 SOCKET4677_AZIF0045P001C01CS-SA     I2 @S9S_MB_2U_LIB.S9S_MB_2U(SCH_1):PAGE70
    U1 EH61 VSS1319 SOCKET4677_AZIF0045P001C01CS-SA     I2 @S9S_MB_2U_LIB.S9S_MB_2U(SCH_1):PAGE70
    U1 EH67 VSS1320 SOCKET4677_AZIF0045P001C01CS-SA     I2 @S9S_MB_2U_LIB.S9S_MB_2U(SCH_1):PAGE70
    U1 EH79 VSS1322 SOCKET4677_AZIF0045P001C01CS-SA     I2 @S9S_MB_2U_LIB.S9S_MB_2U(SCH_1):PAGE70
    U1 EJ11 VSS1325 SOCKET4677_AZIF0045P001C01CS-SA     I2 @S9S_MB_2U_LIB.S9S_MB_2U(SCH_1):PAGE70
    U1 EJ17 VSS1328 SOCKET4677_AZIF0045P001C01CS-SA     I2 @S9S_MB_2U_LIB.S9S_MB_2U(SCH_1):PAGE70
    U1 EJ25 VSS1331 SOCKET4677_AZIF0045P001C01CS-SA     I2 @S9S_MB_2U_LIB.S9S_MB_2U(SCH_1):PAGE70
    U1 EJ35 VSS1334 SOCKET4677_AZIF0045P001C01CS-SA     I2 @S9S_MB_2U_LIB.S9S_MB_2U(SCH_1):PAGE70
    U1 EJ54 VSS1340 SOCKET4677_AZIF0045P001C01CS-SA     I2 @S9S_MB_2U_LIB.S9S_MB_2U(SCH_1):PAGE70
    U1 EJ62 VSS1343 SOCKET4677_AZIF0045P001C01CS-SA     I2 @S9S_MB_2U_LIB.S9S_MB_2U(SCH_1):PAGE70
    U1 EJ68 VSS1345 SOCKET4677_AZIF0045P001C01CS-SA     I2 @S9S_MB_2U_LIB.S9S_MB_2U(SCH_1):PAGE70
    U1 EJ72 VSS1347 SOCKET4677_AZIF0045P001C01CS-SA     I2 @S9S_MB_2U_LIB.S9S_MB_2U(SCH_1):PAGE70
    U1 EK16 VSS1355 SOCKET4677_AZIF0045P001C01CS-SA     I2 @S9S_MB_2U_LIB.S9S_MB_2U(SCH_1):PAGE70
    U1 EK20 VSS1357 SOCKET4677_AZIF0045P001C01CS-SA     I2 @S9S_MB_2U_LIB.S9S_MB_2U(SCH_1):PAGE70
    U1 EK26 VSS1359 SOCKET4677_AZIF0045P001C01CS-SA     I2 @S9S_MB_2U_LIB.S9S_MB_2U(SCH_1):PAGE70
    U1 EK44 VSS1366 SOCKET4677_AZIF0045P001C01CS-SA     I2 @S9S_MB_2U_LIB.S9S_MB_2U(SCH_1):PAGE70
    U1 EK51 VSS1368 SOCKET4677_AZIF0045P001C01CS-SA     I2 @S9S_MB_2U_LIB.S9S_MB_2U(SCH_1):PAGE70
    U1 EK53 VSS1369 SOCKET4677_AZIF0045P001C01CS-SA     I2 @S9S_MB_2U_LIB.S9S_MB_2U(SCH_1):PAGE70
    U1 EK59 VSS1371 SOCKET4677_AZIF0045P001C01CS-SA     I2 @S9S_MB_2U_LIB.S9S_MB_2U(SCH_1):PAGE70
    U1 EK63 VSS1372 SOCKET4677_AZIF0045P001C01CS-SA     I2 @S9S_MB_2U_LIB.S9S_MB_2U(SCH_1):PAGE70
    U1 EK71 VSS1375 SOCKET4677_AZIF0045P001C01CS-SA     I2 @S9S_MB_2U_LIB.S9S_MB_2U(SCH_1):PAGE70
    U1 EK77 VSS1377 SOCKET4677_AZIF0045P001C01CS-SA     I2 @S9S_MB_2U_LIB.S9S_MB_2U(SCH_1):PAGE70
    U1 EK79 VSS1378 SOCKET4677_AZIF0045P001C01CS-SA     I2 @S9S_MB_2U_LIB.S9S_MB_2U(SCH_1):PAGE70
    U1 EK83 VSS1379 SOCKET4677_AZIF0045P001C01CS-SA     I2 @S9S_MB_2U_LIB.S9S_MB_2U(SCH_1):PAGE70
    U1 EK89 VSS1380 SOCKET4677_AZIF0045P001C01CS-SA     I2 @S9S_MB_2U_LIB.S9S_MB_2U(SCH_1):PAGE70
    U1 EL15 VSS1381 SOCKET4677_AZIF0045P001C01CS-SA     I2 @S9S_MB_2U_LIB.S9S_MB_2U(SCH_1):PAGE70
    U1 EL52 VSS1391 SOCKET4677_AZIF0045P001C01CS-SA     I2 @S9S_MB_2U_LIB.S9S_MB_2U(SCH_1):PAGE70
    U1 EL58 VSS1394 SOCKET4677_AZIF0045P001C01CS-SA     I2 @S9S_MB_2U_LIB.S9S_MB_2U(SCH_1):PAGE70
    U1  EL7 VSS1396 SOCKET4677_AZIF0045P001C01CS-SA     I2 @S9S_MB_2U_LIB.S9S_MB_2U(SCH_1):PAGE70
    U1 EL70 VSS1397 SOCKET4677_AZIF0045P001C01CS-SA     I2 @S9S_MB_2U_LIB.S9S_MB_2U(SCH_1):PAGE70
    U1 EL72 VSS1398 SOCKET4677_AZIF0045P001C01CS-SA     I2 @S9S_MB_2U_LIB.S9S_MB_2U(SCH_1):PAGE70
    U1 EL86 VSS1400 SOCKET4677_AZIF0045P001C01CS-SA     I2 @S9S_MB_2U_LIB.S9S_MB_2U(SCH_1):PAGE70
    U1  EL9 VSS1401 SOCKET4677_AZIF0045P001C01CS-SA     I2 @S9S_MB_2U_LIB.S9S_MB_2U(SCH_1):PAGE70
    U1 EM49 VSS1405 SOCKET4677_AZIF0045P001C01CS-SA     I2 @S9S_MB_2U_LIB.S9S_MB_2U(SCH_1):PAGE70
    U1 EM79 VSS1409 SOCKET4677_AZIF0045P001C01CS-SA     I2 @S9S_MB_2U_LIB.S9S_MB_2U(SCH_1):PAGE70
    U1 EH36 VSS1419 SOCKET4677_AZIF0045P001C01CS-SA     I2 @S9S_MB_2U_LIB.S9S_MB_2U(SCH_1):PAGE70
    U1 EH49 VSS1421 SOCKET4677_AZIF0045P001C01CS-SA     I2 @S9S_MB_2U_LIB.S9S_MB_2U(SCH_1):PAGE70
    U1 EH73 VSS1422 SOCKET4677_AZIF0045P001C01CS-SA     I2 @S9S_MB_2U_LIB.S9S_MB_2U(SCH_1):PAGE70
    U1 EH81 VSS1423 SOCKET4677_AZIF0045P001C01CS-SA     I2 @S9S_MB_2U_LIB.S9S_MB_2U(SCH_1):PAGE70
    U1 EH83 VSS1424 SOCKET4677_AZIF0045P001C01CS-SA     I2 @S9S_MB_2U_LIB.S9S_MB_2U(SCH_1):PAGE70
    U1 EJ13 VSS1425 SOCKET4677_AZIF0045P001C01CS-SA     I2 @S9S_MB_2U_LIB.S9S_MB_2U(SCH_1):PAGE70
    U1 EJ19 VSS1426 SOCKET4677_AZIF0045P001C01CS-SA     I2 @S9S_MB_2U_LIB.S9S_MB_2U(SCH_1):PAGE70
    U1 EN39 VSS1427 SOCKET4677_AZIF0045P001C01CS-SA     I2 @S9S_MB_2U_LIB.S9S_MB_2U(SCH_1):PAGE70
    U1 EJ23 VSS1428 SOCKET4677_AZIF0045P001C01CS-SA     I2 @S9S_MB_2U_LIB.S9S_MB_2U(SCH_1):PAGE70
    U1 EJ29 VSS1429 SOCKET4677_AZIF0045P001C01CS-SA     I2 @S9S_MB_2U_LIB.S9S_MB_2U(SCH_1):PAGE70
    U1 EJ31 VSS1430 SOCKET4677_AZIF0045P001C01CS-SA     I2 @S9S_MB_2U_LIB.S9S_MB_2U(SCH_1):PAGE70
    U1 EJ37 VSS1431 SOCKET4677_AZIF0045P001C01CS-SA     I2 @S9S_MB_2U_LIB.S9S_MB_2U(SCH_1):PAGE70
    U1 EJ41 VSS1432 SOCKET4677_AZIF0045P001C01CS-SA     I2 @S9S_MB_2U_LIB.S9S_MB_2U(SCH_1):PAGE70
    U1 EJ43 VSS1433 SOCKET4677_AZIF0045P001C01CS-SA     I2 @S9S_MB_2U_LIB.S9S_MB_2U(SCH_1):PAGE70
    U1 EJ48 VSS1434 SOCKET4677_AZIF0045P001C01CS-SA     I2 @S9S_MB_2U_LIB.S9S_MB_2U(SCH_1):PAGE70
    U1 EJ50 VSS1435 SOCKET4677_AZIF0045P001C01CS-SA     I2 @S9S_MB_2U_LIB.S9S_MB_2U(SCH_1):PAGE70
    U1 EN58 VSS1436 SOCKET4677_AZIF0045P001C01CS-SA     I2 @S9S_MB_2U_LIB.S9S_MB_2U(SCH_1):PAGE70
    U1 EN60 VSS1437 SOCKET4677_AZIF0045P001C01CS-SA     I2 @S9S_MB_2U_LIB.S9S_MB_2U(SCH_1):PAGE70
    U1 EN62 VSS1438 SOCKET4677_AZIF0045P001C01CS-SA     I2 @S9S_MB_2U_LIB.S9S_MB_2U(SCH_1):PAGE70
    U1 EJ56 VSS1439 SOCKET4677_AZIF0045P001C01CS-SA     I2 @S9S_MB_2U_LIB.S9S_MB_2U(SCH_1):PAGE70
    U1 EN66 VSS1440 SOCKET4677_AZIF0045P001C01CS-SA     I2 @S9S_MB_2U_LIB.S9S_MB_2U(SCH_1):PAGE70
    U1 EN72 VSS1441 SOCKET4677_AZIF0045P001C01CS-SA     I2 @S9S_MB_2U_LIB.S9S_MB_2U(SCH_1):PAGE70
    U1 EJ60 VSS1442 SOCKET4677_AZIF0045P001C01CS-SA     I2 @S9S_MB_2U_LIB.S9S_MB_2U(SCH_1):PAGE70
    U1 EJ66 VSS1443 SOCKET4677_AZIF0045P001C01CS-SA     I2 @S9S_MB_2U_LIB.S9S_MB_2U(SCH_1):PAGE70
    U1  EJ7 VSS1444 SOCKET4677_AZIF0045P001C01CS-SA     I2 @S9S_MB_2U_LIB.S9S_MB_2U(SCH_1):PAGE70
    U1 EN88 VSS1445 SOCKET4677_AZIF0045P001C01CS-SA     I2 @S9S_MB_2U_LIB.S9S_MB_2U(SCH_1):PAGE70
    U1  EN9 VSS1446 SOCKET4677_AZIF0045P001C01CS-SA     I2 @S9S_MB_2U_LIB.S9S_MB_2U(SCH_1):PAGE70
    U1 EJ74 VSS1447 SOCKET4677_AZIF0045P001C01CS-SA     I2 @S9S_MB_2U_LIB.S9S_MB_2U(SCH_1):PAGE70
    U1 EJ78 VSS1448 SOCKET4677_AZIF0045P001C01CS-SA     I2 @S9S_MB_2U_LIB.S9S_MB_2U(SCH_1):PAGE70
    U1 EJ88 VSS1449 SOCKET4677_AZIF0045P001C01CS-SA     I2 @S9S_MB_2U_LIB.S9S_MB_2U(SCH_1):PAGE70
    U1  EJ9 VSS1450 SOCKET4677_AZIF0045P001C01CS-SA     I2 @S9S_MB_2U_LIB.S9S_MB_2U(SCH_1):PAGE70
    U1 EK10 VSS1451 SOCKET4677_AZIF0045P001C01CS-SA     I2 @S9S_MB_2U_LIB.S9S_MB_2U(SCH_1):PAGE70
    U1 EP69 VSS1452 SOCKET4677_AZIF0045P001C01CS-SA     I2 @S9S_MB_2U_LIB.S9S_MB_2U(SCH_1):PAGE70
    U1 EP71 VSS1453 SOCKET4677_AZIF0045P001C01CS-SA     I2 @S9S_MB_2U_LIB.S9S_MB_2U(SCH_1):PAGE70
    U1 EP77 VSS1454 SOCKET4677_AZIF0045P001C01CS-SA     I2 @S9S_MB_2U_LIB.S9S_MB_2U(SCH_1):PAGE70
    U1 EK14 VSS1455 SOCKET4677_AZIF0045P001C01CS-SA     I2 @S9S_MB_2U_LIB.S9S_MB_2U(SCH_1):PAGE70
    U1 ER15 VSS1456 SOCKET4677_AZIF0045P001C01CS-SA     I2 @S9S_MB_2U_LIB.S9S_MB_2U(SCH_1):PAGE70
    U1 ER21 VSS1457 SOCKET4677_AZIF0045P001C01CS-SA     I2 @S9S_MB_2U_LIB.S9S_MB_2U(SCH_1):PAGE70
    U1  EK2 VSS1458 SOCKET4677_AZIF0045P001C01CS-SA     I2 @S9S_MB_2U_LIB.S9S_MB_2U(SCH_1):PAGE70
    U1 EK22 VSS1459 SOCKET4677_AZIF0045P001C01CS-SA     I2 @S9S_MB_2U_LIB.S9S_MB_2U(SCH_1):PAGE70
    U1 EK28 VSS1460 SOCKET4677_AZIF0045P001C01CS-SA     I2 @S9S_MB_2U_LIB.S9S_MB_2U(SCH_1):PAGE70
    U1 EK32 VSS1461 SOCKET4677_AZIF0045P001C01CS-SA     I2 @S9S_MB_2U_LIB.S9S_MB_2U(SCH_1):PAGE70
    U1 ER39 VSS1462 SOCKET4677_AZIF0045P001C01CS-SA     I2 @S9S_MB_2U_LIB.S9S_MB_2U(SCH_1):PAGE70
    U1 EK34 VSS1463 SOCKET4677_AZIF0045P001C01CS-SA     I2 @S9S_MB_2U_LIB.S9S_MB_2U(SCH_1):PAGE70
    U1 ER52 VSS1464 SOCKET4677_AZIF0045P001C01CS-SA     I2 @S9S_MB_2U_LIB.S9S_MB_2U(SCH_1):PAGE70
    U1 EK38 VSS1465 SOCKET4677_AZIF0045P001C01CS-SA     I2 @S9S_MB_2U_LIB.S9S_MB_2U(SCH_1):PAGE70
    U1  EK4 VSS1466 SOCKET4677_AZIF0045P001C01CS-SA     I2 @S9S_MB_2U_LIB.S9S_MB_2U(SCH_1):PAGE70
    U1 ER58 VSS1467 SOCKET4677_AZIF0045P001C01CS-SA     I2 @S9S_MB_2U_LIB.S9S_MB_2U(SCH_1):PAGE70
    U1 ER64 VSS1468 SOCKET4677_AZIF0045P001C01CS-SA     I2 @S9S_MB_2U_LIB.S9S_MB_2U(SCH_1):PAGE70
    U1 EK40 VSS1469 SOCKET4677_AZIF0045P001C01CS-SA     I2 @S9S_MB_2U_LIB.S9S_MB_2U(SCH_1):PAGE70
    U1 EK47 VSS1470 SOCKET4677_AZIF0045P001C01CS-SA     I2 @S9S_MB_2U_LIB.S9S_MB_2U(SCH_1):PAGE70
    U1 EK57 VSS1471 SOCKET4677_AZIF0045P001C01CS-SA     I2 @S9S_MB_2U_LIB.S9S_MB_2U(SCH_1):PAGE70
    U1 EK65 VSS1472 SOCKET4677_AZIF0045P001C01CS-SA     I2 @S9S_MB_2U_LIB.S9S_MB_2U(SCH_1):PAGE70
    U1 EK69 VSS1473 SOCKET4677_AZIF0045P001C01CS-SA     I2 @S9S_MB_2U_LIB.S9S_MB_2U(SCH_1):PAGE70
    U1 EK75 VSS1474 SOCKET4677_AZIF0045P001C01CS-SA     I2 @S9S_MB_2U_LIB.S9S_MB_2U(SCH_1):PAGE70
    U1 EL21 VSS1475 SOCKET4677_AZIF0045P001C01CS-SA     I2 @S9S_MB_2U_LIB.S9S_MB_2U(SCH_1):PAGE70
    U1  ER9 VSS1476 SOCKET4677_AZIF0045P001C01CS-SA     I2 @S9S_MB_2U_LIB.S9S_MB_2U(SCH_1):PAGE70
    U1 EL27 VSS1477 SOCKET4677_AZIF0045P001C01CS-SA     I2 @S9S_MB_2U_LIB.S9S_MB_2U(SCH_1):PAGE70
    U1 ET14 VSS1478 SOCKET4677_AZIF0045P001C01CS-SA     I2 @S9S_MB_2U_LIB.S9S_MB_2U(SCH_1):PAGE70
    U1  EL3 VSS1479 SOCKET4677_AZIF0045P001C01CS-SA     I2 @S9S_MB_2U_LIB.S9S_MB_2U(SCH_1):PAGE70
    U1 ET20 VSS1480 SOCKET4677_AZIF0045P001C01CS-SA     I2 @S9S_MB_2U_LIB.S9S_MB_2U(SCH_1):PAGE70
    U1 EL33 VSS1481 SOCKET4677_AZIF0045P001C01CS-SA     I2 @S9S_MB_2U_LIB.S9S_MB_2U(SCH_1):PAGE70
    U1 ET26 VSS1482 SOCKET4677_AZIF0045P001C01CS-SA     I2 @S9S_MB_2U_LIB.S9S_MB_2U(SCH_1):PAGE70
    U1 EL39 VSS1483 SOCKET4677_AZIF0045P001C01CS-SA     I2 @S9S_MB_2U_LIB.S9S_MB_2U(SCH_1):PAGE70
    U1 ET32 VSS1484 SOCKET4677_AZIF0045P001C01CS-SA     I2 @S9S_MB_2U_LIB.S9S_MB_2U(SCH_1):PAGE70
    U1 EL45 VSS1485 SOCKET4677_AZIF0045P001C01CS-SA     I2 @S9S_MB_2U_LIB.S9S_MB_2U(SCH_1):PAGE70
    U1  EL5 VSS1486 SOCKET4677_AZIF0045P001C01CS-SA     I2 @S9S_MB_2U_LIB.S9S_MB_2U(SCH_1):PAGE70
    U1 EL64 VSS1488 SOCKET4677_AZIF0045P001C01CS-SA     I2 @S9S_MB_2U_LIB.S9S_MB_2U(SCH_1):PAGE70
    U1 EL76 VSS1489 SOCKET4677_AZIF0045P001C01CS-SA     I2 @S9S_MB_2U_LIB.S9S_MB_2U(SCH_1):PAGE70
    U1 ET53 VSS1491 SOCKET4677_AZIF0045P001C01CS-SA     I2 @S9S_MB_2U_LIB.S9S_MB_2U(SCH_1):PAGE70
    U1 EM42 VSS1492 SOCKET4677_AZIF0045P001C01CS-SA     I2 @S9S_MB_2U_LIB.S9S_MB_2U(SCH_1):PAGE70
    U1 ET59 VSS1493 SOCKET4677_AZIF0045P001C01CS-SA     I2 @S9S_MB_2U_LIB.S9S_MB_2U(SCH_1):PAGE70
    U1 EM73 VSS1496 SOCKET4677_AZIF0045P001C01CS-SA     I2 @S9S_MB_2U_LIB.S9S_MB_2U(SCH_1):PAGE70
    U1  EM8 VSS1497 SOCKET4677_AZIF0045P001C01CS-SA     I2 @S9S_MB_2U_LIB.S9S_MB_2U(SCH_1):PAGE70
    U1 EM81 VSS1498 SOCKET4677_AZIF0045P001C01CS-SA     I2 @S9S_MB_2U_LIB.S9S_MB_2U(SCH_1):PAGE70
    U1 EM83 VSS1499 SOCKET4677_AZIF0045P001C01CS-SA     I2 @S9S_MB_2U_LIB.S9S_MB_2U(SCH_1):PAGE70
    U1 EN11 VSS1500 SOCKET4677_AZIF0045P001C01CS-SA     I2 @S9S_MB_2U_LIB.S9S_MB_2U(SCH_1):PAGE70
    U1 EN13 VSS1501 SOCKET4677_AZIF0045P001C01CS-SA     I2 @S9S_MB_2U_LIB.S9S_MB_2U(SCH_1):PAGE70
    U1 EN15 VSS1503 SOCKET4677_AZIF0045P001C01CS-SA     I2 @S9S_MB_2U_LIB.S9S_MB_2U(SCH_1):PAGE70
    U1 EN17 VSS1505 SOCKET4677_AZIF0045P001C01CS-SA     I2 @S9S_MB_2U_LIB.S9S_MB_2U(SCH_1):PAGE70
    U1 EN19 VSS1506 SOCKET4677_AZIF0045P001C01CS-SA     I2 @S9S_MB_2U_LIB.S9S_MB_2U(SCH_1):PAGE70
    U1 EN21 VSS1512 SOCKET4677_AZIF0045P001C01CS-SA     I2 @S9S_MB_2U_LIB.S9S_MB_2U(SCH_1):PAGE70
    U1 EN23 VSS1513 SOCKET4677_AZIF0045P001C01CS-SA     I2 @S9S_MB_2U_LIB.S9S_MB_2U(SCH_1):PAGE70
    U1 EN25 VSS1515 SOCKET4677_AZIF0045P001C01CS-SA     I2 @S9S_MB_2U_LIB.S9S_MB_2U(SCH_1):PAGE70
    U1 EN27 VSS1517 SOCKET4677_AZIF0045P001C01CS-SA     I2 @S9S_MB_2U_LIB.S9S_MB_2U(SCH_1):PAGE70
    U1 EN29 VSS1518 SOCKET4677_AZIF0045P001C01CS-SA     I2 @S9S_MB_2U_LIB.S9S_MB_2U(SCH_1):PAGE70
    U1 EN31 VSS1520 SOCKET4677_AZIF0045P001C01CS-SA     I2 @S9S_MB_2U_LIB.S9S_MB_2U(SCH_1):PAGE70
    U1 EN33 VSS1522 SOCKET4677_AZIF0045P001C01CS-SA     I2 @S9S_MB_2U_LIB.S9S_MB_2U(SCH_1):PAGE70
    U1 EN35 VSS1524 SOCKET4677_AZIF0045P001C01CS-SA     I2 @S9S_MB_2U_LIB.S9S_MB_2U(SCH_1):PAGE70
    U1 EN37 VSS1525 SOCKET4677_AZIF0045P001C01CS-SA     I2 @S9S_MB_2U_LIB.S9S_MB_2U(SCH_1):PAGE70
    U1 EN41 VSS1526 SOCKET4677_AZIF0045P001C01CS-SA     I2 @S9S_MB_2U_LIB.S9S_MB_2U(SCH_1):PAGE70
    U1 EN43 VSS1528 SOCKET4677_AZIF0045P001C01CS-SA     I2 @S9S_MB_2U_LIB.S9S_MB_2U(SCH_1):PAGE70
    U1 EN45 VSS1529 SOCKET4677_AZIF0045P001C01CS-SA     I2 @S9S_MB_2U_LIB.S9S_MB_2U(SCH_1):PAGE70
    U1 EN48 VSS1530 SOCKET4677_AZIF0045P001C01CS-SA     I2 @S9S_MB_2U_LIB.S9S_MB_2U(SCH_1):PAGE70
    U1 EN50 VSS1531 SOCKET4677_AZIF0045P001C01CS-SA     I2 @S9S_MB_2U_LIB.S9S_MB_2U(SCH_1):PAGE70
    U1 EN52 VSS1533 SOCKET4677_AZIF0045P001C01CS-SA     I2 @S9S_MB_2U_LIB.S9S_MB_2U(SCH_1):PAGE70
    U1 EN54 VSS1537 SOCKET4677_AZIF0045P001C01CS-SA     I2 @S9S_MB_2U_LIB.S9S_MB_2U(SCH_1):PAGE70
    U1 EN56 VSS1539 SOCKET4677_AZIF0045P001C01CS-SA     I2 @S9S_MB_2U_LIB.S9S_MB_2U(SCH_1):PAGE70
    U1 EN64 VSS1540 SOCKET4677_AZIF0045P001C01CS-SA     I2 @S9S_MB_2U_LIB.S9S_MB_2U(SCH_1):PAGE70
    U1 EN78 VSS1541 SOCKET4677_AZIF0045P001C01CS-SA     I2 @S9S_MB_2U_LIB.S9S_MB_2U(SCH_1):PAGE70
    U1 EN80 VSS1542 SOCKET4677_AZIF0045P001C01CS-SA     I2 @S9S_MB_2U_LIB.S9S_MB_2U(SCH_1):PAGE70
    U1 EP67 VSS1543 SOCKET4677_AZIF0045P001C01CS-SA     I2 @S9S_MB_2U_LIB.S9S_MB_2U(SCH_1):PAGE70
    U1 EP83 VSS1545 SOCKET4677_AZIF0045P001C01CS-SA     I2 @S9S_MB_2U_LIB.S9S_MB_2U(SCH_1):PAGE70
    U1 ER27 VSS1547 SOCKET4677_AZIF0045P001C01CS-SA     I2 @S9S_MB_2U_LIB.S9S_MB_2U(SCH_1):PAGE70
    U1 ER33 VSS1548 SOCKET4677_AZIF0045P001C01CS-SA     I2 @S9S_MB_2U_LIB.S9S_MB_2U(SCH_1):PAGE70
    U1  ER5 VSS1549 SOCKET4677_AZIF0045P001C01CS-SA     I2 @S9S_MB_2U_LIB.S9S_MB_2U(SCH_1):PAGE70
    U1  ER7 VSS1550 SOCKET4677_AZIF0045P001C01CS-SA     I2 @S9S_MB_2U_LIB.S9S_MB_2U(SCH_1):PAGE70
    U1 ER70 VSS1551 SOCKET4677_AZIF0045P001C01CS-SA     I2 @S9S_MB_2U_LIB.S9S_MB_2U(SCH_1):PAGE70
    U1 ER74 VSS1552 SOCKET4677_AZIF0045P001C01CS-SA     I2 @S9S_MB_2U_LIB.S9S_MB_2U(SCH_1):PAGE70
    U1 ER78 VSS1553 SOCKET4677_AZIF0045P001C01CS-SA     I2 @S9S_MB_2U_LIB.S9S_MB_2U(SCH_1):PAGE70
    U1 ER80 VSS1554 SOCKET4677_AZIF0045P001C01CS-SA     I2 @S9S_MB_2U_LIB.S9S_MB_2U(SCH_1):PAGE70
    U1 ER84 VSS1555 SOCKET4677_AZIF0045P001C01CS-SA     I2 @S9S_MB_2U_LIB.S9S_MB_2U(SCH_1):PAGE70
    U1 ER86 VSS1556 SOCKET4677_AZIF0045P001C01CS-SA     I2 @S9S_MB_2U_LIB.S9S_MB_2U(SCH_1):PAGE70
    U1 ET10 VSS1557 SOCKET4677_AZIF0045P001C01CS-SA     I2 @S9S_MB_2U_LIB.S9S_MB_2U(SCH_1):PAGE70
    U1 ET16 VSS1559 SOCKET4677_AZIF0045P001C01CS-SA     I2 @S9S_MB_2U_LIB.S9S_MB_2U(SCH_1):PAGE70
    U1 ET22 VSS1561 SOCKET4677_AZIF0045P001C01CS-SA     I2 @S9S_MB_2U_LIB.S9S_MB_2U(SCH_1):PAGE70
    U1 ET28 VSS1562 SOCKET4677_AZIF0045P001C01CS-SA     I2 @S9S_MB_2U_LIB.S9S_MB_2U(SCH_1):PAGE70
    U1 ET34 VSS1563 SOCKET4677_AZIF0045P001C01CS-SA     I2 @S9S_MB_2U_LIB.S9S_MB_2U(SCH_1):PAGE70
    U1 ET38 VSS1565 SOCKET4677_AZIF0045P001C01CS-SA     I2 @S9S_MB_2U_LIB.S9S_MB_2U(SCH_1):PAGE70
    U1 ET57 VSS1569 SOCKET4677_AZIF0045P001C01CS-SA     I2 @S9S_MB_2U_LIB.S9S_MB_2U(SCH_1):PAGE70
    U1 ER41 VSS1834 SOCKET4677_AZIF0045P001C01CS-SA     I2 @S9S_MB_2U_LIB.S9S_MB_2U(SCH_1):PAGE70
    U1 ER43 VSS1835 SOCKET4677_AZIF0045P001C01CS-SA     I2 @S9S_MB_2U_LIB.S9S_MB_2U(SCH_1):PAGE70
    U1 ER48 VSS1836 SOCKET4677_AZIF0045P001C01CS-SA     I2 @S9S_MB_2U_LIB.S9S_MB_2U(SCH_1):PAGE70
    U1 ER50 VSS1837 SOCKET4677_AZIF0045P001C01CS-SA     I2 @S9S_MB_2U_LIB.S9S_MB_2U(SCH_1):PAGE70
    U1 DY12 VSS1111 SOCKET4677_AZIF0045P001C01CS-SA     I5 @S9S_MB_2U_LIB.S9S_MB_2U(SCH_1):PAGE70
    U1 DY16 VSS1112 SOCKET4677_AZIF0045P001C01CS-SA     I5 @S9S_MB_2U_LIB.S9S_MB_2U(SCH_1):PAGE70
    U1  DY4 VSS1115 SOCKET4677_AZIF0045P001C01CS-SA     I5 @S9S_MB_2U_LIB.S9S_MB_2U(SCH_1):PAGE70
    U1 DY42 VSS1116 SOCKET4677_AZIF0045P001C01CS-SA     I5 @S9S_MB_2U_LIB.S9S_MB_2U(SCH_1):PAGE70
    U1 EA39 VSS1141 SOCKET4677_AZIF0045P001C01CS-SA     I5 @S9S_MB_2U_LIB.S9S_MB_2U(SCH_1):PAGE70
    U1 EA45 VSS1142 SOCKET4677_AZIF0045P001C01CS-SA     I5 @S9S_MB_2U_LIB.S9S_MB_2U(SCH_1):PAGE70
    U1 EA52 VSS1144 SOCKET4677_AZIF0045P001C01CS-SA     I5 @S9S_MB_2U_LIB.S9S_MB_2U(SCH_1):PAGE70
    U1 EA58 VSS1145 SOCKET4677_AZIF0045P001C01CS-SA     I5 @S9S_MB_2U_LIB.S9S_MB_2U(SCH_1):PAGE70
    U1 EA64 VSS1146 SOCKET4677_AZIF0045P001C01CS-SA     I5 @S9S_MB_2U_LIB.S9S_MB_2U(SCH_1):PAGE70
    U1 EB16 VSS1155 SOCKET4677_AZIF0045P001C01CS-SA     I5 @S9S_MB_2U_LIB.S9S_MB_2U(SCH_1):PAGE70
    U1 EB20 VSS1156 SOCKET4677_AZIF0045P001C01CS-SA     I5 @S9S_MB_2U_LIB.S9S_MB_2U(SCH_1):PAGE70
    U1 EB26 VSS1158 SOCKET4677_AZIF0045P001C01CS-SA     I5 @S9S_MB_2U_LIB.S9S_MB_2U(SCH_1):PAGE70
    U1 EB34 VSS1161 SOCKET4677_AZIF0045P001C01CS-SA     I5 @S9S_MB_2U_LIB.S9S_MB_2U(SCH_1):PAGE70
    U1  EB4 VSS1163 SOCKET4677_AZIF0045P001C01CS-SA     I5 @S9S_MB_2U_LIB.S9S_MB_2U(SCH_1):PAGE70
    U1 EB44 VSS1165 SOCKET4677_AZIF0045P001C01CS-SA     I5 @S9S_MB_2U_LIB.S9S_MB_2U(SCH_1):PAGE70
    U1 EB51 VSS1167 SOCKET4677_AZIF0045P001C01CS-SA     I5 @S9S_MB_2U_LIB.S9S_MB_2U(SCH_1):PAGE70
    U1 EB53 VSS1168 SOCKET4677_AZIF0045P001C01CS-SA     I5 @S9S_MB_2U_LIB.S9S_MB_2U(SCH_1):PAGE70
    U1 EB59 VSS1170 SOCKET4677_AZIF0045P001C01CS-SA     I5 @S9S_MB_2U_LIB.S9S_MB_2U(SCH_1):PAGE70
    U1 EB63 VSS1171 SOCKET4677_AZIF0045P001C01CS-SA     I5 @S9S_MB_2U_LIB.S9S_MB_2U(SCH_1):PAGE70
    U1 EB91 VSS1180 SOCKET4677_AZIF0045P001C01CS-SA     I5 @S9S_MB_2U_LIB.S9S_MB_2U(SCH_1):PAGE70
    U1 EC25 VSS1185 SOCKET4677_AZIF0045P001C01CS-SA     I5 @S9S_MB_2U_LIB.S9S_MB_2U(SCH_1):PAGE70
    U1 EC35 VSS1188 SOCKET4677_AZIF0045P001C01CS-SA     I5 @S9S_MB_2U_LIB.S9S_MB_2U(SCH_1):PAGE70
    U1  EC5 VSS1193 SOCKET4677_AZIF0045P001C01CS-SA     I5 @S9S_MB_2U_LIB.S9S_MB_2U(SCH_1):PAGE70
    U1 EC54 VSS1195 SOCKET4677_AZIF0045P001C01CS-SA     I5 @S9S_MB_2U_LIB.S9S_MB_2U(SCH_1):PAGE70
    U1 EC60 VSS1197 SOCKET4677_AZIF0045P001C01CS-SA     I5 @S9S_MB_2U_LIB.S9S_MB_2U(SCH_1):PAGE70
    U1 EC62 VSS1198 SOCKET4677_AZIF0045P001C01CS-SA     I5 @S9S_MB_2U_LIB.S9S_MB_2U(SCH_1):PAGE70
    U1 EC68 VSS1200 SOCKET4677_AZIF0045P001C01CS-SA     I5 @S9S_MB_2U_LIB.S9S_MB_2U(SCH_1):PAGE70
    U1 ED12 VSS1208 SOCKET4677_AZIF0045P001C01CS-SA     I5 @S9S_MB_2U_LIB.S9S_MB_2U(SCH_1):PAGE70
    U1 ED18 VSS1210 SOCKET4677_AZIF0045P001C01CS-SA     I5 @S9S_MB_2U_LIB.S9S_MB_2U(SCH_1):PAGE70
    U1 ED42 VSS1217 SOCKET4677_AZIF0045P001C01CS-SA     I5 @S9S_MB_2U_LIB.S9S_MB_2U(SCH_1):PAGE70
    U1 ED55 VSS1220 SOCKET4677_AZIF0045P001C01CS-SA     I5 @S9S_MB_2U_LIB.S9S_MB_2U(SCH_1):PAGE70
    U1 ED61 VSS1223 SOCKET4677_AZIF0045P001C01CS-SA     I5 @S9S_MB_2U_LIB.S9S_MB_2U(SCH_1):PAGE70
    U1 ED67 VSS1224 SOCKET4677_AZIF0045P001C01CS-SA     I5 @S9S_MB_2U_LIB.S9S_MB_2U(SCH_1):PAGE70
    U1 ED73 VSS1225 SOCKET4677_AZIF0045P001C01CS-SA     I5 @S9S_MB_2U_LIB.S9S_MB_2U(SCH_1):PAGE70
    U1 EE17 VSS1232 SOCKET4677_AZIF0045P001C01CS-SA     I5 @S9S_MB_2U_LIB.S9S_MB_2U(SCH_1):PAGE70
    U1 EE39 VSS1235 SOCKET4677_AZIF0045P001C01CS-SA     I5 @S9S_MB_2U_LIB.S9S_MB_2U(SCH_1):PAGE70
    U1 EE52 VSS1237 SOCKET4677_AZIF0045P001C01CS-SA     I5 @S9S_MB_2U_LIB.S9S_MB_2U(SCH_1):PAGE70
    U1 DW66 VSS1257 SOCKET4677_AZIF0045P001C01CS-SA     I5 @S9S_MB_2U_LIB.S9S_MB_2U(SCH_1):PAGE70
    U1 DW68 VSS1258 SOCKET4677_AZIF0045P001C01CS-SA     I5 @S9S_MB_2U_LIB.S9S_MB_2U(SCH_1):PAGE70
    U1 DW70 VSS1259 SOCKET4677_AZIF0045P001C01CS-SA     I5 @S9S_MB_2U_LIB.S9S_MB_2U(SCH_1):PAGE70
    U1 DW72 VSS1260 SOCKET4677_AZIF0045P001C01CS-SA     I5 @S9S_MB_2U_LIB.S9S_MB_2U(SCH_1):PAGE70
    U1 DW74 VSS1261 SOCKET4677_AZIF0045P001C01CS-SA     I5 @S9S_MB_2U_LIB.S9S_MB_2U(SCH_1):PAGE70
    U1 DW76 VSS1262 SOCKET4677_AZIF0045P001C01CS-SA     I5 @S9S_MB_2U_LIB.S9S_MB_2U(SCH_1):PAGE70
    U1 DW80 VSS1263 SOCKET4677_AZIF0045P001C01CS-SA     I5 @S9S_MB_2U_LIB.S9S_MB_2U(SCH_1):PAGE70
    U1 DW82 VSS1264 SOCKET4677_AZIF0045P001C01CS-SA     I5 @S9S_MB_2U_LIB.S9S_MB_2U(SCH_1):PAGE70
    U1 EF51 VSS1265 SOCKET4677_AZIF0045P001C01CS-SA     I5 @S9S_MB_2U_LIB.S9S_MB_2U(SCH_1):PAGE70
    U1 DW84 VSS1266 SOCKET4677_AZIF0045P001C01CS-SA     I5 @S9S_MB_2U_LIB.S9S_MB_2U(SCH_1):PAGE70
    U1 DW88 VSS1267 SOCKET4677_AZIF0045P001C01CS-SA     I5 @S9S_MB_2U_LIB.S9S_MB_2U(SCH_1):PAGE70
    U1 DY77 VSS1269 SOCKET4677_AZIF0045P001C01CS-SA     I5 @S9S_MB_2U_LIB.S9S_MB_2U(SCH_1):PAGE70
    U1  DY8 VSS1270 SOCKET4677_AZIF0045P001C01CS-SA     I5 @S9S_MB_2U_LIB.S9S_MB_2U(SCH_1):PAGE70
    U1 EA21 VSS1274 SOCKET4677_AZIF0045P001C01CS-SA     I5 @S9S_MB_2U_LIB.S9S_MB_2U(SCH_1):PAGE70
    U1 EA27 VSS1275 SOCKET4677_AZIF0045P001C01CS-SA     I5 @S9S_MB_2U_LIB.S9S_MB_2U(SCH_1):PAGE70
    U1 EF73 VSS1276 SOCKET4677_AZIF0045P001C01CS-SA     I5 @S9S_MB_2U_LIB.S9S_MB_2U(SCH_1):PAGE70
    U1 EF75 VSS1277 SOCKET4677_AZIF0045P001C01CS-SA     I5 @S9S_MB_2U_LIB.S9S_MB_2U(SCH_1):PAGE70
    U1 EA33 VSS1278 SOCKET4677_AZIF0045P001C01CS-SA     I5 @S9S_MB_2U_LIB.S9S_MB_2U(SCH_1):PAGE70
    U1 EA70 VSS1279 SOCKET4677_AZIF0045P001C01CS-SA     I5 @S9S_MB_2U_LIB.S9S_MB_2U(SCH_1):PAGE70
    U1 EA76 VSS1280 SOCKET4677_AZIF0045P001C01CS-SA     I5 @S9S_MB_2U_LIB.S9S_MB_2U(SCH_1):PAGE70
    U1 EA78 VSS1281 SOCKET4677_AZIF0045P001C01CS-SA     I5 @S9S_MB_2U_LIB.S9S_MB_2U(SCH_1):PAGE70
    U1 EA80 VSS1282 SOCKET4677_AZIF0045P001C01CS-SA     I5 @S9S_MB_2U_LIB.S9S_MB_2U(SCH_1):PAGE70
    U1 EF89 VSS1283 SOCKET4677_AZIF0045P001C01CS-SA     I5 @S9S_MB_2U_LIB.S9S_MB_2U(SCH_1):PAGE70
    U1 EG13 VSS1284 SOCKET4677_AZIF0045P001C01CS-SA     I5 @S9S_MB_2U_LIB.S9S_MB_2U(SCH_1):PAGE70
    U1 EA84 VSS1285 SOCKET4677_AZIF0045P001C01CS-SA     I5 @S9S_MB_2U_LIB.S9S_MB_2U(SCH_1):PAGE70
    U1 EA88 VSS1286 SOCKET4677_AZIF0045P001C01CS-SA     I5 @S9S_MB_2U_LIB.S9S_MB_2U(SCH_1):PAGE70
    U1 EB12 VSS1287 SOCKET4677_AZIF0045P001C01CS-SA     I5 @S9S_MB_2U_LIB.S9S_MB_2U(SCH_1):PAGE70
    U1 EB22 VSS1288 SOCKET4677_AZIF0045P001C01CS-SA     I5 @S9S_MB_2U_LIB.S9S_MB_2U(SCH_1):PAGE70
    U1 EB28 VSS1289 SOCKET4677_AZIF0045P001C01CS-SA     I5 @S9S_MB_2U_LIB.S9S_MB_2U(SCH_1):PAGE70
    U1  EG5 VSS1290 SOCKET4677_AZIF0045P001C01CS-SA     I5 @S9S_MB_2U_LIB.S9S_MB_2U(SCH_1):PAGE70
    U1 EG52 VSS1291 SOCKET4677_AZIF0045P001C01CS-SA     I5 @S9S_MB_2U_LIB.S9S_MB_2U(SCH_1):PAGE70
    U1 EB32 VSS1292 SOCKET4677_AZIF0045P001C01CS-SA     I5 @S9S_MB_2U_LIB.S9S_MB_2U(SCH_1):PAGE70
    U1 EB38 VSS1293 SOCKET4677_AZIF0045P001C01CS-SA     I5 @S9S_MB_2U_LIB.S9S_MB_2U(SCH_1):PAGE70
    U1  EG7 VSS1294 SOCKET4677_AZIF0045P001C01CS-SA     I5 @S9S_MB_2U_LIB.S9S_MB_2U(SCH_1):PAGE70
    U1 EB40 VSS1295 SOCKET4677_AZIF0045P001C01CS-SA     I5 @S9S_MB_2U_LIB.S9S_MB_2U(SCH_1):PAGE70
    U1 EB47 VSS1296 SOCKET4677_AZIF0045P001C01CS-SA     I5 @S9S_MB_2U_LIB.S9S_MB_2U(SCH_1):PAGE70
    U1 EB57 VSS1297 SOCKET4677_AZIF0045P001C01CS-SA     I5 @S9S_MB_2U_LIB.S9S_MB_2U(SCH_1):PAGE70
    U1 EB65 VSS1298 SOCKET4677_AZIF0045P001C01CS-SA     I5 @S9S_MB_2U_LIB.S9S_MB_2U(SCH_1):PAGE70
    U1 EB69 VSS1299 SOCKET4677_AZIF0045P001C01CS-SA     I5 @S9S_MB_2U_LIB.S9S_MB_2U(SCH_1):PAGE70
    U1 EB71 VSS1300 SOCKET4677_AZIF0045P001C01CS-SA     I5 @S9S_MB_2U_LIB.S9S_MB_2U(SCH_1):PAGE70
    U1 EB75 VSS1301 SOCKET4677_AZIF0045P001C01CS-SA     I5 @S9S_MB_2U_LIB.S9S_MB_2U(SCH_1):PAGE70
    U1 EH12 VSS1302 SOCKET4677_AZIF0045P001C01CS-SA     I5 @S9S_MB_2U_LIB.S9S_MB_2U(SCH_1):PAGE70
    U1 EH14 VSS1303 SOCKET4677_AZIF0045P001C01CS-SA     I5 @S9S_MB_2U_LIB.S9S_MB_2U(SCH_1):PAGE70
    U1 EB79 VSS1304 SOCKET4677_AZIF0045P001C01CS-SA     I5 @S9S_MB_2U_LIB.S9S_MB_2U(SCH_1):PAGE70
    U1 EH18 VSS1305 SOCKET4677_AZIF0045P001C01CS-SA     I5 @S9S_MB_2U_LIB.S9S_MB_2U(SCH_1):PAGE70
    U1  EB8 VSS1306 SOCKET4677_AZIF0045P001C01CS-SA     I5 @S9S_MB_2U_LIB.S9S_MB_2U(SCH_1):PAGE70
    U1 EB83 VSS1307 SOCKET4677_AZIF0045P001C01CS-SA     I5 @S9S_MB_2U_LIB.S9S_MB_2U(SCH_1):PAGE70
    U1 EB87 VSS1308 SOCKET4677_AZIF0045P001C01CS-SA     I5 @S9S_MB_2U_LIB.S9S_MB_2U(SCH_1):PAGE70
    U1  EC1 VSS1309 SOCKET4677_AZIF0045P001C01CS-SA     I5 @S9S_MB_2U_LIB.S9S_MB_2U(SCH_1):PAGE70
    U1 EC13 VSS1310 SOCKET4677_AZIF0045P001C01CS-SA     I5 @S9S_MB_2U_LIB.S9S_MB_2U(SCH_1):PAGE70
    U1 EC19 VSS1311 SOCKET4677_AZIF0045P001C01CS-SA     I5 @S9S_MB_2U_LIB.S9S_MB_2U(SCH_1):PAGE70
    U1 EC23 VSS1313 SOCKET4677_AZIF0045P001C01CS-SA     I5 @S9S_MB_2U_LIB.S9S_MB_2U(SCH_1):PAGE70
    U1 EC29 VSS1314 SOCKET4677_AZIF0045P001C01CS-SA     I5 @S9S_MB_2U_LIB.S9S_MB_2U(SCH_1):PAGE70
    U1 EC31 VSS1316 SOCKET4677_AZIF0045P001C01CS-SA     I5 @S9S_MB_2U_LIB.S9S_MB_2U(SCH_1):PAGE70
    U1 EC37 VSS1317 SOCKET4677_AZIF0045P001C01CS-SA     I5 @S9S_MB_2U_LIB.S9S_MB_2U(SCH_1):PAGE70
    U1  EH6 VSS1318 SOCKET4677_AZIF0045P001C01CS-SA     I5 @S9S_MB_2U_LIB.S9S_MB_2U(SCH_1):PAGE70
    U1 EC41 VSS1321 SOCKET4677_AZIF0045P001C01CS-SA     I5 @S9S_MB_2U_LIB.S9S_MB_2U(SCH_1):PAGE70
    U1 EC43 VSS1323 SOCKET4677_AZIF0045P001C01CS-SA     I5 @S9S_MB_2U_LIB.S9S_MB_2U(SCH_1):PAGE70
    U1 EC48 VSS1324 SOCKET4677_AZIF0045P001C01CS-SA     I5 @S9S_MB_2U_LIB.S9S_MB_2U(SCH_1):PAGE70
    U1 EC50 VSS1326 SOCKET4677_AZIF0045P001C01CS-SA     I5 @S9S_MB_2U_LIB.S9S_MB_2U(SCH_1):PAGE70
    U1 EC56 VSS1327 SOCKET4677_AZIF0045P001C01CS-SA     I5 @S9S_MB_2U_LIB.S9S_MB_2U(SCH_1):PAGE70
    U1 EC66 VSS1329 SOCKET4677_AZIF0045P001C01CS-SA     I5 @S9S_MB_2U_LIB.S9S_MB_2U(SCH_1):PAGE70
    U1 EC72 VSS1330 SOCKET4677_AZIF0045P001C01CS-SA     I5 @S9S_MB_2U_LIB.S9S_MB_2U(SCH_1):PAGE70
    U1 EC74 VSS1332 SOCKET4677_AZIF0045P001C01CS-SA     I5 @S9S_MB_2U_LIB.S9S_MB_2U(SCH_1):PAGE70
    U1 EC82 VSS1333 SOCKET4677_AZIF0045P001C01CS-SA     I5 @S9S_MB_2U_LIB.S9S_MB_2U(SCH_1):PAGE70
    U1 EC84 VSS1335 SOCKET4677_AZIF0045P001C01CS-SA     I5 @S9S_MB_2U_LIB.S9S_MB_2U(SCH_1):PAGE70
    U1 EC88 VSS1336 SOCKET4677_AZIF0045P001C01CS-SA     I5 @S9S_MB_2U_LIB.S9S_MB_2U(SCH_1):PAGE70
    U1  EC9 VSS1337 SOCKET4677_AZIF0045P001C01CS-SA     I5 @S9S_MB_2U_LIB.S9S_MB_2U(SCH_1):PAGE70
    U1 ED16 VSS1338 SOCKET4677_AZIF0045P001C01CS-SA     I5 @S9S_MB_2U_LIB.S9S_MB_2U(SCH_1):PAGE70
    U1 ED24 VSS1339 SOCKET4677_AZIF0045P001C01CS-SA     I5 @S9S_MB_2U_LIB.S9S_MB_2U(SCH_1):PAGE70
    U1 ED30 VSS1341 SOCKET4677_AZIF0045P001C01CS-SA     I5 @S9S_MB_2U_LIB.S9S_MB_2U(SCH_1):PAGE70
    U1 ED36 VSS1342 SOCKET4677_AZIF0045P001C01CS-SA     I5 @S9S_MB_2U_LIB.S9S_MB_2U(SCH_1):PAGE70
    U1  ED4 VSS1344 SOCKET4677_AZIF0045P001C01CS-SA     I5 @S9S_MB_2U_LIB.S9S_MB_2U(SCH_1):PAGE70
    U1 ED49 VSS1346 SOCKET4677_AZIF0045P001C01CS-SA     I5 @S9S_MB_2U_LIB.S9S_MB_2U(SCH_1):PAGE70
    U1  ED8 VSS1348 SOCKET4677_AZIF0045P001C01CS-SA     I5 @S9S_MB_2U_LIB.S9S_MB_2U(SCH_1):PAGE70
    U1 EE78 VSS1349 SOCKET4677_AZIF0045P001C01CS-SA     I5 @S9S_MB_2U_LIB.S9S_MB_2U(SCH_1):PAGE70
    U1 EE80 VSS1350 SOCKET4677_AZIF0045P001C01CS-SA     I5 @S9S_MB_2U_LIB.S9S_MB_2U(SCH_1):PAGE70
    U1 EE88 VSS1351 SOCKET4677_AZIF0045P001C01CS-SA     I5 @S9S_MB_2U_LIB.S9S_MB_2U(SCH_1):PAGE70
    U1 EF12 VSS1352 SOCKET4677_AZIF0045P001C01CS-SA     I5 @S9S_MB_2U_LIB.S9S_MB_2U(SCH_1):PAGE70
    U1 EF16 VSS1353 SOCKET4677_AZIF0045P001C01CS-SA     I5 @S9S_MB_2U_LIB.S9S_MB_2U(SCH_1):PAGE70
    U1 EF18 VSS1354 SOCKET4677_AZIF0045P001C01CS-SA     I5 @S9S_MB_2U_LIB.S9S_MB_2U(SCH_1):PAGE70
    U1  EF2 VSS1356 SOCKET4677_AZIF0045P001C01CS-SA     I5 @S9S_MB_2U_LIB.S9S_MB_2U(SCH_1):PAGE70
    U1 EF20 VSS1358 SOCKET4677_AZIF0045P001C01CS-SA     I5 @S9S_MB_2U_LIB.S9S_MB_2U(SCH_1):PAGE70
    U1 EF22 VSS1360 SOCKET4677_AZIF0045P001C01CS-SA     I5 @S9S_MB_2U_LIB.S9S_MB_2U(SCH_1):PAGE70
    U1 EF24 VSS1361 SOCKET4677_AZIF0045P001C01CS-SA     I5 @S9S_MB_2U_LIB.S9S_MB_2U(SCH_1):PAGE70
    U1 EF26 VSS1362 SOCKET4677_AZIF0045P001C01CS-SA     I5 @S9S_MB_2U_LIB.S9S_MB_2U(SCH_1):PAGE70
    U1 EF28 VSS1363 SOCKET4677_AZIF0045P001C01CS-SA     I5 @S9S_MB_2U_LIB.S9S_MB_2U(SCH_1):PAGE70
    U1 EF30 VSS1364 SOCKET4677_AZIF0045P001C01CS-SA     I5 @S9S_MB_2U_LIB.S9S_MB_2U(SCH_1):PAGE70
    U1 EF32 VSS1365 SOCKET4677_AZIF0045P001C01CS-SA     I5 @S9S_MB_2U_LIB.S9S_MB_2U(SCH_1):PAGE70
    U1 EF34 VSS1367 SOCKET4677_AZIF0045P001C01CS-SA     I5 @S9S_MB_2U_LIB.S9S_MB_2U(SCH_1):PAGE70
    U1 EF36 VSS1370 SOCKET4677_AZIF0045P001C01CS-SA     I5 @S9S_MB_2U_LIB.S9S_MB_2U(SCH_1):PAGE70
    U1 EF38 VSS1373 SOCKET4677_AZIF0045P001C01CS-SA     I5 @S9S_MB_2U_LIB.S9S_MB_2U(SCH_1):PAGE70
    U1  EF4 VSS1374 SOCKET4677_AZIF0045P001C01CS-SA     I5 @S9S_MB_2U_LIB.S9S_MB_2U(SCH_1):PAGE70
    U1 EF40 VSS1376 SOCKET4677_AZIF0045P001C01CS-SA     I5 @S9S_MB_2U_LIB.S9S_MB_2U(SCH_1):PAGE70
    U1 EF42 VSS1382 SOCKET4677_AZIF0045P001C01CS-SA     I5 @S9S_MB_2U_LIB.S9S_MB_2U(SCH_1):PAGE70
    U1 EF44 VSS1383 SOCKET4677_AZIF0045P001C01CS-SA     I5 @S9S_MB_2U_LIB.S9S_MB_2U(SCH_1):PAGE70
    U1 EF47 VSS1384 SOCKET4677_AZIF0045P001C01CS-SA     I5 @S9S_MB_2U_LIB.S9S_MB_2U(SCH_1):PAGE70
    U1 EF49 VSS1385 SOCKET4677_AZIF0045P001C01CS-SA     I5 @S9S_MB_2U_LIB.S9S_MB_2U(SCH_1):PAGE70
    U1 EF53 VSS1386 SOCKET4677_AZIF0045P001C01CS-SA     I5 @S9S_MB_2U_LIB.S9S_MB_2U(SCH_1):PAGE70
    U1 EF55 VSS1387 SOCKET4677_AZIF0045P001C01CS-SA     I5 @S9S_MB_2U_LIB.S9S_MB_2U(SCH_1):PAGE70
    U1 EF57 VSS1388 SOCKET4677_AZIF0045P001C01CS-SA     I5 @S9S_MB_2U_LIB.S9S_MB_2U(SCH_1):PAGE70
    U1 EF59 VSS1389 SOCKET4677_AZIF0045P001C01CS-SA     I5 @S9S_MB_2U_LIB.S9S_MB_2U(SCH_1):PAGE70
    U1 EF61 VSS1390 SOCKET4677_AZIF0045P001C01CS-SA     I5 @S9S_MB_2U_LIB.S9S_MB_2U(SCH_1):PAGE70
    U1 EF63 VSS1392 SOCKET4677_AZIF0045P001C01CS-SA     I5 @S9S_MB_2U_LIB.S9S_MB_2U(SCH_1):PAGE70
    U1 EF65 VSS1393 SOCKET4677_AZIF0045P001C01CS-SA     I5 @S9S_MB_2U_LIB.S9S_MB_2U(SCH_1):PAGE70
    U1 EF67 VSS1395 SOCKET4677_AZIF0045P001C01CS-SA     I5 @S9S_MB_2U_LIB.S9S_MB_2U(SCH_1):PAGE70
    U1 EF69 VSS1399 SOCKET4677_AZIF0045P001C01CS-SA     I5 @S9S_MB_2U_LIB.S9S_MB_2U(SCH_1):PAGE70
    U1 EF71 VSS1402 SOCKET4677_AZIF0045P001C01CS-SA     I5 @S9S_MB_2U_LIB.S9S_MB_2U(SCH_1):PAGE70
    U1 EF77 VSS1403 SOCKET4677_AZIF0045P001C01CS-SA     I5 @S9S_MB_2U_LIB.S9S_MB_2U(SCH_1):PAGE70
    U1  EF8 VSS1404 SOCKET4677_AZIF0045P001C01CS-SA     I5 @S9S_MB_2U_LIB.S9S_MB_2U(SCH_1):PAGE70
    U1 EF85 VSS1406 SOCKET4677_AZIF0045P001C01CS-SA     I5 @S9S_MB_2U_LIB.S9S_MB_2U(SCH_1):PAGE70
    U1 EF87 VSS1407 SOCKET4677_AZIF0045P001C01CS-SA     I5 @S9S_MB_2U_LIB.S9S_MB_2U(SCH_1):PAGE70
    U1 EG39 VSS1408 SOCKET4677_AZIF0045P001C01CS-SA     I5 @S9S_MB_2U_LIB.S9S_MB_2U(SCH_1):PAGE70
    U1 EG82 VSS1410 SOCKET4677_AZIF0045P001C01CS-SA     I5 @S9S_MB_2U_LIB.S9S_MB_2U(SCH_1):PAGE70
    U1 EG84 VSS1411 SOCKET4677_AZIF0045P001C01CS-SA     I5 @S9S_MB_2U_LIB.S9S_MB_2U(SCH_1):PAGE70
    U1 EG86 VSS1412 SOCKET4677_AZIF0045P001C01CS-SA     I5 @S9S_MB_2U_LIB.S9S_MB_2U(SCH_1):PAGE70
    U1 EG88 VSS1413 SOCKET4677_AZIF0045P001C01CS-SA     I5 @S9S_MB_2U_LIB.S9S_MB_2U(SCH_1):PAGE70
    U1  EG9 VSS1414 SOCKET4677_AZIF0045P001C01CS-SA     I5 @S9S_MB_2U_LIB.S9S_MB_2U(SCH_1):PAGE70
    U1 EG90 VSS1415 SOCKET4677_AZIF0045P001C01CS-SA     I5 @S9S_MB_2U_LIB.S9S_MB_2U(SCH_1):PAGE70
    U1 EH16 VSS1416 SOCKET4677_AZIF0045P001C01CS-SA     I5 @S9S_MB_2U_LIB.S9S_MB_2U(SCH_1):PAGE70
    U1 EH24 VSS1417 SOCKET4677_AZIF0045P001C01CS-SA     I5 @S9S_MB_2U_LIB.S9S_MB_2U(SCH_1):PAGE70
    U1 EH30 VSS1418 SOCKET4677_AZIF0045P001C01CS-SA     I5 @S9S_MB_2U_LIB.S9S_MB_2U(SCH_1):PAGE70
    U1  EH4 VSS1420 SOCKET4677_AZIF0045P001C01CS-SA     I5 @S9S_MB_2U_LIB.S9S_MB_2U(SCH_1):PAGE70
    U1 DM51 VSS934 SOCKET4677_AZIF0045P001C01CS-SA     I8 @S9S_MB_2U_LIB.S9S_MB_2U(SCH_1):PAGE70
    U1 DM73 VSS945 SOCKET4677_AZIF0045P001C01CS-SA     I8 @S9S_MB_2U_LIB.S9S_MB_2U(SCH_1):PAGE70
    U1 DN17 VSS955 SOCKET4677_AZIF0045P001C01CS-SA     I8 @S9S_MB_2U_LIB.S9S_MB_2U(SCH_1):PAGE70
    U1 DN39 VSS957 SOCKET4677_AZIF0045P001C01CS-SA     I8 @S9S_MB_2U_LIB.S9S_MB_2U(SCH_1):PAGE70
    U1 DN52 VSS959 SOCKET4677_AZIF0045P001C01CS-SA     I8 @S9S_MB_2U_LIB.S9S_MB_2U(SCH_1):PAGE70
    U1 DP12 VSS966 SOCKET4677_AZIF0045P001C01CS-SA     I8 @S9S_MB_2U_LIB.S9S_MB_2U(SCH_1):PAGE70
    U1 DP18 VSS968 SOCKET4677_AZIF0045P001C01CS-SA     I8 @S9S_MB_2U_LIB.S9S_MB_2U(SCH_1):PAGE70
    U1 DP24 VSS969 SOCKET4677_AZIF0045P001C01CS-SA     I8 @S9S_MB_2U_LIB.S9S_MB_2U(SCH_1):PAGE70
    U1 DP42 VSS973 SOCKET4677_AZIF0045P001C01CS-SA     I8 @S9S_MB_2U_LIB.S9S_MB_2U(SCH_1):PAGE70
    U1 DP55 VSS976 SOCKET4677_AZIF0045P001C01CS-SA     I8 @S9S_MB_2U_LIB.S9S_MB_2U(SCH_1):PAGE70
    U1 DP61 VSS979 SOCKET4677_AZIF0045P001C01CS-SA     I8 @S9S_MB_2U_LIB.S9S_MB_2U(SCH_1):PAGE70
    U1 DP67 VSS980 SOCKET4677_AZIF0045P001C01CS-SA     I8 @S9S_MB_2U_LIB.S9S_MB_2U(SCH_1):PAGE70
    U1 DP91 VSS985 SOCKET4677_AZIF0045P001C01CS-SA     I8 @S9S_MB_2U_LIB.S9S_MB_2U(SCH_1):PAGE70
    U1 DR25 VSS990 SOCKET4677_AZIF0045P001C01CS-SA     I8 @S9S_MB_2U_LIB.S9S_MB_2U(SCH_1):PAGE70
    U1 DR35 VSS993 SOCKET4677_AZIF0045P001C01CS-SA     I8 @S9S_MB_2U_LIB.S9S_MB_2U(SCH_1):PAGE70
    U1  DR5 VSS998 SOCKET4677_AZIF0045P001C01CS-SA     I8 @S9S_MB_2U_LIB.S9S_MB_2U(SCH_1):PAGE70
    U1 DR54 VSS1000 SOCKET4677_AZIF0045P001C01CS-SA     I8 @S9S_MB_2U_LIB.S9S_MB_2U(SCH_1):PAGE70
    U1 DR60 VSS1002 SOCKET4677_AZIF0045P001C01CS-SA     I8 @S9S_MB_2U_LIB.S9S_MB_2U(SCH_1):PAGE70
    U1 DR62 VSS1003 SOCKET4677_AZIF0045P001C01CS-SA     I8 @S9S_MB_2U_LIB.S9S_MB_2U(SCH_1):PAGE70
    U1 DR68 VSS1005 SOCKET4677_AZIF0045P001C01CS-SA     I8 @S9S_MB_2U_LIB.S9S_MB_2U(SCH_1):PAGE70
    U1 DR72 VSS1006 SOCKET4677_AZIF0045P001C01CS-SA     I8 @S9S_MB_2U_LIB.S9S_MB_2U(SCH_1):PAGE70
    U1 DT16 VSS1013 SOCKET4677_AZIF0045P001C01CS-SA     I8 @S9S_MB_2U_LIB.S9S_MB_2U(SCH_1):PAGE70
    U1 DT20 VSS1014 SOCKET4677_AZIF0045P001C01CS-SA     I8 @S9S_MB_2U_LIB.S9S_MB_2U(SCH_1):PAGE70
    U1 DT26 VSS1016 SOCKET4677_AZIF0045P001C01CS-SA     I8 @S9S_MB_2U_LIB.S9S_MB_2U(SCH_1):PAGE70
    U1  DT4 VSS1021 SOCKET4677_AZIF0045P001C01CS-SA     I8 @S9S_MB_2U_LIB.S9S_MB_2U(SCH_1):PAGE70
    U1 DT44 VSS1023 SOCKET4677_AZIF0045P001C01CS-SA     I8 @S9S_MB_2U_LIB.S9S_MB_2U(SCH_1):PAGE70
    U1 DT51 VSS1025 SOCKET4677_AZIF0045P001C01CS-SA     I8 @S9S_MB_2U_LIB.S9S_MB_2U(SCH_1):PAGE70
    U1 DT53 VSS1026 SOCKET4677_AZIF0045P001C01CS-SA     I8 @S9S_MB_2U_LIB.S9S_MB_2U(SCH_1):PAGE70
    U1 DT59 VSS1028 SOCKET4677_AZIF0045P001C01CS-SA     I8 @S9S_MB_2U_LIB.S9S_MB_2U(SCH_1):PAGE70
    U1 DT63 VSS1029 SOCKET4677_AZIF0045P001C01CS-SA     I8 @S9S_MB_2U_LIB.S9S_MB_2U(SCH_1):PAGE70
    U1 DT83 VSS1036 SOCKET4677_AZIF0045P001C01CS-SA     I8 @S9S_MB_2U_LIB.S9S_MB_2U(SCH_1):PAGE70
    U1 DU39 VSS1047 SOCKET4677_AZIF0045P001C01CS-SA     I8 @S9S_MB_2U_LIB.S9S_MB_2U(SCH_1):PAGE70
    U1 DU45 VSS1048 SOCKET4677_AZIF0045P001C01CS-SA     I8 @S9S_MB_2U_LIB.S9S_MB_2U(SCH_1):PAGE70
    U1 DU52 VSS1050 SOCKET4677_AZIF0045P001C01CS-SA     I8 @S9S_MB_2U_LIB.S9S_MB_2U(SCH_1):PAGE70
    U1 DU58 VSS1051 SOCKET4677_AZIF0045P001C01CS-SA     I8 @S9S_MB_2U_LIB.S9S_MB_2U(SCH_1):PAGE70
    U1 DU64 VSS1052 SOCKET4677_AZIF0045P001C01CS-SA     I8 @S9S_MB_2U_LIB.S9S_MB_2U(SCH_1):PAGE70
    U1 DU70 VSS1054 SOCKET4677_AZIF0045P001C01CS-SA     I8 @S9S_MB_2U_LIB.S9S_MB_2U(SCH_1):PAGE70
    U1 DV12 VSS1059 SOCKET4677_AZIF0045P001C01CS-SA     I8 @S9S_MB_2U_LIB.S9S_MB_2U(SCH_1):PAGE70
    U1 DV16 VSS1060 SOCKET4677_AZIF0045P001C01CS-SA     I8 @S9S_MB_2U_LIB.S9S_MB_2U(SCH_1):PAGE70
    U1  DV4 VSS1063 SOCKET4677_AZIF0045P001C01CS-SA     I8 @S9S_MB_2U_LIB.S9S_MB_2U(SCH_1):PAGE70
    U1 DV42 VSS1064 SOCKET4677_AZIF0045P001C01CS-SA     I8 @S9S_MB_2U_LIB.S9S_MB_2U(SCH_1):PAGE70
    U1 DW21 VSS1077 SOCKET4677_AZIF0045P001C01CS-SA     I8 @S9S_MB_2U_LIB.S9S_MB_2U(SCH_1):PAGE70
    U1 DW60 VSS1097 SOCKET4677_AZIF0045P001C01CS-SA     I8 @S9S_MB_2U_LIB.S9S_MB_2U(SCH_1):PAGE70
    U1 DM12 VSS1100 SOCKET4677_AZIF0045P001C01CS-SA     I8 @S9S_MB_2U_LIB.S9S_MB_2U(SCH_1):PAGE70
    U1 DM16 VSS1101 SOCKET4677_AZIF0045P001C01CS-SA     I8 @S9S_MB_2U_LIB.S9S_MB_2U(SCH_1):PAGE70
    U1 DM18 VSS1102 SOCKET4677_AZIF0045P001C01CS-SA     I8 @S9S_MB_2U_LIB.S9S_MB_2U(SCH_1):PAGE70
    U1 DM20 VSS1103 SOCKET4677_AZIF0045P001C01CS-SA     I8 @S9S_MB_2U_LIB.S9S_MB_2U(SCH_1):PAGE70
    U1 DM22 VSS1104 SOCKET4677_AZIF0045P001C01CS-SA     I8 @S9S_MB_2U_LIB.S9S_MB_2U(SCH_1):PAGE70
    U1 DM24 VSS1105 SOCKET4677_AZIF0045P001C01CS-SA     I8 @S9S_MB_2U_LIB.S9S_MB_2U(SCH_1):PAGE70
    U1 DM26 VSS1106 SOCKET4677_AZIF0045P001C01CS-SA     I8 @S9S_MB_2U_LIB.S9S_MB_2U(SCH_1):PAGE70
    U1 DM28 VSS1107 SOCKET4677_AZIF0045P001C01CS-SA     I8 @S9S_MB_2U_LIB.S9S_MB_2U(SCH_1):PAGE70
    U1 DM30 VSS1108 SOCKET4677_AZIF0045P001C01CS-SA     I8 @S9S_MB_2U_LIB.S9S_MB_2U(SCH_1):PAGE70
    U1 DM32 VSS1109 SOCKET4677_AZIF0045P001C01CS-SA     I8 @S9S_MB_2U_LIB.S9S_MB_2U(SCH_1):PAGE70
    U1 DM34 VSS1110 SOCKET4677_AZIF0045P001C01CS-SA     I8 @S9S_MB_2U_LIB.S9S_MB_2U(SCH_1):PAGE70
    U1 DM36 VSS1113 SOCKET4677_AZIF0045P001C01CS-SA     I8 @S9S_MB_2U_LIB.S9S_MB_2U(SCH_1):PAGE70
    U1 DM38 VSS1114 SOCKET4677_AZIF0045P001C01CS-SA     I8 @S9S_MB_2U_LIB.S9S_MB_2U(SCH_1):PAGE70
    U1  DM4 VSS1117 SOCKET4677_AZIF0045P001C01CS-SA     I8 @S9S_MB_2U_LIB.S9S_MB_2U(SCH_1):PAGE70
    U1 DM40 VSS1118 SOCKET4677_AZIF0045P001C01CS-SA     I8 @S9S_MB_2U_LIB.S9S_MB_2U(SCH_1):PAGE70
    U1 DM42 VSS1119 SOCKET4677_AZIF0045P001C01CS-SA     I8 @S9S_MB_2U_LIB.S9S_MB_2U(SCH_1):PAGE70
    U1 DM44 VSS1120 SOCKET4677_AZIF0045P001C01CS-SA     I8 @S9S_MB_2U_LIB.S9S_MB_2U(SCH_1):PAGE70
    U1 DM47 VSS1121 SOCKET4677_AZIF0045P001C01CS-SA     I8 @S9S_MB_2U_LIB.S9S_MB_2U(SCH_1):PAGE70
    U1 DM49 VSS1122 SOCKET4677_AZIF0045P001C01CS-SA     I8 @S9S_MB_2U_LIB.S9S_MB_2U(SCH_1):PAGE70
    U1 DM53 VSS1123 SOCKET4677_AZIF0045P001C01CS-SA     I8 @S9S_MB_2U_LIB.S9S_MB_2U(SCH_1):PAGE70
    U1 DM55 VSS1124 SOCKET4677_AZIF0045P001C01CS-SA     I8 @S9S_MB_2U_LIB.S9S_MB_2U(SCH_1):PAGE70
    U1 DM57 VSS1127 SOCKET4677_AZIF0045P001C01CS-SA     I8 @S9S_MB_2U_LIB.S9S_MB_2U(SCH_1):PAGE70
    U1 DM59 VSS1128 SOCKET4677_AZIF0045P001C01CS-SA     I8 @S9S_MB_2U_LIB.S9S_MB_2U(SCH_1):PAGE70
    U1 DM61 VSS1130 SOCKET4677_AZIF0045P001C01CS-SA     I8 @S9S_MB_2U_LIB.S9S_MB_2U(SCH_1):PAGE70
    U1 DM63 VSS1132 SOCKET4677_AZIF0045P001C01CS-SA     I8 @S9S_MB_2U_LIB.S9S_MB_2U(SCH_1):PAGE70
    U1 DM65 VSS1133 SOCKET4677_AZIF0045P001C01CS-SA     I8 @S9S_MB_2U_LIB.S9S_MB_2U(SCH_1):PAGE70
    U1 DM67 VSS1134 SOCKET4677_AZIF0045P001C01CS-SA     I8 @S9S_MB_2U_LIB.S9S_MB_2U(SCH_1):PAGE70
    U1 DM69 VSS1135 SOCKET4677_AZIF0045P001C01CS-SA     I8 @S9S_MB_2U_LIB.S9S_MB_2U(SCH_1):PAGE70
    U1 DM71 VSS1136 SOCKET4677_AZIF0045P001C01CS-SA     I8 @S9S_MB_2U_LIB.S9S_MB_2U(SCH_1):PAGE70
    U1 DM75 VSS1137 SOCKET4677_AZIF0045P001C01CS-SA     I8 @S9S_MB_2U_LIB.S9S_MB_2U(SCH_1):PAGE70
    U1 DM77 VSS1138 SOCKET4677_AZIF0045P001C01CS-SA     I8 @S9S_MB_2U_LIB.S9S_MB_2U(SCH_1):PAGE70
    U1 DM79 VSS1139 SOCKET4677_AZIF0045P001C01CS-SA     I8 @S9S_MB_2U_LIB.S9S_MB_2U(SCH_1):PAGE70
    U1  DM8 VSS1140 SOCKET4677_AZIF0045P001C01CS-SA     I8 @S9S_MB_2U_LIB.S9S_MB_2U(SCH_1):PAGE70
    U1 DN78 VSS1143 SOCKET4677_AZIF0045P001C01CS-SA     I8 @S9S_MB_2U_LIB.S9S_MB_2U(SCH_1):PAGE70
    U1 DN84 VSS1147 SOCKET4677_AZIF0045P001C01CS-SA     I8 @S9S_MB_2U_LIB.S9S_MB_2U(SCH_1):PAGE70
    U1 DN88 VSS1148 SOCKET4677_AZIF0045P001C01CS-SA     I8 @S9S_MB_2U_LIB.S9S_MB_2U(SCH_1):PAGE70
    U1 DP16 VSS1149 SOCKET4677_AZIF0045P001C01CS-SA     I8 @S9S_MB_2U_LIB.S9S_MB_2U(SCH_1):PAGE70
    U1 DP30 VSS1150 SOCKET4677_AZIF0045P001C01CS-SA     I8 @S9S_MB_2U_LIB.S9S_MB_2U(SCH_1):PAGE70
    U1 DP36 VSS1151 SOCKET4677_AZIF0045P001C01CS-SA     I8 @S9S_MB_2U_LIB.S9S_MB_2U(SCH_1):PAGE70
    U1  DP4 VSS1152 SOCKET4677_AZIF0045P001C01CS-SA     I8 @S9S_MB_2U_LIB.S9S_MB_2U(SCH_1):PAGE70
    U1 DP49 VSS1153 SOCKET4677_AZIF0045P001C01CS-SA     I8 @S9S_MB_2U_LIB.S9S_MB_2U(SCH_1):PAGE70
    U1 DP73 VSS1154 SOCKET4677_AZIF0045P001C01CS-SA     I8 @S9S_MB_2U_LIB.S9S_MB_2U(SCH_1):PAGE70
    U1  DP8 VSS1157 SOCKET4677_AZIF0045P001C01CS-SA     I8 @S9S_MB_2U_LIB.S9S_MB_2U(SCH_1):PAGE70
    U1 DP81 VSS1159 SOCKET4677_AZIF0045P001C01CS-SA     I8 @S9S_MB_2U_LIB.S9S_MB_2U(SCH_1):PAGE70
    U1 DP87 VSS1160 SOCKET4677_AZIF0045P001C01CS-SA     I8 @S9S_MB_2U_LIB.S9S_MB_2U(SCH_1):PAGE70
    U1  DR1 VSS1162 SOCKET4677_AZIF0045P001C01CS-SA     I8 @S9S_MB_2U_LIB.S9S_MB_2U(SCH_1):PAGE70
    U1 DR13 VSS1164 SOCKET4677_AZIF0045P001C01CS-SA     I8 @S9S_MB_2U_LIB.S9S_MB_2U(SCH_1):PAGE70
    U1 DR19 VSS1166 SOCKET4677_AZIF0045P001C01CS-SA     I8 @S9S_MB_2U_LIB.S9S_MB_2U(SCH_1):PAGE70
    U1 DR23 VSS1169 SOCKET4677_AZIF0045P001C01CS-SA     I8 @S9S_MB_2U_LIB.S9S_MB_2U(SCH_1):PAGE70
    U1 DR29 VSS1172 SOCKET4677_AZIF0045P001C01CS-SA     I8 @S9S_MB_2U_LIB.S9S_MB_2U(SCH_1):PAGE70
    U1 DR31 VSS1173 SOCKET4677_AZIF0045P001C01CS-SA     I8 @S9S_MB_2U_LIB.S9S_MB_2U(SCH_1):PAGE70
    U1 DR37 VSS1174 SOCKET4677_AZIF0045P001C01CS-SA     I8 @S9S_MB_2U_LIB.S9S_MB_2U(SCH_1):PAGE70
    U1 DR41 VSS1175 SOCKET4677_AZIF0045P001C01CS-SA     I8 @S9S_MB_2U_LIB.S9S_MB_2U(SCH_1):PAGE70
    U1 DR43 VSS1176 SOCKET4677_AZIF0045P001C01CS-SA     I8 @S9S_MB_2U_LIB.S9S_MB_2U(SCH_1):PAGE70
    U1 DR48 VSS1177 SOCKET4677_AZIF0045P001C01CS-SA     I8 @S9S_MB_2U_LIB.S9S_MB_2U(SCH_1):PAGE70
    U1 DR50 VSS1178 SOCKET4677_AZIF0045P001C01CS-SA     I8 @S9S_MB_2U_LIB.S9S_MB_2U(SCH_1):PAGE70
    U1 DR56 VSS1179 SOCKET4677_AZIF0045P001C01CS-SA     I8 @S9S_MB_2U_LIB.S9S_MB_2U(SCH_1):PAGE70
    U1 DR66 VSS1181 SOCKET4677_AZIF0045P001C01CS-SA     I8 @S9S_MB_2U_LIB.S9S_MB_2U(SCH_1):PAGE70
    U1 DR74 VSS1182 SOCKET4677_AZIF0045P001C01CS-SA     I8 @S9S_MB_2U_LIB.S9S_MB_2U(SCH_1):PAGE70
    U1 DR78 VSS1183 SOCKET4677_AZIF0045P001C01CS-SA     I8 @S9S_MB_2U_LIB.S9S_MB_2U(SCH_1):PAGE70
    U1 DR84 VSS1184 SOCKET4677_AZIF0045P001C01CS-SA     I8 @S9S_MB_2U_LIB.S9S_MB_2U(SCH_1):PAGE70
    U1 DR88 VSS1186 SOCKET4677_AZIF0045P001C01CS-SA     I8 @S9S_MB_2U_LIB.S9S_MB_2U(SCH_1):PAGE70
    U1  DR9 VSS1187 SOCKET4677_AZIF0045P001C01CS-SA     I8 @S9S_MB_2U_LIB.S9S_MB_2U(SCH_1):PAGE70
    U1 DT12 VSS1189 SOCKET4677_AZIF0045P001C01CS-SA     I8 @S9S_MB_2U_LIB.S9S_MB_2U(SCH_1):PAGE70
    U1 DT22 VSS1190 SOCKET4677_AZIF0045P001C01CS-SA     I8 @S9S_MB_2U_LIB.S9S_MB_2U(SCH_1):PAGE70
    U1 DT28 VSS1191 SOCKET4677_AZIF0045P001C01CS-SA     I8 @S9S_MB_2U_LIB.S9S_MB_2U(SCH_1):PAGE70
    U1 DT32 VSS1192 SOCKET4677_AZIF0045P001C01CS-SA     I8 @S9S_MB_2U_LIB.S9S_MB_2U(SCH_1):PAGE70
    U1 DT34 VSS1194 SOCKET4677_AZIF0045P001C01CS-SA     I8 @S9S_MB_2U_LIB.S9S_MB_2U(SCH_1):PAGE70
    U1 DT38 VSS1196 SOCKET4677_AZIF0045P001C01CS-SA     I8 @S9S_MB_2U_LIB.S9S_MB_2U(SCH_1):PAGE70
    U1 DT40 VSS1199 SOCKET4677_AZIF0045P001C01CS-SA     I8 @S9S_MB_2U_LIB.S9S_MB_2U(SCH_1):PAGE70
    U1 DT47 VSS1201 SOCKET4677_AZIF0045P001C01CS-SA     I8 @S9S_MB_2U_LIB.S9S_MB_2U(SCH_1):PAGE70
    U1 DT57 VSS1202 SOCKET4677_AZIF0045P001C01CS-SA     I8 @S9S_MB_2U_LIB.S9S_MB_2U(SCH_1):PAGE70
    U1 DT65 VSS1203 SOCKET4677_AZIF0045P001C01CS-SA     I8 @S9S_MB_2U_LIB.S9S_MB_2U(SCH_1):PAGE70
    U1 DT69 VSS1204 SOCKET4677_AZIF0045P001C01CS-SA     I8 @S9S_MB_2U_LIB.S9S_MB_2U(SCH_1):PAGE70
    U1 DT71 VSS1205 SOCKET4677_AZIF0045P001C01CS-SA     I8 @S9S_MB_2U_LIB.S9S_MB_2U(SCH_1):PAGE70
    U1 DT75 VSS1206 SOCKET4677_AZIF0045P001C01CS-SA     I8 @S9S_MB_2U_LIB.S9S_MB_2U(SCH_1):PAGE70
    U1  DT8 VSS1207 SOCKET4677_AZIF0045P001C01CS-SA     I8 @S9S_MB_2U_LIB.S9S_MB_2U(SCH_1):PAGE70
    U1 DU21 VSS1209 SOCKET4677_AZIF0045P001C01CS-SA     I8 @S9S_MB_2U_LIB.S9S_MB_2U(SCH_1):PAGE70
    U1 DU27 VSS1211 SOCKET4677_AZIF0045P001C01CS-SA     I8 @S9S_MB_2U_LIB.S9S_MB_2U(SCH_1):PAGE70
    U1 DU33 VSS1212 SOCKET4677_AZIF0045P001C01CS-SA     I8 @S9S_MB_2U_LIB.S9S_MB_2U(SCH_1):PAGE70
    U1 DU76 VSS1213 SOCKET4677_AZIF0045P001C01CS-SA     I8 @S9S_MB_2U_LIB.S9S_MB_2U(SCH_1):PAGE70
    U1 DU78 VSS1214 SOCKET4677_AZIF0045P001C01CS-SA     I8 @S9S_MB_2U_LIB.S9S_MB_2U(SCH_1):PAGE70
    U1 DU84 VSS1215 SOCKET4677_AZIF0045P001C01CS-SA     I8 @S9S_MB_2U_LIB.S9S_MB_2U(SCH_1):PAGE70
    U1 DU88 VSS1216 SOCKET4677_AZIF0045P001C01CS-SA     I8 @S9S_MB_2U_LIB.S9S_MB_2U(SCH_1):PAGE70
    U1 DV77 VSS1218 SOCKET4677_AZIF0045P001C01CS-SA     I8 @S9S_MB_2U_LIB.S9S_MB_2U(SCH_1):PAGE70
    U1 DV79 VSS1219 SOCKET4677_AZIF0045P001C01CS-SA     I8 @S9S_MB_2U_LIB.S9S_MB_2U(SCH_1):PAGE70
    U1  DV8 VSS1221 SOCKET4677_AZIF0045P001C01CS-SA     I8 @S9S_MB_2U_LIB.S9S_MB_2U(SCH_1):PAGE70
    U1 DV81 VSS1222 SOCKET4677_AZIF0045P001C01CS-SA     I8 @S9S_MB_2U_LIB.S9S_MB_2U(SCH_1):PAGE70
    U1 DV83 VSS1226 SOCKET4677_AZIF0045P001C01CS-SA     I8 @S9S_MB_2U_LIB.S9S_MB_2U(SCH_1):PAGE70
    U1 DV87 VSS1227 SOCKET4677_AZIF0045P001C01CS-SA     I8 @S9S_MB_2U_LIB.S9S_MB_2U(SCH_1):PAGE70
    U1 DV91 VSS1228 SOCKET4677_AZIF0045P001C01CS-SA     I8 @S9S_MB_2U_LIB.S9S_MB_2U(SCH_1):PAGE70
    U1  DW1 VSS1229 SOCKET4677_AZIF0045P001C01CS-SA     I8 @S9S_MB_2U_LIB.S9S_MB_2U(SCH_1):PAGE70
    U1 DW13 VSS1230 SOCKET4677_AZIF0045P001C01CS-SA     I8 @S9S_MB_2U_LIB.S9S_MB_2U(SCH_1):PAGE70
    U1 DW17 VSS1231 SOCKET4677_AZIF0045P001C01CS-SA     I8 @S9S_MB_2U_LIB.S9S_MB_2U(SCH_1):PAGE70
    U1 DW19 VSS1233 SOCKET4677_AZIF0045P001C01CS-SA     I8 @S9S_MB_2U_LIB.S9S_MB_2U(SCH_1):PAGE70
    U1 DW23 VSS1234 SOCKET4677_AZIF0045P001C01CS-SA     I8 @S9S_MB_2U_LIB.S9S_MB_2U(SCH_1):PAGE70
    U1 DW25 VSS1236 SOCKET4677_AZIF0045P001C01CS-SA     I8 @S9S_MB_2U_LIB.S9S_MB_2U(SCH_1):PAGE70
    U1 DW27 VSS1238 SOCKET4677_AZIF0045P001C01CS-SA     I8 @S9S_MB_2U_LIB.S9S_MB_2U(SCH_1):PAGE70
    U1 DW29 VSS1239 SOCKET4677_AZIF0045P001C01CS-SA     I8 @S9S_MB_2U_LIB.S9S_MB_2U(SCH_1):PAGE70
    U1 DW31 VSS1240 SOCKET4677_AZIF0045P001C01CS-SA     I8 @S9S_MB_2U_LIB.S9S_MB_2U(SCH_1):PAGE70
    U1 DW33 VSS1241 SOCKET4677_AZIF0045P001C01CS-SA     I8 @S9S_MB_2U_LIB.S9S_MB_2U(SCH_1):PAGE70
    U1 DW35 VSS1242 SOCKET4677_AZIF0045P001C01CS-SA     I8 @S9S_MB_2U_LIB.S9S_MB_2U(SCH_1):PAGE70
    U1 DW37 VSS1243 SOCKET4677_AZIF0045P001C01CS-SA     I8 @S9S_MB_2U_LIB.S9S_MB_2U(SCH_1):PAGE70
    U1 DW39 VSS1244 SOCKET4677_AZIF0045P001C01CS-SA     I8 @S9S_MB_2U_LIB.S9S_MB_2U(SCH_1):PAGE70
    U1 DW41 VSS1245 SOCKET4677_AZIF0045P001C01CS-SA     I8 @S9S_MB_2U_LIB.S9S_MB_2U(SCH_1):PAGE70
    U1 DW43 VSS1246 SOCKET4677_AZIF0045P001C01CS-SA     I8 @S9S_MB_2U_LIB.S9S_MB_2U(SCH_1):PAGE70
    U1 DW45 VSS1247 SOCKET4677_AZIF0045P001C01CS-SA     I8 @S9S_MB_2U_LIB.S9S_MB_2U(SCH_1):PAGE70
    U1 DW48 VSS1248 SOCKET4677_AZIF0045P001C01CS-SA     I8 @S9S_MB_2U_LIB.S9S_MB_2U(SCH_1):PAGE70
    U1  DW5 VSS1249 SOCKET4677_AZIF0045P001C01CS-SA     I8 @S9S_MB_2U_LIB.S9S_MB_2U(SCH_1):PAGE70
    U1 DW50 VSS1250 SOCKET4677_AZIF0045P001C01CS-SA     I8 @S9S_MB_2U_LIB.S9S_MB_2U(SCH_1):PAGE70
    U1 DW52 VSS1251 SOCKET4677_AZIF0045P001C01CS-SA     I8 @S9S_MB_2U_LIB.S9S_MB_2U(SCH_1):PAGE70
    U1 DW54 VSS1252 SOCKET4677_AZIF0045P001C01CS-SA     I8 @S9S_MB_2U_LIB.S9S_MB_2U(SCH_1):PAGE70
    U1 DW56 VSS1253 SOCKET4677_AZIF0045P001C01CS-SA     I8 @S9S_MB_2U_LIB.S9S_MB_2U(SCH_1):PAGE70
    U1 DW58 VSS1254 SOCKET4677_AZIF0045P001C01CS-SA     I8 @S9S_MB_2U_LIB.S9S_MB_2U(SCH_1):PAGE70
    U1 DW62 VSS1255 SOCKET4677_AZIF0045P001C01CS-SA     I8 @S9S_MB_2U_LIB.S9S_MB_2U(SCH_1):PAGE70
    U1 DW64 VSS1256 SOCKET4677_AZIF0045P001C01CS-SA     I8 @S9S_MB_2U_LIB.S9S_MB_2U(SCH_1):PAGE70
    U1  DW9 VSS1268 SOCKET4677_AZIF0045P001C01CS-SA     I8 @S9S_MB_2U_LIB.S9S_MB_2U(SCH_1):PAGE70
    U1 DB91 VSS723 SOCKET4677_AZIF0045P001C01CS-SA     I2 @S9S_MB_2U_LIB.S9S_MB_2U(SCH_1):PAGE71
    U1  DC1 VSS724 SOCKET4677_AZIF0045P001C01CS-SA     I2 @S9S_MB_2U_LIB.S9S_MB_2U(SCH_1):PAGE71
    U1 DC13 VSS725 SOCKET4677_AZIF0045P001C01CS-SA     I2 @S9S_MB_2U_LIB.S9S_MB_2U(SCH_1):PAGE71
    U1 DC21 VSS726 SOCKET4677_AZIF0045P001C01CS-SA     I2 @S9S_MB_2U_LIB.S9S_MB_2U(SCH_1):PAGE71
    U1 DC52 VSS735 SOCKET4677_AZIF0045P001C01CS-SA     I2 @S9S_MB_2U_LIB.S9S_MB_2U(SCH_1):PAGE71
    U1 DC58 VSS738 SOCKET4677_AZIF0045P001C01CS-SA     I2 @S9S_MB_2U_LIB.S9S_MB_2U(SCH_1):PAGE71
    U1 DC64 VSS739 SOCKET4677_AZIF0045P001C01CS-SA     I2 @S9S_MB_2U_LIB.S9S_MB_2U(SCH_1):PAGE71
    U1 DD12 VSS747 SOCKET4677_AZIF0045P001C01CS-SA     I2 @S9S_MB_2U_LIB.S9S_MB_2U(SCH_1):PAGE71
    U1 DD16 VSS748 SOCKET4677_AZIF0045P001C01CS-SA     I2 @S9S_MB_2U_LIB.S9S_MB_2U(SCH_1):PAGE71
    U1 DD49 VSS753 SOCKET4677_AZIF0045P001C01CS-SA     I2 @S9S_MB_2U_LIB.S9S_MB_2U(SCH_1):PAGE71
    U1 DE39 VSS776 SOCKET4677_AZIF0045P001C01CS-SA     I2 @S9S_MB_2U_LIB.S9S_MB_2U(SCH_1):PAGE71
    U1 DE70 VSS791 SOCKET4677_AZIF0045P001C01CS-SA     I2 @S9S_MB_2U_LIB.S9S_MB_2U(SCH_1):PAGE71
    U1 DF12 VSS798 SOCKET4677_AZIF0045P001C01CS-SA     I2 @S9S_MB_2U_LIB.S9S_MB_2U(SCH_1):PAGE71
    U1 DF16 VSS799 SOCKET4677_AZIF0045P001C01CS-SA     I2 @S9S_MB_2U_LIB.S9S_MB_2U(SCH_1):PAGE71
    U1 DF49 VSS802 SOCKET4677_AZIF0045P001C01CS-SA     I2 @S9S_MB_2U_LIB.S9S_MB_2U(SCH_1):PAGE71
    U1 DF91 VSS806 SOCKET4677_AZIF0045P001C01CS-SA     I2 @S9S_MB_2U_LIB.S9S_MB_2U(SCH_1):PAGE71
    U1  DG1 VSS807 SOCKET4677_AZIF0045P001C01CS-SA     I2 @S9S_MB_2U_LIB.S9S_MB_2U(SCH_1):PAGE71
    U1 DG13 VSS808 SOCKET4677_AZIF0045P001C01CS-SA     I2 @S9S_MB_2U_LIB.S9S_MB_2U(SCH_1):PAGE71
    U1 DG21 VSS809 SOCKET4677_AZIF0045P001C01CS-SA     I2 @S9S_MB_2U_LIB.S9S_MB_2U(SCH_1):PAGE71
    U1 DG52 VSS817 SOCKET4677_AZIF0045P001C01CS-SA     I2 @S9S_MB_2U_LIB.S9S_MB_2U(SCH_1):PAGE71
    U1 DG58 VSS820 SOCKET4677_AZIF0045P001C01CS-SA     I2 @S9S_MB_2U_LIB.S9S_MB_2U(SCH_1):PAGE71
    U1 DG64 VSS821 SOCKET4677_AZIF0045P001C01CS-SA     I2 @S9S_MB_2U_LIB.S9S_MB_2U(SCH_1):PAGE71
    U1 DH16 VSS829 SOCKET4677_AZIF0045P001C01CS-SA     I2 @S9S_MB_2U_LIB.S9S_MB_2U(SCH_1):PAGE71
    U1 DH20 VSS830 SOCKET4677_AZIF0045P001C01CS-SA     I2 @S9S_MB_2U_LIB.S9S_MB_2U(SCH_1):PAGE71
    U1 DH26 VSS832 SOCKET4677_AZIF0045P001C01CS-SA     I2 @S9S_MB_2U_LIB.S9S_MB_2U(SCH_1):PAGE71
    U1 DH34 VSS835 SOCKET4677_AZIF0045P001C01CS-SA     I2 @S9S_MB_2U_LIB.S9S_MB_2U(SCH_1):PAGE71
    U1 DH44 VSS839 SOCKET4677_AZIF0045P001C01CS-SA     I2 @S9S_MB_2U_LIB.S9S_MB_2U(SCH_1):PAGE71
    U1 DH51 VSS841 SOCKET4677_AZIF0045P001C01CS-SA     I2 @S9S_MB_2U_LIB.S9S_MB_2U(SCH_1):PAGE71
    U1 DH53 VSS842 SOCKET4677_AZIF0045P001C01CS-SA     I2 @S9S_MB_2U_LIB.S9S_MB_2U(SCH_1):PAGE71
    U1 DH59 VSS844 SOCKET4677_AZIF0045P001C01CS-SA     I2 @S9S_MB_2U_LIB.S9S_MB_2U(SCH_1):PAGE71
    U1 DH63 VSS845 SOCKET4677_AZIF0045P001C01CS-SA     I2 @S9S_MB_2U_LIB.S9S_MB_2U(SCH_1):PAGE71
    U1 DH69 VSS847 SOCKET4677_AZIF0045P001C01CS-SA     I2 @S9S_MB_2U_LIB.S9S_MB_2U(SCH_1):PAGE71
    U1 DH75 VSS849 SOCKET4677_AZIF0045P001C01CS-SA     I2 @S9S_MB_2U_LIB.S9S_MB_2U(SCH_1):PAGE71
    U1 DJ25 VSS857 SOCKET4677_AZIF0045P001C01CS-SA     I2 @S9S_MB_2U_LIB.S9S_MB_2U(SCH_1):PAGE71
    U1 DJ35 VSS861 SOCKET4677_AZIF0045P001C01CS-SA     I2 @S9S_MB_2U_LIB.S9S_MB_2U(SCH_1):PAGE71
    U1 DJ54 VSS867 SOCKET4677_AZIF0045P001C01CS-SA     I2 @S9S_MB_2U_LIB.S9S_MB_2U(SCH_1):PAGE71
    U1 DJ62 VSS870 SOCKET4677_AZIF0045P001C01CS-SA     I2 @S9S_MB_2U_LIB.S9S_MB_2U(SCH_1):PAGE71
    U1 DJ68 VSS872 SOCKET4677_AZIF0045P001C01CS-SA     I2 @S9S_MB_2U_LIB.S9S_MB_2U(SCH_1):PAGE71
    U1 DK12 VSS880 SOCKET4677_AZIF0045P001C01CS-SA     I2 @S9S_MB_2U_LIB.S9S_MB_2U(SCH_1):PAGE71
    U1 DK18 VSS882 SOCKET4677_AZIF0045P001C01CS-SA     I2 @S9S_MB_2U_LIB.S9S_MB_2U(SCH_1):PAGE71
    U1 DK24 VSS883 SOCKET4677_AZIF0045P001C01CS-SA     I2 @S9S_MB_2U_LIB.S9S_MB_2U(SCH_1):PAGE71
    U1 DK42 VSS887 SOCKET4677_AZIF0045P001C01CS-SA     I2 @S9S_MB_2U_LIB.S9S_MB_2U(SCH_1):PAGE71
    U1 DK55 VSS890 SOCKET4677_AZIF0045P001C01CS-SA     I2 @S9S_MB_2U_LIB.S9S_MB_2U(SCH_1):PAGE71
    U1 DK61 VSS893 SOCKET4677_AZIF0045P001C01CS-SA     I2 @S9S_MB_2U_LIB.S9S_MB_2U(SCH_1):PAGE71
    U1 DK67 VSS894 SOCKET4677_AZIF0045P001C01CS-SA     I2 @S9S_MB_2U_LIB.S9S_MB_2U(SCH_1):PAGE71
    U1  DL1 VSS903 SOCKET4677_AZIF0045P001C01CS-SA     I2 @S9S_MB_2U_LIB.S9S_MB_2U(SCH_1):PAGE71
    U1 DL13 VSS904 SOCKET4677_AZIF0045P001C01CS-SA     I2 @S9S_MB_2U_LIB.S9S_MB_2U(SCH_1):PAGE71
    U1 DL17 VSS905 SOCKET4677_AZIF0045P001C01CS-SA     I2 @S9S_MB_2U_LIB.S9S_MB_2U(SCH_1):PAGE71
    U1  DL5 VSS908 SOCKET4677_AZIF0045P001C01CS-SA     I2 @S9S_MB_2U_LIB.S9S_MB_2U(SCH_1):PAGE71
    U1 DL52 VSS909 SOCKET4677_AZIF0045P001C01CS-SA     I2 @S9S_MB_2U_LIB.S9S_MB_2U(SCH_1):PAGE71
    U1 DC27 VSS949 SOCKET4677_AZIF0045P001C01CS-SA     I2 @S9S_MB_2U_LIB.S9S_MB_2U(SCH_1):PAGE71
    U1 DC33 VSS950 SOCKET4677_AZIF0045P001C01CS-SA     I2 @S9S_MB_2U_LIB.S9S_MB_2U(SCH_1):PAGE71
    U1 DC39 VSS951 SOCKET4677_AZIF0045P001C01CS-SA     I2 @S9S_MB_2U_LIB.S9S_MB_2U(SCH_1):PAGE71
    U1 DC45 VSS952 SOCKET4677_AZIF0045P001C01CS-SA     I2 @S9S_MB_2U_LIB.S9S_MB_2U(SCH_1):PAGE71
    U1  DC5 VSS953 SOCKET4677_AZIF0045P001C01CS-SA     I2 @S9S_MB_2U_LIB.S9S_MB_2U(SCH_1):PAGE71
    U1 DC70 VSS954 SOCKET4677_AZIF0045P001C01CS-SA     I2 @S9S_MB_2U_LIB.S9S_MB_2U(SCH_1):PAGE71
    U1 DC76 VSS956 SOCKET4677_AZIF0045P001C01CS-SA     I2 @S9S_MB_2U_LIB.S9S_MB_2U(SCH_1):PAGE71
    U1 DC78 VSS958 SOCKET4677_AZIF0045P001C01CS-SA     I2 @S9S_MB_2U_LIB.S9S_MB_2U(SCH_1):PAGE71
    U1 DC80 VSS960 SOCKET4677_AZIF0045P001C01CS-SA     I2 @S9S_MB_2U_LIB.S9S_MB_2U(SCH_1):PAGE71
    U1 DC84 VSS961 SOCKET4677_AZIF0045P001C01CS-SA     I2 @S9S_MB_2U_LIB.S9S_MB_2U(SCH_1):PAGE71
    U1 DC88 VSS962 SOCKET4677_AZIF0045P001C01CS-SA     I2 @S9S_MB_2U_LIB.S9S_MB_2U(SCH_1):PAGE71
    U1  DC9 VSS963 SOCKET4677_AZIF0045P001C01CS-SA     I2 @S9S_MB_2U_LIB.S9S_MB_2U(SCH_1):PAGE71
    U1  DD4 VSS964 SOCKET4677_AZIF0045P001C01CS-SA     I2 @S9S_MB_2U_LIB.S9S_MB_2U(SCH_1):PAGE71
    U1 DD79 VSS965 SOCKET4677_AZIF0045P001C01CS-SA     I2 @S9S_MB_2U_LIB.S9S_MB_2U(SCH_1):PAGE71
    U1  DD8 VSS967 SOCKET4677_AZIF0045P001C01CS-SA     I2 @S9S_MB_2U_LIB.S9S_MB_2U(SCH_1):PAGE71
    U1 DE17 VSS970 SOCKET4677_AZIF0045P001C01CS-SA     I2 @S9S_MB_2U_LIB.S9S_MB_2U(SCH_1):PAGE71
    U1 DE19 VSS971 SOCKET4677_AZIF0045P001C01CS-SA     I2 @S9S_MB_2U_LIB.S9S_MB_2U(SCH_1):PAGE71
    U1 DE21 VSS972 SOCKET4677_AZIF0045P001C01CS-SA     I2 @S9S_MB_2U_LIB.S9S_MB_2U(SCH_1):PAGE71
    U1 DE23 VSS974 SOCKET4677_AZIF0045P001C01CS-SA     I2 @S9S_MB_2U_LIB.S9S_MB_2U(SCH_1):PAGE71
    U1 DE25 VSS975 SOCKET4677_AZIF0045P001C01CS-SA     I2 @S9S_MB_2U_LIB.S9S_MB_2U(SCH_1):PAGE71
    U1 DE27 VSS977 SOCKET4677_AZIF0045P001C01CS-SA     I2 @S9S_MB_2U_LIB.S9S_MB_2U(SCH_1):PAGE71
    U1 DE29 VSS978 SOCKET4677_AZIF0045P001C01CS-SA     I2 @S9S_MB_2U_LIB.S9S_MB_2U(SCH_1):PAGE71
    U1 DE31 VSS981 SOCKET4677_AZIF0045P001C01CS-SA     I2 @S9S_MB_2U_LIB.S9S_MB_2U(SCH_1):PAGE71
    U1 DE33 VSS982 SOCKET4677_AZIF0045P001C01CS-SA     I2 @S9S_MB_2U_LIB.S9S_MB_2U(SCH_1):PAGE71
    U1 DE35 VSS983 SOCKET4677_AZIF0045P001C01CS-SA     I2 @S9S_MB_2U_LIB.S9S_MB_2U(SCH_1):PAGE71
    U1 DE37 VSS984 SOCKET4677_AZIF0045P001C01CS-SA     I2 @S9S_MB_2U_LIB.S9S_MB_2U(SCH_1):PAGE71
    U1 DE41 VSS986 SOCKET4677_AZIF0045P001C01CS-SA     I2 @S9S_MB_2U_LIB.S9S_MB_2U(SCH_1):PAGE71
    U1 DE43 VSS987 SOCKET4677_AZIF0045P001C01CS-SA     I2 @S9S_MB_2U_LIB.S9S_MB_2U(SCH_1):PAGE71
    U1 DE45 VSS988 SOCKET4677_AZIF0045P001C01CS-SA     I2 @S9S_MB_2U_LIB.S9S_MB_2U(SCH_1):PAGE71
    U1 DE48 VSS989 SOCKET4677_AZIF0045P001C01CS-SA     I2 @S9S_MB_2U_LIB.S9S_MB_2U(SCH_1):PAGE71
    U1 DE50 VSS991 SOCKET4677_AZIF0045P001C01CS-SA     I2 @S9S_MB_2U_LIB.S9S_MB_2U(SCH_1):PAGE71
    U1 DE52 VSS992 SOCKET4677_AZIF0045P001C01CS-SA     I2 @S9S_MB_2U_LIB.S9S_MB_2U(SCH_1):PAGE71
    U1 DE54 VSS994 SOCKET4677_AZIF0045P001C01CS-SA     I2 @S9S_MB_2U_LIB.S9S_MB_2U(SCH_1):PAGE71
    U1 DE56 VSS995 SOCKET4677_AZIF0045P001C01CS-SA     I2 @S9S_MB_2U_LIB.S9S_MB_2U(SCH_1):PAGE71
    U1 DE58 VSS996 SOCKET4677_AZIF0045P001C01CS-SA     I2 @S9S_MB_2U_LIB.S9S_MB_2U(SCH_1):PAGE71
    U1 DE60 VSS997 SOCKET4677_AZIF0045P001C01CS-SA     I2 @S9S_MB_2U_LIB.S9S_MB_2U(SCH_1):PAGE71
    U1 DE62 VSS999 SOCKET4677_AZIF0045P001C01CS-SA     I2 @S9S_MB_2U_LIB.S9S_MB_2U(SCH_1):PAGE71
    U1 DE64 VSS1001 SOCKET4677_AZIF0045P001C01CS-SA     I2 @S9S_MB_2U_LIB.S9S_MB_2U(SCH_1):PAGE71
    U1 DE66 VSS1004 SOCKET4677_AZIF0045P001C01CS-SA     I2 @S9S_MB_2U_LIB.S9S_MB_2U(SCH_1):PAGE71
    U1 DE68 VSS1007 SOCKET4677_AZIF0045P001C01CS-SA     I2 @S9S_MB_2U_LIB.S9S_MB_2U(SCH_1):PAGE71
    U1 DE72 VSS1008 SOCKET4677_AZIF0045P001C01CS-SA     I2 @S9S_MB_2U_LIB.S9S_MB_2U(SCH_1):PAGE71
    U1 DE74 VSS1009 SOCKET4677_AZIF0045P001C01CS-SA     I2 @S9S_MB_2U_LIB.S9S_MB_2U(SCH_1):PAGE71
    U1 DE76 VSS1010 SOCKET4677_AZIF0045P001C01CS-SA     I2 @S9S_MB_2U_LIB.S9S_MB_2U(SCH_1):PAGE71
    U1 DE82 VSS1011 SOCKET4677_AZIF0045P001C01CS-SA     I2 @S9S_MB_2U_LIB.S9S_MB_2U(SCH_1):PAGE71
    U1 DE84 VSS1012 SOCKET4677_AZIF0045P001C01CS-SA     I2 @S9S_MB_2U_LIB.S9S_MB_2U(SCH_1):PAGE71
    U1 DE88 VSS1015 SOCKET4677_AZIF0045P001C01CS-SA     I2 @S9S_MB_2U_LIB.S9S_MB_2U(SCH_1):PAGE71
    U1  DF4 VSS1017 SOCKET4677_AZIF0045P001C01CS-SA     I2 @S9S_MB_2U_LIB.S9S_MB_2U(SCH_1):PAGE71
    U1 DF79 VSS1018 SOCKET4677_AZIF0045P001C01CS-SA     I2 @S9S_MB_2U_LIB.S9S_MB_2U(SCH_1):PAGE71
    U1  DF8 VSS1019 SOCKET4677_AZIF0045P001C01CS-SA     I2 @S9S_MB_2U_LIB.S9S_MB_2U(SCH_1):PAGE71
    U1 DF87 VSS1020 SOCKET4677_AZIF0045P001C01CS-SA     I2 @S9S_MB_2U_LIB.S9S_MB_2U(SCH_1):PAGE71
    U1 DG27 VSS1022 SOCKET4677_AZIF0045P001C01CS-SA     I2 @S9S_MB_2U_LIB.S9S_MB_2U(SCH_1):PAGE71
    U1 DG33 VSS1024 SOCKET4677_AZIF0045P001C01CS-SA     I2 @S9S_MB_2U_LIB.S9S_MB_2U(SCH_1):PAGE71
    U1 DG39 VSS1027 SOCKET4677_AZIF0045P001C01CS-SA     I2 @S9S_MB_2U_LIB.S9S_MB_2U(SCH_1):PAGE71
    U1 DG45 VSS1030 SOCKET4677_AZIF0045P001C01CS-SA     I2 @S9S_MB_2U_LIB.S9S_MB_2U(SCH_1):PAGE71
    U1  DG5 VSS1031 SOCKET4677_AZIF0045P001C01CS-SA     I2 @S9S_MB_2U_LIB.S9S_MB_2U(SCH_1):PAGE71
    U1 DG70 VSS1032 SOCKET4677_AZIF0045P001C01CS-SA     I2 @S9S_MB_2U_LIB.S9S_MB_2U(SCH_1):PAGE71
    U1 DG76 VSS1033 SOCKET4677_AZIF0045P001C01CS-SA     I2 @S9S_MB_2U_LIB.S9S_MB_2U(SCH_1):PAGE71
    U1 DG80 VSS1034 SOCKET4677_AZIF0045P001C01CS-SA     I2 @S9S_MB_2U_LIB.S9S_MB_2U(SCH_1):PAGE71
    U1 DG84 VSS1035 SOCKET4677_AZIF0045P001C01CS-SA     I2 @S9S_MB_2U_LIB.S9S_MB_2U(SCH_1):PAGE71
    U1 DG88 VSS1037 SOCKET4677_AZIF0045P001C01CS-SA     I2 @S9S_MB_2U_LIB.S9S_MB_2U(SCH_1):PAGE71
    U1  DG9 VSS1038 SOCKET4677_AZIF0045P001C01CS-SA     I2 @S9S_MB_2U_LIB.S9S_MB_2U(SCH_1):PAGE71
    U1 DH12 VSS1039 SOCKET4677_AZIF0045P001C01CS-SA     I2 @S9S_MB_2U_LIB.S9S_MB_2U(SCH_1):PAGE71
    U1 DH22 VSS1040 SOCKET4677_AZIF0045P001C01CS-SA     I2 @S9S_MB_2U_LIB.S9S_MB_2U(SCH_1):PAGE71
    U1 DH28 VSS1041 SOCKET4677_AZIF0045P001C01CS-SA     I2 @S9S_MB_2U_LIB.S9S_MB_2U(SCH_1):PAGE71
    U1 DH32 VSS1042 SOCKET4677_AZIF0045P001C01CS-SA     I2 @S9S_MB_2U_LIB.S9S_MB_2U(SCH_1):PAGE71
    U1 DH38 VSS1043 SOCKET4677_AZIF0045P001C01CS-SA     I2 @S9S_MB_2U_LIB.S9S_MB_2U(SCH_1):PAGE71
    U1  DH4 VSS1044 SOCKET4677_AZIF0045P001C01CS-SA     I2 @S9S_MB_2U_LIB.S9S_MB_2U(SCH_1):PAGE71
    U1 DH40 VSS1045 SOCKET4677_AZIF0045P001C01CS-SA     I2 @S9S_MB_2U_LIB.S9S_MB_2U(SCH_1):PAGE71
    U1 DH47 VSS1046 SOCKET4677_AZIF0045P001C01CS-SA     I2 @S9S_MB_2U_LIB.S9S_MB_2U(SCH_1):PAGE71
    U1 DH57 VSS1049 SOCKET4677_AZIF0045P001C01CS-SA     I2 @S9S_MB_2U_LIB.S9S_MB_2U(SCH_1):PAGE71
    U1 DH65 VSS1053 SOCKET4677_AZIF0045P001C01CS-SA     I2 @S9S_MB_2U_LIB.S9S_MB_2U(SCH_1):PAGE71
    U1 DH71 VSS1055 SOCKET4677_AZIF0045P001C01CS-SA     I2 @S9S_MB_2U_LIB.S9S_MB_2U(SCH_1):PAGE71
    U1 DH77 VSS1056 SOCKET4677_AZIF0045P001C01CS-SA     I2 @S9S_MB_2U_LIB.S9S_MB_2U(SCH_1):PAGE71
    U1  DH8 VSS1057 SOCKET4677_AZIF0045P001C01CS-SA     I2 @S9S_MB_2U_LIB.S9S_MB_2U(SCH_1):PAGE71
    U1 DH85 VSS1058 SOCKET4677_AZIF0045P001C01CS-SA     I2 @S9S_MB_2U_LIB.S9S_MB_2U(SCH_1):PAGE71
    U1 DJ19 VSS1061 SOCKET4677_AZIF0045P001C01CS-SA     I2 @S9S_MB_2U_LIB.S9S_MB_2U(SCH_1):PAGE71
    U1 DJ23 VSS1062 SOCKET4677_AZIF0045P001C01CS-SA     I2 @S9S_MB_2U_LIB.S9S_MB_2U(SCH_1):PAGE71
    U1 DJ29 VSS1065 SOCKET4677_AZIF0045P001C01CS-SA     I2 @S9S_MB_2U_LIB.S9S_MB_2U(SCH_1):PAGE71
    U1 DJ31 VSS1066 SOCKET4677_AZIF0045P001C01CS-SA     I2 @S9S_MB_2U_LIB.S9S_MB_2U(SCH_1):PAGE71
    U1 DJ37 VSS1067 SOCKET4677_AZIF0045P001C01CS-SA     I2 @S9S_MB_2U_LIB.S9S_MB_2U(SCH_1):PAGE71
    U1 DJ41 VSS1068 SOCKET4677_AZIF0045P001C01CS-SA     I2 @S9S_MB_2U_LIB.S9S_MB_2U(SCH_1):PAGE71
    U1 DJ43 VSS1069 SOCKET4677_AZIF0045P001C01CS-SA     I2 @S9S_MB_2U_LIB.S9S_MB_2U(SCH_1):PAGE71
    U1 DJ48 VSS1070 SOCKET4677_AZIF0045P001C01CS-SA     I2 @S9S_MB_2U_LIB.S9S_MB_2U(SCH_1):PAGE71
    U1 DJ50 VSS1071 SOCKET4677_AZIF0045P001C01CS-SA     I2 @S9S_MB_2U_LIB.S9S_MB_2U(SCH_1):PAGE71
    U1 DJ56 VSS1072 SOCKET4677_AZIF0045P001C01CS-SA     I2 @S9S_MB_2U_LIB.S9S_MB_2U(SCH_1):PAGE71
    U1 DJ60 VSS1073 SOCKET4677_AZIF0045P001C01CS-SA     I2 @S9S_MB_2U_LIB.S9S_MB_2U(SCH_1):PAGE71
    U1 DJ66 VSS1074 SOCKET4677_AZIF0045P001C01CS-SA     I2 @S9S_MB_2U_LIB.S9S_MB_2U(SCH_1):PAGE71
    U1 DJ72 VSS1075 SOCKET4677_AZIF0045P001C01CS-SA     I2 @S9S_MB_2U_LIB.S9S_MB_2U(SCH_1):PAGE71
    U1 DJ74 VSS1076 SOCKET4677_AZIF0045P001C01CS-SA     I2 @S9S_MB_2U_LIB.S9S_MB_2U(SCH_1):PAGE71
    U1 DJ80 VSS1078 SOCKET4677_AZIF0045P001C01CS-SA     I2 @S9S_MB_2U_LIB.S9S_MB_2U(SCH_1):PAGE71
    U1 DJ82 VSS1079 SOCKET4677_AZIF0045P001C01CS-SA     I2 @S9S_MB_2U_LIB.S9S_MB_2U(SCH_1):PAGE71
    U1 DJ84 VSS1080 SOCKET4677_AZIF0045P001C01CS-SA     I2 @S9S_MB_2U_LIB.S9S_MB_2U(SCH_1):PAGE71
    U1 DJ88 VSS1081 SOCKET4677_AZIF0045P001C01CS-SA     I2 @S9S_MB_2U_LIB.S9S_MB_2U(SCH_1):PAGE71
    U1 DK16 VSS1082 SOCKET4677_AZIF0045P001C01CS-SA     I2 @S9S_MB_2U_LIB.S9S_MB_2U(SCH_1):PAGE71
    U1 DK30 VSS1083 SOCKET4677_AZIF0045P001C01CS-SA     I2 @S9S_MB_2U_LIB.S9S_MB_2U(SCH_1):PAGE71
    U1 DK36 VSS1084 SOCKET4677_AZIF0045P001C01CS-SA     I2 @S9S_MB_2U_LIB.S9S_MB_2U(SCH_1):PAGE71
    U1  DK4 VSS1085 SOCKET4677_AZIF0045P001C01CS-SA     I2 @S9S_MB_2U_LIB.S9S_MB_2U(SCH_1):PAGE71
    U1 DK49 VSS1086 SOCKET4677_AZIF0045P001C01CS-SA     I2 @S9S_MB_2U_LIB.S9S_MB_2U(SCH_1):PAGE71
    U1 DK73 VSS1087 SOCKET4677_AZIF0045P001C01CS-SA     I2 @S9S_MB_2U_LIB.S9S_MB_2U(SCH_1):PAGE71
    U1 DK77 VSS1088 SOCKET4677_AZIF0045P001C01CS-SA     I2 @S9S_MB_2U_LIB.S9S_MB_2U(SCH_1):PAGE71
    U1 DK79 VSS1089 SOCKET4677_AZIF0045P001C01CS-SA     I2 @S9S_MB_2U_LIB.S9S_MB_2U(SCH_1):PAGE71
    U1  DK8 VSS1090 SOCKET4677_AZIF0045P001C01CS-SA     I2 @S9S_MB_2U_LIB.S9S_MB_2U(SCH_1):PAGE71
    U1 DK81 VSS1091 SOCKET4677_AZIF0045P001C01CS-SA     I2 @S9S_MB_2U_LIB.S9S_MB_2U(SCH_1):PAGE71
    U1 DK83 VSS1092 SOCKET4677_AZIF0045P001C01CS-SA     I2 @S9S_MB_2U_LIB.S9S_MB_2U(SCH_1):PAGE71
    U1 DK87 VSS1093 SOCKET4677_AZIF0045P001C01CS-SA     I2 @S9S_MB_2U_LIB.S9S_MB_2U(SCH_1):PAGE71
    U1 DK91 VSS1094 SOCKET4677_AZIF0045P001C01CS-SA     I2 @S9S_MB_2U_LIB.S9S_MB_2U(SCH_1):PAGE71
    U1 DL39 VSS1095 SOCKET4677_AZIF0045P001C01CS-SA     I2 @S9S_MB_2U_LIB.S9S_MB_2U(SCH_1):PAGE71
    U1 DL84 VSS1096 SOCKET4677_AZIF0045P001C01CS-SA     I2 @S9S_MB_2U_LIB.S9S_MB_2U(SCH_1):PAGE71
    U1 DL88 VSS1098 SOCKET4677_AZIF0045P001C01CS-SA     I2 @S9S_MB_2U_LIB.S9S_MB_2U(SCH_1):PAGE71
    U1  DL9 VSS1099 SOCKET4677_AZIF0045P001C01CS-SA     I2 @S9S_MB_2U_LIB.S9S_MB_2U(SCH_1):PAGE71
    U1 CM16 VSS436 SOCKET4677_AZIF0045P001C01CS-SA     I5 @S9S_MB_2U_LIB.S9S_MB_2U(SCH_1):PAGE71
    U1 CM22 VSS438 SOCKET4677_AZIF0045P001C01CS-SA     I5 @S9S_MB_2U_LIB.S9S_MB_2U(SCH_1):PAGE71
    U1 CN76 VSS471 SOCKET4677_AZIF0045P001C01CS-SA     I5 @S9S_MB_2U_LIB.S9S_MB_2U(SCH_1):PAGE71
    U1 CP16 VSS478 SOCKET4677_AZIF0045P001C01CS-SA     I5 @S9S_MB_2U_LIB.S9S_MB_2U(SCH_1):PAGE71
    U1 CP79 VSS493 SOCKET4677_AZIF0045P001C01CS-SA     I5 @S9S_MB_2U_LIB.S9S_MB_2U(SCH_1):PAGE71
    U1 CR78 VSS514 SOCKET4677_AZIF0045P001C01CS-SA     I5 @S9S_MB_2U_LIB.S9S_MB_2U(SCH_1):PAGE71
    U1 CT16 VSS521 SOCKET4677_AZIF0045P001C01CS-SA     I5 @S9S_MB_2U_LIB.S9S_MB_2U(SCH_1):PAGE71
    U1  CT4 VSS526 SOCKET4677_AZIF0045P001C01CS-SA     I5 @S9S_MB_2U_LIB.S9S_MB_2U(SCH_1):PAGE71
    U1  CT8 VSS534 SOCKET4677_AZIF0045P001C01CS-SA     I5 @S9S_MB_2U_LIB.S9S_MB_2U(SCH_1):PAGE71
    U1 CT89 VSS537 SOCKET4677_AZIF0045P001C01CS-SA     I5 @S9S_MB_2U_LIB.S9S_MB_2U(SCH_1):PAGE71
    U1 CU25 VSS544 SOCKET4677_AZIF0045P001C01CS-SA     I5 @S9S_MB_2U_LIB.S9S_MB_2U(SCH_1):PAGE71
    U1 CU72 VSS553 SOCKET4677_AZIF0045P001C01CS-SA     I5 @S9S_MB_2U_LIB.S9S_MB_2U(SCH_1):PAGE71
    U1 CU78 VSS554 SOCKET4677_AZIF0045P001C01CS-SA     I5 @S9S_MB_2U_LIB.S9S_MB_2U(SCH_1):PAGE71
    U1 CV16 VSS558 SOCKET4677_AZIF0045P001C01CS-SA     I5 @S9S_MB_2U_LIB.S9S_MB_2U(SCH_1):PAGE71
    U1 CV26 VSS562 SOCKET4677_AZIF0045P001C01CS-SA     I5 @S9S_MB_2U_LIB.S9S_MB_2U(SCH_1):PAGE71
    U1 CV79 VSS571 SOCKET4677_AZIF0045P001C01CS-SA     I5 @S9S_MB_2U_LIB.S9S_MB_2U(SCH_1):PAGE71
    U1 CW33 VSS583 SOCKET4677_AZIF0045P001C01CS-SA     I5 @S9S_MB_2U_LIB.S9S_MB_2U(SCH_1):PAGE71
    U1 CW70 VSS595 SOCKET4677_AZIF0045P001C01CS-SA     I5 @S9S_MB_2U_LIB.S9S_MB_2U(SCH_1):PAGE71
    U1  CY4 VSS611 SOCKET4677_AZIF0045P001C01CS-SA     I5 @S9S_MB_2U_LIB.S9S_MB_2U(SCH_1):PAGE71
    U1 DA43 VSS679 SOCKET4677_AZIF0045P001C01CS-SA     I5 @S9S_MB_2U_LIB.S9S_MB_2U(SCH_1):PAGE71
    U1 DA68 VSS690 SOCKET4677_AZIF0045P001C01CS-SA     I5 @S9S_MB_2U_LIB.S9S_MB_2U(SCH_1):PAGE71
    U1 DB16 VSS699 SOCKET4677_AZIF0045P001C01CS-SA     I5 @S9S_MB_2U_LIB.S9S_MB_2U(SCH_1):PAGE71
    U1 DB20 VSS700 SOCKET4677_AZIF0045P001C01CS-SA     I5 @S9S_MB_2U_LIB.S9S_MB_2U(SCH_1):PAGE71
    U1 DB26 VSS702 SOCKET4677_AZIF0045P001C01CS-SA     I5 @S9S_MB_2U_LIB.S9S_MB_2U(SCH_1):PAGE71
    U1 DB34 VSS705 SOCKET4677_AZIF0045P001C01CS-SA     I5 @S9S_MB_2U_LIB.S9S_MB_2U(SCH_1):PAGE71
    U1 DB44 VSS709 SOCKET4677_AZIF0045P001C01CS-SA     I5 @S9S_MB_2U_LIB.S9S_MB_2U(SCH_1):PAGE71
    U1 DB51 VSS711 SOCKET4677_AZIF0045P001C01CS-SA     I5 @S9S_MB_2U_LIB.S9S_MB_2U(SCH_1):PAGE71
    U1 DB53 VSS712 SOCKET4677_AZIF0045P001C01CS-SA     I5 @S9S_MB_2U_LIB.S9S_MB_2U(SCH_1):PAGE71
    U1 DB59 VSS714 SOCKET4677_AZIF0045P001C01CS-SA     I5 @S9S_MB_2U_LIB.S9S_MB_2U(SCH_1):PAGE71
    U1 DB63 VSS715 SOCKET4677_AZIF0045P001C01CS-SA     I5 @S9S_MB_2U_LIB.S9S_MB_2U(SCH_1):PAGE71
    U1 DB69 VSS717 SOCKET4677_AZIF0045P001C01CS-SA     I5 @S9S_MB_2U_LIB.S9S_MB_2U(SCH_1):PAGE71
    U1 DB75 VSS719 SOCKET4677_AZIF0045P001C01CS-SA     I5 @S9S_MB_2U_LIB.S9S_MB_2U(SCH_1):PAGE71
    U1 CK63 VSS744 SOCKET4677_AZIF0045P001C01CS-SA     I5 @S9S_MB_2U_LIB.S9S_MB_2U(SCH_1):PAGE71
    U1 CK69 VSS745 SOCKET4677_AZIF0045P001C01CS-SA     I5 @S9S_MB_2U_LIB.S9S_MB_2U(SCH_1):PAGE71
    U1 CK81 VSS749 SOCKET4677_AZIF0045P001C01CS-SA     I5 @S9S_MB_2U_LIB.S9S_MB_2U(SCH_1):PAGE71
    U1  CL1 VSS750 SOCKET4677_AZIF0045P001C01CS-SA     I5 @S9S_MB_2U_LIB.S9S_MB_2U(SCH_1):PAGE71
    U1 CL13 VSS751 SOCKET4677_AZIF0045P001C01CS-SA     I5 @S9S_MB_2U_LIB.S9S_MB_2U(SCH_1):PAGE71
    U1 CL17 VSS752 SOCKET4677_AZIF0045P001C01CS-SA     I5 @S9S_MB_2U_LIB.S9S_MB_2U(SCH_1):PAGE71
    U1  CL5 VSS754 SOCKET4677_AZIF0045P001C01CS-SA     I5 @S9S_MB_2U_LIB.S9S_MB_2U(SCH_1):PAGE71
    U1 CL62 VSS755 SOCKET4677_AZIF0045P001C01CS-SA     I5 @S9S_MB_2U_LIB.S9S_MB_2U(SCH_1):PAGE71
    U1 CL74 VSS756 SOCKET4677_AZIF0045P001C01CS-SA     I5 @S9S_MB_2U_LIB.S9S_MB_2U(SCH_1):PAGE71
    U1 CL78 VSS757 SOCKET4677_AZIF0045P001C01CS-SA     I5 @S9S_MB_2U_LIB.S9S_MB_2U(SCH_1):PAGE71
    U1 CL80 VSS758 SOCKET4677_AZIF0045P001C01CS-SA     I5 @S9S_MB_2U_LIB.S9S_MB_2U(SCH_1):PAGE71
    U1 CL82 VSS759 SOCKET4677_AZIF0045P001C01CS-SA     I5 @S9S_MB_2U_LIB.S9S_MB_2U(SCH_1):PAGE71
    U1  CL9 VSS760 SOCKET4677_AZIF0045P001C01CS-SA     I5 @S9S_MB_2U_LIB.S9S_MB_2U(SCH_1):PAGE71
    U1 CM12 VSS761 SOCKET4677_AZIF0045P001C01CS-SA     I5 @S9S_MB_2U_LIB.S9S_MB_2U(SCH_1):PAGE71
    U1 CM20 VSS762 SOCKET4677_AZIF0045P001C01CS-SA     I5 @S9S_MB_2U_LIB.S9S_MB_2U(SCH_1):PAGE71
    U1 CM24 VSS763 SOCKET4677_AZIF0045P001C01CS-SA     I5 @S9S_MB_2U_LIB.S9S_MB_2U(SCH_1):PAGE71
    U1  CM4 VSS764 SOCKET4677_AZIF0045P001C01CS-SA     I5 @S9S_MB_2U_LIB.S9S_MB_2U(SCH_1):PAGE71
    U1 CM61 VSS765 SOCKET4677_AZIF0045P001C01CS-SA     I5 @S9S_MB_2U_LIB.S9S_MB_2U(SCH_1):PAGE71
    U1 CM65 VSS766 SOCKET4677_AZIF0045P001C01CS-SA     I5 @S9S_MB_2U_LIB.S9S_MB_2U(SCH_1):PAGE71
    U1 CM67 VSS767 SOCKET4677_AZIF0045P001C01CS-SA     I5 @S9S_MB_2U_LIB.S9S_MB_2U(SCH_1):PAGE71
    U1 CM79 VSS768 SOCKET4677_AZIF0045P001C01CS-SA     I5 @S9S_MB_2U_LIB.S9S_MB_2U(SCH_1):PAGE71
    U1  CM8 VSS769 SOCKET4677_AZIF0045P001C01CS-SA     I5 @S9S_MB_2U_LIB.S9S_MB_2U(SCH_1):PAGE71
    U1 CM81 VSS770 SOCKET4677_AZIF0045P001C01CS-SA     I5 @S9S_MB_2U_LIB.S9S_MB_2U(SCH_1):PAGE71
    U1 CM83 VSS771 SOCKET4677_AZIF0045P001C01CS-SA     I5 @S9S_MB_2U_LIB.S9S_MB_2U(SCH_1):PAGE71
    U1 CM85 VSS772 SOCKET4677_AZIF0045P001C01CS-SA     I5 @S9S_MB_2U_LIB.S9S_MB_2U(SCH_1):PAGE71
    U1 CN68 VSS773 SOCKET4677_AZIF0045P001C01CS-SA     I5 @S9S_MB_2U_LIB.S9S_MB_2U(SCH_1):PAGE71
    U1 CN70 VSS774 SOCKET4677_AZIF0045P001C01CS-SA     I5 @S9S_MB_2U_LIB.S9S_MB_2U(SCH_1):PAGE71
    U1 CN72 VSS775 SOCKET4677_AZIF0045P001C01CS-SA     I5 @S9S_MB_2U_LIB.S9S_MB_2U(SCH_1):PAGE71
    U1 CN74 VSS777 SOCKET4677_AZIF0045P001C01CS-SA     I5 @S9S_MB_2U_LIB.S9S_MB_2U(SCH_1):PAGE71
    U1 CN84 VSS778 SOCKET4677_AZIF0045P001C01CS-SA     I5 @S9S_MB_2U_LIB.S9S_MB_2U(SCH_1):PAGE71
    U1 CN86 VSS779 SOCKET4677_AZIF0045P001C01CS-SA     I5 @S9S_MB_2U_LIB.S9S_MB_2U(SCH_1):PAGE71
    U1 CP12 VSS780 SOCKET4677_AZIF0045P001C01CS-SA     I5 @S9S_MB_2U_LIB.S9S_MB_2U(SCH_1):PAGE71
    U1 CP18 VSS781 SOCKET4677_AZIF0045P001C01CS-SA     I5 @S9S_MB_2U_LIB.S9S_MB_2U(SCH_1):PAGE71
    U1  CP4 VSS782 SOCKET4677_AZIF0045P001C01CS-SA     I5 @S9S_MB_2U_LIB.S9S_MB_2U(SCH_1):PAGE71
    U1 CP75 VSS783 SOCKET4677_AZIF0045P001C01CS-SA     I5 @S9S_MB_2U_LIB.S9S_MB_2U(SCH_1):PAGE71
    U1 CP77 VSS784 SOCKET4677_AZIF0045P001C01CS-SA     I5 @S9S_MB_2U_LIB.S9S_MB_2U(SCH_1):PAGE71
    U1  CP8 VSS785 SOCKET4677_AZIF0045P001C01CS-SA     I5 @S9S_MB_2U_LIB.S9S_MB_2U(SCH_1):PAGE71
    U1 CP83 VSS786 SOCKET4677_AZIF0045P001C01CS-SA     I5 @S9S_MB_2U_LIB.S9S_MB_2U(SCH_1):PAGE71
    U1 CP87 VSS787 SOCKET4677_AZIF0045P001C01CS-SA     I5 @S9S_MB_2U_LIB.S9S_MB_2U(SCH_1):PAGE71
    U1 CP91 VSS788 SOCKET4677_AZIF0045P001C01CS-SA     I5 @S9S_MB_2U_LIB.S9S_MB_2U(SCH_1):PAGE71
    U1  CR1 VSS789 SOCKET4677_AZIF0045P001C01CS-SA     I5 @S9S_MB_2U_LIB.S9S_MB_2U(SCH_1):PAGE71
    U1 CR11 VSS790 SOCKET4677_AZIF0045P001C01CS-SA     I5 @S9S_MB_2U_LIB.S9S_MB_2U(SCH_1):PAGE71
    U1 CR13 VSS792 SOCKET4677_AZIF0045P001C01CS-SA     I5 @S9S_MB_2U_LIB.S9S_MB_2U(SCH_1):PAGE71
    U1 CR17 VSS793 SOCKET4677_AZIF0045P001C01CS-SA     I5 @S9S_MB_2U_LIB.S9S_MB_2U(SCH_1):PAGE71
    U1  CR5 VSS794 SOCKET4677_AZIF0045P001C01CS-SA     I5 @S9S_MB_2U_LIB.S9S_MB_2U(SCH_1):PAGE71
    U1 CR62 VSS795 SOCKET4677_AZIF0045P001C01CS-SA     I5 @S9S_MB_2U_LIB.S9S_MB_2U(SCH_1):PAGE71
    U1 CR64 VSS796 SOCKET4677_AZIF0045P001C01CS-SA     I5 @S9S_MB_2U_LIB.S9S_MB_2U(SCH_1):PAGE71
    U1 CR84 VSS797 SOCKET4677_AZIF0045P001C01CS-SA     I5 @S9S_MB_2U_LIB.S9S_MB_2U(SCH_1):PAGE71
    U1 CR88 VSS800 SOCKET4677_AZIF0045P001C01CS-SA     I5 @S9S_MB_2U_LIB.S9S_MB_2U(SCH_1):PAGE71
    U1  CR9 VSS801 SOCKET4677_AZIF0045P001C01CS-SA     I5 @S9S_MB_2U_LIB.S9S_MB_2U(SCH_1):PAGE71
    U1 CR90 VSS803 SOCKET4677_AZIF0045P001C01CS-SA     I5 @S9S_MB_2U_LIB.S9S_MB_2U(SCH_1):PAGE71
    U1 CT10 VSS804 SOCKET4677_AZIF0045P001C01CS-SA     I5 @S9S_MB_2U_LIB.S9S_MB_2U(SCH_1):PAGE71
    U1 CT12 VSS805 SOCKET4677_AZIF0045P001C01CS-SA     I5 @S9S_MB_2U_LIB.S9S_MB_2U(SCH_1):PAGE71
    U1 CT69 VSS810 SOCKET4677_AZIF0045P001C01CS-SA     I5 @S9S_MB_2U_LIB.S9S_MB_2U(SCH_1):PAGE71
    U1 CT73 VSS811 SOCKET4677_AZIF0045P001C01CS-SA     I5 @S9S_MB_2U_LIB.S9S_MB_2U(SCH_1):PAGE71
    U1 CT81 VSS812 SOCKET4677_AZIF0045P001C01CS-SA     I5 @S9S_MB_2U_LIB.S9S_MB_2U(SCH_1):PAGE71
    U1 CU19 VSS813 SOCKET4677_AZIF0045P001C01CS-SA     I5 @S9S_MB_2U_LIB.S9S_MB_2U(SCH_1):PAGE71
    U1 CU21 VSS814 SOCKET4677_AZIF0045P001C01CS-SA     I5 @S9S_MB_2U_LIB.S9S_MB_2U(SCH_1):PAGE71
    U1 CU23 VSS815 SOCKET4677_AZIF0045P001C01CS-SA     I5 @S9S_MB_2U_LIB.S9S_MB_2U(SCH_1):PAGE71
    U1 CU60 VSS816 SOCKET4677_AZIF0045P001C01CS-SA     I5 @S9S_MB_2U_LIB.S9S_MB_2U(SCH_1):PAGE71
    U1 CU66 VSS818 SOCKET4677_AZIF0045P001C01CS-SA     I5 @S9S_MB_2U_LIB.S9S_MB_2U(SCH_1):PAGE71
    U1 CU68 VSS819 SOCKET4677_AZIF0045P001C01CS-SA     I5 @S9S_MB_2U_LIB.S9S_MB_2U(SCH_1):PAGE71
    U1 CU84 VSS822 SOCKET4677_AZIF0045P001C01CS-SA     I5 @S9S_MB_2U_LIB.S9S_MB_2U(SCH_1):PAGE71
    U1 CU88 VSS823 SOCKET4677_AZIF0045P001C01CS-SA     I5 @S9S_MB_2U_LIB.S9S_MB_2U(SCH_1):PAGE71
    U1 CV12 VSS824 SOCKET4677_AZIF0045P001C01CS-SA     I5 @S9S_MB_2U_LIB.S9S_MB_2U(SCH_1):PAGE71
    U1  CV4 VSS825 SOCKET4677_AZIF0045P001C01CS-SA     I5 @S9S_MB_2U_LIB.S9S_MB_2U(SCH_1):PAGE71
    U1 CV75 VSS826 SOCKET4677_AZIF0045P001C01CS-SA     I5 @S9S_MB_2U_LIB.S9S_MB_2U(SCH_1):PAGE71
    U1  CV8 VSS827 SOCKET4677_AZIF0045P001C01CS-SA     I5 @S9S_MB_2U_LIB.S9S_MB_2U(SCH_1):PAGE71
    U1 CV83 VSS828 SOCKET4677_AZIF0045P001C01CS-SA     I5 @S9S_MB_2U_LIB.S9S_MB_2U(SCH_1):PAGE71
    U1 CV87 VSS831 SOCKET4677_AZIF0045P001C01CS-SA     I5 @S9S_MB_2U_LIB.S9S_MB_2U(SCH_1):PAGE71
    U1 CV91 VSS833 SOCKET4677_AZIF0045P001C01CS-SA     I5 @S9S_MB_2U_LIB.S9S_MB_2U(SCH_1):PAGE71
    U1  CW1 VSS834 SOCKET4677_AZIF0045P001C01CS-SA     I5 @S9S_MB_2U_LIB.S9S_MB_2U(SCH_1):PAGE71
    U1 CW13 VSS836 SOCKET4677_AZIF0045P001C01CS-SA     I5 @S9S_MB_2U_LIB.S9S_MB_2U(SCH_1):PAGE71
    U1 CW17 VSS837 SOCKET4677_AZIF0045P001C01CS-SA     I5 @S9S_MB_2U_LIB.S9S_MB_2U(SCH_1):PAGE71
    U1  CW5 VSS838 SOCKET4677_AZIF0045P001C01CS-SA     I5 @S9S_MB_2U_LIB.S9S_MB_2U(SCH_1):PAGE71
    U1 CW72 VSS840 SOCKET4677_AZIF0045P001C01CS-SA     I5 @S9S_MB_2U_LIB.S9S_MB_2U(SCH_1):PAGE71
    U1 CW78 VSS843 SOCKET4677_AZIF0045P001C01CS-SA     I5 @S9S_MB_2U_LIB.S9S_MB_2U(SCH_1):PAGE71
    U1 CW84 VSS846 SOCKET4677_AZIF0045P001C01CS-SA     I5 @S9S_MB_2U_LIB.S9S_MB_2U(SCH_1):PAGE71
    U1 CW88 VSS848 SOCKET4677_AZIF0045P001C01CS-SA     I5 @S9S_MB_2U_LIB.S9S_MB_2U(SCH_1):PAGE71
    U1  CW9 VSS850 SOCKET4677_AZIF0045P001C01CS-SA     I5 @S9S_MB_2U_LIB.S9S_MB_2U(SCH_1):PAGE71
    U1 CY12 VSS851 SOCKET4677_AZIF0045P001C01CS-SA     I5 @S9S_MB_2U_LIB.S9S_MB_2U(SCH_1):PAGE71
    U1 CY16 VSS852 SOCKET4677_AZIF0045P001C01CS-SA     I5 @S9S_MB_2U_LIB.S9S_MB_2U(SCH_1):PAGE71
    U1 CY18 VSS853 SOCKET4677_AZIF0045P001C01CS-SA     I5 @S9S_MB_2U_LIB.S9S_MB_2U(SCH_1):PAGE71
    U1 CY26 VSS854 SOCKET4677_AZIF0045P001C01CS-SA     I5 @S9S_MB_2U_LIB.S9S_MB_2U(SCH_1):PAGE71
    U1 CY30 VSS855 SOCKET4677_AZIF0045P001C01CS-SA     I5 @S9S_MB_2U_LIB.S9S_MB_2U(SCH_1):PAGE71
    U1 CY63 VSS856 SOCKET4677_AZIF0045P001C01CS-SA     I5 @S9S_MB_2U_LIB.S9S_MB_2U(SCH_1):PAGE71
    U1 CY73 VSS858 SOCKET4677_AZIF0045P001C01CS-SA     I5 @S9S_MB_2U_LIB.S9S_MB_2U(SCH_1):PAGE71
    U1 CY77 VSS859 SOCKET4677_AZIF0045P001C01CS-SA     I5 @S9S_MB_2U_LIB.S9S_MB_2U(SCH_1):PAGE71
    U1  CY8 VSS860 SOCKET4677_AZIF0045P001C01CS-SA     I5 @S9S_MB_2U_LIB.S9S_MB_2U(SCH_1):PAGE71
    U1 CY81 VSS862 SOCKET4677_AZIF0045P001C01CS-SA     I5 @S9S_MB_2U_LIB.S9S_MB_2U(SCH_1):PAGE71
    U1 CY83 VSS863 SOCKET4677_AZIF0045P001C01CS-SA     I5 @S9S_MB_2U_LIB.S9S_MB_2U(SCH_1):PAGE71
    U1 DA19 VSS910 SOCKET4677_AZIF0045P001C01CS-SA     I5 @S9S_MB_2U_LIB.S9S_MB_2U(SCH_1):PAGE71
    U1 DA23 VSS911 SOCKET4677_AZIF0045P001C01CS-SA     I5 @S9S_MB_2U_LIB.S9S_MB_2U(SCH_1):PAGE71
    U1 DA25 VSS912 SOCKET4677_AZIF0045P001C01CS-SA     I5 @S9S_MB_2U_LIB.S9S_MB_2U(SCH_1):PAGE71
    U1 DA29 VSS913 SOCKET4677_AZIF0045P001C01CS-SA     I5 @S9S_MB_2U_LIB.S9S_MB_2U(SCH_1):PAGE71
    U1 DA31 VSS914 SOCKET4677_AZIF0045P001C01CS-SA     I5 @S9S_MB_2U_LIB.S9S_MB_2U(SCH_1):PAGE71
    U1 DA33 VSS915 SOCKET4677_AZIF0045P001C01CS-SA     I5 @S9S_MB_2U_LIB.S9S_MB_2U(SCH_1):PAGE71
    U1 DA35 VSS916 SOCKET4677_AZIF0045P001C01CS-SA     I5 @S9S_MB_2U_LIB.S9S_MB_2U(SCH_1):PAGE71
    U1 DA37 VSS917 SOCKET4677_AZIF0045P001C01CS-SA     I5 @S9S_MB_2U_LIB.S9S_MB_2U(SCH_1):PAGE71
    U1 DA41 VSS918 SOCKET4677_AZIF0045P001C01CS-SA     I5 @S9S_MB_2U_LIB.S9S_MB_2U(SCH_1):PAGE71
    U1 DA48 VSS919 SOCKET4677_AZIF0045P001C01CS-SA     I5 @S9S_MB_2U_LIB.S9S_MB_2U(SCH_1):PAGE71
    U1 DA50 VSS920 SOCKET4677_AZIF0045P001C01CS-SA     I5 @S9S_MB_2U_LIB.S9S_MB_2U(SCH_1):PAGE71
    U1 DA54 VSS921 SOCKET4677_AZIF0045P001C01CS-SA     I5 @S9S_MB_2U_LIB.S9S_MB_2U(SCH_1):PAGE71
    U1 DA56 VSS922 SOCKET4677_AZIF0045P001C01CS-SA     I5 @S9S_MB_2U_LIB.S9S_MB_2U(SCH_1):PAGE71
    U1 DA58 VSS923 SOCKET4677_AZIF0045P001C01CS-SA     I5 @S9S_MB_2U_LIB.S9S_MB_2U(SCH_1):PAGE71
    U1 DA60 VSS924 SOCKET4677_AZIF0045P001C01CS-SA     I5 @S9S_MB_2U_LIB.S9S_MB_2U(SCH_1):PAGE71
    U1 DA62 VSS925 SOCKET4677_AZIF0045P001C01CS-SA     I5 @S9S_MB_2U_LIB.S9S_MB_2U(SCH_1):PAGE71
    U1 DA66 VSS926 SOCKET4677_AZIF0045P001C01CS-SA     I5 @S9S_MB_2U_LIB.S9S_MB_2U(SCH_1):PAGE71
    U1 DA72 VSS927 SOCKET4677_AZIF0045P001C01CS-SA     I5 @S9S_MB_2U_LIB.S9S_MB_2U(SCH_1):PAGE71
    U1 DA74 VSS928 SOCKET4677_AZIF0045P001C01CS-SA     I5 @S9S_MB_2U_LIB.S9S_MB_2U(SCH_1):PAGE71
    U1 DA80 VSS929 SOCKET4677_AZIF0045P001C01CS-SA     I5 @S9S_MB_2U_LIB.S9S_MB_2U(SCH_1):PAGE71
    U1 DA82 VSS930 SOCKET4677_AZIF0045P001C01CS-SA     I5 @S9S_MB_2U_LIB.S9S_MB_2U(SCH_1):PAGE71
    U1 DA84 VSS931 SOCKET4677_AZIF0045P001C01CS-SA     I5 @S9S_MB_2U_LIB.S9S_MB_2U(SCH_1):PAGE71
    U1 DA88 VSS932 SOCKET4677_AZIF0045P001C01CS-SA     I5 @S9S_MB_2U_LIB.S9S_MB_2U(SCH_1):PAGE71
    U1 DB12 VSS933 SOCKET4677_AZIF0045P001C01CS-SA     I5 @S9S_MB_2U_LIB.S9S_MB_2U(SCH_1):PAGE71
    U1 DB22 VSS935 SOCKET4677_AZIF0045P001C01CS-SA     I5 @S9S_MB_2U_LIB.S9S_MB_2U(SCH_1):PAGE71
    U1 DB28 VSS936 SOCKET4677_AZIF0045P001C01CS-SA     I5 @S9S_MB_2U_LIB.S9S_MB_2U(SCH_1):PAGE71
    U1 DB32 VSS937 SOCKET4677_AZIF0045P001C01CS-SA     I5 @S9S_MB_2U_LIB.S9S_MB_2U(SCH_1):PAGE71
    U1 DB38 VSS938 SOCKET4677_AZIF0045P001C01CS-SA     I5 @S9S_MB_2U_LIB.S9S_MB_2U(SCH_1):PAGE71
    U1  DB4 VSS939 SOCKET4677_AZIF0045P001C01CS-SA     I5 @S9S_MB_2U_LIB.S9S_MB_2U(SCH_1):PAGE71
    U1 DB40 VSS940 SOCKET4677_AZIF0045P001C01CS-SA     I5 @S9S_MB_2U_LIB.S9S_MB_2U(SCH_1):PAGE71
    U1 DB47 VSS941 SOCKET4677_AZIF0045P001C01CS-SA     I5 @S9S_MB_2U_LIB.S9S_MB_2U(SCH_1):PAGE71
    U1 DB57 VSS942 SOCKET4677_AZIF0045P001C01CS-SA     I5 @S9S_MB_2U_LIB.S9S_MB_2U(SCH_1):PAGE71
    U1 DB65 VSS943 SOCKET4677_AZIF0045P001C01CS-SA     I5 @S9S_MB_2U_LIB.S9S_MB_2U(SCH_1):PAGE71
    U1 DB71 VSS944 SOCKET4677_AZIF0045P001C01CS-SA     I5 @S9S_MB_2U_LIB.S9S_MB_2U(SCH_1):PAGE71
    U1 DB77 VSS946 SOCKET4677_AZIF0045P001C01CS-SA     I5 @S9S_MB_2U_LIB.S9S_MB_2U(SCH_1):PAGE71
    U1  DB8 VSS947 SOCKET4677_AZIF0045P001C01CS-SA     I5 @S9S_MB_2U_LIB.S9S_MB_2U(SCH_1):PAGE71
    U1 DB87 VSS948 SOCKET4677_AZIF0045P001C01CS-SA     I5 @S9S_MB_2U_LIB.S9S_MB_2U(SCH_1):PAGE71
    U1 CJ76 VSS383 SOCKET4677_AZIF0045P001C01CS-SA     I8 @S9S_MB_2U_LIB.S9S_MB_2U(SCH_1):PAGE71
    U1  CK4 VSS396 SOCKET4677_AZIF0045P001C01CS-SA     I8 @S9S_MB_2U_LIB.S9S_MB_2U(SCH_1):PAGE71
    U1 BR35 VSS542 SOCKET4677_AZIF0045P001C01CS-SA     I8 @S9S_MB_2U_LIB.S9S_MB_2U(SCH_1):PAGE71
    U1 BR37 VSS543 SOCKET4677_AZIF0045P001C01CS-SA     I8 @S9S_MB_2U_LIB.S9S_MB_2U(SCH_1):PAGE71
    U1 BR39 VSS545 SOCKET4677_AZIF0045P001C01CS-SA     I8 @S9S_MB_2U_LIB.S9S_MB_2U(SCH_1):PAGE71
    U1 BR41 VSS546 SOCKET4677_AZIF0045P001C01CS-SA     I8 @S9S_MB_2U_LIB.S9S_MB_2U(SCH_1):PAGE71
    U1 BR43 VSS547 SOCKET4677_AZIF0045P001C01CS-SA     I8 @S9S_MB_2U_LIB.S9S_MB_2U(SCH_1):PAGE71
    U1 BR45 VSS548 SOCKET4677_AZIF0045P001C01CS-SA     I8 @S9S_MB_2U_LIB.S9S_MB_2U(SCH_1):PAGE71
    U1 BR48 VSS549 SOCKET4677_AZIF0045P001C01CS-SA     I8 @S9S_MB_2U_LIB.S9S_MB_2U(SCH_1):PAGE71
    U1 BR50 VSS550 SOCKET4677_AZIF0045P001C01CS-SA     I8 @S9S_MB_2U_LIB.S9S_MB_2U(SCH_1):PAGE71
    U1 BR52 VSS551 SOCKET4677_AZIF0045P001C01CS-SA     I8 @S9S_MB_2U_LIB.S9S_MB_2U(SCH_1):PAGE71
    U1 BR54 VSS552 SOCKET4677_AZIF0045P001C01CS-SA     I8 @S9S_MB_2U_LIB.S9S_MB_2U(SCH_1):PAGE71
    U1 BR56 VSS555 SOCKET4677_AZIF0045P001C01CS-SA     I8 @S9S_MB_2U_LIB.S9S_MB_2U(SCH_1):PAGE71
    U1 BR58 VSS556 SOCKET4677_AZIF0045P001C01CS-SA     I8 @S9S_MB_2U_LIB.S9S_MB_2U(SCH_1):PAGE71
    U1 BR64 VSS557 SOCKET4677_AZIF0045P001C01CS-SA     I8 @S9S_MB_2U_LIB.S9S_MB_2U(SCH_1):PAGE71
    U1 BR66 VSS559 SOCKET4677_AZIF0045P001C01CS-SA     I8 @S9S_MB_2U_LIB.S9S_MB_2U(SCH_1):PAGE71
    U1 BR68 VSS560 SOCKET4677_AZIF0045P001C01CS-SA     I8 @S9S_MB_2U_LIB.S9S_MB_2U(SCH_1):PAGE71
    U1 BR70 VSS561 SOCKET4677_AZIF0045P001C01CS-SA     I8 @S9S_MB_2U_LIB.S9S_MB_2U(SCH_1):PAGE71
    U1 BR72 VSS563 SOCKET4677_AZIF0045P001C01CS-SA     I8 @S9S_MB_2U_LIB.S9S_MB_2U(SCH_1):PAGE71
    U1 BR74 VSS564 SOCKET4677_AZIF0045P001C01CS-SA     I8 @S9S_MB_2U_LIB.S9S_MB_2U(SCH_1):PAGE71
    U1 BR76 VSS565 SOCKET4677_AZIF0045P001C01CS-SA     I8 @S9S_MB_2U_LIB.S9S_MB_2U(SCH_1):PAGE71
    U1 BR80 VSS566 SOCKET4677_AZIF0045P001C01CS-SA     I8 @S9S_MB_2U_LIB.S9S_MB_2U(SCH_1):PAGE71
    U1 BR82 VSS567 SOCKET4677_AZIF0045P001C01CS-SA     I8 @S9S_MB_2U_LIB.S9S_MB_2U(SCH_1):PAGE71
    U1 BR84 VSS568 SOCKET4677_AZIF0045P001C01CS-SA     I8 @S9S_MB_2U_LIB.S9S_MB_2U(SCH_1):PAGE71
    U1 BR86 VSS569 SOCKET4677_AZIF0045P001C01CS-SA     I8 @S9S_MB_2U_LIB.S9S_MB_2U(SCH_1):PAGE71
    U1 BR88 VSS570 SOCKET4677_AZIF0045P001C01CS-SA     I8 @S9S_MB_2U_LIB.S9S_MB_2U(SCH_1):PAGE71
    U1 BR90 VSS573 SOCKET4677_AZIF0045P001C01CS-SA     I8 @S9S_MB_2U_LIB.S9S_MB_2U(SCH_1):PAGE71
    U1 BT12 VSS574 SOCKET4677_AZIF0045P001C01CS-SA     I8 @S9S_MB_2U_LIB.S9S_MB_2U(SCH_1):PAGE71
    U1 BT16 VSS575 SOCKET4677_AZIF0045P001C01CS-SA     I8 @S9S_MB_2U_LIB.S9S_MB_2U(SCH_1):PAGE71
    U1 BT20 VSS576 SOCKET4677_AZIF0045P001C01CS-SA     I8 @S9S_MB_2U_LIB.S9S_MB_2U(SCH_1):PAGE71
    U1  BT4 VSS577 SOCKET4677_AZIF0045P001C01CS-SA     I8 @S9S_MB_2U_LIB.S9S_MB_2U(SCH_1):PAGE71
    U1  BT8 VSS578 SOCKET4677_AZIF0045P001C01CS-SA     I8 @S9S_MB_2U_LIB.S9S_MB_2U(SCH_1):PAGE71
    U1 BU15 VSS579 SOCKET4677_AZIF0045P001C01CS-SA     I8 @S9S_MB_2U_LIB.S9S_MB_2U(SCH_1):PAGE71
    U1 BU19 VSS580 SOCKET4677_AZIF0045P001C01CS-SA     I8 @S9S_MB_2U_LIB.S9S_MB_2U(SCH_1):PAGE71
    U1 BU21 VSS581 SOCKET4677_AZIF0045P001C01CS-SA     I8 @S9S_MB_2U_LIB.S9S_MB_2U(SCH_1):PAGE71
    U1 BU23 VSS582 SOCKET4677_AZIF0045P001C01CS-SA     I8 @S9S_MB_2U_LIB.S9S_MB_2U(SCH_1):PAGE71
    U1 BU25 VSS584 SOCKET4677_AZIF0045P001C01CS-SA     I8 @S9S_MB_2U_LIB.S9S_MB_2U(SCH_1):PAGE71
    U1 BU31 VSS585 SOCKET4677_AZIF0045P001C01CS-SA     I8 @S9S_MB_2U_LIB.S9S_MB_2U(SCH_1):PAGE71
    U1  BU7 VSS586 SOCKET4677_AZIF0045P001C01CS-SA     I8 @S9S_MB_2U_LIB.S9S_MB_2U(SCH_1):PAGE71
    U1 BV12 VSS587 SOCKET4677_AZIF0045P001C01CS-SA     I8 @S9S_MB_2U_LIB.S9S_MB_2U(SCH_1):PAGE71
    U1 BV16 VSS588 SOCKET4677_AZIF0045P001C01CS-SA     I8 @S9S_MB_2U_LIB.S9S_MB_2U(SCH_1):PAGE71
    U1 BV18 VSS589 SOCKET4677_AZIF0045P001C01CS-SA     I8 @S9S_MB_2U_LIB.S9S_MB_2U(SCH_1):PAGE71
    U1  BV2 VSS590 SOCKET4677_AZIF0045P001C01CS-SA     I8 @S9S_MB_2U_LIB.S9S_MB_2U(SCH_1):PAGE71
    U1 BV20 VSS591 SOCKET4677_AZIF0045P001C01CS-SA     I8 @S9S_MB_2U_LIB.S9S_MB_2U(SCH_1):PAGE71
    U1  BV4 VSS592 SOCKET4677_AZIF0045P001C01CS-SA     I8 @S9S_MB_2U_LIB.S9S_MB_2U(SCH_1):PAGE71
    U1  BV6 VSS593 SOCKET4677_AZIF0045P001C01CS-SA     I8 @S9S_MB_2U_LIB.S9S_MB_2U(SCH_1):PAGE71
    U1  BV8 VSS594 SOCKET4677_AZIF0045P001C01CS-SA     I8 @S9S_MB_2U_LIB.S9S_MB_2U(SCH_1):PAGE71
    U1 BW13 VSS596 SOCKET4677_AZIF0045P001C01CS-SA     I8 @S9S_MB_2U_LIB.S9S_MB_2U(SCH_1):PAGE71
    U1 BW17 VSS597 SOCKET4677_AZIF0045P001C01CS-SA     I8 @S9S_MB_2U_LIB.S9S_MB_2U(SCH_1):PAGE71
    U1 BW27 VSS598 SOCKET4677_AZIF0045P001C01CS-SA     I8 @S9S_MB_2U_LIB.S9S_MB_2U(SCH_1):PAGE71
    U1 BW29 VSS599 SOCKET4677_AZIF0045P001C01CS-SA     I8 @S9S_MB_2U_LIB.S9S_MB_2U(SCH_1):PAGE71
    U1  BW3 VSS600 SOCKET4677_AZIF0045P001C01CS-SA     I8 @S9S_MB_2U_LIB.S9S_MB_2U(SCH_1):PAGE71
    U1 BW31 VSS601 SOCKET4677_AZIF0045P001C01CS-SA     I8 @S9S_MB_2U_LIB.S9S_MB_2U(SCH_1):PAGE71
    U1  BW5 VSS602 SOCKET4677_AZIF0045P001C01CS-SA     I8 @S9S_MB_2U_LIB.S9S_MB_2U(SCH_1):PAGE71
    U1  BW9 VSS603 SOCKET4677_AZIF0045P001C01CS-SA     I8 @S9S_MB_2U_LIB.S9S_MB_2U(SCH_1):PAGE71
    U1 BY12 VSS604 SOCKET4677_AZIF0045P001C01CS-SA     I8 @S9S_MB_2U_LIB.S9S_MB_2U(SCH_1):PAGE71
    U1 BY16 VSS605 SOCKET4677_AZIF0045P001C01CS-SA     I8 @S9S_MB_2U_LIB.S9S_MB_2U(SCH_1):PAGE71
    U1 BY20 VSS606 SOCKET4677_AZIF0045P001C01CS-SA     I8 @S9S_MB_2U_LIB.S9S_MB_2U(SCH_1):PAGE71
    U1  BY4 VSS607 SOCKET4677_AZIF0045P001C01CS-SA     I8 @S9S_MB_2U_LIB.S9S_MB_2U(SCH_1):PAGE71
    U1  BY8 VSS608 SOCKET4677_AZIF0045P001C01CS-SA     I8 @S9S_MB_2U_LIB.S9S_MB_2U(SCH_1):PAGE71
    U1  CA3 VSS620 SOCKET4677_AZIF0045P001C01CS-SA     I8 @S9S_MB_2U_LIB.S9S_MB_2U(SCH_1):PAGE71
    U1 CA31 VSS621 SOCKET4677_AZIF0045P001C01CS-SA     I8 @S9S_MB_2U_LIB.S9S_MB_2U(SCH_1):PAGE71
    U1 CB12 VSS622 SOCKET4677_AZIF0045P001C01CS-SA     I8 @S9S_MB_2U_LIB.S9S_MB_2U(SCH_1):PAGE71
    U1 CB16 VSS623 SOCKET4677_AZIF0045P001C01CS-SA     I8 @S9S_MB_2U_LIB.S9S_MB_2U(SCH_1):PAGE71
    U1 CB20 VSS624 SOCKET4677_AZIF0045P001C01CS-SA     I8 @S9S_MB_2U_LIB.S9S_MB_2U(SCH_1):PAGE71
    U1 CB22 VSS625 SOCKET4677_AZIF0045P001C01CS-SA     I8 @S9S_MB_2U_LIB.S9S_MB_2U(SCH_1):PAGE71
    U1 CB24 VSS626 SOCKET4677_AZIF0045P001C01CS-SA     I8 @S9S_MB_2U_LIB.S9S_MB_2U(SCH_1):PAGE71
    U1 CB26 VSS627 SOCKET4677_AZIF0045P001C01CS-SA     I8 @S9S_MB_2U_LIB.S9S_MB_2U(SCH_1):PAGE71
    U1 CB28 VSS628 SOCKET4677_AZIF0045P001C01CS-SA     I8 @S9S_MB_2U_LIB.S9S_MB_2U(SCH_1):PAGE71
    U1 CB32 VSS629 SOCKET4677_AZIF0045P001C01CS-SA     I8 @S9S_MB_2U_LIB.S9S_MB_2U(SCH_1):PAGE71
    U1 CB34 VSS630 SOCKET4677_AZIF0045P001C01CS-SA     I8 @S9S_MB_2U_LIB.S9S_MB_2U(SCH_1):PAGE71
    U1 CB36 VSS631 SOCKET4677_AZIF0045P001C01CS-SA     I8 @S9S_MB_2U_LIB.S9S_MB_2U(SCH_1):PAGE71
    U1 CB38 VSS632 SOCKET4677_AZIF0045P001C01CS-SA     I8 @S9S_MB_2U_LIB.S9S_MB_2U(SCH_1):PAGE71
    U1  CB4 VSS633 SOCKET4677_AZIF0045P001C01CS-SA     I8 @S9S_MB_2U_LIB.S9S_MB_2U(SCH_1):PAGE71
    U1 CB40 VSS634 SOCKET4677_AZIF0045P001C01CS-SA     I8 @S9S_MB_2U_LIB.S9S_MB_2U(SCH_1):PAGE71
    U1 CB42 VSS635 SOCKET4677_AZIF0045P001C01CS-SA     I8 @S9S_MB_2U_LIB.S9S_MB_2U(SCH_1):PAGE71
    U1 CB44 VSS636 SOCKET4677_AZIF0045P001C01CS-SA     I8 @S9S_MB_2U_LIB.S9S_MB_2U(SCH_1):PAGE71
    U1 CB47 VSS637 SOCKET4677_AZIF0045P001C01CS-SA     I8 @S9S_MB_2U_LIB.S9S_MB_2U(SCH_1):PAGE71
    U1 CB49 VSS638 SOCKET4677_AZIF0045P001C01CS-SA     I8 @S9S_MB_2U_LIB.S9S_MB_2U(SCH_1):PAGE71
    U1 CB51 VSS639 SOCKET4677_AZIF0045P001C01CS-SA     I8 @S9S_MB_2U_LIB.S9S_MB_2U(SCH_1):PAGE71
    U1 CB53 VSS640 SOCKET4677_AZIF0045P001C01CS-SA     I8 @S9S_MB_2U_LIB.S9S_MB_2U(SCH_1):PAGE71
    U1 CB55 VSS641 SOCKET4677_AZIF0045P001C01CS-SA     I8 @S9S_MB_2U_LIB.S9S_MB_2U(SCH_1):PAGE71
    U1 CB57 VSS642 SOCKET4677_AZIF0045P001C01CS-SA     I8 @S9S_MB_2U_LIB.S9S_MB_2U(SCH_1):PAGE71
    U1 CB59 VSS643 SOCKET4677_AZIF0045P001C01CS-SA     I8 @S9S_MB_2U_LIB.S9S_MB_2U(SCH_1):PAGE71
    U1 CB63 VSS644 SOCKET4677_AZIF0045P001C01CS-SA     I8 @S9S_MB_2U_LIB.S9S_MB_2U(SCH_1):PAGE71
    U1 CB65 VSS645 SOCKET4677_AZIF0045P001C01CS-SA     I8 @S9S_MB_2U_LIB.S9S_MB_2U(SCH_1):PAGE71
    U1 CB67 VSS646 SOCKET4677_AZIF0045P001C01CS-SA     I8 @S9S_MB_2U_LIB.S9S_MB_2U(SCH_1):PAGE71
    U1 CB69 VSS647 SOCKET4677_AZIF0045P001C01CS-SA     I8 @S9S_MB_2U_LIB.S9S_MB_2U(SCH_1):PAGE71
    U1 CB71 VSS648 SOCKET4677_AZIF0045P001C01CS-SA     I8 @S9S_MB_2U_LIB.S9S_MB_2U(SCH_1):PAGE71
    U1 CB73 VSS649 SOCKET4677_AZIF0045P001C01CS-SA     I8 @S9S_MB_2U_LIB.S9S_MB_2U(SCH_1):PAGE71
    U1 CB79 VSS650 SOCKET4677_AZIF0045P001C01CS-SA     I8 @S9S_MB_2U_LIB.S9S_MB_2U(SCH_1):PAGE71
    U1  CB8 VSS651 SOCKET4677_AZIF0045P001C01CS-SA     I8 @S9S_MB_2U_LIB.S9S_MB_2U(SCH_1):PAGE71
    U1 CB81 VSS652 SOCKET4677_AZIF0045P001C01CS-SA     I8 @S9S_MB_2U_LIB.S9S_MB_2U(SCH_1):PAGE71
    U1 CB83 VSS653 SOCKET4677_AZIF0045P001C01CS-SA     I8 @S9S_MB_2U_LIB.S9S_MB_2U(SCH_1):PAGE71
    U1 CB85 VSS654 SOCKET4677_AZIF0045P001C01CS-SA     I8 @S9S_MB_2U_LIB.S9S_MB_2U(SCH_1):PAGE71
    U1 CB87 VSS655 SOCKET4677_AZIF0045P001C01CS-SA     I8 @S9S_MB_2U_LIB.S9S_MB_2U(SCH_1):PAGE71
    U1 CB89 VSS656 SOCKET4677_AZIF0045P001C01CS-SA     I8 @S9S_MB_2U_LIB.S9S_MB_2U(SCH_1):PAGE71
    U1 CC13 VSS660 SOCKET4677_AZIF0045P001C01CS-SA     I8 @S9S_MB_2U_LIB.S9S_MB_2U(SCH_1):PAGE71
    U1 CC17 VSS661 SOCKET4677_AZIF0045P001C01CS-SA     I8 @S9S_MB_2U_LIB.S9S_MB_2U(SCH_1):PAGE71
    U1 CC31 VSS664 SOCKET4677_AZIF0045P001C01CS-SA     I8 @S9S_MB_2U_LIB.S9S_MB_2U(SCH_1):PAGE71
    U1  CC5 VSS665 SOCKET4677_AZIF0045P001C01CS-SA     I8 @S9S_MB_2U_LIB.S9S_MB_2U(SCH_1):PAGE71
    U1 CC62 VSS666 SOCKET4677_AZIF0045P001C01CS-SA     I8 @S9S_MB_2U_LIB.S9S_MB_2U(SCH_1):PAGE71
    U1 CC70 VSS667 SOCKET4677_AZIF0045P001C01CS-SA     I8 @S9S_MB_2U_LIB.S9S_MB_2U(SCH_1):PAGE71
    U1 CC72 VSS668 SOCKET4677_AZIF0045P001C01CS-SA     I8 @S9S_MB_2U_LIB.S9S_MB_2U(SCH_1):PAGE71
    U1 CC74 VSS669 SOCKET4677_AZIF0045P001C01CS-SA     I8 @S9S_MB_2U_LIB.S9S_MB_2U(SCH_1):PAGE71
    U1  CC9 VSS670 SOCKET4677_AZIF0045P001C01CS-SA     I8 @S9S_MB_2U_LIB.S9S_MB_2U(SCH_1):PAGE71
    U1 CD12 VSS671 SOCKET4677_AZIF0045P001C01CS-SA     I8 @S9S_MB_2U_LIB.S9S_MB_2U(SCH_1):PAGE71
    U1 CD16 VSS672 SOCKET4677_AZIF0045P001C01CS-SA     I8 @S9S_MB_2U_LIB.S9S_MB_2U(SCH_1):PAGE71
    U1 CD20 VSS673 SOCKET4677_AZIF0045P001C01CS-SA     I8 @S9S_MB_2U_LIB.S9S_MB_2U(SCH_1):PAGE71
    U1  CD4 VSS674 SOCKET4677_AZIF0045P001C01CS-SA     I8 @S9S_MB_2U_LIB.S9S_MB_2U(SCH_1):PAGE71
    U1 CD61 VSS675 SOCKET4677_AZIF0045P001C01CS-SA     I8 @S9S_MB_2U_LIB.S9S_MB_2U(SCH_1):PAGE71
    U1 CD75 VSS676 SOCKET4677_AZIF0045P001C01CS-SA     I8 @S9S_MB_2U_LIB.S9S_MB_2U(SCH_1):PAGE71
    U1 CD77 VSS677 SOCKET4677_AZIF0045P001C01CS-SA     I8 @S9S_MB_2U_LIB.S9S_MB_2U(SCH_1):PAGE71
    U1  CD8 VSS678 SOCKET4677_AZIF0045P001C01CS-SA     I8 @S9S_MB_2U_LIB.S9S_MB_2U(SCH_1):PAGE71
    U1  CE3 VSS680 SOCKET4677_AZIF0045P001C01CS-SA     I8 @S9S_MB_2U_LIB.S9S_MB_2U(SCH_1):PAGE71
    U1 CE60 VSS681 SOCKET4677_AZIF0045P001C01CS-SA     I8 @S9S_MB_2U_LIB.S9S_MB_2U(SCH_1):PAGE71
    U1 CE66 VSS682 SOCKET4677_AZIF0045P001C01CS-SA     I8 @S9S_MB_2U_LIB.S9S_MB_2U(SCH_1):PAGE71
    U1 CE72 VSS683 SOCKET4677_AZIF0045P001C01CS-SA     I8 @S9S_MB_2U_LIB.S9S_MB_2U(SCH_1):PAGE71
    U1 CE76 VSS684 SOCKET4677_AZIF0045P001C01CS-SA     I8 @S9S_MB_2U_LIB.S9S_MB_2U(SCH_1):PAGE71
    U1 CE78 VSS685 SOCKET4677_AZIF0045P001C01CS-SA     I8 @S9S_MB_2U_LIB.S9S_MB_2U(SCH_1):PAGE71
    U1 CF12 VSS686 SOCKET4677_AZIF0045P001C01CS-SA     I8 @S9S_MB_2U_LIB.S9S_MB_2U(SCH_1):PAGE71
    U1 CF16 VSS687 SOCKET4677_AZIF0045P001C01CS-SA     I8 @S9S_MB_2U_LIB.S9S_MB_2U(SCH_1):PAGE71
    U1 CF20 VSS688 SOCKET4677_AZIF0045P001C01CS-SA     I8 @S9S_MB_2U_LIB.S9S_MB_2U(SCH_1):PAGE71
    U1  CF4 VSS689 SOCKET4677_AZIF0045P001C01CS-SA     I8 @S9S_MB_2U_LIB.S9S_MB_2U(SCH_1):PAGE71
    U1 CF69 VSS691 SOCKET4677_AZIF0045P001C01CS-SA     I8 @S9S_MB_2U_LIB.S9S_MB_2U(SCH_1):PAGE71
    U1 CF71 VSS692 SOCKET4677_AZIF0045P001C01CS-SA     I8 @S9S_MB_2U_LIB.S9S_MB_2U(SCH_1):PAGE71
    U1  CF8 VSS693 SOCKET4677_AZIF0045P001C01CS-SA     I8 @S9S_MB_2U_LIB.S9S_MB_2U(SCH_1):PAGE71
    U1  CG1 VSS694 SOCKET4677_AZIF0045P001C01CS-SA     I8 @S9S_MB_2U_LIB.S9S_MB_2U(SCH_1):PAGE71
    U1 CG13 VSS695 SOCKET4677_AZIF0045P001C01CS-SA     I8 @S9S_MB_2U_LIB.S9S_MB_2U(SCH_1):PAGE71
    U1 CG17 VSS696 SOCKET4677_AZIF0045P001C01CS-SA     I8 @S9S_MB_2U_LIB.S9S_MB_2U(SCH_1):PAGE71
    U1 CG21 VSS697 SOCKET4677_AZIF0045P001C01CS-SA     I8 @S9S_MB_2U_LIB.S9S_MB_2U(SCH_1):PAGE71
    U1 CG23 VSS698 SOCKET4677_AZIF0045P001C01CS-SA     I8 @S9S_MB_2U_LIB.S9S_MB_2U(SCH_1):PAGE71
    U1 CG25 VSS701 SOCKET4677_AZIF0045P001C01CS-SA     I8 @S9S_MB_2U_LIB.S9S_MB_2U(SCH_1):PAGE71
    U1  CG5 VSS703 SOCKET4677_AZIF0045P001C01CS-SA     I8 @S9S_MB_2U_LIB.S9S_MB_2U(SCH_1):PAGE71
    U1 CG62 VSS704 SOCKET4677_AZIF0045P001C01CS-SA     I8 @S9S_MB_2U_LIB.S9S_MB_2U(SCH_1):PAGE71
    U1 CG64 VSS706 SOCKET4677_AZIF0045P001C01CS-SA     I8 @S9S_MB_2U_LIB.S9S_MB_2U(SCH_1):PAGE71
    U1 CG70 VSS707 SOCKET4677_AZIF0045P001C01CS-SA     I8 @S9S_MB_2U_LIB.S9S_MB_2U(SCH_1):PAGE71
    U1 CG72 VSS708 SOCKET4677_AZIF0045P001C01CS-SA     I8 @S9S_MB_2U_LIB.S9S_MB_2U(SCH_1):PAGE71
    U1 CG74 VSS710 SOCKET4677_AZIF0045P001C01CS-SA     I8 @S9S_MB_2U_LIB.S9S_MB_2U(SCH_1):PAGE71
    U1 CG78 VSS713 SOCKET4677_AZIF0045P001C01CS-SA     I8 @S9S_MB_2U_LIB.S9S_MB_2U(SCH_1):PAGE71
    U1  CG9 VSS716 SOCKET4677_AZIF0045P001C01CS-SA     I8 @S9S_MB_2U_LIB.S9S_MB_2U(SCH_1):PAGE71
    U1 CH12 VSS718 SOCKET4677_AZIF0045P001C01CS-SA     I8 @S9S_MB_2U_LIB.S9S_MB_2U(SCH_1):PAGE71
    U1 CH16 VSS720 SOCKET4677_AZIF0045P001C01CS-SA     I8 @S9S_MB_2U_LIB.S9S_MB_2U(SCH_1):PAGE71
    U1 CH20 VSS721 SOCKET4677_AZIF0045P001C01CS-SA     I8 @S9S_MB_2U_LIB.S9S_MB_2U(SCH_1):PAGE71
    U1  CH4 VSS722 SOCKET4677_AZIF0045P001C01CS-SA     I8 @S9S_MB_2U_LIB.S9S_MB_2U(SCH_1):PAGE71
    U1 CH67 VSS727 SOCKET4677_AZIF0045P001C01CS-SA     I8 @S9S_MB_2U_LIB.S9S_MB_2U(SCH_1):PAGE71
    U1 CH73 VSS728 SOCKET4677_AZIF0045P001C01CS-SA     I8 @S9S_MB_2U_LIB.S9S_MB_2U(SCH_1):PAGE71
    U1 CH79 VSS729 SOCKET4677_AZIF0045P001C01CS-SA     I8 @S9S_MB_2U_LIB.S9S_MB_2U(SCH_1):PAGE71
    U1  CH8 VSS730 SOCKET4677_AZIF0045P001C01CS-SA     I8 @S9S_MB_2U_LIB.S9S_MB_2U(SCH_1):PAGE71
    U1 CH83 VSS731 SOCKET4677_AZIF0045P001C01CS-SA     I8 @S9S_MB_2U_LIB.S9S_MB_2U(SCH_1):PAGE71
    U1 CH85 VSS732 SOCKET4677_AZIF0045P001C01CS-SA     I8 @S9S_MB_2U_LIB.S9S_MB_2U(SCH_1):PAGE71
    U1 CH87 VSS733 SOCKET4677_AZIF0045P001C01CS-SA     I8 @S9S_MB_2U_LIB.S9S_MB_2U(SCH_1):PAGE71
    U1 CH89 VSS734 SOCKET4677_AZIF0045P001C01CS-SA     I8 @S9S_MB_2U_LIB.S9S_MB_2U(SCH_1):PAGE71
    U1 CJ60 VSS736 SOCKET4677_AZIF0045P001C01CS-SA     I8 @S9S_MB_2U_LIB.S9S_MB_2U(SCH_1):PAGE71
    U1 CJ80 VSS737 SOCKET4677_AZIF0045P001C01CS-SA     I8 @S9S_MB_2U_LIB.S9S_MB_2U(SCH_1):PAGE71
    U1 CK12 VSS740 SOCKET4677_AZIF0045P001C01CS-SA     I8 @S9S_MB_2U_LIB.S9S_MB_2U(SCH_1):PAGE71
    U1 CK16 VSS741 SOCKET4677_AZIF0045P001C01CS-SA     I8 @S9S_MB_2U_LIB.S9S_MB_2U(SCH_1):PAGE71
    U1 CK20 VSS742 SOCKET4677_AZIF0045P001C01CS-SA     I8 @S9S_MB_2U_LIB.S9S_MB_2U(SCH_1):PAGE71
    U1 CK26 VSS743 SOCKET4677_AZIF0045P001C01CS-SA     I8 @S9S_MB_2U_LIB.S9S_MB_2U(SCH_1):PAGE71
    U1  CK8 VSS746 SOCKET4677_AZIF0045P001C01CS-SA     I8 @S9S_MB_2U_LIB.S9S_MB_2U(SCH_1):PAGE71
    U1  BR5   VSS0 SOCKET4677_AZIF0045P001C01CS-SA     I2 @S9S_MB_2U_LIB.S9S_MB_2U(SCH_1):PAGE72
    U1 AW21 VSS356 SOCKET4677_AZIF0045P001C01CS-SA     I2 @S9S_MB_2U_LIB.S9S_MB_2U(SCH_1):PAGE72
    U1 AW23 VSS357 SOCKET4677_AZIF0045P001C01CS-SA     I2 @S9S_MB_2U_LIB.S9S_MB_2U(SCH_1):PAGE72
    U1 AW25 VSS358 SOCKET4677_AZIF0045P001C01CS-SA     I2 @S9S_MB_2U_LIB.S9S_MB_2U(SCH_1):PAGE72
    U1 AW62 VSS360 SOCKET4677_AZIF0045P001C01CS-SA     I2 @S9S_MB_2U_LIB.S9S_MB_2U(SCH_1):PAGE72
    U1 AW66 VSS361 SOCKET4677_AZIF0045P001C01CS-SA     I2 @S9S_MB_2U_LIB.S9S_MB_2U(SCH_1):PAGE72
    U1 AW68 VSS362 SOCKET4677_AZIF0045P001C01CS-SA     I2 @S9S_MB_2U_LIB.S9S_MB_2U(SCH_1):PAGE72
    U1 AW72 VSS363 SOCKET4677_AZIF0045P001C01CS-SA     I2 @S9S_MB_2U_LIB.S9S_MB_2U(SCH_1):PAGE72
    U1 AW80 VSS364 SOCKET4677_AZIF0045P001C01CS-SA     I2 @S9S_MB_2U_LIB.S9S_MB_2U(SCH_1):PAGE72
    U1 AW82 VSS365 SOCKET4677_AZIF0045P001C01CS-SA     I2 @S9S_MB_2U_LIB.S9S_MB_2U(SCH_1):PAGE72
    U1 AW84 VSS366 SOCKET4677_AZIF0045P001C01CS-SA     I2 @S9S_MB_2U_LIB.S9S_MB_2U(SCH_1):PAGE72
    U1 AW88 VSS367 SOCKET4677_AZIF0045P001C01CS-SA     I2 @S9S_MB_2U_LIB.S9S_MB_2U(SCH_1):PAGE72
    U1 AY12 VSS369 SOCKET4677_AZIF0045P001C01CS-SA     I2 @S9S_MB_2U_LIB.S9S_MB_2U(SCH_1):PAGE72
    U1 AY16 VSS370 SOCKET4677_AZIF0045P001C01CS-SA     I2 @S9S_MB_2U_LIB.S9S_MB_2U(SCH_1):PAGE72
    U1  AY4 VSS371 SOCKET4677_AZIF0045P001C01CS-SA     I2 @S9S_MB_2U_LIB.S9S_MB_2U(SCH_1):PAGE72
    U1 AY71 VSS372 SOCKET4677_AZIF0045P001C01CS-SA     I2 @S9S_MB_2U_LIB.S9S_MB_2U(SCH_1):PAGE72
    U1 AY77 VSS373 SOCKET4677_AZIF0045P001C01CS-SA     I2 @S9S_MB_2U_LIB.S9S_MB_2U(SCH_1):PAGE72
    U1 AY79 VSS374 SOCKET4677_AZIF0045P001C01CS-SA     I2 @S9S_MB_2U_LIB.S9S_MB_2U(SCH_1):PAGE72
    U1  AY8 VSS375 SOCKET4677_AZIF0045P001C01CS-SA     I2 @S9S_MB_2U_LIB.S9S_MB_2U(SCH_1):PAGE72
    U1 AY81 VSS376 SOCKET4677_AZIF0045P001C01CS-SA     I2 @S9S_MB_2U_LIB.S9S_MB_2U(SCH_1):PAGE72
    U1 AY83 VSS377 SOCKET4677_AZIF0045P001C01CS-SA     I2 @S9S_MB_2U_LIB.S9S_MB_2U(SCH_1):PAGE72
    U1 BA17 VSS393 SOCKET4677_AZIF0045P001C01CS-SA     I2 @S9S_MB_2U_LIB.S9S_MB_2U(SCH_1):PAGE72
    U1 BA60 VSS394 SOCKET4677_AZIF0045P001C01CS-SA     I2 @S9S_MB_2U_LIB.S9S_MB_2U(SCH_1):PAGE72
    U1 BA64 VSS395 SOCKET4677_AZIF0045P001C01CS-SA     I2 @S9S_MB_2U_LIB.S9S_MB_2U(SCH_1):PAGE72
    U1 BA74 VSS397 SOCKET4677_AZIF0045P001C01CS-SA     I2 @S9S_MB_2U_LIB.S9S_MB_2U(SCH_1):PAGE72
    U1 BA84 VSS398 SOCKET4677_AZIF0045P001C01CS-SA     I2 @S9S_MB_2U_LIB.S9S_MB_2U(SCH_1):PAGE72
    U1 BA88 VSS399 SOCKET4677_AZIF0045P001C01CS-SA     I2 @S9S_MB_2U_LIB.S9S_MB_2U(SCH_1):PAGE72
    U1 BB10 VSS400 SOCKET4677_AZIF0045P001C01CS-SA     I2 @S9S_MB_2U_LIB.S9S_MB_2U(SCH_1):PAGE72
    U1 BB12 VSS401 SOCKET4677_AZIF0045P001C01CS-SA     I2 @S9S_MB_2U_LIB.S9S_MB_2U(SCH_1):PAGE72
    U1 BB16 VSS402 SOCKET4677_AZIF0045P001C01CS-SA     I2 @S9S_MB_2U_LIB.S9S_MB_2U(SCH_1):PAGE72
    U1 BB20 VSS403 SOCKET4677_AZIF0045P001C01CS-SA     I2 @S9S_MB_2U_LIB.S9S_MB_2U(SCH_1):PAGE72
    U1 BB22 VSS404 SOCKET4677_AZIF0045P001C01CS-SA     I2 @S9S_MB_2U_LIB.S9S_MB_2U(SCH_1):PAGE72
    U1 BB24 VSS405 SOCKET4677_AZIF0045P001C01CS-SA     I2 @S9S_MB_2U_LIB.S9S_MB_2U(SCH_1):PAGE72
    U1 BB26 VSS406 SOCKET4677_AZIF0045P001C01CS-SA     I2 @S9S_MB_2U_LIB.S9S_MB_2U(SCH_1):PAGE72
    U1  BB4 VSS407 SOCKET4677_AZIF0045P001C01CS-SA     I2 @S9S_MB_2U_LIB.S9S_MB_2U(SCH_1):PAGE72
    U1 BB63 VSS408 SOCKET4677_AZIF0045P001C01CS-SA     I2 @S9S_MB_2U_LIB.S9S_MB_2U(SCH_1):PAGE72
    U1 BB69 VSS409 SOCKET4677_AZIF0045P001C01CS-SA     I2 @S9S_MB_2U_LIB.S9S_MB_2U(SCH_1):PAGE72
    U1 BB71 VSS410 SOCKET4677_AZIF0045P001C01CS-SA     I2 @S9S_MB_2U_LIB.S9S_MB_2U(SCH_1):PAGE72
    U1 BB77 VSS411 SOCKET4677_AZIF0045P001C01CS-SA     I2 @S9S_MB_2U_LIB.S9S_MB_2U(SCH_1):PAGE72
    U1 BB79 VSS412 SOCKET4677_AZIF0045P001C01CS-SA     I2 @S9S_MB_2U_LIB.S9S_MB_2U(SCH_1):PAGE72
    U1  BB8 VSS413 SOCKET4677_AZIF0045P001C01CS-SA     I2 @S9S_MB_2U_LIB.S9S_MB_2U(SCH_1):PAGE72
    U1 BB83 VSS414 SOCKET4677_AZIF0045P001C01CS-SA     I2 @S9S_MB_2U_LIB.S9S_MB_2U(SCH_1):PAGE72
    U1 BB87 VSS415 SOCKET4677_AZIF0045P001C01CS-SA     I2 @S9S_MB_2U_LIB.S9S_MB_2U(SCH_1):PAGE72
    U1 BB91 VSS416 SOCKET4677_AZIF0045P001C01CS-SA     I2 @S9S_MB_2U_LIB.S9S_MB_2U(SCH_1):PAGE72
    U1  BC1 VSS417 SOCKET4677_AZIF0045P001C01CS-SA     I2 @S9S_MB_2U_LIB.S9S_MB_2U(SCH_1):PAGE72
    U1 BC13 VSS418 SOCKET4677_AZIF0045P001C01CS-SA     I2 @S9S_MB_2U_LIB.S9S_MB_2U(SCH_1):PAGE72
    U1 BC17 VSS419 SOCKET4677_AZIF0045P001C01CS-SA     I2 @S9S_MB_2U_LIB.S9S_MB_2U(SCH_1):PAGE72
    U1  BC5 VSS420 SOCKET4677_AZIF0045P001C01CS-SA     I2 @S9S_MB_2U_LIB.S9S_MB_2U(SCH_1):PAGE72
    U1 BC62 VSS421 SOCKET4677_AZIF0045P001C01CS-SA     I2 @S9S_MB_2U_LIB.S9S_MB_2U(SCH_1):PAGE72
    U1 BC66 VSS422 SOCKET4677_AZIF0045P001C01CS-SA     I2 @S9S_MB_2U_LIB.S9S_MB_2U(SCH_1):PAGE72
    U1 BC72 VSS423 SOCKET4677_AZIF0045P001C01CS-SA     I2 @S9S_MB_2U_LIB.S9S_MB_2U(SCH_1):PAGE72
    U1 BC76 VSS424 SOCKET4677_AZIF0045P001C01CS-SA     I2 @S9S_MB_2U_LIB.S9S_MB_2U(SCH_1):PAGE72
    U1 BC78 VSS425 SOCKET4677_AZIF0045P001C01CS-SA     I2 @S9S_MB_2U_LIB.S9S_MB_2U(SCH_1):PAGE72
    U1 BC84 VSS426 SOCKET4677_AZIF0045P001C01CS-SA     I2 @S9S_MB_2U_LIB.S9S_MB_2U(SCH_1):PAGE72
    U1 BC86 VSS427 SOCKET4677_AZIF0045P001C01CS-SA     I2 @S9S_MB_2U_LIB.S9S_MB_2U(SCH_1):PAGE72
    U1 BC88 VSS428 SOCKET4677_AZIF0045P001C01CS-SA     I2 @S9S_MB_2U_LIB.S9S_MB_2U(SCH_1):PAGE72
    U1  BC9 VSS429 SOCKET4677_AZIF0045P001C01CS-SA     I2 @S9S_MB_2U_LIB.S9S_MB_2U(SCH_1):PAGE72
    U1 BD12 VSS430 SOCKET4677_AZIF0045P001C01CS-SA     I2 @S9S_MB_2U_LIB.S9S_MB_2U(SCH_1):PAGE72
    U1 BD16 VSS431 SOCKET4677_AZIF0045P001C01CS-SA     I2 @S9S_MB_2U_LIB.S9S_MB_2U(SCH_1):PAGE72
    U1 BD20 VSS432 SOCKET4677_AZIF0045P001C01CS-SA     I2 @S9S_MB_2U_LIB.S9S_MB_2U(SCH_1):PAGE72
    U1  BD4 VSS433 SOCKET4677_AZIF0045P001C01CS-SA     I2 @S9S_MB_2U_LIB.S9S_MB_2U(SCH_1):PAGE72
    U1  BD8 VSS434 SOCKET4677_AZIF0045P001C01CS-SA     I2 @S9S_MB_2U_LIB.S9S_MB_2U(SCH_1):PAGE72
    U1 BD81 VSS435 SOCKET4677_AZIF0045P001C01CS-SA     I2 @S9S_MB_2U_LIB.S9S_MB_2U(SCH_1):PAGE72
    U1 BD85 VSS437 SOCKET4677_AZIF0045P001C01CS-SA     I2 @S9S_MB_2U_LIB.S9S_MB_2U(SCH_1):PAGE72
    U1 BD89 VSS439 SOCKET4677_AZIF0045P001C01CS-SA     I2 @S9S_MB_2U_LIB.S9S_MB_2U(SCH_1):PAGE72
    U1 BE64 VSS440 SOCKET4677_AZIF0045P001C01CS-SA     I2 @S9S_MB_2U_LIB.S9S_MB_2U(SCH_1):PAGE72
    U1 BE66 VSS441 SOCKET4677_AZIF0045P001C01CS-SA     I2 @S9S_MB_2U_LIB.S9S_MB_2U(SCH_1):PAGE72
    U1 BE68 VSS442 SOCKET4677_AZIF0045P001C01CS-SA     I2 @S9S_MB_2U_LIB.S9S_MB_2U(SCH_1):PAGE72
    U1 BE74 VSS443 SOCKET4677_AZIF0045P001C01CS-SA     I2 @S9S_MB_2U_LIB.S9S_MB_2U(SCH_1):PAGE72
    U1 BE76 VSS444 SOCKET4677_AZIF0045P001C01CS-SA     I2 @S9S_MB_2U_LIB.S9S_MB_2U(SCH_1):PAGE72
    U1 BE78 VSS445 SOCKET4677_AZIF0045P001C01CS-SA     I2 @S9S_MB_2U_LIB.S9S_MB_2U(SCH_1):PAGE72
    U1 BE84 VSS446 SOCKET4677_AZIF0045P001C01CS-SA     I2 @S9S_MB_2U_LIB.S9S_MB_2U(SCH_1):PAGE72
    U1 BF12 VSS447 SOCKET4677_AZIF0045P001C01CS-SA     I2 @S9S_MB_2U_LIB.S9S_MB_2U(SCH_1):PAGE72
    U1 BF16 VSS448 SOCKET4677_AZIF0045P001C01CS-SA     I2 @S9S_MB_2U_LIB.S9S_MB_2U(SCH_1):PAGE72
    U1 BF20 VSS449 SOCKET4677_AZIF0045P001C01CS-SA     I2 @S9S_MB_2U_LIB.S9S_MB_2U(SCH_1):PAGE72
    U1  BF4 VSS450 SOCKET4677_AZIF0045P001C01CS-SA     I2 @S9S_MB_2U_LIB.S9S_MB_2U(SCH_1):PAGE72
    U1 BF61 VSS451 SOCKET4677_AZIF0045P001C01CS-SA     I2 @S9S_MB_2U_LIB.S9S_MB_2U(SCH_1):PAGE72
    U1 BF63 VSS452 SOCKET4677_AZIF0045P001C01CS-SA     I2 @S9S_MB_2U_LIB.S9S_MB_2U(SCH_1):PAGE72
    U1 BF73 VSS453 SOCKET4677_AZIF0045P001C01CS-SA     I2 @S9S_MB_2U_LIB.S9S_MB_2U(SCH_1):PAGE72
    U1 BF75 VSS454 SOCKET4677_AZIF0045P001C01CS-SA     I2 @S9S_MB_2U_LIB.S9S_MB_2U(SCH_1):PAGE72
    U1 BF79 VSS455 SOCKET4677_AZIF0045P001C01CS-SA     I2 @S9S_MB_2U_LIB.S9S_MB_2U(SCH_1):PAGE72
    U1  BF8 VSS456 SOCKET4677_AZIF0045P001C01CS-SA     I2 @S9S_MB_2U_LIB.S9S_MB_2U(SCH_1):PAGE72
    U1 BF83 VSS457 SOCKET4677_AZIF0045P001C01CS-SA     I2 @S9S_MB_2U_LIB.S9S_MB_2U(SCH_1):PAGE72
    U1  BG1 VSS458 SOCKET4677_AZIF0045P001C01CS-SA     I2 @S9S_MB_2U_LIB.S9S_MB_2U(SCH_1):PAGE72
    U1 BG13 VSS459 SOCKET4677_AZIF0045P001C01CS-SA     I2 @S9S_MB_2U_LIB.S9S_MB_2U(SCH_1):PAGE72
    U1 BG17 VSS460 SOCKET4677_AZIF0045P001C01CS-SA     I2 @S9S_MB_2U_LIB.S9S_MB_2U(SCH_1):PAGE72
    U1 BG21 VSS461 SOCKET4677_AZIF0045P001C01CS-SA     I2 @S9S_MB_2U_LIB.S9S_MB_2U(SCH_1):PAGE72
    U1 BG23 VSS462 SOCKET4677_AZIF0045P001C01CS-SA     I2 @S9S_MB_2U_LIB.S9S_MB_2U(SCH_1):PAGE72
    U1 BG25 VSS463 SOCKET4677_AZIF0045P001C01CS-SA     I2 @S9S_MB_2U_LIB.S9S_MB_2U(SCH_1):PAGE72
    U1  BG5 VSS464 SOCKET4677_AZIF0045P001C01CS-SA     I2 @S9S_MB_2U_LIB.S9S_MB_2U(SCH_1):PAGE72
    U1 BG70 VSS465 SOCKET4677_AZIF0045P001C01CS-SA     I2 @S9S_MB_2U_LIB.S9S_MB_2U(SCH_1):PAGE72
    U1  BG9 VSS466 SOCKET4677_AZIF0045P001C01CS-SA     I2 @S9S_MB_2U_LIB.S9S_MB_2U(SCH_1):PAGE72
    U1 BH12 VSS467 SOCKET4677_AZIF0045P001C01CS-SA     I2 @S9S_MB_2U_LIB.S9S_MB_2U(SCH_1):PAGE72
    U1 BH16 VSS468 SOCKET4677_AZIF0045P001C01CS-SA     I2 @S9S_MB_2U_LIB.S9S_MB_2U(SCH_1):PAGE72
    U1 BH20 VSS469 SOCKET4677_AZIF0045P001C01CS-SA     I2 @S9S_MB_2U_LIB.S9S_MB_2U(SCH_1):PAGE72
    U1  BH4 VSS470 SOCKET4677_AZIF0045P001C01CS-SA     I2 @S9S_MB_2U_LIB.S9S_MB_2U(SCH_1):PAGE72
    U1 BH67 VSS472 SOCKET4677_AZIF0045P001C01CS-SA     I2 @S9S_MB_2U_LIB.S9S_MB_2U(SCH_1):PAGE72
    U1 BH73 VSS473 SOCKET4677_AZIF0045P001C01CS-SA     I2 @S9S_MB_2U_LIB.S9S_MB_2U(SCH_1):PAGE72
    U1 BH77 VSS474 SOCKET4677_AZIF0045P001C01CS-SA     I2 @S9S_MB_2U_LIB.S9S_MB_2U(SCH_1):PAGE72
    U1  BH8 VSS475 SOCKET4677_AZIF0045P001C01CS-SA     I2 @S9S_MB_2U_LIB.S9S_MB_2U(SCH_1):PAGE72
    U1 BH81 VSS476 SOCKET4677_AZIF0045P001C01CS-SA     I2 @S9S_MB_2U_LIB.S9S_MB_2U(SCH_1):PAGE72
    U1 BH83 VSS477 SOCKET4677_AZIF0045P001C01CS-SA     I2 @S9S_MB_2U_LIB.S9S_MB_2U(SCH_1):PAGE72
    U1 BJ62 VSS479 SOCKET4677_AZIF0045P001C01CS-SA     I2 @S9S_MB_2U_LIB.S9S_MB_2U(SCH_1):PAGE72
    U1 BJ68 VSS480 SOCKET4677_AZIF0045P001C01CS-SA     I2 @S9S_MB_2U_LIB.S9S_MB_2U(SCH_1):PAGE72
    U1 BJ80 VSS481 SOCKET4677_AZIF0045P001C01CS-SA     I2 @S9S_MB_2U_LIB.S9S_MB_2U(SCH_1):PAGE72
    U1 BJ82 VSS482 SOCKET4677_AZIF0045P001C01CS-SA     I2 @S9S_MB_2U_LIB.S9S_MB_2U(SCH_1):PAGE72
    U1 BJ84 VSS483 SOCKET4677_AZIF0045P001C01CS-SA     I2 @S9S_MB_2U_LIB.S9S_MB_2U(SCH_1):PAGE72
    U1 BJ86 VSS484 SOCKET4677_AZIF0045P001C01CS-SA     I2 @S9S_MB_2U_LIB.S9S_MB_2U(SCH_1):PAGE72
    U1 BJ88 VSS485 SOCKET4677_AZIF0045P001C01CS-SA     I2 @S9S_MB_2U_LIB.S9S_MB_2U(SCH_1):PAGE72
    U1 BJ90 VSS486 SOCKET4677_AZIF0045P001C01CS-SA     I2 @S9S_MB_2U_LIB.S9S_MB_2U(SCH_1):PAGE72
    U1 BK12 VSS487 SOCKET4677_AZIF0045P001C01CS-SA     I2 @S9S_MB_2U_LIB.S9S_MB_2U(SCH_1):PAGE72
    U1 BK16 VSS488 SOCKET4677_AZIF0045P001C01CS-SA     I2 @S9S_MB_2U_LIB.S9S_MB_2U(SCH_1):PAGE72
    U1 BK20 VSS489 SOCKET4677_AZIF0045P001C01CS-SA     I2 @S9S_MB_2U_LIB.S9S_MB_2U(SCH_1):PAGE72
    U1  BK4 VSS490 SOCKET4677_AZIF0045P001C01CS-SA     I2 @S9S_MB_2U_LIB.S9S_MB_2U(SCH_1):PAGE72
    U1 BK65 VSS491 SOCKET4677_AZIF0045P001C01CS-SA     I2 @S9S_MB_2U_LIB.S9S_MB_2U(SCH_1):PAGE72
    U1 BK71 VSS492 SOCKET4677_AZIF0045P001C01CS-SA     I2 @S9S_MB_2U_LIB.S9S_MB_2U(SCH_1):PAGE72
    U1 BK75 VSS494 SOCKET4677_AZIF0045P001C01CS-SA     I2 @S9S_MB_2U_LIB.S9S_MB_2U(SCH_1):PAGE72
    U1 BK79 VSS495 SOCKET4677_AZIF0045P001C01CS-SA     I2 @S9S_MB_2U_LIB.S9S_MB_2U(SCH_1):PAGE72
    U1  BK8 VSS496 SOCKET4677_AZIF0045P001C01CS-SA     I2 @S9S_MB_2U_LIB.S9S_MB_2U(SCH_1):PAGE72
    U1  BL1 VSS497 SOCKET4677_AZIF0045P001C01CS-SA     I2 @S9S_MB_2U_LIB.S9S_MB_2U(SCH_1):PAGE72
    U1 BL13 VSS498 SOCKET4677_AZIF0045P001C01CS-SA     I2 @S9S_MB_2U_LIB.S9S_MB_2U(SCH_1):PAGE72
    U1 BL17 VSS499 SOCKET4677_AZIF0045P001C01CS-SA     I2 @S9S_MB_2U_LIB.S9S_MB_2U(SCH_1):PAGE72
    U1  BL5 VSS500 SOCKET4677_AZIF0045P001C01CS-SA     I2 @S9S_MB_2U_LIB.S9S_MB_2U(SCH_1):PAGE72
    U1 BL68 VSS501 SOCKET4677_AZIF0045P001C01CS-SA     I2 @S9S_MB_2U_LIB.S9S_MB_2U(SCH_1):PAGE72
    U1 BL70 VSS502 SOCKET4677_AZIF0045P001C01CS-SA     I2 @S9S_MB_2U_LIB.S9S_MB_2U(SCH_1):PAGE72
    U1 BL72 VSS503 SOCKET4677_AZIF0045P001C01CS-SA     I2 @S9S_MB_2U_LIB.S9S_MB_2U(SCH_1):PAGE72
    U1 BL78 VSS504 SOCKET4677_AZIF0045P001C01CS-SA     I2 @S9S_MB_2U_LIB.S9S_MB_2U(SCH_1):PAGE72
    U1  BL9 VSS505 SOCKET4677_AZIF0045P001C01CS-SA     I2 @S9S_MB_2U_LIB.S9S_MB_2U(SCH_1):PAGE72
    U1 BM12 VSS506 SOCKET4677_AZIF0045P001C01CS-SA     I2 @S9S_MB_2U_LIB.S9S_MB_2U(SCH_1):PAGE72
    U1 BM16 VSS507 SOCKET4677_AZIF0045P001C01CS-SA     I2 @S9S_MB_2U_LIB.S9S_MB_2U(SCH_1):PAGE72
    U1 BM20 VSS508 SOCKET4677_AZIF0045P001C01CS-SA     I2 @S9S_MB_2U_LIB.S9S_MB_2U(SCH_1):PAGE72
    U1 BM22 VSS509 SOCKET4677_AZIF0045P001C01CS-SA     I2 @S9S_MB_2U_LIB.S9S_MB_2U(SCH_1):PAGE72
    U1 BM24 VSS510 SOCKET4677_AZIF0045P001C01CS-SA     I2 @S9S_MB_2U_LIB.S9S_MB_2U(SCH_1):PAGE72
    U1 BM26 VSS511 SOCKET4677_AZIF0045P001C01CS-SA     I2 @S9S_MB_2U_LIB.S9S_MB_2U(SCH_1):PAGE72
    U1  BM4 VSS512 SOCKET4677_AZIF0045P001C01CS-SA     I2 @S9S_MB_2U_LIB.S9S_MB_2U(SCH_1):PAGE72
    U1 BM61 VSS513 SOCKET4677_AZIF0045P001C01CS-SA     I2 @S9S_MB_2U_LIB.S9S_MB_2U(SCH_1):PAGE72
    U1 BM73 VSS515 SOCKET4677_AZIF0045P001C01CS-SA     I2 @S9S_MB_2U_LIB.S9S_MB_2U(SCH_1):PAGE72
    U1 BM77 VSS516 SOCKET4677_AZIF0045P001C01CS-SA     I2 @S9S_MB_2U_LIB.S9S_MB_2U(SCH_1):PAGE72
    U1  BM8 VSS517 SOCKET4677_AZIF0045P001C01CS-SA     I2 @S9S_MB_2U_LIB.S9S_MB_2U(SCH_1):PAGE72
    U1 BN31 VSS518 SOCKET4677_AZIF0045P001C01CS-SA     I2 @S9S_MB_2U_LIB.S9S_MB_2U(SCH_1):PAGE72
    U1 BN62 VSS519 SOCKET4677_AZIF0045P001C01CS-SA     I2 @S9S_MB_2U_LIB.S9S_MB_2U(SCH_1):PAGE72
    U1 BN70 VSS520 SOCKET4677_AZIF0045P001C01CS-SA     I2 @S9S_MB_2U_LIB.S9S_MB_2U(SCH_1):PAGE72
    U1 BP12 VSS522 SOCKET4677_AZIF0045P001C01CS-SA     I2 @S9S_MB_2U_LIB.S9S_MB_2U(SCH_1):PAGE72
    U1 BP16 VSS523 SOCKET4677_AZIF0045P001C01CS-SA     I2 @S9S_MB_2U_LIB.S9S_MB_2U(SCH_1):PAGE72
    U1  BP2 VSS524 SOCKET4677_AZIF0045P001C01CS-SA     I2 @S9S_MB_2U_LIB.S9S_MB_2U(SCH_1):PAGE72
    U1 BP20 VSS525 SOCKET4677_AZIF0045P001C01CS-SA     I2 @S9S_MB_2U_LIB.S9S_MB_2U(SCH_1):PAGE72
    U1  BP4 VSS527 SOCKET4677_AZIF0045P001C01CS-SA     I2 @S9S_MB_2U_LIB.S9S_MB_2U(SCH_1):PAGE72
    U1 BP63 VSS528 SOCKET4677_AZIF0045P001C01CS-SA     I2 @S9S_MB_2U_LIB.S9S_MB_2U(SCH_1):PAGE72
    U1 BP71 VSS529 SOCKET4677_AZIF0045P001C01CS-SA     I2 @S9S_MB_2U_LIB.S9S_MB_2U(SCH_1):PAGE72
    U1 BP73 VSS530 SOCKET4677_AZIF0045P001C01CS-SA     I2 @S9S_MB_2U_LIB.S9S_MB_2U(SCH_1):PAGE72
    U1 BP75 VSS531 SOCKET4677_AZIF0045P001C01CS-SA     I2 @S9S_MB_2U_LIB.S9S_MB_2U(SCH_1):PAGE72
    U1 BP77 VSS532 SOCKET4677_AZIF0045P001C01CS-SA     I2 @S9S_MB_2U_LIB.S9S_MB_2U(SCH_1):PAGE72
    U1  BP8 VSS533 SOCKET4677_AZIF0045P001C01CS-SA     I2 @S9S_MB_2U_LIB.S9S_MB_2U(SCH_1):PAGE72
    U1 BR13 VSS535 SOCKET4677_AZIF0045P001C01CS-SA     I2 @S9S_MB_2U_LIB.S9S_MB_2U(SCH_1):PAGE72
    U1 BR17 VSS536 SOCKET4677_AZIF0045P001C01CS-SA     I2 @S9S_MB_2U_LIB.S9S_MB_2U(SCH_1):PAGE72
    U1 BR27 VSS538 SOCKET4677_AZIF0045P001C01CS-SA     I2 @S9S_MB_2U_LIB.S9S_MB_2U(SCH_1):PAGE72
    U1 BR29 VSS539 SOCKET4677_AZIF0045P001C01CS-SA     I2 @S9S_MB_2U_LIB.S9S_MB_2U(SCH_1):PAGE72
    U1 BR31 VSS540 SOCKET4677_AZIF0045P001C01CS-SA     I2 @S9S_MB_2U_LIB.S9S_MB_2U(SCH_1):PAGE72
    U1 BR33 VSS541 SOCKET4677_AZIF0045P001C01CS-SA     I2 @S9S_MB_2U_LIB.S9S_MB_2U(SCH_1):PAGE72
    U1  BR9 VSS572 SOCKET4677_AZIF0045P001C01CS-SA     I2 @S9S_MB_2U_LIB.S9S_MB_2U(SCH_1):PAGE72
    U1 AK12 VSS198 SOCKET4677_AZIF0045P001C01CS-SA     I5 @S9S_MB_2U_LIB.S9S_MB_2U(SCH_1):PAGE72
    U1 AK16 VSS199 SOCKET4677_AZIF0045P001C01CS-SA     I5 @S9S_MB_2U_LIB.S9S_MB_2U(SCH_1):PAGE72
    U1 AK18 VSS200 SOCKET4677_AZIF0045P001C01CS-SA     I5 @S9S_MB_2U_LIB.S9S_MB_2U(SCH_1):PAGE72
    U1 AK24 VSS201 SOCKET4677_AZIF0045P001C01CS-SA     I5 @S9S_MB_2U_LIB.S9S_MB_2U(SCH_1):PAGE72
    U1 AK30 VSS202 SOCKET4677_AZIF0045P001C01CS-SA     I5 @S9S_MB_2U_LIB.S9S_MB_2U(SCH_1):PAGE72
    U1 AK36 VSS203 SOCKET4677_AZIF0045P001C01CS-SA     I5 @S9S_MB_2U_LIB.S9S_MB_2U(SCH_1):PAGE72
    U1  AK4 VSS204 SOCKET4677_AZIF0045P001C01CS-SA     I5 @S9S_MB_2U_LIB.S9S_MB_2U(SCH_1):PAGE72
    U1 AK42 VSS205 SOCKET4677_AZIF0045P001C01CS-SA     I5 @S9S_MB_2U_LIB.S9S_MB_2U(SCH_1):PAGE72
    U1 AK49 VSS206 SOCKET4677_AZIF0045P001C01CS-SA     I5 @S9S_MB_2U_LIB.S9S_MB_2U(SCH_1):PAGE72
    U1 AK55 VSS207 SOCKET4677_AZIF0045P001C01CS-SA     I5 @S9S_MB_2U_LIB.S9S_MB_2U(SCH_1):PAGE72
    U1 AK61 VSS208 SOCKET4677_AZIF0045P001C01CS-SA     I5 @S9S_MB_2U_LIB.S9S_MB_2U(SCH_1):PAGE72
    U1 AK67 VSS209 SOCKET4677_AZIF0045P001C01CS-SA     I5 @S9S_MB_2U_LIB.S9S_MB_2U(SCH_1):PAGE72
    U1 AK73 VSS210 SOCKET4677_AZIF0045P001C01CS-SA     I5 @S9S_MB_2U_LIB.S9S_MB_2U(SCH_1):PAGE72
    U1 AK79 VSS211 SOCKET4677_AZIF0045P001C01CS-SA     I5 @S9S_MB_2U_LIB.S9S_MB_2U(SCH_1):PAGE72
    U1  AK8 VSS212 SOCKET4677_AZIF0045P001C01CS-SA     I5 @S9S_MB_2U_LIB.S9S_MB_2U(SCH_1):PAGE72
    U1 AK81 VSS213 SOCKET4677_AZIF0045P001C01CS-SA     I5 @S9S_MB_2U_LIB.S9S_MB_2U(SCH_1):PAGE72
    U1 AK83 VSS214 SOCKET4677_AZIF0045P001C01CS-SA     I5 @S9S_MB_2U_LIB.S9S_MB_2U(SCH_1):PAGE72
    U1 AK87 VSS215 SOCKET4677_AZIF0045P001C01CS-SA     I5 @S9S_MB_2U_LIB.S9S_MB_2U(SCH_1):PAGE72
    U1 AK91 VSS216 SOCKET4677_AZIF0045P001C01CS-SA     I5 @S9S_MB_2U_LIB.S9S_MB_2U(SCH_1):PAGE72
    U1  AL1 VSS217 SOCKET4677_AZIF0045P001C01CS-SA     I5 @S9S_MB_2U_LIB.S9S_MB_2U(SCH_1):PAGE72
    U1 AL13 VSS218 SOCKET4677_AZIF0045P001C01CS-SA     I5 @S9S_MB_2U_LIB.S9S_MB_2U(SCH_1):PAGE72
    U1 AL17 VSS219 SOCKET4677_AZIF0045P001C01CS-SA     I5 @S9S_MB_2U_LIB.S9S_MB_2U(SCH_1):PAGE72
    U1  AL5 VSS220 SOCKET4677_AZIF0045P001C01CS-SA     I5 @S9S_MB_2U_LIB.S9S_MB_2U(SCH_1):PAGE72
    U1 AL52 VSS221 SOCKET4677_AZIF0045P001C01CS-SA     I5 @S9S_MB_2U_LIB.S9S_MB_2U(SCH_1):PAGE72
    U1 AL80 VSS222 SOCKET4677_AZIF0045P001C01CS-SA     I5 @S9S_MB_2U_LIB.S9S_MB_2U(SCH_1):PAGE72
    U1 AL82 VSS223 SOCKET4677_AZIF0045P001C01CS-SA     I5 @S9S_MB_2U_LIB.S9S_MB_2U(SCH_1):PAGE72
    U1 AL84 VSS224 SOCKET4677_AZIF0045P001C01CS-SA     I5 @S9S_MB_2U_LIB.S9S_MB_2U(SCH_1):PAGE72
    U1 AL88 VSS225 SOCKET4677_AZIF0045P001C01CS-SA     I5 @S9S_MB_2U_LIB.S9S_MB_2U(SCH_1):PAGE72
    U1  AL9 VSS226 SOCKET4677_AZIF0045P001C01CS-SA     I5 @S9S_MB_2U_LIB.S9S_MB_2U(SCH_1):PAGE72
    U1 AM12 VSS227 SOCKET4677_AZIF0045P001C01CS-SA     I5 @S9S_MB_2U_LIB.S9S_MB_2U(SCH_1):PAGE72
    U1 AM16 VSS228 SOCKET4677_AZIF0045P001C01CS-SA     I5 @S9S_MB_2U_LIB.S9S_MB_2U(SCH_1):PAGE72
    U1 AM18 VSS229 SOCKET4677_AZIF0045P001C01CS-SA     I5 @S9S_MB_2U_LIB.S9S_MB_2U(SCH_1):PAGE72
    U1 AM20 VSS230 SOCKET4677_AZIF0045P001C01CS-SA     I5 @S9S_MB_2U_LIB.S9S_MB_2U(SCH_1):PAGE72
    U1 AM22 VSS231 SOCKET4677_AZIF0045P001C01CS-SA     I5 @S9S_MB_2U_LIB.S9S_MB_2U(SCH_1):PAGE72
    U1 AM24 VSS232 SOCKET4677_AZIF0045P001C01CS-SA     I5 @S9S_MB_2U_LIB.S9S_MB_2U(SCH_1):PAGE72
    U1 AM26 VSS233 SOCKET4677_AZIF0045P001C01CS-SA     I5 @S9S_MB_2U_LIB.S9S_MB_2U(SCH_1):PAGE72
    U1 AM28 VSS234 SOCKET4677_AZIF0045P001C01CS-SA     I5 @S9S_MB_2U_LIB.S9S_MB_2U(SCH_1):PAGE72
    U1 AM30 VSS235 SOCKET4677_AZIF0045P001C01CS-SA     I5 @S9S_MB_2U_LIB.S9S_MB_2U(SCH_1):PAGE72
    U1 AM32 VSS236 SOCKET4677_AZIF0045P001C01CS-SA     I5 @S9S_MB_2U_LIB.S9S_MB_2U(SCH_1):PAGE72
    U1 AM34 VSS237 SOCKET4677_AZIF0045P001C01CS-SA     I5 @S9S_MB_2U_LIB.S9S_MB_2U(SCH_1):PAGE72
    U1 AM36 VSS238 SOCKET4677_AZIF0045P001C01CS-SA     I5 @S9S_MB_2U_LIB.S9S_MB_2U(SCH_1):PAGE72
    U1 AM38 VSS239 SOCKET4677_AZIF0045P001C01CS-SA     I5 @S9S_MB_2U_LIB.S9S_MB_2U(SCH_1):PAGE72
    U1  AM4 VSS240 SOCKET4677_AZIF0045P001C01CS-SA     I5 @S9S_MB_2U_LIB.S9S_MB_2U(SCH_1):PAGE72
    U1 AM40 VSS241 SOCKET4677_AZIF0045P001C01CS-SA     I5 @S9S_MB_2U_LIB.S9S_MB_2U(SCH_1):PAGE72
    U1 AM42 VSS242 SOCKET4677_AZIF0045P001C01CS-SA     I5 @S9S_MB_2U_LIB.S9S_MB_2U(SCH_1):PAGE72
    U1 AM44 VSS243 SOCKET4677_AZIF0045P001C01CS-SA     I5 @S9S_MB_2U_LIB.S9S_MB_2U(SCH_1):PAGE72
    U1 AM47 VSS244 SOCKET4677_AZIF0045P001C01CS-SA     I5 @S9S_MB_2U_LIB.S9S_MB_2U(SCH_1):PAGE72
    U1 AM49 VSS245 SOCKET4677_AZIF0045P001C01CS-SA     I5 @S9S_MB_2U_LIB.S9S_MB_2U(SCH_1):PAGE72
    U1 AM51 VSS246 SOCKET4677_AZIF0045P001C01CS-SA     I5 @S9S_MB_2U_LIB.S9S_MB_2U(SCH_1):PAGE72
    U1 AM53 VSS247 SOCKET4677_AZIF0045P001C01CS-SA     I5 @S9S_MB_2U_LIB.S9S_MB_2U(SCH_1):PAGE72
    U1 AM55 VSS248 SOCKET4677_AZIF0045P001C01CS-SA     I5 @S9S_MB_2U_LIB.S9S_MB_2U(SCH_1):PAGE72
    U1 AM57 VSS249 SOCKET4677_AZIF0045P001C01CS-SA     I5 @S9S_MB_2U_LIB.S9S_MB_2U(SCH_1):PAGE72
    U1 AM59 VSS250 SOCKET4677_AZIF0045P001C01CS-SA     I5 @S9S_MB_2U_LIB.S9S_MB_2U(SCH_1):PAGE72
    U1 AM61 VSS251 SOCKET4677_AZIF0045P001C01CS-SA     I5 @S9S_MB_2U_LIB.S9S_MB_2U(SCH_1):PAGE72
    U1 AM63 VSS252 SOCKET4677_AZIF0045P001C01CS-SA     I5 @S9S_MB_2U_LIB.S9S_MB_2U(SCH_1):PAGE72
    U1 AM65 VSS253 SOCKET4677_AZIF0045P001C01CS-SA     I5 @S9S_MB_2U_LIB.S9S_MB_2U(SCH_1):PAGE72
    U1 AM67 VSS254 SOCKET4677_AZIF0045P001C01CS-SA     I5 @S9S_MB_2U_LIB.S9S_MB_2U(SCH_1):PAGE72
    U1 AM69 VSS255 SOCKET4677_AZIF0045P001C01CS-SA     I5 @S9S_MB_2U_LIB.S9S_MB_2U(SCH_1):PAGE72
    U1 AM71 VSS256 SOCKET4677_AZIF0045P001C01CS-SA     I5 @S9S_MB_2U_LIB.S9S_MB_2U(SCH_1):PAGE72
    U1 AM73 VSS257 SOCKET4677_AZIF0045P001C01CS-SA     I5 @S9S_MB_2U_LIB.S9S_MB_2U(SCH_1):PAGE72
    U1 AM75 VSS258 SOCKET4677_AZIF0045P001C01CS-SA     I5 @S9S_MB_2U_LIB.S9S_MB_2U(SCH_1):PAGE72
    U1 AM77 VSS259 SOCKET4677_AZIF0045P001C01CS-SA     I5 @S9S_MB_2U_LIB.S9S_MB_2U(SCH_1):PAGE72
    U1  AM8 VSS260 SOCKET4677_AZIF0045P001C01CS-SA     I5 @S9S_MB_2U_LIB.S9S_MB_2U(SCH_1):PAGE72
    U1 AN52 VSS261 SOCKET4677_AZIF0045P001C01CS-SA     I5 @S9S_MB_2U_LIB.S9S_MB_2U(SCH_1):PAGE72
    U1 AN84 VSS262 SOCKET4677_AZIF0045P001C01CS-SA     I5 @S9S_MB_2U_LIB.S9S_MB_2U(SCH_1):PAGE72
    U1 AN88 VSS263 SOCKET4677_AZIF0045P001C01CS-SA     I5 @S9S_MB_2U_LIB.S9S_MB_2U(SCH_1):PAGE72
    U1 AP12 VSS264 SOCKET4677_AZIF0045P001C01CS-SA     I5 @S9S_MB_2U_LIB.S9S_MB_2U(SCH_1):PAGE72
    U1 AP16 VSS265 SOCKET4677_AZIF0045P001C01CS-SA     I5 @S9S_MB_2U_LIB.S9S_MB_2U(SCH_1):PAGE72
    U1 AP18 VSS266 SOCKET4677_AZIF0045P001C01CS-SA     I5 @S9S_MB_2U_LIB.S9S_MB_2U(SCH_1):PAGE72
    U1 AP24 VSS267 SOCKET4677_AZIF0045P001C01CS-SA     I5 @S9S_MB_2U_LIB.S9S_MB_2U(SCH_1):PAGE72
    U1 AP30 VSS268 SOCKET4677_AZIF0045P001C01CS-SA     I5 @S9S_MB_2U_LIB.S9S_MB_2U(SCH_1):PAGE72
    U1 AP36 VSS269 SOCKET4677_AZIF0045P001C01CS-SA     I5 @S9S_MB_2U_LIB.S9S_MB_2U(SCH_1):PAGE72
    U1  AP4 VSS270 SOCKET4677_AZIF0045P001C01CS-SA     I5 @S9S_MB_2U_LIB.S9S_MB_2U(SCH_1):PAGE72
    U1 AP42 VSS271 SOCKET4677_AZIF0045P001C01CS-SA     I5 @S9S_MB_2U_LIB.S9S_MB_2U(SCH_1):PAGE72
    U1 AP49 VSS272 SOCKET4677_AZIF0045P001C01CS-SA     I5 @S9S_MB_2U_LIB.S9S_MB_2U(SCH_1):PAGE72
    U1 AP55 VSS273 SOCKET4677_AZIF0045P001C01CS-SA     I5 @S9S_MB_2U_LIB.S9S_MB_2U(SCH_1):PAGE72
    U1 AP61 VSS274 SOCKET4677_AZIF0045P001C01CS-SA     I5 @S9S_MB_2U_LIB.S9S_MB_2U(SCH_1):PAGE72
    U1 AP67 VSS275 SOCKET4677_AZIF0045P001C01CS-SA     I5 @S9S_MB_2U_LIB.S9S_MB_2U(SCH_1):PAGE72
    U1 AP73 VSS276 SOCKET4677_AZIF0045P001C01CS-SA     I5 @S9S_MB_2U_LIB.S9S_MB_2U(SCH_1):PAGE72
    U1 AP79 VSS277 SOCKET4677_AZIF0045P001C01CS-SA     I5 @S9S_MB_2U_LIB.S9S_MB_2U(SCH_1):PAGE72
    U1  AP8 VSS278 SOCKET4677_AZIF0045P001C01CS-SA     I5 @S9S_MB_2U_LIB.S9S_MB_2U(SCH_1):PAGE72
    U1 AP83 VSS279 SOCKET4677_AZIF0045P001C01CS-SA     I5 @S9S_MB_2U_LIB.S9S_MB_2U(SCH_1):PAGE72
    U1 AP87 VSS280 SOCKET4677_AZIF0045P001C01CS-SA     I5 @S9S_MB_2U_LIB.S9S_MB_2U(SCH_1):PAGE72
    U1 AP91 VSS281 SOCKET4677_AZIF0045P001C01CS-SA     I5 @S9S_MB_2U_LIB.S9S_MB_2U(SCH_1):PAGE72
    U1  AR1 VSS282 SOCKET4677_AZIF0045P001C01CS-SA     I5 @S9S_MB_2U_LIB.S9S_MB_2U(SCH_1):PAGE72
    U1 AR13 VSS283 SOCKET4677_AZIF0045P001C01CS-SA     I5 @S9S_MB_2U_LIB.S9S_MB_2U(SCH_1):PAGE72
    U1 AR19 VSS284 SOCKET4677_AZIF0045P001C01CS-SA     I5 @S9S_MB_2U_LIB.S9S_MB_2U(SCH_1):PAGE72
    U1 AR23 VSS285 SOCKET4677_AZIF0045P001C01CS-SA     I5 @S9S_MB_2U_LIB.S9S_MB_2U(SCH_1):PAGE72
    U1 AR25 VSS286 SOCKET4677_AZIF0045P001C01CS-SA     I5 @S9S_MB_2U_LIB.S9S_MB_2U(SCH_1):PAGE72
    U1 AR29 VSS287 SOCKET4677_AZIF0045P001C01CS-SA     I5 @S9S_MB_2U_LIB.S9S_MB_2U(SCH_1):PAGE72
    U1 AR31 VSS288 SOCKET4677_AZIF0045P001C01CS-SA     I5 @S9S_MB_2U_LIB.S9S_MB_2U(SCH_1):PAGE72
    U1 AR35 VSS289 SOCKET4677_AZIF0045P001C01CS-SA     I5 @S9S_MB_2U_LIB.S9S_MB_2U(SCH_1):PAGE72
    U1 AR37 VSS290 SOCKET4677_AZIF0045P001C01CS-SA     I5 @S9S_MB_2U_LIB.S9S_MB_2U(SCH_1):PAGE72
    U1 AR41 VSS291 SOCKET4677_AZIF0045P001C01CS-SA     I5 @S9S_MB_2U_LIB.S9S_MB_2U(SCH_1):PAGE72
    U1 AR43 VSS292 SOCKET4677_AZIF0045P001C01CS-SA     I5 @S9S_MB_2U_LIB.S9S_MB_2U(SCH_1):PAGE72
    U1 AR48 VSS293 SOCKET4677_AZIF0045P001C01CS-SA     I5 @S9S_MB_2U_LIB.S9S_MB_2U(SCH_1):PAGE72
    U1  AR5 VSS294 SOCKET4677_AZIF0045P001C01CS-SA     I5 @S9S_MB_2U_LIB.S9S_MB_2U(SCH_1):PAGE72
    U1 AR50 VSS295 SOCKET4677_AZIF0045P001C01CS-SA     I5 @S9S_MB_2U_LIB.S9S_MB_2U(SCH_1):PAGE72
    U1 AR54 VSS296 SOCKET4677_AZIF0045P001C01CS-SA     I5 @S9S_MB_2U_LIB.S9S_MB_2U(SCH_1):PAGE72
    U1 AR56 VSS297 SOCKET4677_AZIF0045P001C01CS-SA     I5 @S9S_MB_2U_LIB.S9S_MB_2U(SCH_1):PAGE72
    U1 AR60 VSS298 SOCKET4677_AZIF0045P001C01CS-SA     I5 @S9S_MB_2U_LIB.S9S_MB_2U(SCH_1):PAGE72
    U1 AR62 VSS299 SOCKET4677_AZIF0045P001C01CS-SA     I5 @S9S_MB_2U_LIB.S9S_MB_2U(SCH_1):PAGE72
    U1 AR66 VSS300 SOCKET4677_AZIF0045P001C01CS-SA     I5 @S9S_MB_2U_LIB.S9S_MB_2U(SCH_1):PAGE72
    U1 AR68 VSS301 SOCKET4677_AZIF0045P001C01CS-SA     I5 @S9S_MB_2U_LIB.S9S_MB_2U(SCH_1):PAGE72
    U1 AR72 VSS302 SOCKET4677_AZIF0045P001C01CS-SA     I5 @S9S_MB_2U_LIB.S9S_MB_2U(SCH_1):PAGE72
    U1 AR74 VSS303 SOCKET4677_AZIF0045P001C01CS-SA     I5 @S9S_MB_2U_LIB.S9S_MB_2U(SCH_1):PAGE72
    U1 AR78 VSS304 SOCKET4677_AZIF0045P001C01CS-SA     I5 @S9S_MB_2U_LIB.S9S_MB_2U(SCH_1):PAGE72
    U1 AR82 VSS305 SOCKET4677_AZIF0045P001C01CS-SA     I5 @S9S_MB_2U_LIB.S9S_MB_2U(SCH_1):PAGE72
    U1 AR84 VSS306 SOCKET4677_AZIF0045P001C01CS-SA     I5 @S9S_MB_2U_LIB.S9S_MB_2U(SCH_1):PAGE72
    U1 AR88 VSS307 SOCKET4677_AZIF0045P001C01CS-SA     I5 @S9S_MB_2U_LIB.S9S_MB_2U(SCH_1):PAGE72
    U1  AR9 VSS308 SOCKET4677_AZIF0045P001C01CS-SA     I5 @S9S_MB_2U_LIB.S9S_MB_2U(SCH_1):PAGE72
    U1 AT12 VSS309 SOCKET4677_AZIF0045P001C01CS-SA     I5 @S9S_MB_2U_LIB.S9S_MB_2U(SCH_1):PAGE72
    U1 AT16 VSS310 SOCKET4677_AZIF0045P001C01CS-SA     I5 @S9S_MB_2U_LIB.S9S_MB_2U(SCH_1):PAGE72
    U1 AT20 VSS311 SOCKET4677_AZIF0045P001C01CS-SA     I5 @S9S_MB_2U_LIB.S9S_MB_2U(SCH_1):PAGE72
    U1 AT22 VSS312 SOCKET4677_AZIF0045P001C01CS-SA     I5 @S9S_MB_2U_LIB.S9S_MB_2U(SCH_1):PAGE72
    U1 AT26 VSS313 SOCKET4677_AZIF0045P001C01CS-SA     I5 @S9S_MB_2U_LIB.S9S_MB_2U(SCH_1):PAGE72
    U1 AT28 VSS314 SOCKET4677_AZIF0045P001C01CS-SA     I5 @S9S_MB_2U_LIB.S9S_MB_2U(SCH_1):PAGE72
    U1 AT32 VSS315 SOCKET4677_AZIF0045P001C01CS-SA     I5 @S9S_MB_2U_LIB.S9S_MB_2U(SCH_1):PAGE72
    U1 AT34 VSS316 SOCKET4677_AZIF0045P001C01CS-SA     I5 @S9S_MB_2U_LIB.S9S_MB_2U(SCH_1):PAGE72
    U1 AT38 VSS317 SOCKET4677_AZIF0045P001C01CS-SA     I5 @S9S_MB_2U_LIB.S9S_MB_2U(SCH_1):PAGE72
    U1  AT4 VSS318 SOCKET4677_AZIF0045P001C01CS-SA     I5 @S9S_MB_2U_LIB.S9S_MB_2U(SCH_1):PAGE72
    U1 AT40 VSS319 SOCKET4677_AZIF0045P001C01CS-SA     I5 @S9S_MB_2U_LIB.S9S_MB_2U(SCH_1):PAGE72
    U1 AT44 VSS320 SOCKET4677_AZIF0045P001C01CS-SA     I5 @S9S_MB_2U_LIB.S9S_MB_2U(SCH_1):PAGE72
    U1 AT51 VSS321 SOCKET4677_AZIF0045P001C01CS-SA     I5 @S9S_MB_2U_LIB.S9S_MB_2U(SCH_1):PAGE72
    U1 AT53 VSS322 SOCKET4677_AZIF0045P001C01CS-SA     I5 @S9S_MB_2U_LIB.S9S_MB_2U(SCH_1):PAGE72
    U1 AT57 VSS323 SOCKET4677_AZIF0045P001C01CS-SA     I5 @S9S_MB_2U_LIB.S9S_MB_2U(SCH_1):PAGE72
    U1 AT59 VSS324 SOCKET4677_AZIF0045P001C01CS-SA     I5 @S9S_MB_2U_LIB.S9S_MB_2U(SCH_1):PAGE72
    U1 AT63 VSS325 SOCKET4677_AZIF0045P001C01CS-SA     I5 @S9S_MB_2U_LIB.S9S_MB_2U(SCH_1):PAGE72
    U1 AT65 VSS326 SOCKET4677_AZIF0045P001C01CS-SA     I5 @S9S_MB_2U_LIB.S9S_MB_2U(SCH_1):PAGE72
    U1 AT69 VSS327 SOCKET4677_AZIF0045P001C01CS-SA     I5 @S9S_MB_2U_LIB.S9S_MB_2U(SCH_1):PAGE72
    U1 AT71 VSS328 SOCKET4677_AZIF0045P001C01CS-SA     I5 @S9S_MB_2U_LIB.S9S_MB_2U(SCH_1):PAGE72
    U1 AT75 VSS329 SOCKET4677_AZIF0045P001C01CS-SA     I5 @S9S_MB_2U_LIB.S9S_MB_2U(SCH_1):PAGE72
    U1 AT77 VSS330 SOCKET4677_AZIF0045P001C01CS-SA     I5 @S9S_MB_2U_LIB.S9S_MB_2U(SCH_1):PAGE72
    U1 AT79 VSS331 SOCKET4677_AZIF0045P001C01CS-SA     I5 @S9S_MB_2U_LIB.S9S_MB_2U(SCH_1):PAGE72
    U1  AT8 VSS332 SOCKET4677_AZIF0045P001C01CS-SA     I5 @S9S_MB_2U_LIB.S9S_MB_2U(SCH_1):PAGE72
    U1 AU27 VSS333 SOCKET4677_AZIF0045P001C01CS-SA     I5 @S9S_MB_2U_LIB.S9S_MB_2U(SCH_1):PAGE72
    U1 AU31 VSS334 SOCKET4677_AZIF0045P001C01CS-SA     I5 @S9S_MB_2U_LIB.S9S_MB_2U(SCH_1):PAGE72
    U1 AU37 VSS335 SOCKET4677_AZIF0045P001C01CS-SA     I5 @S9S_MB_2U_LIB.S9S_MB_2U(SCH_1):PAGE72
    U1 AU39 VSS336 SOCKET4677_AZIF0045P001C01CS-SA     I5 @S9S_MB_2U_LIB.S9S_MB_2U(SCH_1):PAGE72
    U1 AU41 VSS337 SOCKET4677_AZIF0045P001C01CS-SA     I5 @S9S_MB_2U_LIB.S9S_MB_2U(SCH_1):PAGE72
    U1 AU45 VSS338 SOCKET4677_AZIF0045P001C01CS-SA     I5 @S9S_MB_2U_LIB.S9S_MB_2U(SCH_1):PAGE72
    U1 AU48 VSS339 SOCKET4677_AZIF0045P001C01CS-SA     I5 @S9S_MB_2U_LIB.S9S_MB_2U(SCH_1):PAGE72
    U1 AU70 VSS340 SOCKET4677_AZIF0045P001C01CS-SA     I5 @S9S_MB_2U_LIB.S9S_MB_2U(SCH_1):PAGE72
    U1 AU72 VSS341 SOCKET4677_AZIF0045P001C01CS-SA     I5 @S9S_MB_2U_LIB.S9S_MB_2U(SCH_1):PAGE72
    U1 AU74 VSS342 SOCKET4677_AZIF0045P001C01CS-SA     I5 @S9S_MB_2U_LIB.S9S_MB_2U(SCH_1):PAGE72
    U1 AU76 VSS343 SOCKET4677_AZIF0045P001C01CS-SA     I5 @S9S_MB_2U_LIB.S9S_MB_2U(SCH_1):PAGE72
    U1 AU80 VSS344 SOCKET4677_AZIF0045P001C01CS-SA     I5 @S9S_MB_2U_LIB.S9S_MB_2U(SCH_1):PAGE72
    U1 AU84 VSS345 SOCKET4677_AZIF0045P001C01CS-SA     I5 @S9S_MB_2U_LIB.S9S_MB_2U(SCH_1):PAGE72
    U1 AU88 VSS346 SOCKET4677_AZIF0045P001C01CS-SA     I5 @S9S_MB_2U_LIB.S9S_MB_2U(SCH_1):PAGE72
    U1 AV12 VSS347 SOCKET4677_AZIF0045P001C01CS-SA     I5 @S9S_MB_2U_LIB.S9S_MB_2U(SCH_1):PAGE72
    U1 AV16 VSS348 SOCKET4677_AZIF0045P001C01CS-SA     I5 @S9S_MB_2U_LIB.S9S_MB_2U(SCH_1):PAGE72
    U1  AV4 VSS349 SOCKET4677_AZIF0045P001C01CS-SA     I5 @S9S_MB_2U_LIB.S9S_MB_2U(SCH_1):PAGE72
    U1 AV77 VSS350 SOCKET4677_AZIF0045P001C01CS-SA     I5 @S9S_MB_2U_LIB.S9S_MB_2U(SCH_1):PAGE72
    U1  AV8 VSS351 SOCKET4677_AZIF0045P001C01CS-SA     I5 @S9S_MB_2U_LIB.S9S_MB_2U(SCH_1):PAGE72
    U1 AV87 VSS352 SOCKET4677_AZIF0045P001C01CS-SA     I5 @S9S_MB_2U_LIB.S9S_MB_2U(SCH_1):PAGE72
    U1 AV91 VSS353 SOCKET4677_AZIF0045P001C01CS-SA     I5 @S9S_MB_2U_LIB.S9S_MB_2U(SCH_1):PAGE72
    U1  AW1 VSS354 SOCKET4677_AZIF0045P001C01CS-SA     I5 @S9S_MB_2U_LIB.S9S_MB_2U(SCH_1):PAGE72
    U1 AW13 VSS355 SOCKET4677_AZIF0045P001C01CS-SA     I5 @S9S_MB_2U_LIB.S9S_MB_2U(SCH_1):PAGE72
    U1  AW5 VSS359 SOCKET4677_AZIF0045P001C01CS-SA     I5 @S9S_MB_2U_LIB.S9S_MB_2U(SCH_1):PAGE72
    U1  AW9 VSS368 SOCKET4677_AZIF0045P001C01CS-SA     I5 @S9S_MB_2U_LIB.S9S_MB_2U(SCH_1):PAGE72
    U1 AA82  VSS38 SOCKET4677_AZIF0045P001C01CS-SA     I8 @S9S_MB_2U_LIB.S9S_MB_2U(SCH_1):PAGE72
    U1 AA84  VSS39 SOCKET4677_AZIF0045P001C01CS-SA     I8 @S9S_MB_2U_LIB.S9S_MB_2U(SCH_1):PAGE72
    U1 AA88  VSS40 SOCKET4677_AZIF0045P001C01CS-SA     I8 @S9S_MB_2U_LIB.S9S_MB_2U(SCH_1):PAGE72
    U1 AB12  VSS41 SOCKET4677_AZIF0045P001C01CS-SA     I8 @S9S_MB_2U_LIB.S9S_MB_2U(SCH_1):PAGE72
    U1 AB16  VSS42 SOCKET4677_AZIF0045P001C01CS-SA     I8 @S9S_MB_2U_LIB.S9S_MB_2U(SCH_1):PAGE72
    U1 AB20  VSS43 SOCKET4677_AZIF0045P001C01CS-SA     I8 @S9S_MB_2U_LIB.S9S_MB_2U(SCH_1):PAGE72
    U1 AB22  VSS44 SOCKET4677_AZIF0045P001C01CS-SA     I8 @S9S_MB_2U_LIB.S9S_MB_2U(SCH_1):PAGE72
    U1 AB26  VSS45 SOCKET4677_AZIF0045P001C01CS-SA     I8 @S9S_MB_2U_LIB.S9S_MB_2U(SCH_1):PAGE72
    U1 AB28  VSS46 SOCKET4677_AZIF0045P001C01CS-SA     I8 @S9S_MB_2U_LIB.S9S_MB_2U(SCH_1):PAGE72
    U1 AB32  VSS47 SOCKET4677_AZIF0045P001C01CS-SA     I8 @S9S_MB_2U_LIB.S9S_MB_2U(SCH_1):PAGE72
    U1 AB34  VSS48 SOCKET4677_AZIF0045P001C01CS-SA     I8 @S9S_MB_2U_LIB.S9S_MB_2U(SCH_1):PAGE72
    U1 AB38  VSS49 SOCKET4677_AZIF0045P001C01CS-SA     I8 @S9S_MB_2U_LIB.S9S_MB_2U(SCH_1):PAGE72
    U1  AB4  VSS50 SOCKET4677_AZIF0045P001C01CS-SA     I8 @S9S_MB_2U_LIB.S9S_MB_2U(SCH_1):PAGE72
    U1 AB40  VSS51 SOCKET4677_AZIF0045P001C01CS-SA     I8 @S9S_MB_2U_LIB.S9S_MB_2U(SCH_1):PAGE72
    U1 AB44  VSS52 SOCKET4677_AZIF0045P001C01CS-SA     I8 @S9S_MB_2U_LIB.S9S_MB_2U(SCH_1):PAGE72
    U1 AB47  VSS53 SOCKET4677_AZIF0045P001C01CS-SA     I8 @S9S_MB_2U_LIB.S9S_MB_2U(SCH_1):PAGE72
    U1 AB51  VSS54 SOCKET4677_AZIF0045P001C01CS-SA     I8 @S9S_MB_2U_LIB.S9S_MB_2U(SCH_1):PAGE72
    U1 AB53  VSS55 SOCKET4677_AZIF0045P001C01CS-SA     I8 @S9S_MB_2U_LIB.S9S_MB_2U(SCH_1):PAGE72
    U1 AB57  VSS56 SOCKET4677_AZIF0045P001C01CS-SA     I8 @S9S_MB_2U_LIB.S9S_MB_2U(SCH_1):PAGE72
    U1 AB59  VSS57 SOCKET4677_AZIF0045P001C01CS-SA     I8 @S9S_MB_2U_LIB.S9S_MB_2U(SCH_1):PAGE72
    U1 AB63  VSS58 SOCKET4677_AZIF0045P001C01CS-SA     I8 @S9S_MB_2U_LIB.S9S_MB_2U(SCH_1):PAGE72
    U1 AB65  VSS59 SOCKET4677_AZIF0045P001C01CS-SA     I8 @S9S_MB_2U_LIB.S9S_MB_2U(SCH_1):PAGE72
    U1 AB69  VSS60 SOCKET4677_AZIF0045P001C01CS-SA     I8 @S9S_MB_2U_LIB.S9S_MB_2U(SCH_1):PAGE72
    U1 AB71  VSS61 SOCKET4677_AZIF0045P001C01CS-SA     I8 @S9S_MB_2U_LIB.S9S_MB_2U(SCH_1):PAGE72
    U1 AB75  VSS62 SOCKET4677_AZIF0045P001C01CS-SA     I8 @S9S_MB_2U_LIB.S9S_MB_2U(SCH_1):PAGE72
    U1 AB77  VSS63 SOCKET4677_AZIF0045P001C01CS-SA     I8 @S9S_MB_2U_LIB.S9S_MB_2U(SCH_1):PAGE72
    U1 AB79  VSS64 SOCKET4677_AZIF0045P001C01CS-SA     I8 @S9S_MB_2U_LIB.S9S_MB_2U(SCH_1):PAGE72
    U1  AB8  VSS65 SOCKET4677_AZIF0045P001C01CS-SA     I8 @S9S_MB_2U_LIB.S9S_MB_2U(SCH_1):PAGE72
    U1 AB81  VSS66 SOCKET4677_AZIF0045P001C01CS-SA     I8 @S9S_MB_2U_LIB.S9S_MB_2U(SCH_1):PAGE72
    U1 AB83  VSS67 SOCKET4677_AZIF0045P001C01CS-SA     I8 @S9S_MB_2U_LIB.S9S_MB_2U(SCH_1):PAGE72
    U1 AB87  VSS68 SOCKET4677_AZIF0045P001C01CS-SA     I8 @S9S_MB_2U_LIB.S9S_MB_2U(SCH_1):PAGE72
    U1 AB91  VSS69 SOCKET4677_AZIF0045P001C01CS-SA     I8 @S9S_MB_2U_LIB.S9S_MB_2U(SCH_1):PAGE72
    U1  AC1  VSS70 SOCKET4677_AZIF0045P001C01CS-SA     I8 @S9S_MB_2U_LIB.S9S_MB_2U(SCH_1):PAGE72
    U1 AC13  VSS71 SOCKET4677_AZIF0045P001C01CS-SA     I8 @S9S_MB_2U_LIB.S9S_MB_2U(SCH_1):PAGE72
    U1 AC21  VSS72 SOCKET4677_AZIF0045P001C01CS-SA     I8 @S9S_MB_2U_LIB.S9S_MB_2U(SCH_1):PAGE72
    U1 AC27  VSS73 SOCKET4677_AZIF0045P001C01CS-SA     I8 @S9S_MB_2U_LIB.S9S_MB_2U(SCH_1):PAGE72
    U1 AC33  VSS74 SOCKET4677_AZIF0045P001C01CS-SA     I8 @S9S_MB_2U_LIB.S9S_MB_2U(SCH_1):PAGE72
    U1 AC39  VSS75 SOCKET4677_AZIF0045P001C01CS-SA     I8 @S9S_MB_2U_LIB.S9S_MB_2U(SCH_1):PAGE72
    U1 AC45  VSS76 SOCKET4677_AZIF0045P001C01CS-SA     I8 @S9S_MB_2U_LIB.S9S_MB_2U(SCH_1):PAGE72
    U1  AC5  VSS77 SOCKET4677_AZIF0045P001C01CS-SA     I8 @S9S_MB_2U_LIB.S9S_MB_2U(SCH_1):PAGE72
    U1 AC52  VSS78 SOCKET4677_AZIF0045P001C01CS-SA     I8 @S9S_MB_2U_LIB.S9S_MB_2U(SCH_1):PAGE72
    U1 AC58  VSS79 SOCKET4677_AZIF0045P001C01CS-SA     I8 @S9S_MB_2U_LIB.S9S_MB_2U(SCH_1):PAGE72
    U1 AC64  VSS80 SOCKET4677_AZIF0045P001C01CS-SA     I8 @S9S_MB_2U_LIB.S9S_MB_2U(SCH_1):PAGE72
    U1 AC70  VSS81 SOCKET4677_AZIF0045P001C01CS-SA     I8 @S9S_MB_2U_LIB.S9S_MB_2U(SCH_1):PAGE72
    U1 AC76  VSS82 SOCKET4677_AZIF0045P001C01CS-SA     I8 @S9S_MB_2U_LIB.S9S_MB_2U(SCH_1):PAGE72
    U1 AC84  VSS83 SOCKET4677_AZIF0045P001C01CS-SA     I8 @S9S_MB_2U_LIB.S9S_MB_2U(SCH_1):PAGE72
    U1 AC88  VSS84 SOCKET4677_AZIF0045P001C01CS-SA     I8 @S9S_MB_2U_LIB.S9S_MB_2U(SCH_1):PAGE72
    U1  AC9  VSS85 SOCKET4677_AZIF0045P001C01CS-SA     I8 @S9S_MB_2U_LIB.S9S_MB_2U(SCH_1):PAGE72
    U1 AD12  VSS86 SOCKET4677_AZIF0045P001C01CS-SA     I8 @S9S_MB_2U_LIB.S9S_MB_2U(SCH_1):PAGE72
    U1 AD16  VSS87 SOCKET4677_AZIF0045P001C01CS-SA     I8 @S9S_MB_2U_LIB.S9S_MB_2U(SCH_1):PAGE72
    U1  AD4  VSS88 SOCKET4677_AZIF0045P001C01CS-SA     I8 @S9S_MB_2U_LIB.S9S_MB_2U(SCH_1):PAGE72
    U1 AD42  VSS89 SOCKET4677_AZIF0045P001C01CS-SA     I8 @S9S_MB_2U_LIB.S9S_MB_2U(SCH_1):PAGE72
    U1 AD79  VSS90 SOCKET4677_AZIF0045P001C01CS-SA     I8 @S9S_MB_2U_LIB.S9S_MB_2U(SCH_1):PAGE72
    U1  AD8  VSS91 SOCKET4677_AZIF0045P001C01CS-SA     I8 @S9S_MB_2U_LIB.S9S_MB_2U(SCH_1):PAGE72
    U1 AD83  VSS92 SOCKET4677_AZIF0045P001C01CS-SA     I8 @S9S_MB_2U_LIB.S9S_MB_2U(SCH_1):PAGE72
    U1 AE17  VSS93 SOCKET4677_AZIF0045P001C01CS-SA     I8 @S9S_MB_2U_LIB.S9S_MB_2U(SCH_1):PAGE72
    U1 AE19  VSS94 SOCKET4677_AZIF0045P001C01CS-SA     I8 @S9S_MB_2U_LIB.S9S_MB_2U(SCH_1):PAGE72
    U1 AE21  VSS95 SOCKET4677_AZIF0045P001C01CS-SA     I8 @S9S_MB_2U_LIB.S9S_MB_2U(SCH_1):PAGE72
    U1 AE23  VSS96 SOCKET4677_AZIF0045P001C01CS-SA     I8 @S9S_MB_2U_LIB.S9S_MB_2U(SCH_1):PAGE72
    U1 AE25  VSS97 SOCKET4677_AZIF0045P001C01CS-SA     I8 @S9S_MB_2U_LIB.S9S_MB_2U(SCH_1):PAGE72
    U1 AE27  VSS98 SOCKET4677_AZIF0045P001C01CS-SA     I8 @S9S_MB_2U_LIB.S9S_MB_2U(SCH_1):PAGE72
    U1 AE29  VSS99 SOCKET4677_AZIF0045P001C01CS-SA     I8 @S9S_MB_2U_LIB.S9S_MB_2U(SCH_1):PAGE72
    U1 AE31 VSS100 SOCKET4677_AZIF0045P001C01CS-SA     I8 @S9S_MB_2U_LIB.S9S_MB_2U(SCH_1):PAGE72
    U1 AE33 VSS101 SOCKET4677_AZIF0045P001C01CS-SA     I8 @S9S_MB_2U_LIB.S9S_MB_2U(SCH_1):PAGE72
    U1 AE35 VSS102 SOCKET4677_AZIF0045P001C01CS-SA     I8 @S9S_MB_2U_LIB.S9S_MB_2U(SCH_1):PAGE72
    U1 AE37 VSS103 SOCKET4677_AZIF0045P001C01CS-SA     I8 @S9S_MB_2U_LIB.S9S_MB_2U(SCH_1):PAGE72
    U1 AE39 VSS104 SOCKET4677_AZIF0045P001C01CS-SA     I8 @S9S_MB_2U_LIB.S9S_MB_2U(SCH_1):PAGE72
    U1 AE41 VSS105 SOCKET4677_AZIF0045P001C01CS-SA     I8 @S9S_MB_2U_LIB.S9S_MB_2U(SCH_1):PAGE72
    U1 AE43 VSS106 SOCKET4677_AZIF0045P001C01CS-SA     I8 @S9S_MB_2U_LIB.S9S_MB_2U(SCH_1):PAGE72
    U1 AE45 VSS107 SOCKET4677_AZIF0045P001C01CS-SA     I8 @S9S_MB_2U_LIB.S9S_MB_2U(SCH_1):PAGE72
    U1 AE48 VSS108 SOCKET4677_AZIF0045P001C01CS-SA     I8 @S9S_MB_2U_LIB.S9S_MB_2U(SCH_1):PAGE72
    U1 AE50 VSS109 SOCKET4677_AZIF0045P001C01CS-SA     I8 @S9S_MB_2U_LIB.S9S_MB_2U(SCH_1):PAGE72
    U1 AE52 VSS110 SOCKET4677_AZIF0045P001C01CS-SA     I8 @S9S_MB_2U_LIB.S9S_MB_2U(SCH_1):PAGE72
    U1 AE54 VSS111 SOCKET4677_AZIF0045P001C01CS-SA     I8 @S9S_MB_2U_LIB.S9S_MB_2U(SCH_1):PAGE72
    U1 AE56 VSS112 SOCKET4677_AZIF0045P001C01CS-SA     I8 @S9S_MB_2U_LIB.S9S_MB_2U(SCH_1):PAGE72
    U1 AE58 VSS113 SOCKET4677_AZIF0045P001C01CS-SA     I8 @S9S_MB_2U_LIB.S9S_MB_2U(SCH_1):PAGE72
    U1 AE60 VSS114 SOCKET4677_AZIF0045P001C01CS-SA     I8 @S9S_MB_2U_LIB.S9S_MB_2U(SCH_1):PAGE72
    U1 AE62 VSS115 SOCKET4677_AZIF0045P001C01CS-SA     I8 @S9S_MB_2U_LIB.S9S_MB_2U(SCH_1):PAGE72
    U1 AE64 VSS116 SOCKET4677_AZIF0045P001C01CS-SA     I8 @S9S_MB_2U_LIB.S9S_MB_2U(SCH_1):PAGE72
    U1 AE66 VSS117 SOCKET4677_AZIF0045P001C01CS-SA     I8 @S9S_MB_2U_LIB.S9S_MB_2U(SCH_1):PAGE72
    U1 AE68 VSS118 SOCKET4677_AZIF0045P001C01CS-SA     I8 @S9S_MB_2U_LIB.S9S_MB_2U(SCH_1):PAGE72
    U1 AE70 VSS119 SOCKET4677_AZIF0045P001C01CS-SA     I8 @S9S_MB_2U_LIB.S9S_MB_2U(SCH_1):PAGE72
    U1 AE72 VSS120 SOCKET4677_AZIF0045P001C01CS-SA     I8 @S9S_MB_2U_LIB.S9S_MB_2U(SCH_1):PAGE72
    U1 AE74 VSS121 SOCKET4677_AZIF0045P001C01CS-SA     I8 @S9S_MB_2U_LIB.S9S_MB_2U(SCH_1):PAGE72
    U1 AE76 VSS122 SOCKET4677_AZIF0045P001C01CS-SA     I8 @S9S_MB_2U_LIB.S9S_MB_2U(SCH_1):PAGE72
    U1 AE78 VSS123 SOCKET4677_AZIF0045P001C01CS-SA     I8 @S9S_MB_2U_LIB.S9S_MB_2U(SCH_1):PAGE72
    U1 AE84 VSS124 SOCKET4677_AZIF0045P001C01CS-SA     I8 @S9S_MB_2U_LIB.S9S_MB_2U(SCH_1):PAGE72
    U1 AE88 VSS125 SOCKET4677_AZIF0045P001C01CS-SA     I8 @S9S_MB_2U_LIB.S9S_MB_2U(SCH_1):PAGE72
    U1 AF12 VSS126 SOCKET4677_AZIF0045P001C01CS-SA     I8 @S9S_MB_2U_LIB.S9S_MB_2U(SCH_1):PAGE72
    U1 AF16 VSS127 SOCKET4677_AZIF0045P001C01CS-SA     I8 @S9S_MB_2U_LIB.S9S_MB_2U(SCH_1):PAGE72
    U1  AF4 VSS128 SOCKET4677_AZIF0045P001C01CS-SA     I8 @S9S_MB_2U_LIB.S9S_MB_2U(SCH_1):PAGE72
    U1 AF42 VSS129 SOCKET4677_AZIF0045P001C01CS-SA     I8 @S9S_MB_2U_LIB.S9S_MB_2U(SCH_1):PAGE72
    U1  AF8 VSS130 SOCKET4677_AZIF0045P001C01CS-SA     I8 @S9S_MB_2U_LIB.S9S_MB_2U(SCH_1):PAGE72
    U1 AF81 VSS131 SOCKET4677_AZIF0045P001C01CS-SA     I8 @S9S_MB_2U_LIB.S9S_MB_2U(SCH_1):PAGE72
    U1 AF87 VSS132 SOCKET4677_AZIF0045P001C01CS-SA     I8 @S9S_MB_2U_LIB.S9S_MB_2U(SCH_1):PAGE72
    U1 AF91 VSS133 SOCKET4677_AZIF0045P001C01CS-SA     I8 @S9S_MB_2U_LIB.S9S_MB_2U(SCH_1):PAGE72
    U1  AG1 VSS134 SOCKET4677_AZIF0045P001C01CS-SA     I8 @S9S_MB_2U_LIB.S9S_MB_2U(SCH_1):PAGE72
    U1 AG13 VSS135 SOCKET4677_AZIF0045P001C01CS-SA     I8 @S9S_MB_2U_LIB.S9S_MB_2U(SCH_1):PAGE72
    U1 AG21 VSS136 SOCKET4677_AZIF0045P001C01CS-SA     I8 @S9S_MB_2U_LIB.S9S_MB_2U(SCH_1):PAGE72
    U1 AG27 VSS137 SOCKET4677_AZIF0045P001C01CS-SA     I8 @S9S_MB_2U_LIB.S9S_MB_2U(SCH_1):PAGE72
    U1 AG33 VSS138 SOCKET4677_AZIF0045P001C01CS-SA     I8 @S9S_MB_2U_LIB.S9S_MB_2U(SCH_1):PAGE72
    U1 AG39 VSS139 SOCKET4677_AZIF0045P001C01CS-SA     I8 @S9S_MB_2U_LIB.S9S_MB_2U(SCH_1):PAGE72
    U1 AG45 VSS140 SOCKET4677_AZIF0045P001C01CS-SA     I8 @S9S_MB_2U_LIB.S9S_MB_2U(SCH_1):PAGE72
    U1  AG5 VSS141 SOCKET4677_AZIF0045P001C01CS-SA     I8 @S9S_MB_2U_LIB.S9S_MB_2U(SCH_1):PAGE72
    U1 AG52 VSS142 SOCKET4677_AZIF0045P001C01CS-SA     I8 @S9S_MB_2U_LIB.S9S_MB_2U(SCH_1):PAGE72
    U1 AG58 VSS143 SOCKET4677_AZIF0045P001C01CS-SA     I8 @S9S_MB_2U_LIB.S9S_MB_2U(SCH_1):PAGE72
    U1 AG64 VSS144 SOCKET4677_AZIF0045P001C01CS-SA     I8 @S9S_MB_2U_LIB.S9S_MB_2U(SCH_1):PAGE72
    U1 AG70 VSS145 SOCKET4677_AZIF0045P001C01CS-SA     I8 @S9S_MB_2U_LIB.S9S_MB_2U(SCH_1):PAGE72
    U1 AG76 VSS146 SOCKET4677_AZIF0045P001C01CS-SA     I8 @S9S_MB_2U_LIB.S9S_MB_2U(SCH_1):PAGE72
    U1 AG84 VSS147 SOCKET4677_AZIF0045P001C01CS-SA     I8 @S9S_MB_2U_LIB.S9S_MB_2U(SCH_1):PAGE72
    U1 AG88 VSS148 SOCKET4677_AZIF0045P001C01CS-SA     I8 @S9S_MB_2U_LIB.S9S_MB_2U(SCH_1):PAGE72
    U1  AG9 VSS149 SOCKET4677_AZIF0045P001C01CS-SA     I8 @S9S_MB_2U_LIB.S9S_MB_2U(SCH_1):PAGE72
    U1 AH12 VSS150 SOCKET4677_AZIF0045P001C01CS-SA     I8 @S9S_MB_2U_LIB.S9S_MB_2U(SCH_1):PAGE72
    U1 AH16 VSS151 SOCKET4677_AZIF0045P001C01CS-SA     I8 @S9S_MB_2U_LIB.S9S_MB_2U(SCH_1):PAGE72
    U1 AH20 VSS152 SOCKET4677_AZIF0045P001C01CS-SA     I8 @S9S_MB_2U_LIB.S9S_MB_2U(SCH_1):PAGE72
    U1 AH22 VSS153 SOCKET4677_AZIF0045P001C01CS-SA     I8 @S9S_MB_2U_LIB.S9S_MB_2U(SCH_1):PAGE72
    U1 AH26 VSS154 SOCKET4677_AZIF0045P001C01CS-SA     I8 @S9S_MB_2U_LIB.S9S_MB_2U(SCH_1):PAGE72
    U1 AH28 VSS155 SOCKET4677_AZIF0045P001C01CS-SA     I8 @S9S_MB_2U_LIB.S9S_MB_2U(SCH_1):PAGE72
    U1 AH32 VSS156 SOCKET4677_AZIF0045P001C01CS-SA     I8 @S9S_MB_2U_LIB.S9S_MB_2U(SCH_1):PAGE72
    U1 AH34 VSS157 SOCKET4677_AZIF0045P001C01CS-SA     I8 @S9S_MB_2U_LIB.S9S_MB_2U(SCH_1):PAGE72
    U1 AH38 VSS158 SOCKET4677_AZIF0045P001C01CS-SA     I8 @S9S_MB_2U_LIB.S9S_MB_2U(SCH_1):PAGE72
    U1  AH4 VSS159 SOCKET4677_AZIF0045P001C01CS-SA     I8 @S9S_MB_2U_LIB.S9S_MB_2U(SCH_1):PAGE72
    U1 AH40 VSS160 SOCKET4677_AZIF0045P001C01CS-SA     I8 @S9S_MB_2U_LIB.S9S_MB_2U(SCH_1):PAGE72
    U1 AH44 VSS161 SOCKET4677_AZIF0045P001C01CS-SA     I8 @S9S_MB_2U_LIB.S9S_MB_2U(SCH_1):PAGE72
    U1 AH47 VSS162 SOCKET4677_AZIF0045P001C01CS-SA     I8 @S9S_MB_2U_LIB.S9S_MB_2U(SCH_1):PAGE72
    U1 AH51 VSS163 SOCKET4677_AZIF0045P001C01CS-SA     I8 @S9S_MB_2U_LIB.S9S_MB_2U(SCH_1):PAGE72
    U1 AH53 VSS164 SOCKET4677_AZIF0045P001C01CS-SA     I8 @S9S_MB_2U_LIB.S9S_MB_2U(SCH_1):PAGE72
    U1 AH57 VSS165 SOCKET4677_AZIF0045P001C01CS-SA     I8 @S9S_MB_2U_LIB.S9S_MB_2U(SCH_1):PAGE72
    U1 AH59 VSS166 SOCKET4677_AZIF0045P001C01CS-SA     I8 @S9S_MB_2U_LIB.S9S_MB_2U(SCH_1):PAGE72
    U1 AH63 VSS167 SOCKET4677_AZIF0045P001C01CS-SA     I8 @S9S_MB_2U_LIB.S9S_MB_2U(SCH_1):PAGE72
    U1 AH65 VSS168 SOCKET4677_AZIF0045P001C01CS-SA     I8 @S9S_MB_2U_LIB.S9S_MB_2U(SCH_1):PAGE72
    U1 AH69 VSS169 SOCKET4677_AZIF0045P001C01CS-SA     I8 @S9S_MB_2U_LIB.S9S_MB_2U(SCH_1):PAGE72
    U1 AH71 VSS170 SOCKET4677_AZIF0045P001C01CS-SA     I8 @S9S_MB_2U_LIB.S9S_MB_2U(SCH_1):PAGE72
    U1 AH75 VSS171 SOCKET4677_AZIF0045P001C01CS-SA     I8 @S9S_MB_2U_LIB.S9S_MB_2U(SCH_1):PAGE72
    U1 AH77 VSS172 SOCKET4677_AZIF0045P001C01CS-SA     I8 @S9S_MB_2U_LIB.S9S_MB_2U(SCH_1):PAGE72
    U1 AH79 VSS173 SOCKET4677_AZIF0045P001C01CS-SA     I8 @S9S_MB_2U_LIB.S9S_MB_2U(SCH_1):PAGE72
    U1  AH8 VSS174 SOCKET4677_AZIF0045P001C01CS-SA     I8 @S9S_MB_2U_LIB.S9S_MB_2U(SCH_1):PAGE72
    U1 AH83 VSS175 SOCKET4677_AZIF0045P001C01CS-SA     I8 @S9S_MB_2U_LIB.S9S_MB_2U(SCH_1):PAGE72
    U1 AJ19 VSS176 SOCKET4677_AZIF0045P001C01CS-SA     I8 @S9S_MB_2U_LIB.S9S_MB_2U(SCH_1):PAGE72
    U1 AJ23 VSS177 SOCKET4677_AZIF0045P001C01CS-SA     I8 @S9S_MB_2U_LIB.S9S_MB_2U(SCH_1):PAGE72
    U1 AJ25 VSS178 SOCKET4677_AZIF0045P001C01CS-SA     I8 @S9S_MB_2U_LIB.S9S_MB_2U(SCH_1):PAGE72
    U1 AJ29 VSS179 SOCKET4677_AZIF0045P001C01CS-SA     I8 @S9S_MB_2U_LIB.S9S_MB_2U(SCH_1):PAGE72
    U1 AJ31 VSS180 SOCKET4677_AZIF0045P001C01CS-SA     I8 @S9S_MB_2U_LIB.S9S_MB_2U(SCH_1):PAGE72
    U1 AJ35 VSS181 SOCKET4677_AZIF0045P001C01CS-SA     I8 @S9S_MB_2U_LIB.S9S_MB_2U(SCH_1):PAGE72
    U1 AJ37 VSS182 SOCKET4677_AZIF0045P001C01CS-SA     I8 @S9S_MB_2U_LIB.S9S_MB_2U(SCH_1):PAGE72
    U1 AJ41 VSS183 SOCKET4677_AZIF0045P001C01CS-SA     I8 @S9S_MB_2U_LIB.S9S_MB_2U(SCH_1):PAGE72
    U1 AJ43 VSS184 SOCKET4677_AZIF0045P001C01CS-SA     I8 @S9S_MB_2U_LIB.S9S_MB_2U(SCH_1):PAGE72
    U1 AJ48 VSS185 SOCKET4677_AZIF0045P001C01CS-SA     I8 @S9S_MB_2U_LIB.S9S_MB_2U(SCH_1):PAGE72
    U1 AJ50 VSS186 SOCKET4677_AZIF0045P001C01CS-SA     I8 @S9S_MB_2U_LIB.S9S_MB_2U(SCH_1):PAGE72
    U1 AJ54 VSS187 SOCKET4677_AZIF0045P001C01CS-SA     I8 @S9S_MB_2U_LIB.S9S_MB_2U(SCH_1):PAGE72
    U1 AJ56 VSS188 SOCKET4677_AZIF0045P001C01CS-SA     I8 @S9S_MB_2U_LIB.S9S_MB_2U(SCH_1):PAGE72
    U1 AJ60 VSS189 SOCKET4677_AZIF0045P001C01CS-SA     I8 @S9S_MB_2U_LIB.S9S_MB_2U(SCH_1):PAGE72
    U1 AJ62 VSS190 SOCKET4677_AZIF0045P001C01CS-SA     I8 @S9S_MB_2U_LIB.S9S_MB_2U(SCH_1):PAGE72
    U1 AJ66 VSS191 SOCKET4677_AZIF0045P001C01CS-SA     I8 @S9S_MB_2U_LIB.S9S_MB_2U(SCH_1):PAGE72
    U1 AJ68 VSS192 SOCKET4677_AZIF0045P001C01CS-SA     I8 @S9S_MB_2U_LIB.S9S_MB_2U(SCH_1):PAGE72
    U1 AJ72 VSS193 SOCKET4677_AZIF0045P001C01CS-SA     I8 @S9S_MB_2U_LIB.S9S_MB_2U(SCH_1):PAGE72
    U1 AJ74 VSS194 SOCKET4677_AZIF0045P001C01CS-SA     I8 @S9S_MB_2U_LIB.S9S_MB_2U(SCH_1):PAGE72
    U1 AJ78 VSS195 SOCKET4677_AZIF0045P001C01CS-SA     I8 @S9S_MB_2U_LIB.S9S_MB_2U(SCH_1):PAGE72
    U1 AJ84 VSS196 SOCKET4677_AZIF0045P001C01CS-SA     I8 @S9S_MB_2U_LIB.S9S_MB_2U(SCH_1):PAGE72
    U1 AJ88 VSS197 SOCKET4677_AZIF0045P001C01CS-SA     I8 @S9S_MB_2U_LIB.S9S_MB_2U(SCH_1):PAGE72
    U1 AA19  VSS17 SOCKET4677_AZIF0045P001C01CS-SA     I2 @S9S_MB_2U_LIB.S9S_MB_2U(SCH_1):PAGE73
    U1 AA23  VSS18 SOCKET4677_AZIF0045P001C01CS-SA     I2 @S9S_MB_2U_LIB.S9S_MB_2U(SCH_1):PAGE73
    U1 AA25  VSS19 SOCKET4677_AZIF0045P001C01CS-SA     I2 @S9S_MB_2U_LIB.S9S_MB_2U(SCH_1):PAGE73
    U1 AA29  VSS20 SOCKET4677_AZIF0045P001C01CS-SA     I2 @S9S_MB_2U_LIB.S9S_MB_2U(SCH_1):PAGE73
    U1 AA31  VSS21 SOCKET4677_AZIF0045P001C01CS-SA     I2 @S9S_MB_2U_LIB.S9S_MB_2U(SCH_1):PAGE73
    U1 AA35  VSS22 SOCKET4677_AZIF0045P001C01CS-SA     I2 @S9S_MB_2U_LIB.S9S_MB_2U(SCH_1):PAGE73
    U1 AA37  VSS23 SOCKET4677_AZIF0045P001C01CS-SA     I2 @S9S_MB_2U_LIB.S9S_MB_2U(SCH_1):PAGE73
    U1 AA41  VSS24 SOCKET4677_AZIF0045P001C01CS-SA     I2 @S9S_MB_2U_LIB.S9S_MB_2U(SCH_1):PAGE73
    U1 AA43  VSS25 SOCKET4677_AZIF0045P001C01CS-SA     I2 @S9S_MB_2U_LIB.S9S_MB_2U(SCH_1):PAGE73
    U1 AA48  VSS26 SOCKET4677_AZIF0045P001C01CS-SA     I2 @S9S_MB_2U_LIB.S9S_MB_2U(SCH_1):PAGE73
    U1 AA50  VSS27 SOCKET4677_AZIF0045P001C01CS-SA     I2 @S9S_MB_2U_LIB.S9S_MB_2U(SCH_1):PAGE73
    U1 AA54  VSS28 SOCKET4677_AZIF0045P001C01CS-SA     I2 @S9S_MB_2U_LIB.S9S_MB_2U(SCH_1):PAGE73
    U1 AA56  VSS29 SOCKET4677_AZIF0045P001C01CS-SA     I2 @S9S_MB_2U_LIB.S9S_MB_2U(SCH_1):PAGE73
    U1 AA60  VSS30 SOCKET4677_AZIF0045P001C01CS-SA     I2 @S9S_MB_2U_LIB.S9S_MB_2U(SCH_1):PAGE73
    U1 AA62  VSS31 SOCKET4677_AZIF0045P001C01CS-SA     I2 @S9S_MB_2U_LIB.S9S_MB_2U(SCH_1):PAGE73
    U1 AA66  VSS32 SOCKET4677_AZIF0045P001C01CS-SA     I2 @S9S_MB_2U_LIB.S9S_MB_2U(SCH_1):PAGE73
    U1 AA68  VSS33 SOCKET4677_AZIF0045P001C01CS-SA     I2 @S9S_MB_2U_LIB.S9S_MB_2U(SCH_1):PAGE73
    U1 AA72  VSS34 SOCKET4677_AZIF0045P001C01CS-SA     I2 @S9S_MB_2U_LIB.S9S_MB_2U(SCH_1):PAGE73
    U1 AA74  VSS35 SOCKET4677_AZIF0045P001C01CS-SA     I2 @S9S_MB_2U_LIB.S9S_MB_2U(SCH_1):PAGE73
    U1 AA78  VSS36 SOCKET4677_AZIF0045P001C01CS-SA     I2 @S9S_MB_2U_LIB.S9S_MB_2U(SCH_1):PAGE73
    U1 AA80  VSS37 SOCKET4677_AZIF0045P001C01CS-SA     I2 @S9S_MB_2U_LIB.S9S_MB_2U(SCH_1):PAGE73
    U1  P32 VSS1690 SOCKET4677_AZIF0045P001C01CS-SA     I2 @S9S_MB_2U_LIB.S9S_MB_2U(SCH_1):PAGE73
    U1  N76 VSS1696 SOCKET4677_AZIF0045P001C01CS-SA     I2 @S9S_MB_2U_LIB.S9S_MB_2U(SCH_1):PAGE73
    U1  P51 VSS1697 SOCKET4677_AZIF0045P001C01CS-SA     I2 @S9S_MB_2U_LIB.S9S_MB_2U(SCH_1):PAGE73
    U1  N78 VSS1698 SOCKET4677_AZIF0045P001C01CS-SA     I2 @S9S_MB_2U_LIB.S9S_MB_2U(SCH_1):PAGE73
    U1  P57 VSS1699 SOCKET4677_AZIF0045P001C01CS-SA     I2 @S9S_MB_2U_LIB.S9S_MB_2U(SCH_1):PAGE73
    U1  N80 VSS1700 SOCKET4677_AZIF0045P001C01CS-SA     I2 @S9S_MB_2U_LIB.S9S_MB_2U(SCH_1):PAGE73
    U1  N82 VSS1701 SOCKET4677_AZIF0045P001C01CS-SA     I2 @S9S_MB_2U_LIB.S9S_MB_2U(SCH_1):PAGE73
    U1  N84 VSS1702 SOCKET4677_AZIF0045P001C01CS-SA     I2 @S9S_MB_2U_LIB.S9S_MB_2U(SCH_1):PAGE73
    U1  N88 VSS1703 SOCKET4677_AZIF0045P001C01CS-SA     I2 @S9S_MB_2U_LIB.S9S_MB_2U(SCH_1):PAGE73
    U1  P71 VSS1704 SOCKET4677_AZIF0045P001C01CS-SA     I2 @S9S_MB_2U_LIB.S9S_MB_2U(SCH_1):PAGE73
    U1  P12 VSS1705 SOCKET4677_AZIF0045P001C01CS-SA     I2 @S9S_MB_2U_LIB.S9S_MB_2U(SCH_1):PAGE73
    U1  P16 VSS1706 SOCKET4677_AZIF0045P001C01CS-SA     I2 @S9S_MB_2U_LIB.S9S_MB_2U(SCH_1):PAGE73
    U1  P20 VSS1707 SOCKET4677_AZIF0045P001C01CS-SA     I2 @S9S_MB_2U_LIB.S9S_MB_2U(SCH_1):PAGE73
    U1  P22 VSS1708 SOCKET4677_AZIF0045P001C01CS-SA     I2 @S9S_MB_2U_LIB.S9S_MB_2U(SCH_1):PAGE73
    U1  P26 VSS1709 SOCKET4677_AZIF0045P001C01CS-SA     I2 @S9S_MB_2U_LIB.S9S_MB_2U(SCH_1):PAGE73
    U1  P28 VSS1710 SOCKET4677_AZIF0045P001C01CS-SA     I2 @S9S_MB_2U_LIB.S9S_MB_2U(SCH_1):PAGE73
    U1   R1 VSS1711 SOCKET4677_AZIF0045P001C01CS-SA     I2 @S9S_MB_2U_LIB.S9S_MB_2U(SCH_1):PAGE73
    U1  P34 VSS1712 SOCKET4677_AZIF0045P001C01CS-SA     I2 @S9S_MB_2U_LIB.S9S_MB_2U(SCH_1):PAGE73
    U1  P38 VSS1713 SOCKET4677_AZIF0045P001C01CS-SA     I2 @S9S_MB_2U_LIB.S9S_MB_2U(SCH_1):PAGE73
    U1  R19 VSS1714 SOCKET4677_AZIF0045P001C01CS-SA     I2 @S9S_MB_2U_LIB.S9S_MB_2U(SCH_1):PAGE73
    U1  R23 VSS1715 SOCKET4677_AZIF0045P001C01CS-SA     I2 @S9S_MB_2U_LIB.S9S_MB_2U(SCH_1):PAGE73
    U1   P4 VSS1716 SOCKET4677_AZIF0045P001C01CS-SA     I2 @S9S_MB_2U_LIB.S9S_MB_2U(SCH_1):PAGE73
    U1  P40 VSS1717 SOCKET4677_AZIF0045P001C01CS-SA     I2 @S9S_MB_2U_LIB.S9S_MB_2U(SCH_1):PAGE73
    U1  P44 VSS1718 SOCKET4677_AZIF0045P001C01CS-SA     I2 @S9S_MB_2U_LIB.S9S_MB_2U(SCH_1):PAGE73
    U1  P47 VSS1719 SOCKET4677_AZIF0045P001C01CS-SA     I2 @S9S_MB_2U_LIB.S9S_MB_2U(SCH_1):PAGE73
    U1  P53 VSS1720 SOCKET4677_AZIF0045P001C01CS-SA     I2 @S9S_MB_2U_LIB.S9S_MB_2U(SCH_1):PAGE73
    U1  P59 VSS1721 SOCKET4677_AZIF0045P001C01CS-SA     I2 @S9S_MB_2U_LIB.S9S_MB_2U(SCH_1):PAGE73
    U1  P63 VSS1722 SOCKET4677_AZIF0045P001C01CS-SA     I2 @S9S_MB_2U_LIB.S9S_MB_2U(SCH_1):PAGE73
    U1  R48 VSS1723 SOCKET4677_AZIF0045P001C01CS-SA     I2 @S9S_MB_2U_LIB.S9S_MB_2U(SCH_1):PAGE73
    U1  P65 VSS1724 SOCKET4677_AZIF0045P001C01CS-SA     I2 @S9S_MB_2U_LIB.S9S_MB_2U(SCH_1):PAGE73
    U1  P69 VSS1725 SOCKET4677_AZIF0045P001C01CS-SA     I2 @S9S_MB_2U_LIB.S9S_MB_2U(SCH_1):PAGE73
    U1  P75 VSS1726 SOCKET4677_AZIF0045P001C01CS-SA     I2 @S9S_MB_2U_LIB.S9S_MB_2U(SCH_1):PAGE73
    U1  P77 VSS1727 SOCKET4677_AZIF0045P001C01CS-SA     I2 @S9S_MB_2U_LIB.S9S_MB_2U(SCH_1):PAGE73
    U1  R60 VSS1728 SOCKET4677_AZIF0045P001C01CS-SA     I2 @S9S_MB_2U_LIB.S9S_MB_2U(SCH_1):PAGE73
    U1   P8 VSS1729 SOCKET4677_AZIF0045P001C01CS-SA     I2 @S9S_MB_2U_LIB.S9S_MB_2U(SCH_1):PAGE73
    U1  R66 VSS1730 SOCKET4677_AZIF0045P001C01CS-SA     I2 @S9S_MB_2U_LIB.S9S_MB_2U(SCH_1):PAGE73
    U1  P87 VSS1731 SOCKET4677_AZIF0045P001C01CS-SA     I2 @S9S_MB_2U_LIB.S9S_MB_2U(SCH_1):PAGE73
    U1  P91 VSS1732 SOCKET4677_AZIF0045P001C01CS-SA     I2 @S9S_MB_2U_LIB.S9S_MB_2U(SCH_1):PAGE73
    U1  R13 VSS1733 SOCKET4677_AZIF0045P001C01CS-SA     I2 @S9S_MB_2U_LIB.S9S_MB_2U(SCH_1):PAGE73
    U1  R17 VSS1734 SOCKET4677_AZIF0045P001C01CS-SA     I2 @S9S_MB_2U_LIB.S9S_MB_2U(SCH_1):PAGE73
    U1  R25 VSS1735 SOCKET4677_AZIF0045P001C01CS-SA     I2 @S9S_MB_2U_LIB.S9S_MB_2U(SCH_1):PAGE73
    U1  R29 VSS1736 SOCKET4677_AZIF0045P001C01CS-SA     I2 @S9S_MB_2U_LIB.S9S_MB_2U(SCH_1):PAGE73
    U1  R31 VSS1737 SOCKET4677_AZIF0045P001C01CS-SA     I2 @S9S_MB_2U_LIB.S9S_MB_2U(SCH_1):PAGE73
    U1  R35 VSS1738 SOCKET4677_AZIF0045P001C01CS-SA     I2 @S9S_MB_2U_LIB.S9S_MB_2U(SCH_1):PAGE73
    U1  T12 VSS1739 SOCKET4677_AZIF0045P001C01CS-SA     I2 @S9S_MB_2U_LIB.S9S_MB_2U(SCH_1):PAGE73
    U1  T16 VSS1740 SOCKET4677_AZIF0045P001C01CS-SA     I2 @S9S_MB_2U_LIB.S9S_MB_2U(SCH_1):PAGE73
    U1  T18 VSS1741 SOCKET4677_AZIF0045P001C01CS-SA     I2 @S9S_MB_2U_LIB.S9S_MB_2U(SCH_1):PAGE73
    U1  R37 VSS1742 SOCKET4677_AZIF0045P001C01CS-SA     I2 @S9S_MB_2U_LIB.S9S_MB_2U(SCH_1):PAGE73
    U1  R41 VSS1743 SOCKET4677_AZIF0045P001C01CS-SA     I2 @S9S_MB_2U_LIB.S9S_MB_2U(SCH_1):PAGE73
    U1  R43 VSS1744 SOCKET4677_AZIF0045P001C01CS-SA     I2 @S9S_MB_2U_LIB.S9S_MB_2U(SCH_1):PAGE73
    U1   R5 VSS1745 SOCKET4677_AZIF0045P001C01CS-SA     I2 @S9S_MB_2U_LIB.S9S_MB_2U(SCH_1):PAGE73
    U1  T36 VSS1746 SOCKET4677_AZIF0045P001C01CS-SA     I2 @S9S_MB_2U_LIB.S9S_MB_2U(SCH_1):PAGE73
    U1  R50 VSS1747 SOCKET4677_AZIF0045P001C01CS-SA     I2 @S9S_MB_2U_LIB.S9S_MB_2U(SCH_1):PAGE73
    U1  R54 VSS1748 SOCKET4677_AZIF0045P001C01CS-SA     I2 @S9S_MB_2U_LIB.S9S_MB_2U(SCH_1):PAGE73
    U1  T49 VSS1749 SOCKET4677_AZIF0045P001C01CS-SA     I2 @S9S_MB_2U_LIB.S9S_MB_2U(SCH_1):PAGE73
    U1  T55 VSS1750 SOCKET4677_AZIF0045P001C01CS-SA     I2 @S9S_MB_2U_LIB.S9S_MB_2U(SCH_1):PAGE73
    U1  R56 VSS1751 SOCKET4677_AZIF0045P001C01CS-SA     I2 @S9S_MB_2U_LIB.S9S_MB_2U(SCH_1):PAGE73
    U1  R62 VSS1752 SOCKET4677_AZIF0045P001C01CS-SA     I2 @S9S_MB_2U_LIB.S9S_MB_2U(SCH_1):PAGE73
    U1  R68 VSS1753 SOCKET4677_AZIF0045P001C01CS-SA     I2 @S9S_MB_2U_LIB.S9S_MB_2U(SCH_1):PAGE73
    U1  R72 VSS1754 SOCKET4677_AZIF0045P001C01CS-SA     I2 @S9S_MB_2U_LIB.S9S_MB_2U(SCH_1):PAGE73
    U1  R74 VSS1755 SOCKET4677_AZIF0045P001C01CS-SA     I2 @S9S_MB_2U_LIB.S9S_MB_2U(SCH_1):PAGE73
    U1  R78 VSS1756 SOCKET4677_AZIF0045P001C01CS-SA     I2 @S9S_MB_2U_LIB.S9S_MB_2U(SCH_1):PAGE73
    U1  R84 VSS1757 SOCKET4677_AZIF0045P001C01CS-SA     I2 @S9S_MB_2U_LIB.S9S_MB_2U(SCH_1):PAGE73
    U1  R88 VSS1758 SOCKET4677_AZIF0045P001C01CS-SA     I2 @S9S_MB_2U_LIB.S9S_MB_2U(SCH_1):PAGE73
    U1   R9 VSS1759 SOCKET4677_AZIF0045P001C01CS-SA     I2 @S9S_MB_2U_LIB.S9S_MB_2U(SCH_1):PAGE73
    U1  T24 VSS1760 SOCKET4677_AZIF0045P001C01CS-SA     I2 @S9S_MB_2U_LIB.S9S_MB_2U(SCH_1):PAGE73
    U1  T30 VSS1761 SOCKET4677_AZIF0045P001C01CS-SA     I2 @S9S_MB_2U_LIB.S9S_MB_2U(SCH_1):PAGE73
    U1   T4 VSS1762 SOCKET4677_AZIF0045P001C01CS-SA     I2 @S9S_MB_2U_LIB.S9S_MB_2U(SCH_1):PAGE73
    U1  T42 VSS1763 SOCKET4677_AZIF0045P001C01CS-SA     I2 @S9S_MB_2U_LIB.S9S_MB_2U(SCH_1):PAGE73
    U1  T61 VSS1764 SOCKET4677_AZIF0045P001C01CS-SA     I2 @S9S_MB_2U_LIB.S9S_MB_2U(SCH_1):PAGE73
    U1  T67 VSS1765 SOCKET4677_AZIF0045P001C01CS-SA     I2 @S9S_MB_2U_LIB.S9S_MB_2U(SCH_1):PAGE73
    U1  U52 VSS1766 SOCKET4677_AZIF0045P001C01CS-SA     I2 @S9S_MB_2U_LIB.S9S_MB_2U(SCH_1):PAGE73
    U1  T73 VSS1767 SOCKET4677_AZIF0045P001C01CS-SA     I2 @S9S_MB_2U_LIB.S9S_MB_2U(SCH_1):PAGE73
    U1  T79 VSS1768 SOCKET4677_AZIF0045P001C01CS-SA     I2 @S9S_MB_2U_LIB.S9S_MB_2U(SCH_1):PAGE73
    U1   T8 VSS1769 SOCKET4677_AZIF0045P001C01CS-SA     I2 @S9S_MB_2U_LIB.S9S_MB_2U(SCH_1):PAGE73
    U1  T83 VSS1770 SOCKET4677_AZIF0045P001C01CS-SA     I2 @S9S_MB_2U_LIB.S9S_MB_2U(SCH_1):PAGE73
    U1  U39 VSS1771 SOCKET4677_AZIF0045P001C01CS-SA     I2 @S9S_MB_2U_LIB.S9S_MB_2U(SCH_1):PAGE73
    U1  U82 VSS1772 SOCKET4677_AZIF0045P001C01CS-SA     I2 @S9S_MB_2U_LIB.S9S_MB_2U(SCH_1):PAGE73
    U1  U84 VSS1773 SOCKET4677_AZIF0045P001C01CS-SA     I2 @S9S_MB_2U_LIB.S9S_MB_2U(SCH_1):PAGE73
    U1  U88 VSS1774 SOCKET4677_AZIF0045P001C01CS-SA     I2 @S9S_MB_2U_LIB.S9S_MB_2U(SCH_1):PAGE73
    U1  V12 VSS1775 SOCKET4677_AZIF0045P001C01CS-SA     I2 @S9S_MB_2U_LIB.S9S_MB_2U(SCH_1):PAGE73
    U1  V16 VSS1776 SOCKET4677_AZIF0045P001C01CS-SA     I2 @S9S_MB_2U_LIB.S9S_MB_2U(SCH_1):PAGE73
    U1  V18 VSS1777 SOCKET4677_AZIF0045P001C01CS-SA     I2 @S9S_MB_2U_LIB.S9S_MB_2U(SCH_1):PAGE73
    U1  V20 VSS1778 SOCKET4677_AZIF0045P001C01CS-SA     I2 @S9S_MB_2U_LIB.S9S_MB_2U(SCH_1):PAGE73
    U1  V22 VSS1779 SOCKET4677_AZIF0045P001C01CS-SA     I2 @S9S_MB_2U_LIB.S9S_MB_2U(SCH_1):PAGE73
    U1  V24 VSS1780 SOCKET4677_AZIF0045P001C01CS-SA     I2 @S9S_MB_2U_LIB.S9S_MB_2U(SCH_1):PAGE73
    U1  V26 VSS1781 SOCKET4677_AZIF0045P001C01CS-SA     I2 @S9S_MB_2U_LIB.S9S_MB_2U(SCH_1):PAGE73
    U1  V28 VSS1782 SOCKET4677_AZIF0045P001C01CS-SA     I2 @S9S_MB_2U_LIB.S9S_MB_2U(SCH_1):PAGE73
    U1  V30 VSS1783 SOCKET4677_AZIF0045P001C01CS-SA     I2 @S9S_MB_2U_LIB.S9S_MB_2U(SCH_1):PAGE73
    U1  V32 VSS1784 SOCKET4677_AZIF0045P001C01CS-SA     I2 @S9S_MB_2U_LIB.S9S_MB_2U(SCH_1):PAGE73
    U1  V34 VSS1785 SOCKET4677_AZIF0045P001C01CS-SA     I2 @S9S_MB_2U_LIB.S9S_MB_2U(SCH_1):PAGE73
    U1  V36 VSS1786 SOCKET4677_AZIF0045P001C01CS-SA     I2 @S9S_MB_2U_LIB.S9S_MB_2U(SCH_1):PAGE73
    U1  V38 VSS1787 SOCKET4677_AZIF0045P001C01CS-SA     I2 @S9S_MB_2U_LIB.S9S_MB_2U(SCH_1):PAGE73
    U1   V4 VSS1788 SOCKET4677_AZIF0045P001C01CS-SA     I2 @S9S_MB_2U_LIB.S9S_MB_2U(SCH_1):PAGE73
    U1  V49 VSS1789 SOCKET4677_AZIF0045P001C01CS-SA     I2 @S9S_MB_2U_LIB.S9S_MB_2U(SCH_1):PAGE73
    U1  V40 VSS1790 SOCKET4677_AZIF0045P001C01CS-SA     I2 @S9S_MB_2U_LIB.S9S_MB_2U(SCH_1):PAGE73
    U1  V42 VSS1791 SOCKET4677_AZIF0045P001C01CS-SA     I2 @S9S_MB_2U_LIB.S9S_MB_2U(SCH_1):PAGE73
    U1  V44 VSS1792 SOCKET4677_AZIF0045P001C01CS-SA     I2 @S9S_MB_2U_LIB.S9S_MB_2U(SCH_1):PAGE73
    U1  V47 VSS1793 SOCKET4677_AZIF0045P001C01CS-SA     I2 @S9S_MB_2U_LIB.S9S_MB_2U(SCH_1):PAGE73
    U1  V51 VSS1794 SOCKET4677_AZIF0045P001C01CS-SA     I2 @S9S_MB_2U_LIB.S9S_MB_2U(SCH_1):PAGE73
    U1  V53 VSS1795 SOCKET4677_AZIF0045P001C01CS-SA     I2 @S9S_MB_2U_LIB.S9S_MB_2U(SCH_1):PAGE73
    U1  V55 VSS1796 SOCKET4677_AZIF0045P001C01CS-SA     I2 @S9S_MB_2U_LIB.S9S_MB_2U(SCH_1):PAGE73
    U1  V57 VSS1797 SOCKET4677_AZIF0045P001C01CS-SA     I2 @S9S_MB_2U_LIB.S9S_MB_2U(SCH_1):PAGE73
    U1  V59 VSS1798 SOCKET4677_AZIF0045P001C01CS-SA     I2 @S9S_MB_2U_LIB.S9S_MB_2U(SCH_1):PAGE73
    U1  V61 VSS1799 SOCKET4677_AZIF0045P001C01CS-SA     I2 @S9S_MB_2U_LIB.S9S_MB_2U(SCH_1):PAGE73
    U1  V71 VSS1800 SOCKET4677_AZIF0045P001C01CS-SA     I2 @S9S_MB_2U_LIB.S9S_MB_2U(SCH_1):PAGE73
    U1  V73 VSS1801 SOCKET4677_AZIF0045P001C01CS-SA     I2 @S9S_MB_2U_LIB.S9S_MB_2U(SCH_1):PAGE73
    U1  V63 VSS1802 SOCKET4677_AZIF0045P001C01CS-SA     I2 @S9S_MB_2U_LIB.S9S_MB_2U(SCH_1):PAGE73
    U1  V65 VSS1803 SOCKET4677_AZIF0045P001C01CS-SA     I2 @S9S_MB_2U_LIB.S9S_MB_2U(SCH_1):PAGE73
    U1  V67 VSS1804 SOCKET4677_AZIF0045P001C01CS-SA     I2 @S9S_MB_2U_LIB.S9S_MB_2U(SCH_1):PAGE73
    U1  V69 VSS1805 SOCKET4677_AZIF0045P001C01CS-SA     I2 @S9S_MB_2U_LIB.S9S_MB_2U(SCH_1):PAGE73
    U1  V75 VSS1806 SOCKET4677_AZIF0045P001C01CS-SA     I2 @S9S_MB_2U_LIB.S9S_MB_2U(SCH_1):PAGE73
    U1  V91 VSS1807 SOCKET4677_AZIF0045P001C01CS-SA     I2 @S9S_MB_2U_LIB.S9S_MB_2U(SCH_1):PAGE73
    U1   W1 VSS1808 SOCKET4677_AZIF0045P001C01CS-SA     I2 @S9S_MB_2U_LIB.S9S_MB_2U(SCH_1):PAGE73
    U1  W13 VSS1809 SOCKET4677_AZIF0045P001C01CS-SA     I2 @S9S_MB_2U_LIB.S9S_MB_2U(SCH_1):PAGE73
    U1  V77 VSS1810 SOCKET4677_AZIF0045P001C01CS-SA     I2 @S9S_MB_2U_LIB.S9S_MB_2U(SCH_1):PAGE73
    U1  V79 VSS1811 SOCKET4677_AZIF0045P001C01CS-SA     I2 @S9S_MB_2U_LIB.S9S_MB_2U(SCH_1):PAGE73
    U1   V8 VSS1812 SOCKET4677_AZIF0045P001C01CS-SA     I2 @S9S_MB_2U_LIB.S9S_MB_2U(SCH_1):PAGE73
    U1  V87 VSS1813 SOCKET4677_AZIF0045P001C01CS-SA     I2 @S9S_MB_2U_LIB.S9S_MB_2U(SCH_1):PAGE73
    U1   W5 VSS1814 SOCKET4677_AZIF0045P001C01CS-SA     I2 @S9S_MB_2U_LIB.S9S_MB_2U(SCH_1):PAGE73
    U1  W52 VSS1815 SOCKET4677_AZIF0045P001C01CS-SA     I2 @S9S_MB_2U_LIB.S9S_MB_2U(SCH_1):PAGE73
    U1  W39 VSS1816 SOCKET4677_AZIF0045P001C01CS-SA     I2 @S9S_MB_2U_LIB.S9S_MB_2U(SCH_1):PAGE73
    U1  W84 VSS1817 SOCKET4677_AZIF0045P001C01CS-SA     I2 @S9S_MB_2U_LIB.S9S_MB_2U(SCH_1):PAGE73
    U1  W88 VSS1818 SOCKET4677_AZIF0045P001C01CS-SA     I2 @S9S_MB_2U_LIB.S9S_MB_2U(SCH_1):PAGE73
    U1   W9 VSS1819 SOCKET4677_AZIF0045P001C01CS-SA     I2 @S9S_MB_2U_LIB.S9S_MB_2U(SCH_1):PAGE73
    U1  Y12 VSS1820 SOCKET4677_AZIF0045P001C01CS-SA     I2 @S9S_MB_2U_LIB.S9S_MB_2U(SCH_1):PAGE73
    U1  Y16 VSS1821 SOCKET4677_AZIF0045P001C01CS-SA     I2 @S9S_MB_2U_LIB.S9S_MB_2U(SCH_1):PAGE73
    U1  Y18 VSS1822 SOCKET4677_AZIF0045P001C01CS-SA     I2 @S9S_MB_2U_LIB.S9S_MB_2U(SCH_1):PAGE73
    U1  Y24 VSS1823 SOCKET4677_AZIF0045P001C01CS-SA     I2 @S9S_MB_2U_LIB.S9S_MB_2U(SCH_1):PAGE73
    U1  Y30 VSS1824 SOCKET4677_AZIF0045P001C01CS-SA     I2 @S9S_MB_2U_LIB.S9S_MB_2U(SCH_1):PAGE73
    U1  Y36 VSS1825 SOCKET4677_AZIF0045P001C01CS-SA     I2 @S9S_MB_2U_LIB.S9S_MB_2U(SCH_1):PAGE73
    U1   Y4 VSS1826 SOCKET4677_AZIF0045P001C01CS-SA     I2 @S9S_MB_2U_LIB.S9S_MB_2U(SCH_1):PAGE73
    U1  Y42 VSS1827 SOCKET4677_AZIF0045P001C01CS-SA     I2 @S9S_MB_2U_LIB.S9S_MB_2U(SCH_1):PAGE73
    U1  Y61 VSS1828 SOCKET4677_AZIF0045P001C01CS-SA     I2 @S9S_MB_2U_LIB.S9S_MB_2U(SCH_1):PAGE73
    U1  Y67 VSS1829 SOCKET4677_AZIF0045P001C01CS-SA     I2 @S9S_MB_2U_LIB.S9S_MB_2U(SCH_1):PAGE73
    U1  Y49 VSS1830 SOCKET4677_AZIF0045P001C01CS-SA     I2 @S9S_MB_2U_LIB.S9S_MB_2U(SCH_1):PAGE73
    U1  Y55 VSS1831 SOCKET4677_AZIF0045P001C01CS-SA     I2 @S9S_MB_2U_LIB.S9S_MB_2U(SCH_1):PAGE73
    U1   Y8 VSS1832 SOCKET4677_AZIF0045P001C01CS-SA     I2 @S9S_MB_2U_LIB.S9S_MB_2U(SCH_1):PAGE73
    U1  Y73 VSS1833 SOCKET4677_AZIF0045P001C01CS-SA     I2 @S9S_MB_2U_LIB.S9S_MB_2U(SCH_1):PAGE73
    U1  E52 VSS1126 SOCKET4677_AZIF0045P001C01CS-SA     I5 @S9S_MB_2U_LIB.S9S_MB_2U(SCH_1):PAGE73
    U1  E74 VSS1129 SOCKET4677_AZIF0045P001C01CS-SA     I5 @S9S_MB_2U_LIB.S9S_MB_2U(SCH_1):PAGE73
    U1  E78 VSS1131 SOCKET4677_AZIF0045P001C01CS-SA     I5 @S9S_MB_2U_LIB.S9S_MB_2U(SCH_1):PAGE73
    U1  E76 VSS1272 SOCKET4677_AZIF0045P001C01CS-SA     I5 @S9S_MB_2U_LIB.S9S_MB_2U(SCH_1):PAGE73
    U1  E86 VSS1273 SOCKET4677_AZIF0045P001C01CS-SA     I5 @S9S_MB_2U_LIB.S9S_MB_2U(SCH_1):PAGE73
    U1  F12 VSS1494 SOCKET4677_AZIF0045P001C01CS-SA     I5 @S9S_MB_2U_LIB.S9S_MB_2U(SCH_1):PAGE73
    U1  F18 VSS1495 SOCKET4677_AZIF0045P001C01CS-SA     I5 @S9S_MB_2U_LIB.S9S_MB_2U(SCH_1):PAGE73
    U1  F42 VSS1502 SOCKET4677_AZIF0045P001C01CS-SA     I5 @S9S_MB_2U_LIB.S9S_MB_2U(SCH_1):PAGE73
    U1  F55 VSS1504 SOCKET4677_AZIF0045P001C01CS-SA     I5 @S9S_MB_2U_LIB.S9S_MB_2U(SCH_1):PAGE73
    U1   F6 VSS1507 SOCKET4677_AZIF0045P001C01CS-SA     I5 @S9S_MB_2U_LIB.S9S_MB_2U(SCH_1):PAGE73
    U1  F61 VSS1508 SOCKET4677_AZIF0045P001C01CS-SA     I5 @S9S_MB_2U_LIB.S9S_MB_2U(SCH_1):PAGE73
    U1  F67 VSS1509 SOCKET4677_AZIF0045P001C01CS-SA     I5 @S9S_MB_2U_LIB.S9S_MB_2U(SCH_1):PAGE73
    U1  F73 VSS1510 SOCKET4677_AZIF0045P001C01CS-SA     I5 @S9S_MB_2U_LIB.S9S_MB_2U(SCH_1):PAGE73
    U1  F79 VSS1511 SOCKET4677_AZIF0045P001C01CS-SA     I5 @S9S_MB_2U_LIB.S9S_MB_2U(SCH_1):PAGE73
    U1  G11 VSS1514 SOCKET4677_AZIF0045P001C01CS-SA     I5 @S9S_MB_2U_LIB.S9S_MB_2U(SCH_1):PAGE73
    U1  G17 VSS1516 SOCKET4677_AZIF0045P001C01CS-SA     I5 @S9S_MB_2U_LIB.S9S_MB_2U(SCH_1):PAGE73
    U1  G25 VSS1519 SOCKET4677_AZIF0045P001C01CS-SA     I5 @S9S_MB_2U_LIB.S9S_MB_2U(SCH_1):PAGE73
    U1   G3 VSS1521 SOCKET4677_AZIF0045P001C01CS-SA     I5 @S9S_MB_2U_LIB.S9S_MB_2U(SCH_1):PAGE73
    U1  G35 VSS1523 SOCKET4677_AZIF0045P001C01CS-SA     I5 @S9S_MB_2U_LIB.S9S_MB_2U(SCH_1):PAGE73
    U1  G48 VSS1527 SOCKET4677_AZIF0045P001C01CS-SA     I5 @S9S_MB_2U_LIB.S9S_MB_2U(SCH_1):PAGE73
    U1  G60 VSS1532 SOCKET4677_AZIF0045P001C01CS-SA     I5 @S9S_MB_2U_LIB.S9S_MB_2U(SCH_1):PAGE73
    U1  G66 VSS1534 SOCKET4677_AZIF0045P001C01CS-SA     I5 @S9S_MB_2U_LIB.S9S_MB_2U(SCH_1):PAGE73
    U1  G68 VSS1535 SOCKET4677_AZIF0045P001C01CS-SA     I5 @S9S_MB_2U_LIB.S9S_MB_2U(SCH_1):PAGE73
    U1   G7 VSS1536 SOCKET4677_AZIF0045P001C01CS-SA     I5 @S9S_MB_2U_LIB.S9S_MB_2U(SCH_1):PAGE73
    U1  G74 VSS1538 SOCKET4677_AZIF0045P001C01CS-SA     I5 @S9S_MB_2U_LIB.S9S_MB_2U(SCH_1):PAGE73
    U1  H14 VSS1544 SOCKET4677_AZIF0045P001C01CS-SA     I5 @S9S_MB_2U_LIB.S9S_MB_2U(SCH_1):PAGE73
    U1   H2 VSS1546 SOCKET4677_AZIF0045P001C01CS-SA     I5 @S9S_MB_2U_LIB.S9S_MB_2U(SCH_1):PAGE73
    U1  H51 VSS1558 SOCKET4677_AZIF0045P001C01CS-SA     I5 @S9S_MB_2U_LIB.S9S_MB_2U(SCH_1):PAGE73
    U1  H57 VSS1560 SOCKET4677_AZIF0045P001C01CS-SA     I5 @S9S_MB_2U_LIB.S9S_MB_2U(SCH_1):PAGE73
    U1  H65 VSS1564 SOCKET4677_AZIF0045P001C01CS-SA     I5 @S9S_MB_2U_LIB.S9S_MB_2U(SCH_1):PAGE73
    U1  H75 VSS1567 SOCKET4677_AZIF0045P001C01CS-SA     I5 @S9S_MB_2U_LIB.S9S_MB_2U(SCH_1):PAGE73
    U1  F24 VSS1570 SOCKET4677_AZIF0045P001C01CS-SA     I5 @S9S_MB_2U_LIB.S9S_MB_2U(SCH_1):PAGE73
    U1  F30 VSS1571 SOCKET4677_AZIF0045P001C01CS-SA     I5 @S9S_MB_2U_LIB.S9S_MB_2U(SCH_1):PAGE73
    U1  F36 VSS1572 SOCKET4677_AZIF0045P001C01CS-SA     I5 @S9S_MB_2U_LIB.S9S_MB_2U(SCH_1):PAGE73
    U1   F4 VSS1573 SOCKET4677_AZIF0045P001C01CS-SA     I5 @S9S_MB_2U_LIB.S9S_MB_2U(SCH_1):PAGE73
    U1  F49 VSS1574 SOCKET4677_AZIF0045P001C01CS-SA     I5 @S9S_MB_2U_LIB.S9S_MB_2U(SCH_1):PAGE73
    U1  J21 VSS1575 SOCKET4677_AZIF0045P001C01CS-SA     I5 @S9S_MB_2U_LIB.S9S_MB_2U(SCH_1):PAGE73
    U1  F83 VSS1576 SOCKET4677_AZIF0045P001C01CS-SA     I5 @S9S_MB_2U_LIB.S9S_MB_2U(SCH_1):PAGE73
    U1  F89 VSS1577 SOCKET4677_AZIF0045P001C01CS-SA     I5 @S9S_MB_2U_LIB.S9S_MB_2U(SCH_1):PAGE73
    U1  G13 VSS1578 SOCKET4677_AZIF0045P001C01CS-SA     I5 @S9S_MB_2U_LIB.S9S_MB_2U(SCH_1):PAGE73
    U1  G19 VSS1579 SOCKET4677_AZIF0045P001C01CS-SA     I5 @S9S_MB_2U_LIB.S9S_MB_2U(SCH_1):PAGE73
    U1  J39 VSS1580 SOCKET4677_AZIF0045P001C01CS-SA     I5 @S9S_MB_2U_LIB.S9S_MB_2U(SCH_1):PAGE73
    U1  G23 VSS1581 SOCKET4677_AZIF0045P001C01CS-SA     I5 @S9S_MB_2U_LIB.S9S_MB_2U(SCH_1):PAGE73
    U1   J5 VSS1582 SOCKET4677_AZIF0045P001C01CS-SA     I5 @S9S_MB_2U_LIB.S9S_MB_2U(SCH_1):PAGE73
    U1  G29 VSS1583 SOCKET4677_AZIF0045P001C01CS-SA     I5 @S9S_MB_2U_LIB.S9S_MB_2U(SCH_1):PAGE73
    U1  G31 VSS1584 SOCKET4677_AZIF0045P001C01CS-SA     I5 @S9S_MB_2U_LIB.S9S_MB_2U(SCH_1):PAGE73
    U1  G37 VSS1585 SOCKET4677_AZIF0045P001C01CS-SA     I5 @S9S_MB_2U_LIB.S9S_MB_2U(SCH_1):PAGE73
    U1  G41 VSS1586 SOCKET4677_AZIF0045P001C01CS-SA     I5 @S9S_MB_2U_LIB.S9S_MB_2U(SCH_1):PAGE73
    U1  J64 VSS1587 SOCKET4677_AZIF0045P001C01CS-SA     I5 @S9S_MB_2U_LIB.S9S_MB_2U(SCH_1):PAGE73
    U1  G43 VSS1588 SOCKET4677_AZIF0045P001C01CS-SA     I5 @S9S_MB_2U_LIB.S9S_MB_2U(SCH_1):PAGE73
    U1  J70 VSS1589 SOCKET4677_AZIF0045P001C01CS-SA     I5 @S9S_MB_2U_LIB.S9S_MB_2U(SCH_1):PAGE73
    U1  G50 VSS1590 SOCKET4677_AZIF0045P001C01CS-SA     I5 @S9S_MB_2U_LIB.S9S_MB_2U(SCH_1):PAGE73
    U1  G54 VSS1591 SOCKET4677_AZIF0045P001C01CS-SA     I5 @S9S_MB_2U_LIB.S9S_MB_2U(SCH_1):PAGE73
    U1  G56 VSS1592 SOCKET4677_AZIF0045P001C01CS-SA     I5 @S9S_MB_2U_LIB.S9S_MB_2U(SCH_1):PAGE73
    U1  G62 VSS1593 SOCKET4677_AZIF0045P001C01CS-SA     I5 @S9S_MB_2U_LIB.S9S_MB_2U(SCH_1):PAGE73
    U1  G72 VSS1594 SOCKET4677_AZIF0045P001C01CS-SA     I5 @S9S_MB_2U_LIB.S9S_MB_2U(SCH_1):PAGE73
    U1  J88 VSS1595 SOCKET4677_AZIF0045P001C01CS-SA     I5 @S9S_MB_2U_LIB.S9S_MB_2U(SCH_1):PAGE73
    U1   J9 VSS1596 SOCKET4677_AZIF0045P001C01CS-SA     I5 @S9S_MB_2U_LIB.S9S_MB_2U(SCH_1):PAGE73
    U1  K12 VSS1597 SOCKET4677_AZIF0045P001C01CS-SA     I5 @S9S_MB_2U_LIB.S9S_MB_2U(SCH_1):PAGE73
    U1  K14 VSS1598 SOCKET4677_AZIF0045P001C01CS-SA     I5 @S9S_MB_2U_LIB.S9S_MB_2U(SCH_1):PAGE73
    U1   K2 VSS1599 SOCKET4677_AZIF0045P001C01CS-SA     I5 @S9S_MB_2U_LIB.S9S_MB_2U(SCH_1):PAGE73
    U1  G84 VSS1600 SOCKET4677_AZIF0045P001C01CS-SA     I5 @S9S_MB_2U_LIB.S9S_MB_2U(SCH_1):PAGE73
    U1  G88 VSS1601 SOCKET4677_AZIF0045P001C01CS-SA     I5 @S9S_MB_2U_LIB.S9S_MB_2U(SCH_1):PAGE73
    U1  K42 VSS1602 SOCKET4677_AZIF0045P001C01CS-SA     I5 @S9S_MB_2U_LIB.S9S_MB_2U(SCH_1):PAGE73
    U1  K49 VSS1603 SOCKET4677_AZIF0045P001C01CS-SA     I5 @S9S_MB_2U_LIB.S9S_MB_2U(SCH_1):PAGE73
    U1  G90 VSS1604 SOCKET4677_AZIF0045P001C01CS-SA     I5 @S9S_MB_2U_LIB.S9S_MB_2U(SCH_1):PAGE73
    U1  H10 VSS1605 SOCKET4677_AZIF0045P001C01CS-SA     I5 @S9S_MB_2U_LIB.S9S_MB_2U(SCH_1):PAGE73
    U1  H16 VSS1606 SOCKET4677_AZIF0045P001C01CS-SA     I5 @S9S_MB_2U_LIB.S9S_MB_2U(SCH_1):PAGE73
    U1  H20 VSS1607 SOCKET4677_AZIF0045P001C01CS-SA     I5 @S9S_MB_2U_LIB.S9S_MB_2U(SCH_1):PAGE73
    U1  H22 VSS1608 SOCKET4677_AZIF0045P001C01CS-SA     I5 @S9S_MB_2U_LIB.S9S_MB_2U(SCH_1):PAGE73
    U1  H26 VSS1609 SOCKET4677_AZIF0045P001C01CS-SA     I5 @S9S_MB_2U_LIB.S9S_MB_2U(SCH_1):PAGE73
    U1  H28 VSS1610 SOCKET4677_AZIF0045P001C01CS-SA     I5 @S9S_MB_2U_LIB.S9S_MB_2U(SCH_1):PAGE73
    U1  H32 VSS1611 SOCKET4677_AZIF0045P001C01CS-SA     I5 @S9S_MB_2U_LIB.S9S_MB_2U(SCH_1):PAGE73
    U1  H34 VSS1612 SOCKET4677_AZIF0045P001C01CS-SA     I5 @S9S_MB_2U_LIB.S9S_MB_2U(SCH_1):PAGE73
    U1  H38 VSS1613 SOCKET4677_AZIF0045P001C01CS-SA     I5 @S9S_MB_2U_LIB.S9S_MB_2U(SCH_1):PAGE73
    U1  L19 VSS1614 SOCKET4677_AZIF0045P001C01CS-SA     I5 @S9S_MB_2U_LIB.S9S_MB_2U(SCH_1):PAGE73
    U1   H4 VSS1615 SOCKET4677_AZIF0045P001C01CS-SA     I5 @S9S_MB_2U_LIB.S9S_MB_2U(SCH_1):PAGE73
    U1  H40 VSS1616 SOCKET4677_AZIF0045P001C01CS-SA     I5 @S9S_MB_2U_LIB.S9S_MB_2U(SCH_1):PAGE73
    U1  H44 VSS1617 SOCKET4677_AZIF0045P001C01CS-SA     I5 @S9S_MB_2U_LIB.S9S_MB_2U(SCH_1):PAGE73
    U1  H47 VSS1618 SOCKET4677_AZIF0045P001C01CS-SA     I5 @S9S_MB_2U_LIB.S9S_MB_2U(SCH_1):PAGE73
    U1  H53 VSS1619 SOCKET4677_AZIF0045P001C01CS-SA     I5 @S9S_MB_2U_LIB.S9S_MB_2U(SCH_1):PAGE73
    U1  H59 VSS1620 SOCKET4677_AZIF0045P001C01CS-SA     I5 @S9S_MB_2U_LIB.S9S_MB_2U(SCH_1):PAGE73
    U1   H6 VSS1621 SOCKET4677_AZIF0045P001C01CS-SA     I5 @S9S_MB_2U_LIB.S9S_MB_2U(SCH_1):PAGE73
    U1  H63 VSS1622 SOCKET4677_AZIF0045P001C01CS-SA     I5 @S9S_MB_2U_LIB.S9S_MB_2U(SCH_1):PAGE73
    U1  H69 VSS1623 SOCKET4677_AZIF0045P001C01CS-SA     I5 @S9S_MB_2U_LIB.S9S_MB_2U(SCH_1):PAGE73
    U1  H71 VSS1624 SOCKET4677_AZIF0045P001C01CS-SA     I5 @S9S_MB_2U_LIB.S9S_MB_2U(SCH_1):PAGE73
    U1  H79 VSS1625 SOCKET4677_AZIF0045P001C01CS-SA     I5 @S9S_MB_2U_LIB.S9S_MB_2U(SCH_1):PAGE73
    U1   H8 VSS1626 SOCKET4677_AZIF0045P001C01CS-SA     I5 @S9S_MB_2U_LIB.S9S_MB_2U(SCH_1):PAGE73
    U1  H81 VSS1627 SOCKET4677_AZIF0045P001C01CS-SA     I5 @S9S_MB_2U_LIB.S9S_MB_2U(SCH_1):PAGE73
    U1  J15 VSS1628 SOCKET4677_AZIF0045P001C01CS-SA     I5 @S9S_MB_2U_LIB.S9S_MB_2U(SCH_1):PAGE73
    U1  J27 VSS1629 SOCKET4677_AZIF0045P001C01CS-SA     I5 @S9S_MB_2U_LIB.S9S_MB_2U(SCH_1):PAGE73
    U1  J33 VSS1630 SOCKET4677_AZIF0045P001C01CS-SA     I5 @S9S_MB_2U_LIB.S9S_MB_2U(SCH_1):PAGE73
    U1  J45 VSS1631 SOCKET4677_AZIF0045P001C01CS-SA     I5 @S9S_MB_2U_LIB.S9S_MB_2U(SCH_1):PAGE73
    U1  J52 VSS1632 SOCKET4677_AZIF0045P001C01CS-SA     I5 @S9S_MB_2U_LIB.S9S_MB_2U(SCH_1):PAGE73
    U1  J58 VSS1633 SOCKET4677_AZIF0045P001C01CS-SA     I5 @S9S_MB_2U_LIB.S9S_MB_2U(SCH_1):PAGE73
    U1  L58 VSS1634 SOCKET4677_AZIF0045P001C01CS-SA     I5 @S9S_MB_2U_LIB.S9S_MB_2U(SCH_1):PAGE73
    U1  J76 VSS1635 SOCKET4677_AZIF0045P001C01CS-SA     I5 @S9S_MB_2U_LIB.S9S_MB_2U(SCH_1):PAGE73
    U1  J78 VSS1636 SOCKET4677_AZIF0045P001C01CS-SA     I5 @S9S_MB_2U_LIB.S9S_MB_2U(SCH_1):PAGE73
    U1  J84 VSS1637 SOCKET4677_AZIF0045P001C01CS-SA     I5 @S9S_MB_2U_LIB.S9S_MB_2U(SCH_1):PAGE73
    U1  J86 VSS1638 SOCKET4677_AZIF0045P001C01CS-SA     I5 @S9S_MB_2U_LIB.S9S_MB_2U(SCH_1):PAGE73
    U1  K77 VSS1639 SOCKET4677_AZIF0045P001C01CS-SA     I5 @S9S_MB_2U_LIB.S9S_MB_2U(SCH_1):PAGE73
    U1  L70 VSS1640 SOCKET4677_AZIF0045P001C01CS-SA     I5 @S9S_MB_2U_LIB.S9S_MB_2U(SCH_1):PAGE73
    U1   K8 VSS1641 SOCKET4677_AZIF0045P001C01CS-SA     I5 @S9S_MB_2U_LIB.S9S_MB_2U(SCH_1):PAGE73
    U1  K83 VSS1642 SOCKET4677_AZIF0045P001C01CS-SA     I5 @S9S_MB_2U_LIB.S9S_MB_2U(SCH_1):PAGE73
    U1  K85 VSS1643 SOCKET4677_AZIF0045P001C01CS-SA     I5 @S9S_MB_2U_LIB.S9S_MB_2U(SCH_1):PAGE73
    U1  L13 VSS1644 SOCKET4677_AZIF0045P001C01CS-SA     I5 @S9S_MB_2U_LIB.S9S_MB_2U(SCH_1):PAGE73
    U1  L15 VSS1645 SOCKET4677_AZIF0045P001C01CS-SA     I5 @S9S_MB_2U_LIB.S9S_MB_2U(SCH_1):PAGE73
    U1  L88 VSS1646 SOCKET4677_AZIF0045P001C01CS-SA     I5 @S9S_MB_2U_LIB.S9S_MB_2U(SCH_1):PAGE73
    U1   L9 VSS1647 SOCKET4677_AZIF0045P001C01CS-SA     I5 @S9S_MB_2U_LIB.S9S_MB_2U(SCH_1):PAGE73
    U1  L90 VSS1648 SOCKET4677_AZIF0045P001C01CS-SA     I5 @S9S_MB_2U_LIB.S9S_MB_2U(SCH_1):PAGE73
    U1  M12 VSS1649 SOCKET4677_AZIF0045P001C01CS-SA     I5 @S9S_MB_2U_LIB.S9S_MB_2U(SCH_1):PAGE73
    U1  L17 VSS1650 SOCKET4677_AZIF0045P001C01CS-SA     I5 @S9S_MB_2U_LIB.S9S_MB_2U(SCH_1):PAGE73
    U1  L21 VSS1651 SOCKET4677_AZIF0045P001C01CS-SA     I5 @S9S_MB_2U_LIB.S9S_MB_2U(SCH_1):PAGE73
    U1   M4 VSS1652 SOCKET4677_AZIF0045P001C01CS-SA     I5 @S9S_MB_2U_LIB.S9S_MB_2U(SCH_1):PAGE73
    U1  M42 VSS1653 SOCKET4677_AZIF0045P001C01CS-SA     I5 @S9S_MB_2U_LIB.S9S_MB_2U(SCH_1):PAGE73
    U1  M49 VSS1654 SOCKET4677_AZIF0045P001C01CS-SA     I5 @S9S_MB_2U_LIB.S9S_MB_2U(SCH_1):PAGE73
    U1  L23 VSS1655 SOCKET4677_AZIF0045P001C01CS-SA     I5 @S9S_MB_2U_LIB.S9S_MB_2U(SCH_1):PAGE73
    U1  L25 VSS1656 SOCKET4677_AZIF0045P001C01CS-SA     I5 @S9S_MB_2U_LIB.S9S_MB_2U(SCH_1):PAGE73
    U1   M8 VSS1657 SOCKET4677_AZIF0045P001C01CS-SA     I5 @S9S_MB_2U_LIB.S9S_MB_2U(SCH_1):PAGE73
    U1  L27 VSS1658 SOCKET4677_AZIF0045P001C01CS-SA     I5 @S9S_MB_2U_LIB.S9S_MB_2U(SCH_1):PAGE73
    U1  L29 VSS1659 SOCKET4677_AZIF0045P001C01CS-SA     I5 @S9S_MB_2U_LIB.S9S_MB_2U(SCH_1):PAGE73
    U1  L31 VSS1660 SOCKET4677_AZIF0045P001C01CS-SA     I5 @S9S_MB_2U_LIB.S9S_MB_2U(SCH_1):PAGE73
    U1  L33 VSS1661 SOCKET4677_AZIF0045P001C01CS-SA     I5 @S9S_MB_2U_LIB.S9S_MB_2U(SCH_1):PAGE73
    U1  L35 VSS1662 SOCKET4677_AZIF0045P001C01CS-SA     I5 @S9S_MB_2U_LIB.S9S_MB_2U(SCH_1):PAGE73
    U1  L37 VSS1663 SOCKET4677_AZIF0045P001C01CS-SA     I5 @S9S_MB_2U_LIB.S9S_MB_2U(SCH_1):PAGE73
    U1  N21 VSS1664 SOCKET4677_AZIF0045P001C01CS-SA     I5 @S9S_MB_2U_LIB.S9S_MB_2U(SCH_1):PAGE73
    U1  L39 VSS1665 SOCKET4677_AZIF0045P001C01CS-SA     I5 @S9S_MB_2U_LIB.S9S_MB_2U(SCH_1):PAGE73
    U1  L41 VSS1666 SOCKET4677_AZIF0045P001C01CS-SA     I5 @S9S_MB_2U_LIB.S9S_MB_2U(SCH_1):PAGE73
    U1  L43 VSS1667 SOCKET4677_AZIF0045P001C01CS-SA     I5 @S9S_MB_2U_LIB.S9S_MB_2U(SCH_1):PAGE73
    U1  L45 VSS1668 SOCKET4677_AZIF0045P001C01CS-SA     I5 @S9S_MB_2U_LIB.S9S_MB_2U(SCH_1):PAGE73
    U1  N39 VSS1669 SOCKET4677_AZIF0045P001C01CS-SA     I5 @S9S_MB_2U_LIB.S9S_MB_2U(SCH_1):PAGE73
    U1  L48 VSS1670 SOCKET4677_AZIF0045P001C01CS-SA     I5 @S9S_MB_2U_LIB.S9S_MB_2U(SCH_1):PAGE73
    U1   L5 VSS1671 SOCKET4677_AZIF0045P001C01CS-SA     I5 @S9S_MB_2U_LIB.S9S_MB_2U(SCH_1):PAGE73
    U1  L50 VSS1672 SOCKET4677_AZIF0045P001C01CS-SA     I5 @S9S_MB_2U_LIB.S9S_MB_2U(SCH_1):PAGE73
    U1  L52 VSS1673 SOCKET4677_AZIF0045P001C01CS-SA     I5 @S9S_MB_2U_LIB.S9S_MB_2U(SCH_1):PAGE73
    U1  L54 VSS1674 SOCKET4677_AZIF0045P001C01CS-SA     I5 @S9S_MB_2U_LIB.S9S_MB_2U(SCH_1):PAGE73
    U1  N64 VSS1675 SOCKET4677_AZIF0045P001C01CS-SA     I5 @S9S_MB_2U_LIB.S9S_MB_2U(SCH_1):PAGE73
    U1  L56 VSS1676 SOCKET4677_AZIF0045P001C01CS-SA     I5 @S9S_MB_2U_LIB.S9S_MB_2U(SCH_1):PAGE73
    U1  L60 VSS1677 SOCKET4677_AZIF0045P001C01CS-SA     I5 @S9S_MB_2U_LIB.S9S_MB_2U(SCH_1):PAGE73
    U1  L62 VSS1678 SOCKET4677_AZIF0045P001C01CS-SA     I5 @S9S_MB_2U_LIB.S9S_MB_2U(SCH_1):PAGE73
    U1  L64 VSS1679 SOCKET4677_AZIF0045P001C01CS-SA     I5 @S9S_MB_2U_LIB.S9S_MB_2U(SCH_1):PAGE73
    U1  L66 VSS1680 SOCKET4677_AZIF0045P001C01CS-SA     I5 @S9S_MB_2U_LIB.S9S_MB_2U(SCH_1):PAGE73
    U1  L68 VSS1681 SOCKET4677_AZIF0045P001C01CS-SA     I5 @S9S_MB_2U_LIB.S9S_MB_2U(SCH_1):PAGE73
    U1  L72 VSS1682 SOCKET4677_AZIF0045P001C01CS-SA     I5 @S9S_MB_2U_LIB.S9S_MB_2U(SCH_1):PAGE73
    U1  L74 VSS1683 SOCKET4677_AZIF0045P001C01CS-SA     I5 @S9S_MB_2U_LIB.S9S_MB_2U(SCH_1):PAGE73
    U1  L76 VSS1684 SOCKET4677_AZIF0045P001C01CS-SA     I5 @S9S_MB_2U_LIB.S9S_MB_2U(SCH_1):PAGE73
    U1  L78 VSS1685 SOCKET4677_AZIF0045P001C01CS-SA     I5 @S9S_MB_2U_LIB.S9S_MB_2U(SCH_1):PAGE73
    U1  M81 VSS1686 SOCKET4677_AZIF0045P001C01CS-SA     I5 @S9S_MB_2U_LIB.S9S_MB_2U(SCH_1):PAGE73
    U1  M83 VSS1687 SOCKET4677_AZIF0045P001C01CS-SA     I5 @S9S_MB_2U_LIB.S9S_MB_2U(SCH_1):PAGE73
    U1  N15 VSS1688 SOCKET4677_AZIF0045P001C01CS-SA     I5 @S9S_MB_2U_LIB.S9S_MB_2U(SCH_1):PAGE73
    U1  N27 VSS1689 SOCKET4677_AZIF0045P001C01CS-SA     I5 @S9S_MB_2U_LIB.S9S_MB_2U(SCH_1):PAGE73
    U1  N33 VSS1691 SOCKET4677_AZIF0045P001C01CS-SA     I5 @S9S_MB_2U_LIB.S9S_MB_2U(SCH_1):PAGE73
    U1  N45 VSS1692 SOCKET4677_AZIF0045P001C01CS-SA     I5 @S9S_MB_2U_LIB.S9S_MB_2U(SCH_1):PAGE73
    U1  N52 VSS1693 SOCKET4677_AZIF0045P001C01CS-SA     I5 @S9S_MB_2U_LIB.S9S_MB_2U(SCH_1):PAGE73
    U1  N58 VSS1694 SOCKET4677_AZIF0045P001C01CS-SA     I5 @S9S_MB_2U_LIB.S9S_MB_2U(SCH_1):PAGE73
    U1  N70 VSS1695 SOCKET4677_AZIF0045P001C01CS-SA     I5 @S9S_MB_2U_LIB.S9S_MB_2U(SCH_1):PAGE73
    U1  A11   VSS1 SOCKET4677_AZIF0045P001C01CS-SA     I8 @S9S_MB_2U_LIB.S9S_MB_2U(SCH_1):PAGE73
    U1  A13   VSS2 SOCKET4677_AZIF0045P001C01CS-SA     I8 @S9S_MB_2U_LIB.S9S_MB_2U(SCH_1):PAGE73
    U1  A17   VSS3 SOCKET4677_AZIF0045P001C01CS-SA     I8 @S9S_MB_2U_LIB.S9S_MB_2U(SCH_1):PAGE73
    U1  A19   VSS4 SOCKET4677_AZIF0045P001C01CS-SA     I8 @S9S_MB_2U_LIB.S9S_MB_2U(SCH_1):PAGE73
    U1  A23   VSS5 SOCKET4677_AZIF0045P001C01CS-SA     I8 @S9S_MB_2U_LIB.S9S_MB_2U(SCH_1):PAGE73
    U1  A25   VSS6 SOCKET4677_AZIF0045P001C01CS-SA     I8 @S9S_MB_2U_LIB.S9S_MB_2U(SCH_1):PAGE73
    U1  A29   VSS7 SOCKET4677_AZIF0045P001C01CS-SA     I8 @S9S_MB_2U_LIB.S9S_MB_2U(SCH_1):PAGE73
    U1  A31   VSS8 SOCKET4677_AZIF0045P001C01CS-SA     I8 @S9S_MB_2U_LIB.S9S_MB_2U(SCH_1):PAGE73
    U1  A35   VSS9 SOCKET4677_AZIF0045P001C01CS-SA     I8 @S9S_MB_2U_LIB.S9S_MB_2U(SCH_1):PAGE73
    U1  A37  VSS10 SOCKET4677_AZIF0045P001C01CS-SA     I8 @S9S_MB_2U_LIB.S9S_MB_2U(SCH_1):PAGE73
    U1  A41  VSS11 SOCKET4677_AZIF0045P001C01CS-SA     I8 @S9S_MB_2U_LIB.S9S_MB_2U(SCH_1):PAGE73
    U1  A50  VSS12 SOCKET4677_AZIF0045P001C01CS-SA     I8 @S9S_MB_2U_LIB.S9S_MB_2U(SCH_1):PAGE73
    U1  A54  VSS13 SOCKET4677_AZIF0045P001C01CS-SA     I8 @S9S_MB_2U_LIB.S9S_MB_2U(SCH_1):PAGE73
    U1  A56  VSS14 SOCKET4677_AZIF0045P001C01CS-SA     I8 @S9S_MB_2U_LIB.S9S_MB_2U(SCH_1):PAGE73
    U1  A60  VSS15 SOCKET4677_AZIF0045P001C01CS-SA     I8 @S9S_MB_2U_LIB.S9S_MB_2U(SCH_1):PAGE73
    U1  A62  VSS16 SOCKET4677_AZIF0045P001C01CS-SA     I8 @S9S_MB_2U_LIB.S9S_MB_2U(SCH_1):PAGE73
    U1  B12 VSS378 SOCKET4677_AZIF0045P001C01CS-SA     I8 @S9S_MB_2U_LIB.S9S_MB_2U(SCH_1):PAGE73
    U1  B18 VSS379 SOCKET4677_AZIF0045P001C01CS-SA     I8 @S9S_MB_2U_LIB.S9S_MB_2U(SCH_1):PAGE73
    U1  B24 VSS380 SOCKET4677_AZIF0045P001C01CS-SA     I8 @S9S_MB_2U_LIB.S9S_MB_2U(SCH_1):PAGE73
    U1  B30 VSS381 SOCKET4677_AZIF0045P001C01CS-SA     I8 @S9S_MB_2U_LIB.S9S_MB_2U(SCH_1):PAGE73
    U1  B36 VSS382 SOCKET4677_AZIF0045P001C01CS-SA     I8 @S9S_MB_2U_LIB.S9S_MB_2U(SCH_1):PAGE73
    U1  B42 VSS384 SOCKET4677_AZIF0045P001C01CS-SA     I8 @S9S_MB_2U_LIB.S9S_MB_2U(SCH_1):PAGE73
    U1  B49 VSS385 SOCKET4677_AZIF0045P001C01CS-SA     I8 @S9S_MB_2U_LIB.S9S_MB_2U(SCH_1):PAGE73
    U1  B55 VSS386 SOCKET4677_AZIF0045P001C01CS-SA     I8 @S9S_MB_2U_LIB.S9S_MB_2U(SCH_1):PAGE73
    U1   B6 VSS387 SOCKET4677_AZIF0045P001C01CS-SA     I8 @S9S_MB_2U_LIB.S9S_MB_2U(SCH_1):PAGE73
    U1  B61 VSS388 SOCKET4677_AZIF0045P001C01CS-SA     I8 @S9S_MB_2U_LIB.S9S_MB_2U(SCH_1):PAGE73
    U1  B67 VSS389 SOCKET4677_AZIF0045P001C01CS-SA     I8 @S9S_MB_2U_LIB.S9S_MB_2U(SCH_1):PAGE73
    U1  B75 VSS390 SOCKET4677_AZIF0045P001C01CS-SA     I8 @S9S_MB_2U_LIB.S9S_MB_2U(SCH_1):PAGE73
    U1  B83 VSS391 SOCKET4677_AZIF0045P001C01CS-SA     I8 @S9S_MB_2U_LIB.S9S_MB_2U(SCH_1):PAGE73
    U1  B87 VSS392 SOCKET4677_AZIF0045P001C01CS-SA     I8 @S9S_MB_2U_LIB.S9S_MB_2U(SCH_1):PAGE73
    U1  C39 VSS609 SOCKET4677_AZIF0045P001C01CS-SA     I8 @S9S_MB_2U_LIB.S9S_MB_2U(SCH_1):PAGE73
    U1  C45 VSS610 SOCKET4677_AZIF0045P001C01CS-SA     I8 @S9S_MB_2U_LIB.S9S_MB_2U(SCH_1):PAGE73
    U1   C5 VSS612 SOCKET4677_AZIF0045P001C01CS-SA     I8 @S9S_MB_2U_LIB.S9S_MB_2U(SCH_1):PAGE73
    U1  C52 VSS613 SOCKET4677_AZIF0045P001C01CS-SA     I8 @S9S_MB_2U_LIB.S9S_MB_2U(SCH_1):PAGE73
    U1  C72 VSS614 SOCKET4677_AZIF0045P001C01CS-SA     I8 @S9S_MB_2U_LIB.S9S_MB_2U(SCH_1):PAGE73
    U1  C74 VSS615 SOCKET4677_AZIF0045P001C01CS-SA     I8 @S9S_MB_2U_LIB.S9S_MB_2U(SCH_1):PAGE73
    U1  C78 VSS616 SOCKET4677_AZIF0045P001C01CS-SA     I8 @S9S_MB_2U_LIB.S9S_MB_2U(SCH_1):PAGE73
    U1  C80 VSS617 SOCKET4677_AZIF0045P001C01CS-SA     I8 @S9S_MB_2U_LIB.S9S_MB_2U(SCH_1):PAGE73
    U1  C82 VSS618 SOCKET4677_AZIF0045P001C01CS-SA     I8 @S9S_MB_2U_LIB.S9S_MB_2U(SCH_1):PAGE73
    U1  C86 VSS619 SOCKET4677_AZIF0045P001C01CS-SA     I8 @S9S_MB_2U_LIB.S9S_MB_2U(SCH_1):PAGE73
    U1  D63 VSS657 SOCKET4677_AZIF0045P001C01CS-SA     I8 @S9S_MB_2U_LIB.S9S_MB_2U(SCH_1):PAGE73
    U1  D65 VSS658 SOCKET4677_AZIF0045P001C01CS-SA     I8 @S9S_MB_2U_LIB.S9S_MB_2U(SCH_1):PAGE73
    U1  D67 VSS659 SOCKET4677_AZIF0045P001C01CS-SA     I8 @S9S_MB_2U_LIB.S9S_MB_2U(SCH_1):PAGE73
    U1  D79 VSS662 SOCKET4677_AZIF0045P001C01CS-SA     I8 @S9S_MB_2U_LIB.S9S_MB_2U(SCH_1):PAGE73
    U1   D8 VSS663 SOCKET4677_AZIF0045P001C01CS-SA     I8 @S9S_MB_2U_LIB.S9S_MB_2U(SCH_1):PAGE73
    U1  D10 VSS864 SOCKET4677_AZIF0045P001C01CS-SA     I8 @S9S_MB_2U_LIB.S9S_MB_2U(SCH_1):PAGE73
    U1  D12 VSS865 SOCKET4677_AZIF0045P001C01CS-SA     I8 @S9S_MB_2U_LIB.S9S_MB_2U(SCH_1):PAGE73
    U1  D14 VSS866 SOCKET4677_AZIF0045P001C01CS-SA     I8 @S9S_MB_2U_LIB.S9S_MB_2U(SCH_1):PAGE73
    U1  D16 VSS868 SOCKET4677_AZIF0045P001C01CS-SA     I8 @S9S_MB_2U_LIB.S9S_MB_2U(SCH_1):PAGE73
    U1  D18 VSS869 SOCKET4677_AZIF0045P001C01CS-SA     I8 @S9S_MB_2U_LIB.S9S_MB_2U(SCH_1):PAGE73
    U1  D20 VSS871 SOCKET4677_AZIF0045P001C01CS-SA     I8 @S9S_MB_2U_LIB.S9S_MB_2U(SCH_1):PAGE73
    U1  D22 VSS873 SOCKET4677_AZIF0045P001C01CS-SA     I8 @S9S_MB_2U_LIB.S9S_MB_2U(SCH_1):PAGE73
    U1  D24 VSS874 SOCKET4677_AZIF0045P001C01CS-SA     I8 @S9S_MB_2U_LIB.S9S_MB_2U(SCH_1):PAGE73
    U1  D26 VSS875 SOCKET4677_AZIF0045P001C01CS-SA     I8 @S9S_MB_2U_LIB.S9S_MB_2U(SCH_1):PAGE73
    U1  D28 VSS876 SOCKET4677_AZIF0045P001C01CS-SA     I8 @S9S_MB_2U_LIB.S9S_MB_2U(SCH_1):PAGE73
    U1  D30 VSS877 SOCKET4677_AZIF0045P001C01CS-SA     I8 @S9S_MB_2U_LIB.S9S_MB_2U(SCH_1):PAGE73
    U1  D32 VSS878 SOCKET4677_AZIF0045P001C01CS-SA     I8 @S9S_MB_2U_LIB.S9S_MB_2U(SCH_1):PAGE73
    U1  D34 VSS879 SOCKET4677_AZIF0045P001C01CS-SA     I8 @S9S_MB_2U_LIB.S9S_MB_2U(SCH_1):PAGE73
    U1  D36 VSS881 SOCKET4677_AZIF0045P001C01CS-SA     I8 @S9S_MB_2U_LIB.S9S_MB_2U(SCH_1):PAGE73
    U1  D38 VSS884 SOCKET4677_AZIF0045P001C01CS-SA     I8 @S9S_MB_2U_LIB.S9S_MB_2U(SCH_1):PAGE73
    U1  D40 VSS885 SOCKET4677_AZIF0045P001C01CS-SA     I8 @S9S_MB_2U_LIB.S9S_MB_2U(SCH_1):PAGE73
    U1  D42 VSS886 SOCKET4677_AZIF0045P001C01CS-SA     I8 @S9S_MB_2U_LIB.S9S_MB_2U(SCH_1):PAGE73
    U1  D44 VSS888 SOCKET4677_AZIF0045P001C01CS-SA     I8 @S9S_MB_2U_LIB.S9S_MB_2U(SCH_1):PAGE73
    U1  D47 VSS889 SOCKET4677_AZIF0045P001C01CS-SA     I8 @S9S_MB_2U_LIB.S9S_MB_2U(SCH_1):PAGE73
    U1  D49 VSS891 SOCKET4677_AZIF0045P001C01CS-SA     I8 @S9S_MB_2U_LIB.S9S_MB_2U(SCH_1):PAGE73
    U1  D51 VSS892 SOCKET4677_AZIF0045P001C01CS-SA     I8 @S9S_MB_2U_LIB.S9S_MB_2U(SCH_1):PAGE73
    U1  D53 VSS895 SOCKET4677_AZIF0045P001C01CS-SA     I8 @S9S_MB_2U_LIB.S9S_MB_2U(SCH_1):PAGE73
    U1  D55 VSS896 SOCKET4677_AZIF0045P001C01CS-SA     I8 @S9S_MB_2U_LIB.S9S_MB_2U(SCH_1):PAGE73
    U1  D57 VSS897 SOCKET4677_AZIF0045P001C01CS-SA     I8 @S9S_MB_2U_LIB.S9S_MB_2U(SCH_1):PAGE73
    U1  D59 VSS898 SOCKET4677_AZIF0045P001C01CS-SA     I8 @S9S_MB_2U_LIB.S9S_MB_2U(SCH_1):PAGE73
    U1   D6 VSS899 SOCKET4677_AZIF0045P001C01CS-SA     I8 @S9S_MB_2U_LIB.S9S_MB_2U(SCH_1):PAGE73
    U1  D61 VSS900 SOCKET4677_AZIF0045P001C01CS-SA     I8 @S9S_MB_2U_LIB.S9S_MB_2U(SCH_1):PAGE73
    U1  D69 VSS901 SOCKET4677_AZIF0045P001C01CS-SA     I8 @S9S_MB_2U_LIB.S9S_MB_2U(SCH_1):PAGE73
    U1  D71 VSS902 SOCKET4677_AZIF0045P001C01CS-SA     I8 @S9S_MB_2U_LIB.S9S_MB_2U(SCH_1):PAGE73
    U1  D81 VSS906 SOCKET4677_AZIF0045P001C01CS-SA     I8 @S9S_MB_2U_LIB.S9S_MB_2U(SCH_1):PAGE73
    U1  D83 VSS907 SOCKET4677_AZIF0045P001C01CS-SA     I8 @S9S_MB_2U_LIB.S9S_MB_2U(SCH_1):PAGE73
    U1   E5 VSS1125 SOCKET4677_AZIF0045P001C01CS-SA     I8 @S9S_MB_2U_LIB.S9S_MB_2U(SCH_1):PAGE73
    U1  E39 VSS1271 SOCKET4677_AZIF0045P001C01CS-SA     I8 @S9S_MB_2U_LIB.S9S_MB_2U(SCH_1):PAGE73
  C407    2      B Q_CAP_C0402-22UF,4V,20%,X6S,CHA     I7 @S9S_MB_2U_LIB.S9S_MB_2U(SCH_1):PAGE74
  C409    2      B Q_CAP_C0402-22UF,4V,20%,X6S,CHA     I8 @S9S_MB_2U_LIB.S9S_MB_2U(SCH_1):PAGE74
  C411    2      B Q_CAP_C0402-22UF,4V,20%,X6S,CHA     I9 @S9S_MB_2U_LIB.S9S_MB_2U(SCH_1):PAGE74
  C413    2      B Q_CAP_C0402-22UF,4V,20%,X6S,CHA    I10 @S9S_MB_2U_LIB.S9S_MB_2U(SCH_1):PAGE74
  C101    2      B Q_CAP_C0805-47UF,4V,20%,X6S,CHA    I13 @S9S_MB_2U_LIB.S9S_MB_2U(SCH_1):PAGE74
  C969    2      B Q_CAP_C0402-10UF,6.3V,20%,X6S,B    I15 @S9S_MB_2U_LIB.S9S_MB_2U(SCH_1):PAGE74
  C401    2      B Q_CAP_C0402-22UF,4V,20%,X6S,CHA    I17 @S9S_MB_2U_LIB.S9S_MB_2U(SCH_1):PAGE74
  C212    2      B Q_CAP_C0805-47UF,4V,20%,X6S,CHA    I18 @S9S_MB_2U_LIB.S9S_MB_2U(SCH_1):PAGE74
  C403    2      B Q_CAP_C0402-22UF,4V,20%,X6S,CHA    I19 @S9S_MB_2U_LIB.S9S_MB_2U(SCH_1):PAGE74
  C213    2      B Q_CAP_C0805-47UF,4V,20%,X6S,CHA    I20 @S9S_MB_2U_LIB.S9S_MB_2U(SCH_1):PAGE74
  C973    2      B Q_CAP_C0402-10UF,6.3V,20%,X6S,B    I21 @S9S_MB_2U_LIB.S9S_MB_2U(SCH_1):PAGE74
  C977    2      B Q_CAP_C0402-10UF,6.3V,20%,X6S,B    I22 @S9S_MB_2U_LIB.S9S_MB_2U(SCH_1):PAGE74
  C968    2      B Q_CAP_C0402-10UF,6.3V,20%,X6S,B    I23 @S9S_MB_2U_LIB.S9S_MB_2U(SCH_1):PAGE74
  C976    2      B Q_CAP_C0402-10UF,6.3V,20%,X6S,B    I29 @S9S_MB_2U_LIB.S9S_MB_2U(SCH_1):PAGE74
  C971    2      B Q_CAP_C0402-10UF,6.3V,20%,X6S,B    I30 @S9S_MB_2U_LIB.S9S_MB_2U(SCH_1):PAGE74
  C975    2      B Q_CAP_C0402-10UF,6.3V,20%,X6S,B    I32 @S9S_MB_2U_LIB.S9S_MB_2U(SCH_1):PAGE74
  C974    2      B Q_CAP_C0402-10UF,6.3V,20%,X6S,B    I33 @S9S_MB_2U_LIB.S9S_MB_2U(SCH_1):PAGE74
  C214    2      B Q_CAP_C0805-47UF,4V,20%,X6S,CHA    I35 @S9S_MB_2U_LIB.S9S_MB_2U(SCH_1):PAGE74
  C215    2      B Q_CAP_C0805-47UF,4V,20%,X6S,CHA    I36 @S9S_MB_2U_LIB.S9S_MB_2U(SCH_1):PAGE74
  C981    2      B Q_CAP_C0402-10UF,6.3V,20%,X6S,B    I37 @S9S_MB_2U_LIB.S9S_MB_2U(SCH_1):PAGE74
  C985    2      B Q_CAP_C0402-10UF,6.3V,20%,X6S,B    I38 @S9S_MB_2U_LIB.S9S_MB_2U(SCH_1):PAGE74
  C216    2      B Q_CAP_C0805-47UF,4V,20%,X6S,CHA    I40 @S9S_MB_2U_LIB.S9S_MB_2U(SCH_1):PAGE74
  C410    2      B Q_CAP_C0402-22UF,4V,20%,X6S,CHA    I41 @S9S_MB_2U_LIB.S9S_MB_2U(SCH_1):PAGE74
  C412    2      B Q_CAP_C0402-22UF,4V,20%,X6S,CHA    I42 @S9S_MB_2U_LIB.S9S_MB_2U(SCH_1):PAGE74
  C218    2      B Q_CAP_C0805-47UF,4V,20%,X6S,CHA    I44 @S9S_MB_2U_LIB.S9S_MB_2U(SCH_1):PAGE74
  C993    2      B Q_CAP_C0402-10UF,6.3V,20%,X6S,B    I46 @S9S_MB_2U_LIB.S9S_MB_2U(SCH_1):PAGE74
  C997    2      B Q_CAP_C0402-10UF,6.3V,20%,X6S,B    I47 @S9S_MB_2U_LIB.S9S_MB_2U(SCH_1):PAGE74
  C980    2      B Q_CAP_C0402-10UF,6.3V,20%,X6S,B    I48 @S9S_MB_2U_LIB.S9S_MB_2U(SCH_1):PAGE74
  C984    2      B Q_CAP_C0402-10UF,6.3V,20%,X6S,B    I49 @S9S_MB_2U_LIB.S9S_MB_2U(SCH_1):PAGE74
  C979    2      B Q_CAP_C0402-10UF,6.3V,20%,X6S,B    I50 @S9S_MB_2U_LIB.S9S_MB_2U(SCH_1):PAGE74
  C978    2      B Q_CAP_C0402-10UF,6.3V,20%,X6S,B    I51 @S9S_MB_2U_LIB.S9S_MB_2U(SCH_1):PAGE74
  C983    2      B Q_CAP_C0402-10UF,6.3V,20%,X6S,B    I52 @S9S_MB_2U_LIB.S9S_MB_2U(SCH_1):PAGE74
  C982    2      B Q_CAP_C0402-10UF,6.3V,20%,X6S,B    I53 @S9S_MB_2U_LIB.S9S_MB_2U(SCH_1):PAGE74
  C988    2      B Q_CAP_C0402-10UF,6.3V,20%,X6S,B    I54 @S9S_MB_2U_LIB.S9S_MB_2U(SCH_1):PAGE74
  C996    2      B Q_CAP_C0402-10UF,6.3V,20%,X6S,B    I56 @S9S_MB_2U_LIB.S9S_MB_2U(SCH_1):PAGE74
  C986    2      B Q_CAP_C0402-10UF,6.3V,20%,X6S,B    I58 @S9S_MB_2U_LIB.S9S_MB_2U(SCH_1):PAGE74
  C991    2      B Q_CAP_C0402-10UF,6.3V,20%,X6S,B    I59 @S9S_MB_2U_LIB.S9S_MB_2U(SCH_1):PAGE74
  C990    2      B Q_CAP_C0402-10UF,6.3V,20%,X6S,B    I60 @S9S_MB_2U_LIB.S9S_MB_2U(SCH_1):PAGE74
  C995    2      B Q_CAP_C0402-10UF,6.3V,20%,X6S,B    I61 @S9S_MB_2U_LIB.S9S_MB_2U(SCH_1):PAGE74
  C415    2      B Q_CAP_C0402-22UF,4V,20%,X6S,CHA    I64 @S9S_MB_2U_LIB.S9S_MB_2U(SCH_1):PAGE74
  C417    2      B Q_CAP_C0402-22UF,4V,20%,X6S,CHA    I65 @S9S_MB_2U_LIB.S9S_MB_2U(SCH_1):PAGE74
  C418    2      B Q_CAP_C0402-22UF,4V,20%,X6S,CHA    I68 @S9S_MB_2U_LIB.S9S_MB_2U(SCH_1):PAGE74
  C414    2      B Q_CAP_C0402-22UF,4V,20%,X6S,CHA    I70 @S9S_MB_2U_LIB.S9S_MB_2U(SCH_1):PAGE74
  C219    2      B Q_CAP_C0805-47UF,4V,20%,X6S,CHA    I71 @S9S_MB_2U_LIB.S9S_MB_2U(SCH_1):PAGE74
  C416    2      B Q_CAP_C0402-22UF,4V,20%,X6S,CHA    I72 @S9S_MB_2U_LIB.S9S_MB_2U(SCH_1):PAGE74
  C220    2      B Q_CAP_C0805-47UF,4V,20%,X6S,CHA    I74 @S9S_MB_2U_LIB.S9S_MB_2U(SCH_1):PAGE74
 C1001    2      B Q_CAP_C0402-10UF,6.3V,20%,X6S,B    I75 @S9S_MB_2U_LIB.S9S_MB_2U(SCH_1):PAGE74
 C1005    2      B Q_CAP_C0402-10UF,6.3V,20%,X6S,B    I77 @S9S_MB_2U_LIB.S9S_MB_2U(SCH_1):PAGE74
 C1009    2      B Q_CAP_C0402-22UF,4V,20%,X6S,CHA    I78 @S9S_MB_2U_LIB.S9S_MB_2U(SCH_1):PAGE74
 C1013    2      B Q_CAP_C0402-22UF,4V,20%,X6S,CHA    I80 @S9S_MB_2U_LIB.S9S_MB_2U(SCH_1):PAGE74
 C1000    2      B Q_CAP_C0402-10UF,6.3V,20%,X6S,B    I81 @S9S_MB_2U_LIB.S9S_MB_2U(SCH_1):PAGE74
  C999    2      B Q_CAP_C0402-10UF,6.3V,20%,X6S,B    I85 @S9S_MB_2U_LIB.S9S_MB_2U(SCH_1):PAGE74
  C998    2      B Q_CAP_C0402-10UF,6.3V,20%,X6S,B    I86 @S9S_MB_2U_LIB.S9S_MB_2U(SCH_1):PAGE74
 C1003    2      B Q_CAP_C0402-10UF,6.3V,20%,X6S,B    I87 @S9S_MB_2U_LIB.S9S_MB_2U(SCH_1):PAGE74
 C1002    2      B Q_CAP_C0402-10UF,6.3V,20%,X6S,B    I89 @S9S_MB_2U_LIB.S9S_MB_2U(SCH_1):PAGE74
 C1008    2      B Q_CAP_C0402-22UF,4V,20%,X6S,CHA    I90 @S9S_MB_2U_LIB.S9S_MB_2U(SCH_1):PAGE74
 C1012    2      B Q_CAP_C0402-22UF,4V,20%,X6S,CHA    I92 @S9S_MB_2U_LIB.S9S_MB_2U(SCH_1):PAGE74
 C1007    2      B Q_CAP_C0402-22UF,4V,20%,X6S,CHA    I93 @S9S_MB_2U_LIB.S9S_MB_2U(SCH_1):PAGE74
 C1006    2      B Q_CAP_C0402-22UF,4V,20%,X6S,CHA    I95 @S9S_MB_2U_LIB.S9S_MB_2U(SCH_1):PAGE74
 C1011    2      B Q_CAP_C0402-22UF,4V,20%,X6S,CHA    I96 @S9S_MB_2U_LIB.S9S_MB_2U(SCH_1):PAGE74
 C1010    2      B Q_CAP_C0402-22UF,4V,20%,X6S,CHA    I97 @S9S_MB_2U_LIB.S9S_MB_2U(SCH_1):PAGE74
  C419    2      B Q_CAP_C0402-22UF,4V,20%,X6S,CHA    I98 @S9S_MB_2U_LIB.S9S_MB_2U(SCH_1):PAGE74
  C590    2      B Q_CAP_C0402-22UF,4V,20%,X6S,CHA   I102 @S9S_MB_2U_LIB.S9S_MB_2U(SCH_1):PAGE74
  C421    2      B Q_CAP_C0402-22UF,4V,20%,X6S,CHA   I103 @S9S_MB_2U_LIB.S9S_MB_2U(SCH_1):PAGE74
 C1017    2      B Q_CAP_C0402-22UF,4V,20%,X6S,CHA   I105 @S9S_MB_2U_LIB.S9S_MB_2U(SCH_1):PAGE74
 C1016    2      B Q_CAP_C0402-22UF,4V,20%,X6S,CHA   I111 @S9S_MB_2U_LIB.S9S_MB_2U(SCH_1):PAGE74
 C1020    2      B Q_CAP_C0402-22UF,4V,20%,X6S,CHA   I112 @S9S_MB_2U_LIB.S9S_MB_2U(SCH_1):PAGE74
 C1015    2      B Q_CAP_C0402-22UF,4V,20%,X6S,CHA   I113 @S9S_MB_2U_LIB.S9S_MB_2U(SCH_1):PAGE74
 C1014    2      B Q_CAP_C0402-22UF,4V,20%,X6S,CHA   I114 @S9S_MB_2U_LIB.S9S_MB_2U(SCH_1):PAGE74
 C1019    2      B Q_CAP_C0402-22UF,4V,20%,X6S,CHA   I115 @S9S_MB_2U_LIB.S9S_MB_2U(SCH_1):PAGE74
 C1036    2      B Q_CAP_C0402-22UF,4V,20%,X6S,CHA   I131 @S9S_MB_2U_LIB.S9S_MB_2U(SCH_1):PAGE74
 C1040    2      B Q_CAP_C0402-22UF,4V,20%,X6S,CHA   I132 @S9S_MB_2U_LIB.S9S_MB_2U(SCH_1):PAGE74
 C1035    2      B Q_CAP_C0402-22UF,4V,20%,X6S,CHA   I133 @S9S_MB_2U_LIB.S9S_MB_2U(SCH_1):PAGE74
 C1034    2      B Q_CAP_C0402-22UF,4V,20%,X6S,CHA   I134 @S9S_MB_2U_LIB.S9S_MB_2U(SCH_1):PAGE74
 C1039    2      B Q_CAP_C0402-22UF,4V,20%,X6S,CHA   I135 @S9S_MB_2U_LIB.S9S_MB_2U(SCH_1):PAGE74
 C1038    2      B Q_CAP_C0402-22UF,4V,20%,X6S,CHA   I137 @S9S_MB_2U_LIB.S9S_MB_2U(SCH_1):PAGE74
 C1044    2      B Q_CAP_C0402-22UF,4V,20%,X6S,CHA   I139 @S9S_MB_2U_LIB.S9S_MB_2U(SCH_1):PAGE74
 C1043    2      B Q_CAP_C0402-22UF,4V,20%,X6S,CHA   I141 @S9S_MB_2U_LIB.S9S_MB_2U(SCH_1):PAGE74
  C408    2      B Q_CAP_C0402-22UF,4V,20%,X6S,CHA   I142 @S9S_MB_2U_LIB.S9S_MB_2U(SCH_1):PAGE74
  C493    2      B Q_CAP_C0805-47UF,4V,20%,X6S,CHA     I1 @S9S_MB_2U_LIB.S9S_MB_2U(SCH_1):PAGE75
  C497    2      B Q_CAP_C0805-47UF,4V,20%,X6S,CHA     I3 @S9S_MB_2U_LIB.S9S_MB_2U(SCH_1):PAGE75
  C501    2      B Q_CAP_C0805-47UF,4V,20%,X6S,CHA     I4 @S9S_MB_2U_LIB.S9S_MB_2U(SCH_1):PAGE75
  C532    2      B Q_CAP_C0603-47UF,2.5V,20%,X6S,A    I14 @S9S_MB_2U_LIB.S9S_MB_2U(SCH_1):PAGE75
  C359    2      B Q_CAP_C0805-47UF,4V,20%,X6S,CHA    I25 @S9S_MB_2U_LIB.S9S_MB_2U(SCH_1):PAGE75
  C362    2      B Q_CAP_C0805-47UF,4V,20%,X6S,CHA    I26 @S9S_MB_2U_LIB.S9S_MB_2U(SCH_1):PAGE75
  C358    2      B Q_CAP_C0805-47UF,4V,20%,X6S,CHA    I27 @S9S_MB_2U_LIB.S9S_MB_2U(SCH_1):PAGE75
  C361    2      B Q_CAP_C0805-47UF,4V,20%,X6S,CHA    I28 @S9S_MB_2U_LIB.S9S_MB_2U(SCH_1):PAGE75
  C368    2      B Q_CAP_C0805-47UF,4V,20%,X6S,CHA    I33 @S9S_MB_2U_LIB.S9S_MB_2U(SCH_1):PAGE75
 C1396    2      B Q_CAP_C0805-47UF,4V,20%,X6S,CHA    I43 @S9S_MB_2U_LIB.S9S_MB_2U(SCH_1):PAGE75
 C1397    2      B Q_CAP_C0805-47UF,4V,20%,X6S,CHA    I44 @S9S_MB_2U_LIB.S9S_MB_2U(SCH_1):PAGE75
  C391    2      B Q_CAP_C0805-47UF,4V,20%,X6S,CHA    I49 @S9S_MB_2U_LIB.S9S_MB_2U(SCH_1):PAGE75
  C379    2      B Q_CAP_C0805-47UF,4V,20%,X6S,CHA    I50 @S9S_MB_2U_LIB.S9S_MB_2U(SCH_1):PAGE75
  C393    2      B Q_CAP_C0805-47UF,4V,20%,X6S,CHA    I52 @S9S_MB_2U_LIB.S9S_MB_2U(SCH_1):PAGE75
  C360    2      B Q_CAP_C0805-47UF,4V,20%,X6S,CHA    I54 @S9S_MB_2U_LIB.S9S_MB_2U(SCH_1):PAGE75
  C381    2      B Q_CAP_C0805-47UF,4V,20%,X6S,CHA    I67 @S9S_MB_2U_LIB.S9S_MB_2U(SCH_1):PAGE75
  C494    2      B Q_CAP_C0805-47UF,4V,20%,X6S,CHA     I1 @S9S_MB_2U_LIB.S9S_MB_2U(SCH_1):PAGE76
  C528    2      B Q_CAP_C0805-47UF,4V,20%,X6S,CHA     I6 @S9S_MB_2U_LIB.S9S_MB_2U(SCH_1):PAGE76
  C530    2      B Q_CAP_C0805-47UF,4V,20%,X6S,CHA     I7 @S9S_MB_2U_LIB.S9S_MB_2U(SCH_1):PAGE76
 C1399    2      B Q_CAP_C0805-47UF,4V,20%,X6S,CHA    I13 @S9S_MB_2U_LIB.S9S_MB_2U(SCH_1):PAGE76
  C499    2      B Q_CAP_C0805-47UF,4V,20%,X6S,CHA    I18 @S9S_MB_2U_LIB.S9S_MB_2U(SCH_1):PAGE76
  C503    2      B Q_CAP_C0805-47UF,4V,20%,X6S,CHA    I20 @S9S_MB_2U_LIB.S9S_MB_2U(SCH_1):PAGE76
  C510    2      B Q_CAP_C0805-47UF,4V,20%,X6S,CHA    I27 @S9S_MB_2U_LIB.S9S_MB_2U(SCH_1):PAGE76
  C514    2      B Q_CAP_C0805-47UF,4V,20%,X6S,CHA    I28 @S9S_MB_2U_LIB.S9S_MB_2U(SCH_1):PAGE76
  C517    2      B Q_CAP_C0805-47UF,4V,20%,X6S,CHA    I29 @S9S_MB_2U_LIB.S9S_MB_2U(SCH_1):PAGE76
  C531    2      B Q_CAP_C0805-47UF,4V,20%,X6S,CHA    I31 @S9S_MB_2U_LIB.S9S_MB_2U(SCH_1):PAGE76
  C529    2      B Q_CAP_C0805-47UF,4V,20%,X6S,CHA    I41 @S9S_MB_2U_LIB.S9S_MB_2U(SCH_1):PAGE76
  C396    2      B Q_CAP_C0805-47UF,4V,20%,X6S,CHA    I46 @S9S_MB_2U_LIB.S9S_MB_2U(SCH_1):PAGE76
  C398    2      B Q_CAP_C0805-47UF,4V,20%,X6S,CHA    I47 @S9S_MB_2U_LIB.S9S_MB_2U(SCH_1):PAGE76
  C424    2      B Q_CAP_C0402-22UF,4V,20%,X6S,CHA     I1 @S9S_MB_2U_LIB.S9S_MB_2U(SCH_1):PAGE77
  C428    2      B Q_CAP_C0402-22UF,4V,20%,X6S,CHA     I4 @S9S_MB_2U_LIB.S9S_MB_2U(SCH_1):PAGE77
  C430    2      B Q_CAP_C0402-22UF,4V,20%,X6S,CHA     I5 @S9S_MB_2U_LIB.S9S_MB_2U(SCH_1):PAGE77
  C423    2      B Q_CAP_C0402-22UF,4V,20%,X6S,CHA     I7 @S9S_MB_2U_LIB.S9S_MB_2U(SCH_1):PAGE77
  C425    2      B Q_CAP_C0402-22UF,4V,20%,X6S,CHA     I8 @S9S_MB_2U_LIB.S9S_MB_2U(SCH_1):PAGE77
  C225    2      B Q_CAP_C0805-47UF,4V,20%,X6S,CHA    I10 @S9S_MB_2U_LIB.S9S_MB_2U(SCH_1):PAGE77
  C230    2      B Q_CAP_C0805-47UF,4V,20%,X6S,CHA    I11 @S9S_MB_2U_LIB.S9S_MB_2U(SCH_1):PAGE77
  C224    2      B Q_CAP_C0402-10UF,6.3V,20%,X6S,B    I13 @S9S_MB_2U_LIB.S9S_MB_2U(SCH_1):PAGE77
  C427    2      B Q_CAP_C0402-22UF,4V,20%,X6S,CHA    I15 @S9S_MB_2U_LIB.S9S_MB_2U(SCH_1):PAGE77
  C429    2      B Q_CAP_C0402-22UF,4V,20%,X6S,CHA    I17 @S9S_MB_2U_LIB.S9S_MB_2U(SCH_1):PAGE77
  C240    2      B Q_CAP_C0805-47UF,4V,20%,X6S,CHA    I18 @S9S_MB_2U_LIB.S9S_MB_2U(SCH_1):PAGE77
  C234    2      B Q_CAP_C0402-10UF,6.3V,20%,X6S,B    I19 @S9S_MB_2U_LIB.S9S_MB_2U(SCH_1):PAGE77
  C239    2      B Q_CAP_C0402-10UF,6.3V,20%,X6S,B    I20 @S9S_MB_2U_LIB.S9S_MB_2U(SCH_1):PAGE77
  C223    2      B Q_CAP_C0402-10UF,6.3V,20%,X6S,B    I22 @S9S_MB_2U_LIB.S9S_MB_2U(SCH_1):PAGE77
  C228    2      B Q_CAP_C0402-10UF,6.3V,20%,X6S,B    I23 @S9S_MB_2U_LIB.S9S_MB_2U(SCH_1):PAGE77
  C222    2      B Q_CAP_C0402-10UF,6.3V,20%,X6S,B    I25 @S9S_MB_2U_LIB.S9S_MB_2U(SCH_1):PAGE77
  C221    2      B Q_CAP_C0402-10UF,6.3V,20%,X6S,B    I28 @S9S_MB_2U_LIB.S9S_MB_2U(SCH_1):PAGE77
  C226    2      B Q_CAP_C0402-10UF,6.3V,20%,X6S,B    I29 @S9S_MB_2U_LIB.S9S_MB_2U(SCH_1):PAGE77
  C233    2      B Q_CAP_C0402-10UF,6.3V,20%,X6S,B    I30 @S9S_MB_2U_LIB.S9S_MB_2U(SCH_1):PAGE77
  C238    2      B Q_CAP_C0402-10UF,6.3V,20%,X6S,B    I31 @S9S_MB_2U_LIB.S9S_MB_2U(SCH_1):PAGE77
  C232    2      B Q_CAP_C0402-10UF,6.3V,20%,X6S,B    I32 @S9S_MB_2U_LIB.S9S_MB_2U(SCH_1):PAGE77
  C231    2      B Q_CAP_C0402-10UF,6.3V,20%,X6S,B    I33 @S9S_MB_2U_LIB.S9S_MB_2U(SCH_1):PAGE77
  C237    2      B Q_CAP_C0402-10UF,6.3V,20%,X6S,B    I34 @S9S_MB_2U_LIB.S9S_MB_2U(SCH_1):PAGE77
  C236    2      B Q_CAP_C0402-10UF,6.3V,20%,X6S,B    I35 @S9S_MB_2U_LIB.S9S_MB_2U(SCH_1):PAGE77
  C431    2      B Q_CAP_C0402-22UF,4V,20%,X6S,CHA    I37 @S9S_MB_2U_LIB.S9S_MB_2U(SCH_1):PAGE77
  C433    2      B Q_CAP_C0402-22UF,4V,20%,X6S,CHA    I38 @S9S_MB_2U_LIB.S9S_MB_2U(SCH_1):PAGE77
  C435    2      B Q_CAP_C0402-22UF,4V,20%,X6S,CHA    I39 @S9S_MB_2U_LIB.S9S_MB_2U(SCH_1):PAGE77
  C245    2      B Q_CAP_C0805-47UF,4V,20%,X6S,CHA    I41 @S9S_MB_2U_LIB.S9S_MB_2U(SCH_1):PAGE77
  C432    2      B Q_CAP_C0402-22UF,4V,20%,X6S,CHA    I42 @S9S_MB_2U_LIB.S9S_MB_2U(SCH_1):PAGE77
  C250    2      B Q_CAP_C0805-47UF,4V,20%,X6S,CHA    I44 @S9S_MB_2U_LIB.S9S_MB_2U(SCH_1):PAGE77
  C244    2      B Q_CAP_C0402-10UF,6.3V,20%,X6S,B    I45 @S9S_MB_2U_LIB.S9S_MB_2U(SCH_1):PAGE77
  C249    2      B Q_CAP_C0402-10UF,6.3V,20%,X6S,B    I46 @S9S_MB_2U_LIB.S9S_MB_2U(SCH_1):PAGE77
  C434    2      B Q_CAP_C0402-22UF,4V,20%,X6S,CHA    I47 @S9S_MB_2U_LIB.S9S_MB_2U(SCH_1):PAGE77
  C255    2      B Q_CAP_C0805-47UF,4V,20%,X6S,CHA    I48 @S9S_MB_2U_LIB.S9S_MB_2U(SCH_1):PAGE77
  C436    2      B Q_CAP_C0402-22UF,4V,20%,X6S,CHA    I49 @S9S_MB_2U_LIB.S9S_MB_2U(SCH_1):PAGE77
  C260    2      B Q_CAP_C0805-47UF,4V,20%,X6S,CHA    I50 @S9S_MB_2U_LIB.S9S_MB_2U(SCH_1):PAGE77
  C254    2      B Q_CAP_C0402-10UF,6.3V,20%,X6S,B    I51 @S9S_MB_2U_LIB.S9S_MB_2U(SCH_1):PAGE77
  C259    2      B Q_CAP_C0402-10UF,6.3V,20%,X6S,B    I52 @S9S_MB_2U_LIB.S9S_MB_2U(SCH_1):PAGE77
  C439    2      B Q_CAP_C0402-22UF,4V,20%,X6S,CHA    I53 @S9S_MB_2U_LIB.S9S_MB_2U(SCH_1):PAGE77
  C441    2      B Q_CAP_C0402-22UF,4V,20%,X6S,CHA    I55 @S9S_MB_2U_LIB.S9S_MB_2U(SCH_1):PAGE77
  C442    2      B Q_CAP_C0402-22UF,4V,20%,X6S,CHA    I57 @S9S_MB_2U_LIB.S9S_MB_2U(SCH_1):PAGE77
  C438    2      B Q_CAP_C0402-22UF,4V,20%,X6S,CHA    I58 @S9S_MB_2U_LIB.S9S_MB_2U(SCH_1):PAGE77
  C265    2      B Q_CAP_C0805-47UF,4V,20%,X6S,CHA    I59 @S9S_MB_2U_LIB.S9S_MB_2U(SCH_1):PAGE77
  C440    2      B Q_CAP_C0402-22UF,4V,20%,X6S,CHA    I61 @S9S_MB_2U_LIB.S9S_MB_2U(SCH_1):PAGE77
  C270    2      B Q_CAP_C0805-47UF,4V,20%,X6S,CHA    I62 @S9S_MB_2U_LIB.S9S_MB_2U(SCH_1):PAGE77
  C264    2      B Q_CAP_C0402-10UF,6.3V,20%,X6S,B    I63 @S9S_MB_2U_LIB.S9S_MB_2U(SCH_1):PAGE77
  C274    2      B Q_CAP_C0402-22UF,4V,20%,X6S,CHA    I66 @S9S_MB_2U_LIB.S9S_MB_2U(SCH_1):PAGE77
  C278    2      B Q_CAP_C0402-22UF,4V,20%,X6S,CHA    I71 @S9S_MB_2U_LIB.S9S_MB_2U(SCH_1):PAGE77
  C282    2      B Q_CAP_C0402-22UF,4V,20%,X6S,CHA    I73 @S9S_MB_2U_LIB.S9S_MB_2U(SCH_1):PAGE77
  C248    2      B Q_CAP_C0402-10UF,6.3V,20%,X6S,B    I75 @S9S_MB_2U_LIB.S9S_MB_2U(SCH_1):PAGE77
  C242    2      B Q_CAP_C0402-10UF,6.3V,20%,X6S,B    I76 @S9S_MB_2U_LIB.S9S_MB_2U(SCH_1):PAGE77
  C247    2      B Q_CAP_C0402-10UF,6.3V,20%,X6S,B    I78 @S9S_MB_2U_LIB.S9S_MB_2U(SCH_1):PAGE77
  C246    2      B Q_CAP_C0402-10UF,6.3V,20%,X6S,B    I79 @S9S_MB_2U_LIB.S9S_MB_2U(SCH_1):PAGE77
  C258    2      B Q_CAP_C0402-10UF,6.3V,20%,X6S,B    I81 @S9S_MB_2U_LIB.S9S_MB_2U(SCH_1):PAGE77
  C251    2      B Q_CAP_C0402-10UF,6.3V,20%,X6S,B    I83 @S9S_MB_2U_LIB.S9S_MB_2U(SCH_1):PAGE77
  C257    2      B Q_CAP_C0402-10UF,6.3V,20%,X6S,B    I84 @S9S_MB_2U_LIB.S9S_MB_2U(SCH_1):PAGE77
  C263    2      B Q_CAP_C0402-10UF,6.3V,20%,X6S,B    I86 @S9S_MB_2U_LIB.S9S_MB_2U(SCH_1):PAGE77
  C268    2      B Q_CAP_C0402-10UF,6.3V,20%,X6S,B    I88 @S9S_MB_2U_LIB.S9S_MB_2U(SCH_1):PAGE77
  C262    2      B Q_CAP_C0402-10UF,6.3V,20%,X6S,B    I93 @S9S_MB_2U_LIB.S9S_MB_2U(SCH_1):PAGE77
  C261    2      B Q_CAP_C0402-10UF,6.3V,20%,X6S,B    I95 @S9S_MB_2U_LIB.S9S_MB_2U(SCH_1):PAGE77
  C272    2      B Q_CAP_C0402-22UF,4V,20%,X6S,CHA    I98 @S9S_MB_2U_LIB.S9S_MB_2U(SCH_1):PAGE77
  C271    2      B Q_CAP_C0402-22UF,4V,20%,X6S,CHA   I100 @S9S_MB_2U_LIB.S9S_MB_2U(SCH_1):PAGE77
  C277    2      B Q_CAP_C0402-22UF,4V,20%,X6S,CHA   I101 @S9S_MB_2U_LIB.S9S_MB_2U(SCH_1):PAGE77
  C281    2      B Q_CAP_C0402-22UF,4V,20%,X6S,CHA   I102 @S9S_MB_2U_LIB.S9S_MB_2U(SCH_1):PAGE77
  C276    2      B Q_CAP_C0402-22UF,4V,20%,X6S,CHA   I103 @S9S_MB_2U_LIB.S9S_MB_2U(SCH_1):PAGE77
  C275    2      B Q_CAP_C0402-22UF,4V,20%,X6S,CHA   I104 @S9S_MB_2U_LIB.S9S_MB_2U(SCH_1):PAGE77
  C280    2      B Q_CAP_C0402-22UF,4V,20%,X6S,CHA   I105 @S9S_MB_2U_LIB.S9S_MB_2U(SCH_1):PAGE77
  C279    2      B Q_CAP_C0402-22UF,4V,20%,X6S,CHA   I106 @S9S_MB_2U_LIB.S9S_MB_2U(SCH_1):PAGE77
  C444    2      B Q_CAP_C0402-22UF,4V,20%,X6S,CHA   I109 @S9S_MB_2U_LIB.S9S_MB_2U(SCH_1):PAGE77
  C445    2      B Q_CAP_C0402-22UF,4V,20%,X6S,CHA   I110 @S9S_MB_2U_LIB.S9S_MB_2U(SCH_1):PAGE77
  C286    2      B Q_CAP_C0402-22UF,4V,20%,X6S,CHA   I111 @S9S_MB_2U_LIB.S9S_MB_2U(SCH_1):PAGE77
  C290    2      B Q_CAP_C0402-22UF,4V,20%,X6S,CHA   I112 @S9S_MB_2U_LIB.S9S_MB_2U(SCH_1):PAGE77
  C446    2      B Q_CAP_C0402-22UF,4V,20%,X6S,CHA   I113 @S9S_MB_2U_LIB.S9S_MB_2U(SCH_1):PAGE77
  C294    2      B Q_CAP_C0402-22UF,4V,20%,X6S,CHA   I114 @S9S_MB_2U_LIB.S9S_MB_2U(SCH_1):PAGE77
  C298    2      B Q_CAP_C0402-22UF,4V,20%,X6S,CHA   I115 @S9S_MB_2U_LIB.S9S_MB_2U(SCH_1):PAGE77
  C302    2      B Q_CAP_C0402-22UF,4V,20%,X6S,CHA   I117 @S9S_MB_2U_LIB.S9S_MB_2U(SCH_1):PAGE77
  C306    2      B Q_CAP_C0402-22UF,4V,20%,X6S,CHA   I118 @S9S_MB_2U_LIB.S9S_MB_2U(SCH_1):PAGE77
  C285    2      B Q_CAP_C0402-22UF,4V,20%,X6S,CHA   I119 @S9S_MB_2U_LIB.S9S_MB_2U(SCH_1):PAGE77
  C289    2      B Q_CAP_C0402-22UF,4V,20%,X6S,CHA   I120 @S9S_MB_2U_LIB.S9S_MB_2U(SCH_1):PAGE77
  C284    2      B Q_CAP_C0402-22UF,4V,20%,X6S,CHA   I121 @S9S_MB_2U_LIB.S9S_MB_2U(SCH_1):PAGE77
  C283    2      B Q_CAP_C0402-22UF,4V,20%,X6S,CHA   I122 @S9S_MB_2U_LIB.S9S_MB_2U(SCH_1):PAGE77
  C288    2      B Q_CAP_C0402-22UF,4V,20%,X6S,CHA   I123 @S9S_MB_2U_LIB.S9S_MB_2U(SCH_1):PAGE77
  C293    2      B Q_CAP_C0402-22UF,4V,20%,X6S,CHA   I125 @S9S_MB_2U_LIB.S9S_MB_2U(SCH_1):PAGE77
  C297    2      B Q_CAP_C0402-22UF,4V,20%,X6S,CHA   I126 @S9S_MB_2U_LIB.S9S_MB_2U(SCH_1):PAGE77
  C296    2      B Q_CAP_C0402-22UF,4V,20%,X6S,CHA   I129 @S9S_MB_2U_LIB.S9S_MB_2U(SCH_1):PAGE77
  C295    2      B Q_CAP_C0402-22UF,4V,20%,X6S,CHA   I130 @S9S_MB_2U_LIB.S9S_MB_2U(SCH_1):PAGE77
  C299    2      B Q_CAP_C0402-22UF,4V,20%,X6S,CHA   I131 @S9S_MB_2U_LIB.S9S_MB_2U(SCH_1):PAGE77
  C300    2      B Q_CAP_C0402-22UF,4V,20%,X6S,CHA   I132 @S9S_MB_2U_LIB.S9S_MB_2U(SCH_1):PAGE77
  C301    2      B Q_CAP_C0402-22UF,4V,20%,X6S,CHA   I133 @S9S_MB_2U_LIB.S9S_MB_2U(SCH_1):PAGE77
  C305    2      B Q_CAP_C0402-22UF,4V,20%,X6S,CHA   I134 @S9S_MB_2U_LIB.S9S_MB_2U(SCH_1):PAGE77
  C309    2      B Q_CAP_C0402-22UF,4V,20%,X6S,CHA   I136 @S9S_MB_2U_LIB.S9S_MB_2U(SCH_1):PAGE77
  C304    2      B Q_CAP_C0402-22UF,4V,20%,X6S,CHA   I138 @S9S_MB_2U_LIB.S9S_MB_2U(SCH_1):PAGE77
  C308    2      B Q_CAP_C0402-22UF,4V,20%,X6S,CHA   I140 @S9S_MB_2U_LIB.S9S_MB_2U(SCH_1):PAGE77
  C453    2      B Q_CAP_C0805-47UF,4V,20%,X6S,CHA     I3 @S9S_MB_2U_LIB.S9S_MB_2U(SCH_1):PAGE78
  C461    2      B Q_CAP_C0805-47UF,4V,20%,X6S,CHA     I5 @S9S_MB_2U_LIB.S9S_MB_2U(SCH_1):PAGE78
  C465    2      B Q_CAP_C0603-47UF,2.5V,20%,X6S,A     I7 @S9S_MB_2U_LIB.S9S_MB_2U(SCH_1):PAGE78
  C490    2      B Q_CAP_C0402-22UF,4V,20%,X6S,CHA    I23 @S9S_MB_2U_LIB.S9S_MB_2U(SCH_1):PAGE78
  C451    2      B Q_CAP_C0805-47UF,4V,20%,X6S,CHA    I24 @S9S_MB_2U_LIB.S9S_MB_2U(SCH_1):PAGE78
  C318    2      B Q_CAP_C0805-47UF,4V,20%,X6S,CHA    I27 @S9S_MB_2U_LIB.S9S_MB_2U(SCH_1):PAGE78
  C474    2      B Q_CAP_C0805-47UF,4V,20%,X6S,CHA    I29 @S9S_MB_2U_LIB.S9S_MB_2U(SCH_1):PAGE78
  C327    2      B Q_CAP_C0805-47UF,4V,20%,X6S,CHA    I32 @S9S_MB_2U_LIB.S9S_MB_2U(SCH_1):PAGE78
  C336    2      B Q_CAP_C0805-47UF,4V,20%,X6S,CHA    I35 @S9S_MB_2U_LIB.S9S_MB_2U(SCH_1):PAGE78
  C314    2      B Q_CAP_C0805-47UF,4V,20%,X6S,CHA    I37 @S9S_MB_2U_LIB.S9S_MB_2U(SCH_1):PAGE78
  C320    2      B Q_CAP_C0805-47UF,4V,20%,X6S,CHA    I39 @S9S_MB_2U_LIB.S9S_MB_2U(SCH_1):PAGE78
  C323    2      B Q_CAP_C0805-47UF,4V,20%,X6S,CHA    I40 @S9S_MB_2U_LIB.S9S_MB_2U(SCH_1):PAGE78
  C326    2      B Q_CAP_C0805-47UF,4V,20%,X6S,CHA    I41 @S9S_MB_2U_LIB.S9S_MB_2U(SCH_1):PAGE78
 C1391    2      B Q_CAP_C0603-47UF,2.5V,20%,X6S,A    I52 @S9S_MB_2U_LIB.S9S_MB_2U(SCH_1):PAGE78
  C313    2      B Q_CAP_C0805-47UF,4V,20%,X6S,CHA    I58 @S9S_MB_2U_LIB.S9S_MB_2U(SCH_1):PAGE78
  C316    2      B Q_CAP_C0805-47UF,4V,20%,X6S,CHA    I60 @S9S_MB_2U_LIB.S9S_MB_2U(SCH_1):PAGE78
  C353    2      B Q_CAP_C0805-47UF,4V,20%,X6S,CHA    I65 @S9S_MB_2U_LIB.S9S_MB_2U(SCH_1):PAGE78
  C337    2      B Q_CAP_C0805-47UF,4V,20%,X6S,CHA    I66 @S9S_MB_2U_LIB.S9S_MB_2U(SCH_1):PAGE78
  C483    2      B Q_CAP_C0805-47UF,4V,20%,X6S,CHA    I68 @S9S_MB_2U_LIB.S9S_MB_2U(SCH_1):PAGE78
  C450    2      B Q_CAP_C0805-47UF,4V,20%,X6S,CHA     I1 @S9S_MB_2U_LIB.S9S_MB_2U(SCH_1):PAGE79
  C454    2      B Q_CAP_C0805-47UF,4V,20%,X6S,CHA     I3 @S9S_MB_2U_LIB.S9S_MB_2U(SCH_1):PAGE79
  C458    2      B Q_CAP_C0805-47UF,4V,20%,X6S,CHA     I4 @S9S_MB_2U_LIB.S9S_MB_2U(SCH_1):PAGE79
  C462    2      B Q_CAP_C0805-47UF,4V,20%,X6S,CHA     I5 @S9S_MB_2U_LIB.S9S_MB_2U(SCH_1):PAGE79
  C466    2      B Q_CAP_C0805-47UF,4V,20%,X6S,CHA     I7 @S9S_MB_2U_LIB.S9S_MB_2U(SCH_1):PAGE79
  C470    2      B Q_CAP_C0805-47UF,4V,20%,X6S,CHA     I8 @S9S_MB_2U_LIB.S9S_MB_2U(SCH_1):PAGE79
  C473    2      B Q_CAP_C0805-47UF,4V,20%,X6S,CHA     I9 @S9S_MB_2U_LIB.S9S_MB_2U(SCH_1):PAGE79
  C487    2      B Q_CAP_C0805-47UF,4V,20%,X6S,CHA    I10 @S9S_MB_2U_LIB.S9S_MB_2U(SCH_1):PAGE79
  C486    2      B Q_CAP_C0805-47UF,4V,20%,X6S,CHA    I11 @S9S_MB_2U_LIB.S9S_MB_2U(SCH_1):PAGE79
 C1364    2      B Q_CAP_C0402-22UF,4V,20%,X6S,CHA     I9 @S9S_MB_2U_LIB.S9S_MB_2U(SCH_1):PAGE80
 C1365    2      B Q_CAP_C0402-22UF,4V,20%,X6S,CHA    I20 @S9S_MB_2U_LIB.S9S_MB_2U(SCH_1):PAGE80
 C1366    2      B Q_CAP_C0402-22UF,4V,20%,X6S,CHA    I28 @S9S_MB_2U_LIB.S9S_MB_2U(SCH_1):PAGE80
    C3    2      B Q_CAP_C0805-10UF,16V,10%,X6S,CA   I188 @S9S_MB_2U_LIB.S9S_MB_2U(SCH_1):PAGE82
    C4    2      B Q_CAP_C0805-10UF,16V,10%,X6S,CA   I190 @S9S_MB_2U_LIB.S9S_MB_2U(SCH_1):PAGE82
    C2    2      B Q_CAP_C0402-2.2UF,6.3V,20%,X6SA   I192 @S9S_MB_2U_LIB.S9S_MB_2U(SCH_1):PAGE82
   R26    2      B Q_RES_0402LF-10K,1%,1/16W,CHIPA   I196 @S9S_MB_2U_LIB.S9S_MB_2U(SCH_1):PAGE82
   R27    2      B Q_RES_0402LF-15.4K,1%,1/16W,CHA    I10 @S9S_MB_2U_LIB.S9S_MB_2U(SCH_1):PAGE83
    C5    2      B Q_CAP_C0402-2.2UF,6.3V,20%,X6SA   I120 @S9S_MB_2U_LIB.S9S_MB_2U(SCH_1):PAGE83
    C6    2      B Q_CAP_C0805-10UF,16V,10%,X6S,CA   I122 @S9S_MB_2U_LIB.S9S_MB_2U(SCH_1):PAGE83
    C7    2      B Q_CAP_C0805-10UF,16V,10%,X6S,CA   I144 @S9S_MB_2U_LIB.S9S_MB_2U(SCH_1):PAGE83
    J2   G1     G1 SCONN288_ADR50017P087CC-SCONN2A   I179 @S9S_MB_2U_LIB.S9S_MB_2U(SCH_1):PAGE83
    J2   G2     G2 SCONN288_ADR50017P087CC-SCONN2A   I179 @S9S_MB_2U_LIB.S9S_MB_2U(SCH_1):PAGE83
    J2   G3     G3 SCONN288_ADR50017P087CC-SCONN2A   I179 @S9S_MB_2U_LIB.S9S_MB_2U(SCH_1):PAGE83
    J2    6   VSS0 SCONN288_ADR50017P087CC-SCONN2A   I179 @S9S_MB_2U_LIB.S9S_MB_2U(SCH_1):PAGE83
    J2    8   VSS1 SCONN288_ADR50017P087CC-SCONN2A   I179 @S9S_MB_2U_LIB.S9S_MB_2U(SCH_1):PAGE83
    J2   10   VSS2 SCONN288_ADR50017P087CC-SCONN2A   I179 @S9S_MB_2U_LIB.S9S_MB_2U(SCH_1):PAGE83
    J2   13   VSS3 SCONN288_ADR50017P087CC-SCONN2A   I179 @S9S_MB_2U_LIB.S9S_MB_2U(SCH_1):PAGE83
    J2   15   VSS4 SCONN288_ADR50017P087CC-SCONN2A   I179 @S9S_MB_2U_LIB.S9S_MB_2U(SCH_1):PAGE83
    J2   17   VSS5 SCONN288_ADR50017P087CC-SCONN2A   I179 @S9S_MB_2U_LIB.S9S_MB_2U(SCH_1):PAGE83
    J2   19   VSS6 SCONN288_ADR50017P087CC-SCONN2A   I179 @S9S_MB_2U_LIB.S9S_MB_2U(SCH_1):PAGE83
    J2   21   VSS7 SCONN288_ADR50017P087CC-SCONN2A   I179 @S9S_MB_2U_LIB.S9S_MB_2U(SCH_1):PAGE83
    J2   24   VSS8 SCONN288_ADR50017P087CC-SCONN2A   I179 @S9S_MB_2U_LIB.S9S_MB_2U(SCH_1):PAGE83
    J2   26   VSS9 SCONN288_ADR50017P087CC-SCONN2A   I179 @S9S_MB_2U_LIB.S9S_MB_2U(SCH_1):PAGE83
    J2   28  VSS10 SCONN288_ADR50017P087CC-SCONN2A   I179 @S9S_MB_2U_LIB.S9S_MB_2U(SCH_1):PAGE83
    J2   30  VSS11 SCONN288_ADR50017P087CC-SCONN2A   I179 @S9S_MB_2U_LIB.S9S_MB_2U(SCH_1):PAGE83
    J2   32  VSS12 SCONN288_ADR50017P087CC-SCONN2A   I179 @S9S_MB_2U_LIB.S9S_MB_2U(SCH_1):PAGE83
    J2   35  VSS13 SCONN288_ADR50017P087CC-SCONN2A   I179 @S9S_MB_2U_LIB.S9S_MB_2U(SCH_1):PAGE83
    J2   37  VSS14 SCONN288_ADR50017P087CC-SCONN2A   I179 @S9S_MB_2U_LIB.S9S_MB_2U(SCH_1):PAGE83
    J2   39  VSS15 SCONN288_ADR50017P087CC-SCONN2A   I179 @S9S_MB_2U_LIB.S9S_MB_2U(SCH_1):PAGE83
    J2   41  VSS16 SCONN288_ADR50017P087CC-SCONN2A   I179 @S9S_MB_2U_LIB.S9S_MB_2U(SCH_1):PAGE83
    J2   43  VSS17 SCONN288_ADR50017P087CC-SCONN2A   I179 @S9S_MB_2U_LIB.S9S_MB_2U(SCH_1):PAGE83
    J2   46  VSS18 SCONN288_ADR50017P087CC-SCONN2A   I179 @S9S_MB_2U_LIB.S9S_MB_2U(SCH_1):PAGE83
    J2   48  VSS19 SCONN288_ADR50017P087CC-SCONN2A   I179 @S9S_MB_2U_LIB.S9S_MB_2U(SCH_1):PAGE83
    J2   50  VSS20 SCONN288_ADR50017P087CC-SCONN2A   I179 @S9S_MB_2U_LIB.S9S_MB_2U(SCH_1):PAGE83
    J2   52  VSS21 SCONN288_ADR50017P087CC-SCONN2A   I179 @S9S_MB_2U_LIB.S9S_MB_2U(SCH_1):PAGE83
    J2   54  VSS22 SCONN288_ADR50017P087CC-SCONN2A   I179 @S9S_MB_2U_LIB.S9S_MB_2U(SCH_1):PAGE83
    J2   57  VSS23 SCONN288_ADR50017P087CC-SCONN2A   I179 @S9S_MB_2U_LIB.S9S_MB_2U(SCH_1):PAGE83
    J2   59  VSS24 SCONN288_ADR50017P087CC-SCONN2A   I179 @S9S_MB_2U_LIB.S9S_MB_2U(SCH_1):PAGE83
    J2   61  VSS25 SCONN288_ADR50017P087CC-SCONN2A   I179 @S9S_MB_2U_LIB.S9S_MB_2U(SCH_1):PAGE83
    J2   63  VSS26 SCONN288_ADR50017P087CC-SCONN2A   I179 @S9S_MB_2U_LIB.S9S_MB_2U(SCH_1):PAGE83
    J2   65  VSS27 SCONN288_ADR50017P087CC-SCONN2A   I179 @S9S_MB_2U_LIB.S9S_MB_2U(SCH_1):PAGE83
    J2   67  VSS28 SCONN288_ADR50017P087CC-SCONN2A   I179 @S9S_MB_2U_LIB.S9S_MB_2U(SCH_1):PAGE83
    J2   69  VSS29 SCONN288_ADR50017P087CC-SCONN2A   I179 @S9S_MB_2U_LIB.S9S_MB_2U(SCH_1):PAGE83
    J2   71  VSS30 SCONN288_ADR50017P087CC-SCONN2A   I179 @S9S_MB_2U_LIB.S9S_MB_2U(SCH_1):PAGE83
    J2   73  VSS31 SCONN288_ADR50017P087CC-SCONN2A   I179 @S9S_MB_2U_LIB.S9S_MB_2U(SCH_1):PAGE83
    J2   75  VSS32 SCONN288_ADR50017P087CC-SCONN2A   I179 @S9S_MB_2U_LIB.S9S_MB_2U(SCH_1):PAGE83
    J2   77  VSS33 SCONN288_ADR50017P087CC-SCONN2A   I179 @S9S_MB_2U_LIB.S9S_MB_2U(SCH_1):PAGE83
    J2   79  VSS34 SCONN288_ADR50017P087CC-SCONN2A   I179 @S9S_MB_2U_LIB.S9S_MB_2U(SCH_1):PAGE83
    J2   81  VSS35 SCONN288_ADR50017P087CC-SCONN2A   I179 @S9S_MB_2U_LIB.S9S_MB_2U(SCH_1):PAGE83
    J2   83  VSS36 SCONN288_ADR50017P087CC-SCONN2A   I179 @S9S_MB_2U_LIB.S9S_MB_2U(SCH_1):PAGE83
    J2   85  VSS37 SCONN288_ADR50017P087CC-SCONN2A   I179 @S9S_MB_2U_LIB.S9S_MB_2U(SCH_1):PAGE83
    J2   88  VSS38 SCONN288_ADR50017P087CC-SCONN2A   I179 @S9S_MB_2U_LIB.S9S_MB_2U(SCH_1):PAGE83
    J2   90  VSS39 SCONN288_ADR50017P087CC-SCONN2A   I179 @S9S_MB_2U_LIB.S9S_MB_2U(SCH_1):PAGE83
    J2   92  VSS40 SCONN288_ADR50017P087CC-SCONN2A   I179 @S9S_MB_2U_LIB.S9S_MB_2U(SCH_1):PAGE83
    J2   95  VSS41 SCONN288_ADR50017P087CC-SCONN2A   I179 @S9S_MB_2U_LIB.S9S_MB_2U(SCH_1):PAGE83
    J2   97  VSS42 SCONN288_ADR50017P087CC-SCONN2A   I179 @S9S_MB_2U_LIB.S9S_MB_2U(SCH_1):PAGE83
    J2   99  VSS43 SCONN288_ADR50017P087CC-SCONN2A   I179 @S9S_MB_2U_LIB.S9S_MB_2U(SCH_1):PAGE83
    J2  101  VSS44 SCONN288_ADR50017P087CC-SCONN2A   I179 @S9S_MB_2U_LIB.S9S_MB_2U(SCH_1):PAGE83
    J2  103  VSS45 SCONN288_ADR50017P087CC-SCONN2A   I179 @S9S_MB_2U_LIB.S9S_MB_2U(SCH_1):PAGE83
    J2  106  VSS46 SCONN288_ADR50017P087CC-SCONN2A   I179 @S9S_MB_2U_LIB.S9S_MB_2U(SCH_1):PAGE83
    J2  108  VSS47 SCONN288_ADR50017P087CC-SCONN2A   I179 @S9S_MB_2U_LIB.S9S_MB_2U(SCH_1):PAGE83
    J2  110  VSS48 SCONN288_ADR50017P087CC-SCONN2A   I179 @S9S_MB_2U_LIB.S9S_MB_2U(SCH_1):PAGE83
    J2  112  VSS49 SCONN288_ADR50017P087CC-SCONN2A   I179 @S9S_MB_2U_LIB.S9S_MB_2U(SCH_1):PAGE83
    J2  114  VSS50 SCONN288_ADR50017P087CC-SCONN2A   I179 @S9S_MB_2U_LIB.S9S_MB_2U(SCH_1):PAGE83
    J2  117  VSS51 SCONN288_ADR50017P087CC-SCONN2A   I179 @S9S_MB_2U_LIB.S9S_MB_2U(SCH_1):PAGE83
    J2  119  VSS52 SCONN288_ADR50017P087CC-SCONN2A   I179 @S9S_MB_2U_LIB.S9S_MB_2U(SCH_1):PAGE83
    J2  121  VSS53 SCONN288_ADR50017P087CC-SCONN2A   I179 @S9S_MB_2U_LIB.S9S_MB_2U(SCH_1):PAGE83
    J2  123  VSS54 SCONN288_ADR50017P087CC-SCONN2A   I179 @S9S_MB_2U_LIB.S9S_MB_2U(SCH_1):PAGE83
    J2  125  VSS55 SCONN288_ADR50017P087CC-SCONN2A   I179 @S9S_MB_2U_LIB.S9S_MB_2U(SCH_1):PAGE83
    J2  128  VSS56 SCONN288_ADR50017P087CC-SCONN2A   I179 @S9S_MB_2U_LIB.S9S_MB_2U(SCH_1):PAGE83
    J2  130  VSS57 SCONN288_ADR50017P087CC-SCONN2A   I179 @S9S_MB_2U_LIB.S9S_MB_2U(SCH_1):PAGE83
    J2  132  VSS58 SCONN288_ADR50017P087CC-SCONN2A   I179 @S9S_MB_2U_LIB.S9S_MB_2U(SCH_1):PAGE83
    J2  134  VSS59 SCONN288_ADR50017P087CC-SCONN2A   I179 @S9S_MB_2U_LIB.S9S_MB_2U(SCH_1):PAGE83
    J2  136  VSS60 SCONN288_ADR50017P087CC-SCONN2A   I179 @S9S_MB_2U_LIB.S9S_MB_2U(SCH_1):PAGE83
    J2  139  VSS61 SCONN288_ADR50017P087CC-SCONN2A   I179 @S9S_MB_2U_LIB.S9S_MB_2U(SCH_1):PAGE83
    J2  141  VSS62 SCONN288_ADR50017P087CC-SCONN2A   I179 @S9S_MB_2U_LIB.S9S_MB_2U(SCH_1):PAGE83
    J2  143  VSS63 SCONN288_ADR50017P087CC-SCONN2A   I179 @S9S_MB_2U_LIB.S9S_MB_2U(SCH_1):PAGE83
    J2  151  VSS64 SCONN288_ADR50017P087CC-SCONN2A   I179 @S9S_MB_2U_LIB.S9S_MB_2U(SCH_1):PAGE83
    J2  153  VSS65 SCONN288_ADR50017P087CC-SCONN2A   I179 @S9S_MB_2U_LIB.S9S_MB_2U(SCH_1):PAGE83
    J2  155  VSS66 SCONN288_ADR50017P087CC-SCONN2A   I179 @S9S_MB_2U_LIB.S9S_MB_2U(SCH_1):PAGE83
    J2  158  VSS67 SCONN288_ADR50017P087CC-SCONN2A   I179 @S9S_MB_2U_LIB.S9S_MB_2U(SCH_1):PAGE83
    J2  160  VSS68 SCONN288_ADR50017P087CC-SCONN2A   I179 @S9S_MB_2U_LIB.S9S_MB_2U(SCH_1):PAGE83
    J2  162  VSS69 SCONN288_ADR50017P087CC-SCONN2A   I179 @S9S_MB_2U_LIB.S9S_MB_2U(SCH_1):PAGE83
    J2  164  VSS70 SCONN288_ADR50017P087CC-SCONN2A   I179 @S9S_MB_2U_LIB.S9S_MB_2U(SCH_1):PAGE83
    J2  166  VSS71 SCONN288_ADR50017P087CC-SCONN2A   I179 @S9S_MB_2U_LIB.S9S_MB_2U(SCH_1):PAGE83
    J2  169  VSS72 SCONN288_ADR50017P087CC-SCONN2A   I179 @S9S_MB_2U_LIB.S9S_MB_2U(SCH_1):PAGE83
    J2  171  VSS73 SCONN288_ADR50017P087CC-SCONN2A   I179 @S9S_MB_2U_LIB.S9S_MB_2U(SCH_1):PAGE83
    J2  173  VSS74 SCONN288_ADR50017P087CC-SCONN2A   I179 @S9S_MB_2U_LIB.S9S_MB_2U(SCH_1):PAGE83
    J2  175  VSS75 SCONN288_ADR50017P087CC-SCONN2A   I179 @S9S_MB_2U_LIB.S9S_MB_2U(SCH_1):PAGE83
    J2  177  VSS76 SCONN288_ADR50017P087CC-SCONN2A   I179 @S9S_MB_2U_LIB.S9S_MB_2U(SCH_1):PAGE83
    J2  180  VSS77 SCONN288_ADR50017P087CC-SCONN2A   I179 @S9S_MB_2U_LIB.S9S_MB_2U(SCH_1):PAGE83
    J2  182  VSS78 SCONN288_ADR50017P087CC-SCONN2A   I179 @S9S_MB_2U_LIB.S9S_MB_2U(SCH_1):PAGE83
    J2  184  VSS79 SCONN288_ADR50017P087CC-SCONN2A   I179 @S9S_MB_2U_LIB.S9S_MB_2U(SCH_1):PAGE83
    J2  186  VSS80 SCONN288_ADR50017P087CC-SCONN2A   I179 @S9S_MB_2U_LIB.S9S_MB_2U(SCH_1):PAGE83
    J2  188  VSS81 SCONN288_ADR50017P087CC-SCONN2A   I179 @S9S_MB_2U_LIB.S9S_MB_2U(SCH_1):PAGE83
    J2  191  VSS82 SCONN288_ADR50017P087CC-SCONN2A   I179 @S9S_MB_2U_LIB.S9S_MB_2U(SCH_1):PAGE83
    J2  193  VSS83 SCONN288_ADR50017P087CC-SCONN2A   I179 @S9S_MB_2U_LIB.S9S_MB_2U(SCH_1):PAGE83
    J2  195  VSS84 SCONN288_ADR50017P087CC-SCONN2A   I179 @S9S_MB_2U_LIB.S9S_MB_2U(SCH_1):PAGE83
    J2  197  VSS85 SCONN288_ADR50017P087CC-SCONN2A   I179 @S9S_MB_2U_LIB.S9S_MB_2U(SCH_1):PAGE83
    J2  199  VSS86 SCONN288_ADR50017P087CC-SCONN2A   I179 @S9S_MB_2U_LIB.S9S_MB_2U(SCH_1):PAGE83
    J2  202  VSS87 SCONN288_ADR50017P087CC-SCONN2A   I179 @S9S_MB_2U_LIB.S9S_MB_2U(SCH_1):PAGE83
    J2  204  VSS88 SCONN288_ADR50017P087CC-SCONN2A   I179 @S9S_MB_2U_LIB.S9S_MB_2U(SCH_1):PAGE83
    J2  206  VSS89 SCONN288_ADR50017P087CC-SCONN2A   I179 @S9S_MB_2U_LIB.S9S_MB_2U(SCH_1):PAGE83
    J2  208  VSS90 SCONN288_ADR50017P087CC-SCONN2A   I179 @S9S_MB_2U_LIB.S9S_MB_2U(SCH_1):PAGE83
    J2  210  VSS91 SCONN288_ADR50017P087CC-SCONN2A   I179 @S9S_MB_2U_LIB.S9S_MB_2U(SCH_1):PAGE83
    J2  212  VSS92 SCONN288_ADR50017P087CC-SCONN2A   I179 @S9S_MB_2U_LIB.S9S_MB_2U(SCH_1):PAGE83
    J2  214  VSS93 SCONN288_ADR50017P087CC-SCONN2A   I179 @S9S_MB_2U_LIB.S9S_MB_2U(SCH_1):PAGE83
    J2  216  VSS94 SCONN288_ADR50017P087CC-SCONN2A   I179 @S9S_MB_2U_LIB.S9S_MB_2U(SCH_1):PAGE83
    J2  219  VSS95 SCONN288_ADR50017P087CC-SCONN2A   I179 @S9S_MB_2U_LIB.S9S_MB_2U(SCH_1):PAGE83
    J2  222  VSS96 SCONN288_ADR50017P087CC-SCONN2A   I179 @S9S_MB_2U_LIB.S9S_MB_2U(SCH_1):PAGE83
    J2  224  VSS97 SCONN288_ADR50017P087CC-SCONN2A   I179 @S9S_MB_2U_LIB.S9S_MB_2U(SCH_1):PAGE83
    J2  226  VSS98 SCONN288_ADR50017P087CC-SCONN2A   I179 @S9S_MB_2U_LIB.S9S_MB_2U(SCH_1):PAGE83
    J2  228  VSS99 SCONN288_ADR50017P087CC-SCONN2A   I179 @S9S_MB_2U_LIB.S9S_MB_2U(SCH_1):PAGE83
    J2  230 VSS100 SCONN288_ADR50017P087CC-SCONN2A   I179 @S9S_MB_2U_LIB.S9S_MB_2U(SCH_1):PAGE83
    J2  233 VSS101 SCONN288_ADR50017P087CC-SCONN2A   I179 @S9S_MB_2U_LIB.S9S_MB_2U(SCH_1):PAGE83
    J2  235 VSS102 SCONN288_ADR50017P087CC-SCONN2A   I179 @S9S_MB_2U_LIB.S9S_MB_2U(SCH_1):PAGE83
    J2  237 VSS103 SCONN288_ADR50017P087CC-SCONN2A   I179 @S9S_MB_2U_LIB.S9S_MB_2U(SCH_1):PAGE83
    J2  240 VSS104 SCONN288_ADR50017P087CC-SCONN2A   I179 @S9S_MB_2U_LIB.S9S_MB_2U(SCH_1):PAGE83
    J2  242 VSS105 SCONN288_ADR50017P087CC-SCONN2A   I179 @S9S_MB_2U_LIB.S9S_MB_2U(SCH_1):PAGE83
    J2  244 VSS106 SCONN288_ADR50017P087CC-SCONN2A   I179 @S9S_MB_2U_LIB.S9S_MB_2U(SCH_1):PAGE83
    J2  246 VSS107 SCONN288_ADR50017P087CC-SCONN2A   I179 @S9S_MB_2U_LIB.S9S_MB_2U(SCH_1):PAGE83
    J2  248 VSS108 SCONN288_ADR50017P087CC-SCONN2A   I179 @S9S_MB_2U_LIB.S9S_MB_2U(SCH_1):PAGE83
    J2  251 VSS109 SCONN288_ADR50017P087CC-SCONN2A   I179 @S9S_MB_2U_LIB.S9S_MB_2U(SCH_1):PAGE83
    J2  253 VSS110 SCONN288_ADR50017P087CC-SCONN2A   I179 @S9S_MB_2U_LIB.S9S_MB_2U(SCH_1):PAGE83
    J2  255 VSS111 SCONN288_ADR50017P087CC-SCONN2A   I179 @S9S_MB_2U_LIB.S9S_MB_2U(SCH_1):PAGE83
    J2  257 VSS112 SCONN288_ADR50017P087CC-SCONN2A   I179 @S9S_MB_2U_LIB.S9S_MB_2U(SCH_1):PAGE83
    J2  259 VSS113 SCONN288_ADR50017P087CC-SCONN2A   I179 @S9S_MB_2U_LIB.S9S_MB_2U(SCH_1):PAGE83
    J2  262 VSS114 SCONN288_ADR50017P087CC-SCONN2A   I179 @S9S_MB_2U_LIB.S9S_MB_2U(SCH_1):PAGE83
    J2  264 VSS115 SCONN288_ADR50017P087CC-SCONN2A   I179 @S9S_MB_2U_LIB.S9S_MB_2U(SCH_1):PAGE83
    J2  266 VSS116 SCONN288_ADR50017P087CC-SCONN2A   I179 @S9S_MB_2U_LIB.S9S_MB_2U(SCH_1):PAGE83
    J2  268 VSS117 SCONN288_ADR50017P087CC-SCONN2A   I179 @S9S_MB_2U_LIB.S9S_MB_2U(SCH_1):PAGE83
    J2  270 VSS118 SCONN288_ADR50017P087CC-SCONN2A   I179 @S9S_MB_2U_LIB.S9S_MB_2U(SCH_1):PAGE83
    J2  273 VSS119 SCONN288_ADR50017P087CC-SCONN2A   I179 @S9S_MB_2U_LIB.S9S_MB_2U(SCH_1):PAGE83
    J2  275 VSS120 SCONN288_ADR50017P087CC-SCONN2A   I179 @S9S_MB_2U_LIB.S9S_MB_2U(SCH_1):PAGE83
    J2  277 VSS121 SCONN288_ADR50017P087CC-SCONN2A   I179 @S9S_MB_2U_LIB.S9S_MB_2U(SCH_1):PAGE83
    J2  279 VSS122 SCONN288_ADR50017P087CC-SCONN2A   I179 @S9S_MB_2U_LIB.S9S_MB_2U(SCH_1):PAGE83
    J2  281 VSS123 SCONN288_ADR50017P087CC-SCONN2A   I179 @S9S_MB_2U_LIB.S9S_MB_2U(SCH_1):PAGE83
    J2  284 VSS124 SCONN288_ADR50017P087CC-SCONN2A   I179 @S9S_MB_2U_LIB.S9S_MB_2U(SCH_1):PAGE83
    J2  286 VSS125 SCONN288_ADR50017P087CC-SCONN2A   I179 @S9S_MB_2U_LIB.S9S_MB_2U(SCH_1):PAGE83
    J2  288 VSS126 SCONN288_ADR50017P087CC-SCONN2A   I179 @S9S_MB_2U_LIB.S9S_MB_2U(SCH_1):PAGE83
   R28    2      B Q_RES_0402LF-23.2K,1%,1/16W,CHA    I10 @S9S_MB_2U_LIB.S9S_MB_2U(SCH_1):PAGE84
    C8    2      B Q_CAP_C0402-2.2UF,6.3V,20%,X6SA   I121 @S9S_MB_2U_LIB.S9S_MB_2U(SCH_1):PAGE84
    C9    2      B Q_CAP_C0805-10UF,16V,10%,X6S,CA   I122 @S9S_MB_2U_LIB.S9S_MB_2U(SCH_1):PAGE84
   C10    2      B Q_CAP_C0805-10UF,16V,10%,X6S,CA   I144 @S9S_MB_2U_LIB.S9S_MB_2U(SCH_1):PAGE84
    J3   G1     G1 SCONN288_ADR50017P130CC-SCONN2A   I178 @S9S_MB_2U_LIB.S9S_MB_2U(SCH_1):PAGE84
    J3   G2     G2 SCONN288_ADR50017P130CC-SCONN2A   I178 @S9S_MB_2U_LIB.S9S_MB_2U(SCH_1):PAGE84
    J3   G3     G3 SCONN288_ADR50017P130CC-SCONN2A   I178 @S9S_MB_2U_LIB.S9S_MB_2U(SCH_1):PAGE84
    J3    6   VSS0 SCONN288_ADR50017P130CC-SCONN2A   I178 @S9S_MB_2U_LIB.S9S_MB_2U(SCH_1):PAGE84
    J3    8   VSS1 SCONN288_ADR50017P130CC-SCONN2A   I178 @S9S_MB_2U_LIB.S9S_MB_2U(SCH_1):PAGE84
    J3   10   VSS2 SCONN288_ADR50017P130CC-SCONN2A   I178 @S9S_MB_2U_LIB.S9S_MB_2U(SCH_1):PAGE84
    J3   13   VSS3 SCONN288_ADR50017P130CC-SCONN2A   I178 @S9S_MB_2U_LIB.S9S_MB_2U(SCH_1):PAGE84
    J3   15   VSS4 SCONN288_ADR50017P130CC-SCONN2A   I178 @S9S_MB_2U_LIB.S9S_MB_2U(SCH_1):PAGE84
    J3   17   VSS5 SCONN288_ADR50017P130CC-SCONN2A   I178 @S9S_MB_2U_LIB.S9S_MB_2U(SCH_1):PAGE84
    J3   19   VSS6 SCONN288_ADR50017P130CC-SCONN2A   I178 @S9S_MB_2U_LIB.S9S_MB_2U(SCH_1):PAGE84
    J3   21   VSS7 SCONN288_ADR50017P130CC-SCONN2A   I178 @S9S_MB_2U_LIB.S9S_MB_2U(SCH_1):PAGE84
    J3   24   VSS8 SCONN288_ADR50017P130CC-SCONN2A   I178 @S9S_MB_2U_LIB.S9S_MB_2U(SCH_1):PAGE84
    J3   26   VSS9 SCONN288_ADR50017P130CC-SCONN2A   I178 @S9S_MB_2U_LIB.S9S_MB_2U(SCH_1):PAGE84
    J3   28  VSS10 SCONN288_ADR50017P130CC-SCONN2A   I178 @S9S_MB_2U_LIB.S9S_MB_2U(SCH_1):PAGE84
    J3   30  VSS11 SCONN288_ADR50017P130CC-SCONN2A   I178 @S9S_MB_2U_LIB.S9S_MB_2U(SCH_1):PAGE84
    J3   32  VSS12 SCONN288_ADR50017P130CC-SCONN2A   I178 @S9S_MB_2U_LIB.S9S_MB_2U(SCH_1):PAGE84
    J3   35  VSS13 SCONN288_ADR50017P130CC-SCONN2A   I178 @S9S_MB_2U_LIB.S9S_MB_2U(SCH_1):PAGE84
    J3   37  VSS14 SCONN288_ADR50017P130CC-SCONN2A   I178 @S9S_MB_2U_LIB.S9S_MB_2U(SCH_1):PAGE84
    J3   39  VSS15 SCONN288_ADR50017P130CC-SCONN2A   I178 @S9S_MB_2U_LIB.S9S_MB_2U(SCH_1):PAGE84
    J3   41  VSS16 SCONN288_ADR50017P130CC-SCONN2A   I178 @S9S_MB_2U_LIB.S9S_MB_2U(SCH_1):PAGE84
    J3   43  VSS17 SCONN288_ADR50017P130CC-SCONN2A   I178 @S9S_MB_2U_LIB.S9S_MB_2U(SCH_1):PAGE84
    J3   46  VSS18 SCONN288_ADR50017P130CC-SCONN2A   I178 @S9S_MB_2U_LIB.S9S_MB_2U(SCH_1):PAGE84
    J3   48  VSS19 SCONN288_ADR50017P130CC-SCONN2A   I178 @S9S_MB_2U_LIB.S9S_MB_2U(SCH_1):PAGE84
    J3   50  VSS20 SCONN288_ADR50017P130CC-SCONN2A   I178 @S9S_MB_2U_LIB.S9S_MB_2U(SCH_1):PAGE84
    J3   52  VSS21 SCONN288_ADR50017P130CC-SCONN2A   I178 @S9S_MB_2U_LIB.S9S_MB_2U(SCH_1):PAGE84
    J3   54  VSS22 SCONN288_ADR50017P130CC-SCONN2A   I178 @S9S_MB_2U_LIB.S9S_MB_2U(SCH_1):PAGE84
    J3   57  VSS23 SCONN288_ADR50017P130CC-SCONN2A   I178 @S9S_MB_2U_LIB.S9S_MB_2U(SCH_1):PAGE84
    J3   59  VSS24 SCONN288_ADR50017P130CC-SCONN2A   I178 @S9S_MB_2U_LIB.S9S_MB_2U(SCH_1):PAGE84
    J3   61  VSS25 SCONN288_ADR50017P130CC-SCONN2A   I178 @S9S_MB_2U_LIB.S9S_MB_2U(SCH_1):PAGE84
    J3   63  VSS26 SCONN288_ADR50017P130CC-SCONN2A   I178 @S9S_MB_2U_LIB.S9S_MB_2U(SCH_1):PAGE84
    J3   65  VSS27 SCONN288_ADR50017P130CC-SCONN2A   I178 @S9S_MB_2U_LIB.S9S_MB_2U(SCH_1):PAGE84
    J3   67  VSS28 SCONN288_ADR50017P130CC-SCONN2A   I178 @S9S_MB_2U_LIB.S9S_MB_2U(SCH_1):PAGE84
    J3   69  VSS29 SCONN288_ADR50017P130CC-SCONN2A   I178 @S9S_MB_2U_LIB.S9S_MB_2U(SCH_1):PAGE84
    J3   71  VSS30 SCONN288_ADR50017P130CC-SCONN2A   I178 @S9S_MB_2U_LIB.S9S_MB_2U(SCH_1):PAGE84
    J3   73  VSS31 SCONN288_ADR50017P130CC-SCONN2A   I178 @S9S_MB_2U_LIB.S9S_MB_2U(SCH_1):PAGE84
    J3   75  VSS32 SCONN288_ADR50017P130CC-SCONN2A   I178 @S9S_MB_2U_LIB.S9S_MB_2U(SCH_1):PAGE84
    J3   77  VSS33 SCONN288_ADR50017P130CC-SCONN2A   I178 @S9S_MB_2U_LIB.S9S_MB_2U(SCH_1):PAGE84
    J3   79  VSS34 SCONN288_ADR50017P130CC-SCONN2A   I178 @S9S_MB_2U_LIB.S9S_MB_2U(SCH_1):PAGE84
    J3   81  VSS35 SCONN288_ADR50017P130CC-SCONN2A   I178 @S9S_MB_2U_LIB.S9S_MB_2U(SCH_1):PAGE84
    J3   83  VSS36 SCONN288_ADR50017P130CC-SCONN2A   I178 @S9S_MB_2U_LIB.S9S_MB_2U(SCH_1):PAGE84
    J3   85  VSS37 SCONN288_ADR50017P130CC-SCONN2A   I178 @S9S_MB_2U_LIB.S9S_MB_2U(SCH_1):PAGE84
    J3   88  VSS38 SCONN288_ADR50017P130CC-SCONN2A   I178 @S9S_MB_2U_LIB.S9S_MB_2U(SCH_1):PAGE84
    J3   90  VSS39 SCONN288_ADR50017P130CC-SCONN2A   I178 @S9S_MB_2U_LIB.S9S_MB_2U(SCH_1):PAGE84
    J3   92  VSS40 SCONN288_ADR50017P130CC-SCONN2A   I178 @S9S_MB_2U_LIB.S9S_MB_2U(SCH_1):PAGE84
    J3   95  VSS41 SCONN288_ADR50017P130CC-SCONN2A   I178 @S9S_MB_2U_LIB.S9S_MB_2U(SCH_1):PAGE84
    J3   97  VSS42 SCONN288_ADR50017P130CC-SCONN2A   I178 @S9S_MB_2U_LIB.S9S_MB_2U(SCH_1):PAGE84
    J3   99  VSS43 SCONN288_ADR50017P130CC-SCONN2A   I178 @S9S_MB_2U_LIB.S9S_MB_2U(SCH_1):PAGE84
    J3  101  VSS44 SCONN288_ADR50017P130CC-SCONN2A   I178 @S9S_MB_2U_LIB.S9S_MB_2U(SCH_1):PAGE84
    J3  103  VSS45 SCONN288_ADR50017P130CC-SCONN2A   I178 @S9S_MB_2U_LIB.S9S_MB_2U(SCH_1):PAGE84
    J3  106  VSS46 SCONN288_ADR50017P130CC-SCONN2A   I178 @S9S_MB_2U_LIB.S9S_MB_2U(SCH_1):PAGE84
    J3  108  VSS47 SCONN288_ADR50017P130CC-SCONN2A   I178 @S9S_MB_2U_LIB.S9S_MB_2U(SCH_1):PAGE84
    J3  110  VSS48 SCONN288_ADR50017P130CC-SCONN2A   I178 @S9S_MB_2U_LIB.S9S_MB_2U(SCH_1):PAGE84
    J3  112  VSS49 SCONN288_ADR50017P130CC-SCONN2A   I178 @S9S_MB_2U_LIB.S9S_MB_2U(SCH_1):PAGE84
    J3  114  VSS50 SCONN288_ADR50017P130CC-SCONN2A   I178 @S9S_MB_2U_LIB.S9S_MB_2U(SCH_1):PAGE84
    J3  117  VSS51 SCONN288_ADR50017P130CC-SCONN2A   I178 @S9S_MB_2U_LIB.S9S_MB_2U(SCH_1):PAGE84
    J3  119  VSS52 SCONN288_ADR50017P130CC-SCONN2A   I178 @S9S_MB_2U_LIB.S9S_MB_2U(SCH_1):PAGE84
    J3  121  VSS53 SCONN288_ADR50017P130CC-SCONN2A   I178 @S9S_MB_2U_LIB.S9S_MB_2U(SCH_1):PAGE84
    J3  123  VSS54 SCONN288_ADR50017P130CC-SCONN2A   I178 @S9S_MB_2U_LIB.S9S_MB_2U(SCH_1):PAGE84
    J3  125  VSS55 SCONN288_ADR50017P130CC-SCONN2A   I178 @S9S_MB_2U_LIB.S9S_MB_2U(SCH_1):PAGE84
    J3  128  VSS56 SCONN288_ADR50017P130CC-SCONN2A   I178 @S9S_MB_2U_LIB.S9S_MB_2U(SCH_1):PAGE84
    J3  130  VSS57 SCONN288_ADR50017P130CC-SCONN2A   I178 @S9S_MB_2U_LIB.S9S_MB_2U(SCH_1):PAGE84
    J3  132  VSS58 SCONN288_ADR50017P130CC-SCONN2A   I178 @S9S_MB_2U_LIB.S9S_MB_2U(SCH_1):PAGE84
    J3  134  VSS59 SCONN288_ADR50017P130CC-SCONN2A   I178 @S9S_MB_2U_LIB.S9S_MB_2U(SCH_1):PAGE84
    J3  136  VSS60 SCONN288_ADR50017P130CC-SCONN2A   I178 @S9S_MB_2U_LIB.S9S_MB_2U(SCH_1):PAGE84
    J3  139  VSS61 SCONN288_ADR50017P130CC-SCONN2A   I178 @S9S_MB_2U_LIB.S9S_MB_2U(SCH_1):PAGE84
    J3  141  VSS62 SCONN288_ADR50017P130CC-SCONN2A   I178 @S9S_MB_2U_LIB.S9S_MB_2U(SCH_1):PAGE84
    J3  143  VSS63 SCONN288_ADR50017P130CC-SCONN2A   I178 @S9S_MB_2U_LIB.S9S_MB_2U(SCH_1):PAGE84
    J3  151  VSS64 SCONN288_ADR50017P130CC-SCONN2A   I178 @S9S_MB_2U_LIB.S9S_MB_2U(SCH_1):PAGE84
    J3  153  VSS65 SCONN288_ADR50017P130CC-SCONN2A   I178 @S9S_MB_2U_LIB.S9S_MB_2U(SCH_1):PAGE84
    J3  155  VSS66 SCONN288_ADR50017P130CC-SCONN2A   I178 @S9S_MB_2U_LIB.S9S_MB_2U(SCH_1):PAGE84
    J3  158  VSS67 SCONN288_ADR50017P130CC-SCONN2A   I178 @S9S_MB_2U_LIB.S9S_MB_2U(SCH_1):PAGE84
    J3  160  VSS68 SCONN288_ADR50017P130CC-SCONN2A   I178 @S9S_MB_2U_LIB.S9S_MB_2U(SCH_1):PAGE84
    J3  162  VSS69 SCONN288_ADR50017P130CC-SCONN2A   I178 @S9S_MB_2U_LIB.S9S_MB_2U(SCH_1):PAGE84
    J3  164  VSS70 SCONN288_ADR50017P130CC-SCONN2A   I178 @S9S_MB_2U_LIB.S9S_MB_2U(SCH_1):PAGE84
    J3  166  VSS71 SCONN288_ADR50017P130CC-SCONN2A   I178 @S9S_MB_2U_LIB.S9S_MB_2U(SCH_1):PAGE84
    J3  169  VSS72 SCONN288_ADR50017P130CC-SCONN2A   I178 @S9S_MB_2U_LIB.S9S_MB_2U(SCH_1):PAGE84
    J3  171  VSS73 SCONN288_ADR50017P130CC-SCONN2A   I178 @S9S_MB_2U_LIB.S9S_MB_2U(SCH_1):PAGE84
    J3  173  VSS74 SCONN288_ADR50017P130CC-SCONN2A   I178 @S9S_MB_2U_LIB.S9S_MB_2U(SCH_1):PAGE84
    J3  175  VSS75 SCONN288_ADR50017P130CC-SCONN2A   I178 @S9S_MB_2U_LIB.S9S_MB_2U(SCH_1):PAGE84
    J3  177  VSS76 SCONN288_ADR50017P130CC-SCONN2A   I178 @S9S_MB_2U_LIB.S9S_MB_2U(SCH_1):PAGE84
    J3  180  VSS77 SCONN288_ADR50017P130CC-SCONN2A   I178 @S9S_MB_2U_LIB.S9S_MB_2U(SCH_1):PAGE84
    J3  182  VSS78 SCONN288_ADR50017P130CC-SCONN2A   I178 @S9S_MB_2U_LIB.S9S_MB_2U(SCH_1):PAGE84
    J3  184  VSS79 SCONN288_ADR50017P130CC-SCONN2A   I178 @S9S_MB_2U_LIB.S9S_MB_2U(SCH_1):PAGE84
    J3  186  VSS80 SCONN288_ADR50017P130CC-SCONN2A   I178 @S9S_MB_2U_LIB.S9S_MB_2U(SCH_1):PAGE84
    J3  188  VSS81 SCONN288_ADR50017P130CC-SCONN2A   I178 @S9S_MB_2U_LIB.S9S_MB_2U(SCH_1):PAGE84
    J3  191  VSS82 SCONN288_ADR50017P130CC-SCONN2A   I178 @S9S_MB_2U_LIB.S9S_MB_2U(SCH_1):PAGE84
    J3  193  VSS83 SCONN288_ADR50017P130CC-SCONN2A   I178 @S9S_MB_2U_LIB.S9S_MB_2U(SCH_1):PAGE84
    J3  195  VSS84 SCONN288_ADR50017P130CC-SCONN2A   I178 @S9S_MB_2U_LIB.S9S_MB_2U(SCH_1):PAGE84
    J3  197  VSS85 SCONN288_ADR50017P130CC-SCONN2A   I178 @S9S_MB_2U_LIB.S9S_MB_2U(SCH_1):PAGE84
    J3  199  VSS86 SCONN288_ADR50017P130CC-SCONN2A   I178 @S9S_MB_2U_LIB.S9S_MB_2U(SCH_1):PAGE84
    J3  202  VSS87 SCONN288_ADR50017P130CC-SCONN2A   I178 @S9S_MB_2U_LIB.S9S_MB_2U(SCH_1):PAGE84
    J3  204  VSS88 SCONN288_ADR50017P130CC-SCONN2A   I178 @S9S_MB_2U_LIB.S9S_MB_2U(SCH_1):PAGE84
    J3  206  VSS89 SCONN288_ADR50017P130CC-SCONN2A   I178 @S9S_MB_2U_LIB.S9S_MB_2U(SCH_1):PAGE84
    J3  208  VSS90 SCONN288_ADR50017P130CC-SCONN2A   I178 @S9S_MB_2U_LIB.S9S_MB_2U(SCH_1):PAGE84
    J3  210  VSS91 SCONN288_ADR50017P130CC-SCONN2A   I178 @S9S_MB_2U_LIB.S9S_MB_2U(SCH_1):PAGE84
    J3  212  VSS92 SCONN288_ADR50017P130CC-SCONN2A   I178 @S9S_MB_2U_LIB.S9S_MB_2U(SCH_1):PAGE84
    J3  214  VSS93 SCONN288_ADR50017P130CC-SCONN2A   I178 @S9S_MB_2U_LIB.S9S_MB_2U(SCH_1):PAGE84
    J3  216  VSS94 SCONN288_ADR50017P130CC-SCONN2A   I178 @S9S_MB_2U_LIB.S9S_MB_2U(SCH_1):PAGE84
    J3  219  VSS95 SCONN288_ADR50017P130CC-SCONN2A   I178 @S9S_MB_2U_LIB.S9S_MB_2U(SCH_1):PAGE84
    J3  222  VSS96 SCONN288_ADR50017P130CC-SCONN2A   I178 @S9S_MB_2U_LIB.S9S_MB_2U(SCH_1):PAGE84
    J3  224  VSS97 SCONN288_ADR50017P130CC-SCONN2A   I178 @S9S_MB_2U_LIB.S9S_MB_2U(SCH_1):PAGE84
    J3  226  VSS98 SCONN288_ADR50017P130CC-SCONN2A   I178 @S9S_MB_2U_LIB.S9S_MB_2U(SCH_1):PAGE84
    J3  228  VSS99 SCONN288_ADR50017P130CC-SCONN2A   I178 @S9S_MB_2U_LIB.S9S_MB_2U(SCH_1):PAGE84
    J3  230 VSS100 SCONN288_ADR50017P130CC-SCONN2A   I178 @S9S_MB_2U_LIB.S9S_MB_2U(SCH_1):PAGE84
    J3  233 VSS101 SCONN288_ADR50017P130CC-SCONN2A   I178 @S9S_MB_2U_LIB.S9S_MB_2U(SCH_1):PAGE84
    J3  235 VSS102 SCONN288_ADR50017P130CC-SCONN2A   I178 @S9S_MB_2U_LIB.S9S_MB_2U(SCH_1):PAGE84
    J3  237 VSS103 SCONN288_ADR50017P130CC-SCONN2A   I178 @S9S_MB_2U_LIB.S9S_MB_2U(SCH_1):PAGE84
    J3  240 VSS104 SCONN288_ADR50017P130CC-SCONN2A   I178 @S9S_MB_2U_LIB.S9S_MB_2U(SCH_1):PAGE84
    J3  242 VSS105 SCONN288_ADR50017P130CC-SCONN2A   I178 @S9S_MB_2U_LIB.S9S_MB_2U(SCH_1):PAGE84
    J3  244 VSS106 SCONN288_ADR50017P130CC-SCONN2A   I178 @S9S_MB_2U_LIB.S9S_MB_2U(SCH_1):PAGE84
    J3  246 VSS107 SCONN288_ADR50017P130CC-SCONN2A   I178 @S9S_MB_2U_LIB.S9S_MB_2U(SCH_1):PAGE84
    J3  248 VSS108 SCONN288_ADR50017P130CC-SCONN2A   I178 @S9S_MB_2U_LIB.S9S_MB_2U(SCH_1):PAGE84
    J3  251 VSS109 SCONN288_ADR50017P130CC-SCONN2A   I178 @S9S_MB_2U_LIB.S9S_MB_2U(SCH_1):PAGE84
    J3  253 VSS110 SCONN288_ADR50017P130CC-SCONN2A   I178 @S9S_MB_2U_LIB.S9S_MB_2U(SCH_1):PAGE84
    J3  255 VSS111 SCONN288_ADR50017P130CC-SCONN2A   I178 @S9S_MB_2U_LIB.S9S_MB_2U(SCH_1):PAGE84
    J3  257 VSS112 SCONN288_ADR50017P130CC-SCONN2A   I178 @S9S_MB_2U_LIB.S9S_MB_2U(SCH_1):PAGE84
    J3  259 VSS113 SCONN288_ADR50017P130CC-SCONN2A   I178 @S9S_MB_2U_LIB.S9S_MB_2U(SCH_1):PAGE84
    J3  262 VSS114 SCONN288_ADR50017P130CC-SCONN2A   I178 @S9S_MB_2U_LIB.S9S_MB_2U(SCH_1):PAGE84
    J3  264 VSS115 SCONN288_ADR50017P130CC-SCONN2A   I178 @S9S_MB_2U_LIB.S9S_MB_2U(SCH_1):PAGE84
    J3  266 VSS116 SCONN288_ADR50017P130CC-SCONN2A   I178 @S9S_MB_2U_LIB.S9S_MB_2U(SCH_1):PAGE84
    J3  268 VSS117 SCONN288_ADR50017P130CC-SCONN2A   I178 @S9S_MB_2U_LIB.S9S_MB_2U(SCH_1):PAGE84
    J3  270 VSS118 SCONN288_ADR50017P130CC-SCONN2A   I178 @S9S_MB_2U_LIB.S9S_MB_2U(SCH_1):PAGE84
    J3  273 VSS119 SCONN288_ADR50017P130CC-SCONN2A   I178 @S9S_MB_2U_LIB.S9S_MB_2U(SCH_1):PAGE84
    J3  275 VSS120 SCONN288_ADR50017P130CC-SCONN2A   I178 @S9S_MB_2U_LIB.S9S_MB_2U(SCH_1):PAGE84
    J3  277 VSS121 SCONN288_ADR50017P130CC-SCONN2A   I178 @S9S_MB_2U_LIB.S9S_MB_2U(SCH_1):PAGE84
    J3  279 VSS122 SCONN288_ADR50017P130CC-SCONN2A   I178 @S9S_MB_2U_LIB.S9S_MB_2U(SCH_1):PAGE84
    J3  281 VSS123 SCONN288_ADR50017P130CC-SCONN2A   I178 @S9S_MB_2U_LIB.S9S_MB_2U(SCH_1):PAGE84
    J3  284 VSS124 SCONN288_ADR50017P130CC-SCONN2A   I178 @S9S_MB_2U_LIB.S9S_MB_2U(SCH_1):PAGE84
    J3  286 VSS125 SCONN288_ADR50017P130CC-SCONN2A   I178 @S9S_MB_2U_LIB.S9S_MB_2U(SCH_1):PAGE84
    J3  288 VSS126 SCONN288_ADR50017P130CC-SCONN2A   I178 @S9S_MB_2U_LIB.S9S_MB_2U(SCH_1):PAGE84
   R29    2      B Q_RES_0402LF-35.7K,1%,1/16W,CHA     I1 @S9S_MB_2U_LIB.S9S_MB_2U(SCH_1):PAGE85
   C11    2      B Q_CAP_C0402-2.2UF,6.3V,20%,X6SA   I121 @S9S_MB_2U_LIB.S9S_MB_2U(SCH_1):PAGE85
   C12    2      B Q_CAP_C0805-10UF,16V,10%,X6S,CA   I125 @S9S_MB_2U_LIB.S9S_MB_2U(SCH_1):PAGE85
   C13    2      B Q_CAP_C0805-10UF,16V,10%,X6S,CA   I127 @S9S_MB_2U_LIB.S9S_MB_2U(SCH_1):PAGE85
    J4   G1     G1 SCONN288_ADR50017P087CC-SCONN2A   I174 @S9S_MB_2U_LIB.S9S_MB_2U(SCH_1):PAGE85
    J4   G2     G2 SCONN288_ADR50017P087CC-SCONN2A   I174 @S9S_MB_2U_LIB.S9S_MB_2U(SCH_1):PAGE85
    J4   G3     G3 SCONN288_ADR50017P087CC-SCONN2A   I174 @S9S_MB_2U_LIB.S9S_MB_2U(SCH_1):PAGE85
    J4    6   VSS0 SCONN288_ADR50017P087CC-SCONN2A   I174 @S9S_MB_2U_LIB.S9S_MB_2U(SCH_1):PAGE85
    J4    8   VSS1 SCONN288_ADR50017P087CC-SCONN2A   I174 @S9S_MB_2U_LIB.S9S_MB_2U(SCH_1):PAGE85
    J4   10   VSS2 SCONN288_ADR50017P087CC-SCONN2A   I174 @S9S_MB_2U_LIB.S9S_MB_2U(SCH_1):PAGE85
    J4   13   VSS3 SCONN288_ADR50017P087CC-SCONN2A   I174 @S9S_MB_2U_LIB.S9S_MB_2U(SCH_1):PAGE85
    J4   15   VSS4 SCONN288_ADR50017P087CC-SCONN2A   I174 @S9S_MB_2U_LIB.S9S_MB_2U(SCH_1):PAGE85
    J4   17   VSS5 SCONN288_ADR50017P087CC-SCONN2A   I174 @S9S_MB_2U_LIB.S9S_MB_2U(SCH_1):PAGE85
    J4   19   VSS6 SCONN288_ADR50017P087CC-SCONN2A   I174 @S9S_MB_2U_LIB.S9S_MB_2U(SCH_1):PAGE85
    J4   21   VSS7 SCONN288_ADR50017P087CC-SCONN2A   I174 @S9S_MB_2U_LIB.S9S_MB_2U(SCH_1):PAGE85
    J4   24   VSS8 SCONN288_ADR50017P087CC-SCONN2A   I174 @S9S_MB_2U_LIB.S9S_MB_2U(SCH_1):PAGE85
    J4   26   VSS9 SCONN288_ADR50017P087CC-SCONN2A   I174 @S9S_MB_2U_LIB.S9S_MB_2U(SCH_1):PAGE85
    J4   28  VSS10 SCONN288_ADR50017P087CC-SCONN2A   I174 @S9S_MB_2U_LIB.S9S_MB_2U(SCH_1):PAGE85
    J4   30  VSS11 SCONN288_ADR50017P087CC-SCONN2A   I174 @S9S_MB_2U_LIB.S9S_MB_2U(SCH_1):PAGE85
    J4   32  VSS12 SCONN288_ADR50017P087CC-SCONN2A   I174 @S9S_MB_2U_LIB.S9S_MB_2U(SCH_1):PAGE85
    J4   35  VSS13 SCONN288_ADR50017P087CC-SCONN2A   I174 @S9S_MB_2U_LIB.S9S_MB_2U(SCH_1):PAGE85
    J4   37  VSS14 SCONN288_ADR50017P087CC-SCONN2A   I174 @S9S_MB_2U_LIB.S9S_MB_2U(SCH_1):PAGE85
    J4   39  VSS15 SCONN288_ADR50017P087CC-SCONN2A   I174 @S9S_MB_2U_LIB.S9S_MB_2U(SCH_1):PAGE85
    J4   41  VSS16 SCONN288_ADR50017P087CC-SCONN2A   I174 @S9S_MB_2U_LIB.S9S_MB_2U(SCH_1):PAGE85
    J4   43  VSS17 SCONN288_ADR50017P087CC-SCONN2A   I174 @S9S_MB_2U_LIB.S9S_MB_2U(SCH_1):PAGE85
    J4   46  VSS18 SCONN288_ADR50017P087CC-SCONN2A   I174 @S9S_MB_2U_LIB.S9S_MB_2U(SCH_1):PAGE85
    J4   48  VSS19 SCONN288_ADR50017P087CC-SCONN2A   I174 @S9S_MB_2U_LIB.S9S_MB_2U(SCH_1):PAGE85
    J4   50  VSS20 SCONN288_ADR50017P087CC-SCONN2A   I174 @S9S_MB_2U_LIB.S9S_MB_2U(SCH_1):PAGE85
    J4   52  VSS21 SCONN288_ADR50017P087CC-SCONN2A   I174 @S9S_MB_2U_LIB.S9S_MB_2U(SCH_1):PAGE85
    J4   54  VSS22 SCONN288_ADR50017P087CC-SCONN2A   I174 @S9S_MB_2U_LIB.S9S_MB_2U(SCH_1):PAGE85
    J4   57  VSS23 SCONN288_ADR50017P087CC-SCONN2A   I174 @S9S_MB_2U_LIB.S9S_MB_2U(SCH_1):PAGE85
    J4   59  VSS24 SCONN288_ADR50017P087CC-SCONN2A   I174 @S9S_MB_2U_LIB.S9S_MB_2U(SCH_1):PAGE85
    J4   61  VSS25 SCONN288_ADR50017P087CC-SCONN2A   I174 @S9S_MB_2U_LIB.S9S_MB_2U(SCH_1):PAGE85
    J4   63  VSS26 SCONN288_ADR50017P087CC-SCONN2A   I174 @S9S_MB_2U_LIB.S9S_MB_2U(SCH_1):PAGE85
    J4   65  VSS27 SCONN288_ADR50017P087CC-SCONN2A   I174 @S9S_MB_2U_LIB.S9S_MB_2U(SCH_1):PAGE85
    J4   67  VSS28 SCONN288_ADR50017P087CC-SCONN2A   I174 @S9S_MB_2U_LIB.S9S_MB_2U(SCH_1):PAGE85
    J4   69  VSS29 SCONN288_ADR50017P087CC-SCONN2A   I174 @S9S_MB_2U_LIB.S9S_MB_2U(SCH_1):PAGE85
    J4   71  VSS30 SCONN288_ADR50017P087CC-SCONN2A   I174 @S9S_MB_2U_LIB.S9S_MB_2U(SCH_1):PAGE85
    J4   73  VSS31 SCONN288_ADR50017P087CC-SCONN2A   I174 @S9S_MB_2U_LIB.S9S_MB_2U(SCH_1):PAGE85
    J4   75  VSS32 SCONN288_ADR50017P087CC-SCONN2A   I174 @S9S_MB_2U_LIB.S9S_MB_2U(SCH_1):PAGE85
    J4   77  VSS33 SCONN288_ADR50017P087CC-SCONN2A   I174 @S9S_MB_2U_LIB.S9S_MB_2U(SCH_1):PAGE85
    J4   79  VSS34 SCONN288_ADR50017P087CC-SCONN2A   I174 @S9S_MB_2U_LIB.S9S_MB_2U(SCH_1):PAGE85
    J4   81  VSS35 SCONN288_ADR50017P087CC-SCONN2A   I174 @S9S_MB_2U_LIB.S9S_MB_2U(SCH_1):PAGE85
    J4   83  VSS36 SCONN288_ADR50017P087CC-SCONN2A   I174 @S9S_MB_2U_LIB.S9S_MB_2U(SCH_1):PAGE85
    J4   85  VSS37 SCONN288_ADR50017P087CC-SCONN2A   I174 @S9S_MB_2U_LIB.S9S_MB_2U(SCH_1):PAGE85
    J4   88  VSS38 SCONN288_ADR50017P087CC-SCONN2A   I174 @S9S_MB_2U_LIB.S9S_MB_2U(SCH_1):PAGE85
    J4   90  VSS39 SCONN288_ADR50017P087CC-SCONN2A   I174 @S9S_MB_2U_LIB.S9S_MB_2U(SCH_1):PAGE85
    J4   92  VSS40 SCONN288_ADR50017P087CC-SCONN2A   I174 @S9S_MB_2U_LIB.S9S_MB_2U(SCH_1):PAGE85
    J4   95  VSS41 SCONN288_ADR50017P087CC-SCONN2A   I174 @S9S_MB_2U_LIB.S9S_MB_2U(SCH_1):PAGE85
    J4   97  VSS42 SCONN288_ADR50017P087CC-SCONN2A   I174 @S9S_MB_2U_LIB.S9S_MB_2U(SCH_1):PAGE85
    J4   99  VSS43 SCONN288_ADR50017P087CC-SCONN2A   I174 @S9S_MB_2U_LIB.S9S_MB_2U(SCH_1):PAGE85
    J4  101  VSS44 SCONN288_ADR50017P087CC-SCONN2A   I174 @S9S_MB_2U_LIB.S9S_MB_2U(SCH_1):PAGE85
    J4  103  VSS45 SCONN288_ADR50017P087CC-SCONN2A   I174 @S9S_MB_2U_LIB.S9S_MB_2U(SCH_1):PAGE85
    J4  106  VSS46 SCONN288_ADR50017P087CC-SCONN2A   I174 @S9S_MB_2U_LIB.S9S_MB_2U(SCH_1):PAGE85
    J4  108  VSS47 SCONN288_ADR50017P087CC-SCONN2A   I174 @S9S_MB_2U_LIB.S9S_MB_2U(SCH_1):PAGE85
    J4  110  VSS48 SCONN288_ADR50017P087CC-SCONN2A   I174 @S9S_MB_2U_LIB.S9S_MB_2U(SCH_1):PAGE85
    J4  112  VSS49 SCONN288_ADR50017P087CC-SCONN2A   I174 @S9S_MB_2U_LIB.S9S_MB_2U(SCH_1):PAGE85
    J4  114  VSS50 SCONN288_ADR50017P087CC-SCONN2A   I174 @S9S_MB_2U_LIB.S9S_MB_2U(SCH_1):PAGE85
    J4  117  VSS51 SCONN288_ADR50017P087CC-SCONN2A   I174 @S9S_MB_2U_LIB.S9S_MB_2U(SCH_1):PAGE85
    J4  119  VSS52 SCONN288_ADR50017P087CC-SCONN2A   I174 @S9S_MB_2U_LIB.S9S_MB_2U(SCH_1):PAGE85
    J4  121  VSS53 SCONN288_ADR50017P087CC-SCONN2A   I174 @S9S_MB_2U_LIB.S9S_MB_2U(SCH_1):PAGE85
    J4  123  VSS54 SCONN288_ADR50017P087CC-SCONN2A   I174 @S9S_MB_2U_LIB.S9S_MB_2U(SCH_1):PAGE85
    J4  125  VSS55 SCONN288_ADR50017P087CC-SCONN2A   I174 @S9S_MB_2U_LIB.S9S_MB_2U(SCH_1):PAGE85
    J4  128  VSS56 SCONN288_ADR50017P087CC-SCONN2A   I174 @S9S_MB_2U_LIB.S9S_MB_2U(SCH_1):PAGE85
    J4  130  VSS57 SCONN288_ADR50017P087CC-SCONN2A   I174 @S9S_MB_2U_LIB.S9S_MB_2U(SCH_1):PAGE85
    J4  132  VSS58 SCONN288_ADR50017P087CC-SCONN2A   I174 @S9S_MB_2U_LIB.S9S_MB_2U(SCH_1):PAGE85
    J4  134  VSS59 SCONN288_ADR50017P087CC-SCONN2A   I174 @S9S_MB_2U_LIB.S9S_MB_2U(SCH_1):PAGE85
    J4  136  VSS60 SCONN288_ADR50017P087CC-SCONN2A   I174 @S9S_MB_2U_LIB.S9S_MB_2U(SCH_1):PAGE85
    J4  139  VSS61 SCONN288_ADR50017P087CC-SCONN2A   I174 @S9S_MB_2U_LIB.S9S_MB_2U(SCH_1):PAGE85
    J4  141  VSS62 SCONN288_ADR50017P087CC-SCONN2A   I174 @S9S_MB_2U_LIB.S9S_MB_2U(SCH_1):PAGE85
    J4  143  VSS63 SCONN288_ADR50017P087CC-SCONN2A   I174 @S9S_MB_2U_LIB.S9S_MB_2U(SCH_1):PAGE85
    J4  151  VSS64 SCONN288_ADR50017P087CC-SCONN2A   I174 @S9S_MB_2U_LIB.S9S_MB_2U(SCH_1):PAGE85
    J4  153  VSS65 SCONN288_ADR50017P087CC-SCONN2A   I174 @S9S_MB_2U_LIB.S9S_MB_2U(SCH_1):PAGE85
    J4  155  VSS66 SCONN288_ADR50017P087CC-SCONN2A   I174 @S9S_MB_2U_LIB.S9S_MB_2U(SCH_1):PAGE85
    J4  158  VSS67 SCONN288_ADR50017P087CC-SCONN2A   I174 @S9S_MB_2U_LIB.S9S_MB_2U(SCH_1):PAGE85
    J4  160  VSS68 SCONN288_ADR50017P087CC-SCONN2A   I174 @S9S_MB_2U_LIB.S9S_MB_2U(SCH_1):PAGE85
    J4  162  VSS69 SCONN288_ADR50017P087CC-SCONN2A   I174 @S9S_MB_2U_LIB.S9S_MB_2U(SCH_1):PAGE85
    J4  164  VSS70 SCONN288_ADR50017P087CC-SCONN2A   I174 @S9S_MB_2U_LIB.S9S_MB_2U(SCH_1):PAGE85
    J4  166  VSS71 SCONN288_ADR50017P087CC-SCONN2A   I174 @S9S_MB_2U_LIB.S9S_MB_2U(SCH_1):PAGE85
    J4  169  VSS72 SCONN288_ADR50017P087CC-SCONN2A   I174 @S9S_MB_2U_LIB.S9S_MB_2U(SCH_1):PAGE85
    J4  171  VSS73 SCONN288_ADR50017P087CC-SCONN2A   I174 @S9S_MB_2U_LIB.S9S_MB_2U(SCH_1):PAGE85
    J4  173  VSS74 SCONN288_ADR50017P087CC-SCONN2A   I174 @S9S_MB_2U_LIB.S9S_MB_2U(SCH_1):PAGE85
    J4  175  VSS75 SCONN288_ADR50017P087CC-SCONN2A   I174 @S9S_MB_2U_LIB.S9S_MB_2U(SCH_1):PAGE85
    J4  177  VSS76 SCONN288_ADR50017P087CC-SCONN2A   I174 @S9S_MB_2U_LIB.S9S_MB_2U(SCH_1):PAGE85
    J4  180  VSS77 SCONN288_ADR50017P087CC-SCONN2A   I174 @S9S_MB_2U_LIB.S9S_MB_2U(SCH_1):PAGE85
    J4  182  VSS78 SCONN288_ADR50017P087CC-SCONN2A   I174 @S9S_MB_2U_LIB.S9S_MB_2U(SCH_1):PAGE85
    J4  184  VSS79 SCONN288_ADR50017P087CC-SCONN2A   I174 @S9S_MB_2U_LIB.S9S_MB_2U(SCH_1):PAGE85
    J4  186  VSS80 SCONN288_ADR50017P087CC-SCONN2A   I174 @S9S_MB_2U_LIB.S9S_MB_2U(SCH_1):PAGE85
    J4  188  VSS81 SCONN288_ADR50017P087CC-SCONN2A   I174 @S9S_MB_2U_LIB.S9S_MB_2U(SCH_1):PAGE85
    J4  191  VSS82 SCONN288_ADR50017P087CC-SCONN2A   I174 @S9S_MB_2U_LIB.S9S_MB_2U(SCH_1):PAGE85
    J4  193  VSS83 SCONN288_ADR50017P087CC-SCONN2A   I174 @S9S_MB_2U_LIB.S9S_MB_2U(SCH_1):PAGE85
    J4  195  VSS84 SCONN288_ADR50017P087CC-SCONN2A   I174 @S9S_MB_2U_LIB.S9S_MB_2U(SCH_1):PAGE85
    J4  197  VSS85 SCONN288_ADR50017P087CC-SCONN2A   I174 @S9S_MB_2U_LIB.S9S_MB_2U(SCH_1):PAGE85
    J4  199  VSS86 SCONN288_ADR50017P087CC-SCONN2A   I174 @S9S_MB_2U_LIB.S9S_MB_2U(SCH_1):PAGE85
    J4  202  VSS87 SCONN288_ADR50017P087CC-SCONN2A   I174 @S9S_MB_2U_LIB.S9S_MB_2U(SCH_1):PAGE85
    J4  204  VSS88 SCONN288_ADR50017P087CC-SCONN2A   I174 @S9S_MB_2U_LIB.S9S_MB_2U(SCH_1):PAGE85
    J4  206  VSS89 SCONN288_ADR50017P087CC-SCONN2A   I174 @S9S_MB_2U_LIB.S9S_MB_2U(SCH_1):PAGE85
    J4  208  VSS90 SCONN288_ADR50017P087CC-SCONN2A   I174 @S9S_MB_2U_LIB.S9S_MB_2U(SCH_1):PAGE85
    J4  210  VSS91 SCONN288_ADR50017P087CC-SCONN2A   I174 @S9S_MB_2U_LIB.S9S_MB_2U(SCH_1):PAGE85
    J4  212  VSS92 SCONN288_ADR50017P087CC-SCONN2A   I174 @S9S_MB_2U_LIB.S9S_MB_2U(SCH_1):PAGE85
    J4  214  VSS93 SCONN288_ADR50017P087CC-SCONN2A   I174 @S9S_MB_2U_LIB.S9S_MB_2U(SCH_1):PAGE85
    J4  216  VSS94 SCONN288_ADR50017P087CC-SCONN2A   I174 @S9S_MB_2U_LIB.S9S_MB_2U(SCH_1):PAGE85
    J4  219  VSS95 SCONN288_ADR50017P087CC-SCONN2A   I174 @S9S_MB_2U_LIB.S9S_MB_2U(SCH_1):PAGE85
    J4  222  VSS96 SCONN288_ADR50017P087CC-SCONN2A   I174 @S9S_MB_2U_LIB.S9S_MB_2U(SCH_1):PAGE85
    J4  224  VSS97 SCONN288_ADR50017P087CC-SCONN2A   I174 @S9S_MB_2U_LIB.S9S_MB_2U(SCH_1):PAGE85
    J4  226  VSS98 SCONN288_ADR50017P087CC-SCONN2A   I174 @S9S_MB_2U_LIB.S9S_MB_2U(SCH_1):PAGE85
    J4  228  VSS99 SCONN288_ADR50017P087CC-SCONN2A   I174 @S9S_MB_2U_LIB.S9S_MB_2U(SCH_1):PAGE85
    J4  230 VSS100 SCONN288_ADR50017P087CC-SCONN2A   I174 @S9S_MB_2U_LIB.S9S_MB_2U(SCH_1):PAGE85
    J4  233 VSS101 SCONN288_ADR50017P087CC-SCONN2A   I174 @S9S_MB_2U_LIB.S9S_MB_2U(SCH_1):PAGE85
    J4  235 VSS102 SCONN288_ADR50017P087CC-SCONN2A   I174 @S9S_MB_2U_LIB.S9S_MB_2U(SCH_1):PAGE85
    J4  237 VSS103 SCONN288_ADR50017P087CC-SCONN2A   I174 @S9S_MB_2U_LIB.S9S_MB_2U(SCH_1):PAGE85
    J4  240 VSS104 SCONN288_ADR50017P087CC-SCONN2A   I174 @S9S_MB_2U_LIB.S9S_MB_2U(SCH_1):PAGE85
    J4  242 VSS105 SCONN288_ADR50017P087CC-SCONN2A   I174 @S9S_MB_2U_LIB.S9S_MB_2U(SCH_1):PAGE85
    J4  244 VSS106 SCONN288_ADR50017P087CC-SCONN2A   I174 @S9S_MB_2U_LIB.S9S_MB_2U(SCH_1):PAGE85
    J4  246 VSS107 SCONN288_ADR50017P087CC-SCONN2A   I174 @S9S_MB_2U_LIB.S9S_MB_2U(SCH_1):PAGE85
    J4  248 VSS108 SCONN288_ADR50017P087CC-SCONN2A   I174 @S9S_MB_2U_LIB.S9S_MB_2U(SCH_1):PAGE85
    J4  251 VSS109 SCONN288_ADR50017P087CC-SCONN2A   I174 @S9S_MB_2U_LIB.S9S_MB_2U(SCH_1):PAGE85
    J4  253 VSS110 SCONN288_ADR50017P087CC-SCONN2A   I174 @S9S_MB_2U_LIB.S9S_MB_2U(SCH_1):PAGE85
    J4  255 VSS111 SCONN288_ADR50017P087CC-SCONN2A   I174 @S9S_MB_2U_LIB.S9S_MB_2U(SCH_1):PAGE85
    J4  257 VSS112 SCONN288_ADR50017P087CC-SCONN2A   I174 @S9S_MB_2U_LIB.S9S_MB_2U(SCH_1):PAGE85
    J4  259 VSS113 SCONN288_ADR50017P087CC-SCONN2A   I174 @S9S_MB_2U_LIB.S9S_MB_2U(SCH_1):PAGE85
    J4  262 VSS114 SCONN288_ADR50017P087CC-SCONN2A   I174 @S9S_MB_2U_LIB.S9S_MB_2U(SCH_1):PAGE85
    J4  264 VSS115 SCONN288_ADR50017P087CC-SCONN2A   I174 @S9S_MB_2U_LIB.S9S_MB_2U(SCH_1):PAGE85
    J4  266 VSS116 SCONN288_ADR50017P087CC-SCONN2A   I174 @S9S_MB_2U_LIB.S9S_MB_2U(SCH_1):PAGE85
    J4  268 VSS117 SCONN288_ADR50017P087CC-SCONN2A   I174 @S9S_MB_2U_LIB.S9S_MB_2U(SCH_1):PAGE85
    J4  270 VSS118 SCONN288_ADR50017P087CC-SCONN2A   I174 @S9S_MB_2U_LIB.S9S_MB_2U(SCH_1):PAGE85
    J4  273 VSS119 SCONN288_ADR50017P087CC-SCONN2A   I174 @S9S_MB_2U_LIB.S9S_MB_2U(SCH_1):PAGE85
    J4  275 VSS120 SCONN288_ADR50017P087CC-SCONN2A   I174 @S9S_MB_2U_LIB.S9S_MB_2U(SCH_1):PAGE85
    J4  277 VSS121 SCONN288_ADR50017P087CC-SCONN2A   I174 @S9S_MB_2U_LIB.S9S_MB_2U(SCH_1):PAGE85
    J4  279 VSS122 SCONN288_ADR50017P087CC-SCONN2A   I174 @S9S_MB_2U_LIB.S9S_MB_2U(SCH_1):PAGE85
    J4  281 VSS123 SCONN288_ADR50017P087CC-SCONN2A   I174 @S9S_MB_2U_LIB.S9S_MB_2U(SCH_1):PAGE85
    J4  284 VSS124 SCONN288_ADR50017P087CC-SCONN2A   I174 @S9S_MB_2U_LIB.S9S_MB_2U(SCH_1):PAGE85
    J4  286 VSS125 SCONN288_ADR50017P087CC-SCONN2A   I174 @S9S_MB_2U_LIB.S9S_MB_2U(SCH_1):PAGE85
    J4  288 VSS126 SCONN288_ADR50017P087CC-SCONN2A   I174 @S9S_MB_2U_LIB.S9S_MB_2U(SCH_1):PAGE85
   R30    2      B Q_RES_0402LF-54.9K,1%,1/16W,CHA     I3 @S9S_MB_2U_LIB.S9S_MB_2U(SCH_1):PAGE86
   C14    2      B Q_CAP_C0402-2.2UF,6.3V,20%,X6SA   I120 @S9S_MB_2U_LIB.S9S_MB_2U(SCH_1):PAGE86
   C15    2      B Q_CAP_C0805-10UF,16V,10%,X6S,CA   I121 @S9S_MB_2U_LIB.S9S_MB_2U(SCH_1):PAGE86
   C16    2      B Q_CAP_C0805-10UF,16V,10%,X6S,CA   I123 @S9S_MB_2U_LIB.S9S_MB_2U(SCH_1):PAGE86
    J5   G1     G1 SCONN288_ADR50017P130CC-SCONN2A   I174 @S9S_MB_2U_LIB.S9S_MB_2U(SCH_1):PAGE86
    J5   G2     G2 SCONN288_ADR50017P130CC-SCONN2A   I174 @S9S_MB_2U_LIB.S9S_MB_2U(SCH_1):PAGE86
    J5   G3     G3 SCONN288_ADR50017P130CC-SCONN2A   I174 @S9S_MB_2U_LIB.S9S_MB_2U(SCH_1):PAGE86
    J5    6   VSS0 SCONN288_ADR50017P130CC-SCONN2A   I174 @S9S_MB_2U_LIB.S9S_MB_2U(SCH_1):PAGE86
    J5    8   VSS1 SCONN288_ADR50017P130CC-SCONN2A   I174 @S9S_MB_2U_LIB.S9S_MB_2U(SCH_1):PAGE86
    J5   10   VSS2 SCONN288_ADR50017P130CC-SCONN2A   I174 @S9S_MB_2U_LIB.S9S_MB_2U(SCH_1):PAGE86
    J5   13   VSS3 SCONN288_ADR50017P130CC-SCONN2A   I174 @S9S_MB_2U_LIB.S9S_MB_2U(SCH_1):PAGE86
    J5   15   VSS4 SCONN288_ADR50017P130CC-SCONN2A   I174 @S9S_MB_2U_LIB.S9S_MB_2U(SCH_1):PAGE86
    J5   17   VSS5 SCONN288_ADR50017P130CC-SCONN2A   I174 @S9S_MB_2U_LIB.S9S_MB_2U(SCH_1):PAGE86
    J5   19   VSS6 SCONN288_ADR50017P130CC-SCONN2A   I174 @S9S_MB_2U_LIB.S9S_MB_2U(SCH_1):PAGE86
    J5   21   VSS7 SCONN288_ADR50017P130CC-SCONN2A   I174 @S9S_MB_2U_LIB.S9S_MB_2U(SCH_1):PAGE86
    J5   24   VSS8 SCONN288_ADR50017P130CC-SCONN2A   I174 @S9S_MB_2U_LIB.S9S_MB_2U(SCH_1):PAGE86
    J5   26   VSS9 SCONN288_ADR50017P130CC-SCONN2A   I174 @S9S_MB_2U_LIB.S9S_MB_2U(SCH_1):PAGE86
    J5   28  VSS10 SCONN288_ADR50017P130CC-SCONN2A   I174 @S9S_MB_2U_LIB.S9S_MB_2U(SCH_1):PAGE86
    J5   30  VSS11 SCONN288_ADR50017P130CC-SCONN2A   I174 @S9S_MB_2U_LIB.S9S_MB_2U(SCH_1):PAGE86
    J5   32  VSS12 SCONN288_ADR50017P130CC-SCONN2A   I174 @S9S_MB_2U_LIB.S9S_MB_2U(SCH_1):PAGE86
    J5   35  VSS13 SCONN288_ADR50017P130CC-SCONN2A   I174 @S9S_MB_2U_LIB.S9S_MB_2U(SCH_1):PAGE86
    J5   37  VSS14 SCONN288_ADR50017P130CC-SCONN2A   I174 @S9S_MB_2U_LIB.S9S_MB_2U(SCH_1):PAGE86
    J5   39  VSS15 SCONN288_ADR50017P130CC-SCONN2A   I174 @S9S_MB_2U_LIB.S9S_MB_2U(SCH_1):PAGE86
    J5   41  VSS16 SCONN288_ADR50017P130CC-SCONN2A   I174 @S9S_MB_2U_LIB.S9S_MB_2U(SCH_1):PAGE86
    J5   43  VSS17 SCONN288_ADR50017P130CC-SCONN2A   I174 @S9S_MB_2U_LIB.S9S_MB_2U(SCH_1):PAGE86
    J5   46  VSS18 SCONN288_ADR50017P130CC-SCONN2A   I174 @S9S_MB_2U_LIB.S9S_MB_2U(SCH_1):PAGE86
    J5   48  VSS19 SCONN288_ADR50017P130CC-SCONN2A   I174 @S9S_MB_2U_LIB.S9S_MB_2U(SCH_1):PAGE86
    J5   50  VSS20 SCONN288_ADR50017P130CC-SCONN2A   I174 @S9S_MB_2U_LIB.S9S_MB_2U(SCH_1):PAGE86
    J5   52  VSS21 SCONN288_ADR50017P130CC-SCONN2A   I174 @S9S_MB_2U_LIB.S9S_MB_2U(SCH_1):PAGE86
    J5   54  VSS22 SCONN288_ADR50017P130CC-SCONN2A   I174 @S9S_MB_2U_LIB.S9S_MB_2U(SCH_1):PAGE86
    J5   57  VSS23 SCONN288_ADR50017P130CC-SCONN2A   I174 @S9S_MB_2U_LIB.S9S_MB_2U(SCH_1):PAGE86
    J5   59  VSS24 SCONN288_ADR50017P130CC-SCONN2A   I174 @S9S_MB_2U_LIB.S9S_MB_2U(SCH_1):PAGE86
    J5   61  VSS25 SCONN288_ADR50017P130CC-SCONN2A   I174 @S9S_MB_2U_LIB.S9S_MB_2U(SCH_1):PAGE86
    J5   63  VSS26 SCONN288_ADR50017P130CC-SCONN2A   I174 @S9S_MB_2U_LIB.S9S_MB_2U(SCH_1):PAGE86
    J5   65  VSS27 SCONN288_ADR50017P130CC-SCONN2A   I174 @S9S_MB_2U_LIB.S9S_MB_2U(SCH_1):PAGE86
    J5   67  VSS28 SCONN288_ADR50017P130CC-SCONN2A   I174 @S9S_MB_2U_LIB.S9S_MB_2U(SCH_1):PAGE86
    J5   69  VSS29 SCONN288_ADR50017P130CC-SCONN2A   I174 @S9S_MB_2U_LIB.S9S_MB_2U(SCH_1):PAGE86
    J5   71  VSS30 SCONN288_ADR50017P130CC-SCONN2A   I174 @S9S_MB_2U_LIB.S9S_MB_2U(SCH_1):PAGE86
    J5   73  VSS31 SCONN288_ADR50017P130CC-SCONN2A   I174 @S9S_MB_2U_LIB.S9S_MB_2U(SCH_1):PAGE86
    J5   75  VSS32 SCONN288_ADR50017P130CC-SCONN2A   I174 @S9S_MB_2U_LIB.S9S_MB_2U(SCH_1):PAGE86
    J5   77  VSS33 SCONN288_ADR50017P130CC-SCONN2A   I174 @S9S_MB_2U_LIB.S9S_MB_2U(SCH_1):PAGE86
    J5   79  VSS34 SCONN288_ADR50017P130CC-SCONN2A   I174 @S9S_MB_2U_LIB.S9S_MB_2U(SCH_1):PAGE86
    J5   81  VSS35 SCONN288_ADR50017P130CC-SCONN2A   I174 @S9S_MB_2U_LIB.S9S_MB_2U(SCH_1):PAGE86
    J5   83  VSS36 SCONN288_ADR50017P130CC-SCONN2A   I174 @S9S_MB_2U_LIB.S9S_MB_2U(SCH_1):PAGE86
    J5   85  VSS37 SCONN288_ADR50017P130CC-SCONN2A   I174 @S9S_MB_2U_LIB.S9S_MB_2U(SCH_1):PAGE86
    J5   88  VSS38 SCONN288_ADR50017P130CC-SCONN2A   I174 @S9S_MB_2U_LIB.S9S_MB_2U(SCH_1):PAGE86
    J5   90  VSS39 SCONN288_ADR50017P130CC-SCONN2A   I174 @S9S_MB_2U_LIB.S9S_MB_2U(SCH_1):PAGE86
    J5   92  VSS40 SCONN288_ADR50017P130CC-SCONN2A   I174 @S9S_MB_2U_LIB.S9S_MB_2U(SCH_1):PAGE86
    J5   95  VSS41 SCONN288_ADR50017P130CC-SCONN2A   I174 @S9S_MB_2U_LIB.S9S_MB_2U(SCH_1):PAGE86
    J5   97  VSS42 SCONN288_ADR50017P130CC-SCONN2A   I174 @S9S_MB_2U_LIB.S9S_MB_2U(SCH_1):PAGE86
    J5   99  VSS43 SCONN288_ADR50017P130CC-SCONN2A   I174 @S9S_MB_2U_LIB.S9S_MB_2U(SCH_1):PAGE86
    J5  101  VSS44 SCONN288_ADR50017P130CC-SCONN2A   I174 @S9S_MB_2U_LIB.S9S_MB_2U(SCH_1):PAGE86
    J5  103  VSS45 SCONN288_ADR50017P130CC-SCONN2A   I174 @S9S_MB_2U_LIB.S9S_MB_2U(SCH_1):PAGE86
    J5  106  VSS46 SCONN288_ADR50017P130CC-SCONN2A   I174 @S9S_MB_2U_LIB.S9S_MB_2U(SCH_1):PAGE86
    J5  108  VSS47 SCONN288_ADR50017P130CC-SCONN2A   I174 @S9S_MB_2U_LIB.S9S_MB_2U(SCH_1):PAGE86
    J5  110  VSS48 SCONN288_ADR50017P130CC-SCONN2A   I174 @S9S_MB_2U_LIB.S9S_MB_2U(SCH_1):PAGE86
    J5  112  VSS49 SCONN288_ADR50017P130CC-SCONN2A   I174 @S9S_MB_2U_LIB.S9S_MB_2U(SCH_1):PAGE86
    J5  114  VSS50 SCONN288_ADR50017P130CC-SCONN2A   I174 @S9S_MB_2U_LIB.S9S_MB_2U(SCH_1):PAGE86
    J5  117  VSS51 SCONN288_ADR50017P130CC-SCONN2A   I174 @S9S_MB_2U_LIB.S9S_MB_2U(SCH_1):PAGE86
    J5  119  VSS52 SCONN288_ADR50017P130CC-SCONN2A   I174 @S9S_MB_2U_LIB.S9S_MB_2U(SCH_1):PAGE86
    J5  121  VSS53 SCONN288_ADR50017P130CC-SCONN2A   I174 @S9S_MB_2U_LIB.S9S_MB_2U(SCH_1):PAGE86
    J5  123  VSS54 SCONN288_ADR50017P130CC-SCONN2A   I174 @S9S_MB_2U_LIB.S9S_MB_2U(SCH_1):PAGE86
    J5  125  VSS55 SCONN288_ADR50017P130CC-SCONN2A   I174 @S9S_MB_2U_LIB.S9S_MB_2U(SCH_1):PAGE86
    J5  128  VSS56 SCONN288_ADR50017P130CC-SCONN2A   I174 @S9S_MB_2U_LIB.S9S_MB_2U(SCH_1):PAGE86
    J5  130  VSS57 SCONN288_ADR50017P130CC-SCONN2A   I174 @S9S_MB_2U_LIB.S9S_MB_2U(SCH_1):PAGE86
    J5  132  VSS58 SCONN288_ADR50017P130CC-SCONN2A   I174 @S9S_MB_2U_LIB.S9S_MB_2U(SCH_1):PAGE86
    J5  134  VSS59 SCONN288_ADR50017P130CC-SCONN2A   I174 @S9S_MB_2U_LIB.S9S_MB_2U(SCH_1):PAGE86
    J5  136  VSS60 SCONN288_ADR50017P130CC-SCONN2A   I174 @S9S_MB_2U_LIB.S9S_MB_2U(SCH_1):PAGE86
    J5  139  VSS61 SCONN288_ADR50017P130CC-SCONN2A   I174 @S9S_MB_2U_LIB.S9S_MB_2U(SCH_1):PAGE86
    J5  141  VSS62 SCONN288_ADR50017P130CC-SCONN2A   I174 @S9S_MB_2U_LIB.S9S_MB_2U(SCH_1):PAGE86
    J5  143  VSS63 SCONN288_ADR50017P130CC-SCONN2A   I174 @S9S_MB_2U_LIB.S9S_MB_2U(SCH_1):PAGE86
    J5  151  VSS64 SCONN288_ADR50017P130CC-SCONN2A   I174 @S9S_MB_2U_LIB.S9S_MB_2U(SCH_1):PAGE86
    J5  153  VSS65 SCONN288_ADR50017P130CC-SCONN2A   I174 @S9S_MB_2U_LIB.S9S_MB_2U(SCH_1):PAGE86
    J5  155  VSS66 SCONN288_ADR50017P130CC-SCONN2A   I174 @S9S_MB_2U_LIB.S9S_MB_2U(SCH_1):PAGE86
    J5  158  VSS67 SCONN288_ADR50017P130CC-SCONN2A   I174 @S9S_MB_2U_LIB.S9S_MB_2U(SCH_1):PAGE86
    J5  160  VSS68 SCONN288_ADR50017P130CC-SCONN2A   I174 @S9S_MB_2U_LIB.S9S_MB_2U(SCH_1):PAGE86
    J5  162  VSS69 SCONN288_ADR50017P130CC-SCONN2A   I174 @S9S_MB_2U_LIB.S9S_MB_2U(SCH_1):PAGE86
    J5  164  VSS70 SCONN288_ADR50017P130CC-SCONN2A   I174 @S9S_MB_2U_LIB.S9S_MB_2U(SCH_1):PAGE86
    J5  166  VSS71 SCONN288_ADR50017P130CC-SCONN2A   I174 @S9S_MB_2U_LIB.S9S_MB_2U(SCH_1):PAGE86
    J5  169  VSS72 SCONN288_ADR50017P130CC-SCONN2A   I174 @S9S_MB_2U_LIB.S9S_MB_2U(SCH_1):PAGE86
    J5  171  VSS73 SCONN288_ADR50017P130CC-SCONN2A   I174 @S9S_MB_2U_LIB.S9S_MB_2U(SCH_1):PAGE86
    J5  173  VSS74 SCONN288_ADR50017P130CC-SCONN2A   I174 @S9S_MB_2U_LIB.S9S_MB_2U(SCH_1):PAGE86
    J5  175  VSS75 SCONN288_ADR50017P130CC-SCONN2A   I174 @S9S_MB_2U_LIB.S9S_MB_2U(SCH_1):PAGE86
    J5  177  VSS76 SCONN288_ADR50017P130CC-SCONN2A   I174 @S9S_MB_2U_LIB.S9S_MB_2U(SCH_1):PAGE86
    J5  180  VSS77 SCONN288_ADR50017P130CC-SCONN2A   I174 @S9S_MB_2U_LIB.S9S_MB_2U(SCH_1):PAGE86
    J5  182  VSS78 SCONN288_ADR50017P130CC-SCONN2A   I174 @S9S_MB_2U_LIB.S9S_MB_2U(SCH_1):PAGE86
    J5  184  VSS79 SCONN288_ADR50017P130CC-SCONN2A   I174 @S9S_MB_2U_LIB.S9S_MB_2U(SCH_1):PAGE86
    J5  186  VSS80 SCONN288_ADR50017P130CC-SCONN2A   I174 @S9S_MB_2U_LIB.S9S_MB_2U(SCH_1):PAGE86
    J5  188  VSS81 SCONN288_ADR50017P130CC-SCONN2A   I174 @S9S_MB_2U_LIB.S9S_MB_2U(SCH_1):PAGE86
    J5  191  VSS82 SCONN288_ADR50017P130CC-SCONN2A   I174 @S9S_MB_2U_LIB.S9S_MB_2U(SCH_1):PAGE86
    J5  193  VSS83 SCONN288_ADR50017P130CC-SCONN2A   I174 @S9S_MB_2U_LIB.S9S_MB_2U(SCH_1):PAGE86
    J5  195  VSS84 SCONN288_ADR50017P130CC-SCONN2A   I174 @S9S_MB_2U_LIB.S9S_MB_2U(SCH_1):PAGE86
    J5  197  VSS85 SCONN288_ADR50017P130CC-SCONN2A   I174 @S9S_MB_2U_LIB.S9S_MB_2U(SCH_1):PAGE86
    J5  199  VSS86 SCONN288_ADR50017P130CC-SCONN2A   I174 @S9S_MB_2U_LIB.S9S_MB_2U(SCH_1):PAGE86
    J5  202  VSS87 SCONN288_ADR50017P130CC-SCONN2A   I174 @S9S_MB_2U_LIB.S9S_MB_2U(SCH_1):PAGE86
    J5  204  VSS88 SCONN288_ADR50017P130CC-SCONN2A   I174 @S9S_MB_2U_LIB.S9S_MB_2U(SCH_1):PAGE86
    J5  206  VSS89 SCONN288_ADR50017P130CC-SCONN2A   I174 @S9S_MB_2U_LIB.S9S_MB_2U(SCH_1):PAGE86
    J5  208  VSS90 SCONN288_ADR50017P130CC-SCONN2A   I174 @S9S_MB_2U_LIB.S9S_MB_2U(SCH_1):PAGE86
    J5  210  VSS91 SCONN288_ADR50017P130CC-SCONN2A   I174 @S9S_MB_2U_LIB.S9S_MB_2U(SCH_1):PAGE86
    J5  212  VSS92 SCONN288_ADR50017P130CC-SCONN2A   I174 @S9S_MB_2U_LIB.S9S_MB_2U(SCH_1):PAGE86
    J5  214  VSS93 SCONN288_ADR50017P130CC-SCONN2A   I174 @S9S_MB_2U_LIB.S9S_MB_2U(SCH_1):PAGE86
    J5  216  VSS94 SCONN288_ADR50017P130CC-SCONN2A   I174 @S9S_MB_2U_LIB.S9S_MB_2U(SCH_1):PAGE86
    J5  219  VSS95 SCONN288_ADR50017P130CC-SCONN2A   I174 @S9S_MB_2U_LIB.S9S_MB_2U(SCH_1):PAGE86
    J5  222  VSS96 SCONN288_ADR50017P130CC-SCONN2A   I174 @S9S_MB_2U_LIB.S9S_MB_2U(SCH_1):PAGE86
    J5  224  VSS97 SCONN288_ADR50017P130CC-SCONN2A   I174 @S9S_MB_2U_LIB.S9S_MB_2U(SCH_1):PAGE86
    J5  226  VSS98 SCONN288_ADR50017P130CC-SCONN2A   I174 @S9S_MB_2U_LIB.S9S_MB_2U(SCH_1):PAGE86
    J5  228  VSS99 SCONN288_ADR50017P130CC-SCONN2A   I174 @S9S_MB_2U_LIB.S9S_MB_2U(SCH_1):PAGE86
    J5  230 VSS100 SCONN288_ADR50017P130CC-SCONN2A   I174 @S9S_MB_2U_LIB.S9S_MB_2U(SCH_1):PAGE86
    J5  233 VSS101 SCONN288_ADR50017P130CC-SCONN2A   I174 @S9S_MB_2U_LIB.S9S_MB_2U(SCH_1):PAGE86
    J5  235 VSS102 SCONN288_ADR50017P130CC-SCONN2A   I174 @S9S_MB_2U_LIB.S9S_MB_2U(SCH_1):PAGE86
    J5  237 VSS103 SCONN288_ADR50017P130CC-SCONN2A   I174 @S9S_MB_2U_LIB.S9S_MB_2U(SCH_1):PAGE86
    J5  240 VSS104 SCONN288_ADR50017P130CC-SCONN2A   I174 @S9S_MB_2U_LIB.S9S_MB_2U(SCH_1):PAGE86
    J5  242 VSS105 SCONN288_ADR50017P130CC-SCONN2A   I174 @S9S_MB_2U_LIB.S9S_MB_2U(SCH_1):PAGE86
    J5  244 VSS106 SCONN288_ADR50017P130CC-SCONN2A   I174 @S9S_MB_2U_LIB.S9S_MB_2U(SCH_1):PAGE86
    J5  246 VSS107 SCONN288_ADR50017P130CC-SCONN2A   I174 @S9S_MB_2U_LIB.S9S_MB_2U(SCH_1):PAGE86
    J5  248 VSS108 SCONN288_ADR50017P130CC-SCONN2A   I174 @S9S_MB_2U_LIB.S9S_MB_2U(SCH_1):PAGE86
    J5  251 VSS109 SCONN288_ADR50017P130CC-SCONN2A   I174 @S9S_MB_2U_LIB.S9S_MB_2U(SCH_1):PAGE86
    J5  253 VSS110 SCONN288_ADR50017P130CC-SCONN2A   I174 @S9S_MB_2U_LIB.S9S_MB_2U(SCH_1):PAGE86
    J5  255 VSS111 SCONN288_ADR50017P130CC-SCONN2A   I174 @S9S_MB_2U_LIB.S9S_MB_2U(SCH_1):PAGE86
    J5  257 VSS112 SCONN288_ADR50017P130CC-SCONN2A   I174 @S9S_MB_2U_LIB.S9S_MB_2U(SCH_1):PAGE86
    J5  259 VSS113 SCONN288_ADR50017P130CC-SCONN2A   I174 @S9S_MB_2U_LIB.S9S_MB_2U(SCH_1):PAGE86
    J5  262 VSS114 SCONN288_ADR50017P130CC-SCONN2A   I174 @S9S_MB_2U_LIB.S9S_MB_2U(SCH_1):PAGE86
    J5  264 VSS115 SCONN288_ADR50017P130CC-SCONN2A   I174 @S9S_MB_2U_LIB.S9S_MB_2U(SCH_1):PAGE86
    J5  266 VSS116 SCONN288_ADR50017P130CC-SCONN2A   I174 @S9S_MB_2U_LIB.S9S_MB_2U(SCH_1):PAGE86
    J5  268 VSS117 SCONN288_ADR50017P130CC-SCONN2A   I174 @S9S_MB_2U_LIB.S9S_MB_2U(SCH_1):PAGE86
    J5  270 VSS118 SCONN288_ADR50017P130CC-SCONN2A   I174 @S9S_MB_2U_LIB.S9S_MB_2U(SCH_1):PAGE86
    J5  273 VSS119 SCONN288_ADR50017P130CC-SCONN2A   I174 @S9S_MB_2U_LIB.S9S_MB_2U(SCH_1):PAGE86
    J5  275 VSS120 SCONN288_ADR50017P130CC-SCONN2A   I174 @S9S_MB_2U_LIB.S9S_MB_2U(SCH_1):PAGE86
    J5  277 VSS121 SCONN288_ADR50017P130CC-SCONN2A   I174 @S9S_MB_2U_LIB.S9S_MB_2U(SCH_1):PAGE86
    J5  279 VSS122 SCONN288_ADR50017P130CC-SCONN2A   I174 @S9S_MB_2U_LIB.S9S_MB_2U(SCH_1):PAGE86
    J5  281 VSS123 SCONN288_ADR50017P130CC-SCONN2A   I174 @S9S_MB_2U_LIB.S9S_MB_2U(SCH_1):PAGE86
    J5  284 VSS124 SCONN288_ADR50017P130CC-SCONN2A   I174 @S9S_MB_2U_LIB.S9S_MB_2U(SCH_1):PAGE86
    J5  286 VSS125 SCONN288_ADR50017P130CC-SCONN2A   I174 @S9S_MB_2U_LIB.S9S_MB_2U(SCH_1):PAGE86
    J5  288 VSS126 SCONN288_ADR50017P130CC-SCONN2A   I174 @S9S_MB_2U_LIB.S9S_MB_2U(SCH_1):PAGE86
   R31    2      B Q_RES_0402LF-84.5K,1%,1/16W,CHA    I45 @S9S_MB_2U_LIB.S9S_MB_2U(SCH_1):PAGE87
   C17    2      B Q_CAP_C0402-2.2UF,6.3V,20%,X6SA   I120 @S9S_MB_2U_LIB.S9S_MB_2U(SCH_1):PAGE87
   C18    2      B Q_CAP_C0805-10UF,16V,10%,X6S,CA   I124 @S9S_MB_2U_LIB.S9S_MB_2U(SCH_1):PAGE87
   C19    2      B Q_CAP_C0805-10UF,16V,10%,X6S,CA   I127 @S9S_MB_2U_LIB.S9S_MB_2U(SCH_1):PAGE87
    J6   G1     G1 SCONN288_ADR50017P087CC-SCONN2A   I175 @S9S_MB_2U_LIB.S9S_MB_2U(SCH_1):PAGE87
    J6   G2     G2 SCONN288_ADR50017P087CC-SCONN2A   I175 @S9S_MB_2U_LIB.S9S_MB_2U(SCH_1):PAGE87
    J6   G3     G3 SCONN288_ADR50017P087CC-SCONN2A   I175 @S9S_MB_2U_LIB.S9S_MB_2U(SCH_1):PAGE87
    J6    6   VSS0 SCONN288_ADR50017P087CC-SCONN2A   I175 @S9S_MB_2U_LIB.S9S_MB_2U(SCH_1):PAGE87
    J6    8   VSS1 SCONN288_ADR50017P087CC-SCONN2A   I175 @S9S_MB_2U_LIB.S9S_MB_2U(SCH_1):PAGE87
    J6   10   VSS2 SCONN288_ADR50017P087CC-SCONN2A   I175 @S9S_MB_2U_LIB.S9S_MB_2U(SCH_1):PAGE87
    J6   13   VSS3 SCONN288_ADR50017P087CC-SCONN2A   I175 @S9S_MB_2U_LIB.S9S_MB_2U(SCH_1):PAGE87
    J6   15   VSS4 SCONN288_ADR50017P087CC-SCONN2A   I175 @S9S_MB_2U_LIB.S9S_MB_2U(SCH_1):PAGE87
    J6   17   VSS5 SCONN288_ADR50017P087CC-SCONN2A   I175 @S9S_MB_2U_LIB.S9S_MB_2U(SCH_1):PAGE87
    J6   19   VSS6 SCONN288_ADR50017P087CC-SCONN2A   I175 @S9S_MB_2U_LIB.S9S_MB_2U(SCH_1):PAGE87
    J6   21   VSS7 SCONN288_ADR50017P087CC-SCONN2A   I175 @S9S_MB_2U_LIB.S9S_MB_2U(SCH_1):PAGE87
    J6   24   VSS8 SCONN288_ADR50017P087CC-SCONN2A   I175 @S9S_MB_2U_LIB.S9S_MB_2U(SCH_1):PAGE87
    J6   26   VSS9 SCONN288_ADR50017P087CC-SCONN2A   I175 @S9S_MB_2U_LIB.S9S_MB_2U(SCH_1):PAGE87
    J6   28  VSS10 SCONN288_ADR50017P087CC-SCONN2A   I175 @S9S_MB_2U_LIB.S9S_MB_2U(SCH_1):PAGE87
    J6   30  VSS11 SCONN288_ADR50017P087CC-SCONN2A   I175 @S9S_MB_2U_LIB.S9S_MB_2U(SCH_1):PAGE87
    J6   32  VSS12 SCONN288_ADR50017P087CC-SCONN2A   I175 @S9S_MB_2U_LIB.S9S_MB_2U(SCH_1):PAGE87
    J6   35  VSS13 SCONN288_ADR50017P087CC-SCONN2A   I175 @S9S_MB_2U_LIB.S9S_MB_2U(SCH_1):PAGE87
    J6   37  VSS14 SCONN288_ADR50017P087CC-SCONN2A   I175 @S9S_MB_2U_LIB.S9S_MB_2U(SCH_1):PAGE87
    J6   39  VSS15 SCONN288_ADR50017P087CC-SCONN2A   I175 @S9S_MB_2U_LIB.S9S_MB_2U(SCH_1):PAGE87
    J6   41  VSS16 SCONN288_ADR50017P087CC-SCONN2A   I175 @S9S_MB_2U_LIB.S9S_MB_2U(SCH_1):PAGE87
    J6   43  VSS17 SCONN288_ADR50017P087CC-SCONN2A   I175 @S9S_MB_2U_LIB.S9S_MB_2U(SCH_1):PAGE87
    J6   46  VSS18 SCONN288_ADR50017P087CC-SCONN2A   I175 @S9S_MB_2U_LIB.S9S_MB_2U(SCH_1):PAGE87
    J6   48  VSS19 SCONN288_ADR50017P087CC-SCONN2A   I175 @S9S_MB_2U_LIB.S9S_MB_2U(SCH_1):PAGE87
    J6   50  VSS20 SCONN288_ADR50017P087CC-SCONN2A   I175 @S9S_MB_2U_LIB.S9S_MB_2U(SCH_1):PAGE87
    J6   52  VSS21 SCONN288_ADR50017P087CC-SCONN2A   I175 @S9S_MB_2U_LIB.S9S_MB_2U(SCH_1):PAGE87
    J6   54  VSS22 SCONN288_ADR50017P087CC-SCONN2A   I175 @S9S_MB_2U_LIB.S9S_MB_2U(SCH_1):PAGE87
    J6   57  VSS23 SCONN288_ADR50017P087CC-SCONN2A   I175 @S9S_MB_2U_LIB.S9S_MB_2U(SCH_1):PAGE87
    J6   59  VSS24 SCONN288_ADR50017P087CC-SCONN2A   I175 @S9S_MB_2U_LIB.S9S_MB_2U(SCH_1):PAGE87
    J6   61  VSS25 SCONN288_ADR50017P087CC-SCONN2A   I175 @S9S_MB_2U_LIB.S9S_MB_2U(SCH_1):PAGE87
    J6   63  VSS26 SCONN288_ADR50017P087CC-SCONN2A   I175 @S9S_MB_2U_LIB.S9S_MB_2U(SCH_1):PAGE87
    J6   65  VSS27 SCONN288_ADR50017P087CC-SCONN2A   I175 @S9S_MB_2U_LIB.S9S_MB_2U(SCH_1):PAGE87
    J6   67  VSS28 SCONN288_ADR50017P087CC-SCONN2A   I175 @S9S_MB_2U_LIB.S9S_MB_2U(SCH_1):PAGE87
    J6   69  VSS29 SCONN288_ADR50017P087CC-SCONN2A   I175 @S9S_MB_2U_LIB.S9S_MB_2U(SCH_1):PAGE87
    J6   71  VSS30 SCONN288_ADR50017P087CC-SCONN2A   I175 @S9S_MB_2U_LIB.S9S_MB_2U(SCH_1):PAGE87
    J6   73  VSS31 SCONN288_ADR50017P087CC-SCONN2A   I175 @S9S_MB_2U_LIB.S9S_MB_2U(SCH_1):PAGE87
    J6   75  VSS32 SCONN288_ADR50017P087CC-SCONN2A   I175 @S9S_MB_2U_LIB.S9S_MB_2U(SCH_1):PAGE87
    J6   77  VSS33 SCONN288_ADR50017P087CC-SCONN2A   I175 @S9S_MB_2U_LIB.S9S_MB_2U(SCH_1):PAGE87
    J6   79  VSS34 SCONN288_ADR50017P087CC-SCONN2A   I175 @S9S_MB_2U_LIB.S9S_MB_2U(SCH_1):PAGE87
    J6   81  VSS35 SCONN288_ADR50017P087CC-SCONN2A   I175 @S9S_MB_2U_LIB.S9S_MB_2U(SCH_1):PAGE87
    J6   83  VSS36 SCONN288_ADR50017P087CC-SCONN2A   I175 @S9S_MB_2U_LIB.S9S_MB_2U(SCH_1):PAGE87
    J6   85  VSS37 SCONN288_ADR50017P087CC-SCONN2A   I175 @S9S_MB_2U_LIB.S9S_MB_2U(SCH_1):PAGE87
    J6   88  VSS38 SCONN288_ADR50017P087CC-SCONN2A   I175 @S9S_MB_2U_LIB.S9S_MB_2U(SCH_1):PAGE87
    J6   90  VSS39 SCONN288_ADR50017P087CC-SCONN2A   I175 @S9S_MB_2U_LIB.S9S_MB_2U(SCH_1):PAGE87
    J6   92  VSS40 SCONN288_ADR50017P087CC-SCONN2A   I175 @S9S_MB_2U_LIB.S9S_MB_2U(SCH_1):PAGE87
    J6   95  VSS41 SCONN288_ADR50017P087CC-SCONN2A   I175 @S9S_MB_2U_LIB.S9S_MB_2U(SCH_1):PAGE87
    J6   97  VSS42 SCONN288_ADR50017P087CC-SCONN2A   I175 @S9S_MB_2U_LIB.S9S_MB_2U(SCH_1):PAGE87
    J6   99  VSS43 SCONN288_ADR50017P087CC-SCONN2A   I175 @S9S_MB_2U_LIB.S9S_MB_2U(SCH_1):PAGE87
    J6  101  VSS44 SCONN288_ADR50017P087CC-SCONN2A   I175 @S9S_MB_2U_LIB.S9S_MB_2U(SCH_1):PAGE87
    J6  103  VSS45 SCONN288_ADR50017P087CC-SCONN2A   I175 @S9S_MB_2U_LIB.S9S_MB_2U(SCH_1):PAGE87
    J6  106  VSS46 SCONN288_ADR50017P087CC-SCONN2A   I175 @S9S_MB_2U_LIB.S9S_MB_2U(SCH_1):PAGE87
    J6  108  VSS47 SCONN288_ADR50017P087CC-SCONN2A   I175 @S9S_MB_2U_LIB.S9S_MB_2U(SCH_1):PAGE87
    J6  110  VSS48 SCONN288_ADR50017P087CC-SCONN2A   I175 @S9S_MB_2U_LIB.S9S_MB_2U(SCH_1):PAGE87
    J6  112  VSS49 SCONN288_ADR50017P087CC-SCONN2A   I175 @S9S_MB_2U_LIB.S9S_MB_2U(SCH_1):PAGE87
    J6  114  VSS50 SCONN288_ADR50017P087CC-SCONN2A   I175 @S9S_MB_2U_LIB.S9S_MB_2U(SCH_1):PAGE87
    J6  117  VSS51 SCONN288_ADR50017P087CC-SCONN2A   I175 @S9S_MB_2U_LIB.S9S_MB_2U(SCH_1):PAGE87
    J6  119  VSS52 SCONN288_ADR50017P087CC-SCONN2A   I175 @S9S_MB_2U_LIB.S9S_MB_2U(SCH_1):PAGE87
    J6  121  VSS53 SCONN288_ADR50017P087CC-SCONN2A   I175 @S9S_MB_2U_LIB.S9S_MB_2U(SCH_1):PAGE87
    J6  123  VSS54 SCONN288_ADR50017P087CC-SCONN2A   I175 @S9S_MB_2U_LIB.S9S_MB_2U(SCH_1):PAGE87
    J6  125  VSS55 SCONN288_ADR50017P087CC-SCONN2A   I175 @S9S_MB_2U_LIB.S9S_MB_2U(SCH_1):PAGE87
    J6  128  VSS56 SCONN288_ADR50017P087CC-SCONN2A   I175 @S9S_MB_2U_LIB.S9S_MB_2U(SCH_1):PAGE87
    J6  130  VSS57 SCONN288_ADR50017P087CC-SCONN2A   I175 @S9S_MB_2U_LIB.S9S_MB_2U(SCH_1):PAGE87
    J6  132  VSS58 SCONN288_ADR50017P087CC-SCONN2A   I175 @S9S_MB_2U_LIB.S9S_MB_2U(SCH_1):PAGE87
    J6  134  VSS59 SCONN288_ADR50017P087CC-SCONN2A   I175 @S9S_MB_2U_LIB.S9S_MB_2U(SCH_1):PAGE87
    J6  136  VSS60 SCONN288_ADR50017P087CC-SCONN2A   I175 @S9S_MB_2U_LIB.S9S_MB_2U(SCH_1):PAGE87
    J6  139  VSS61 SCONN288_ADR50017P087CC-SCONN2A   I175 @S9S_MB_2U_LIB.S9S_MB_2U(SCH_1):PAGE87
    J6  141  VSS62 SCONN288_ADR50017P087CC-SCONN2A   I175 @S9S_MB_2U_LIB.S9S_MB_2U(SCH_1):PAGE87
    J6  143  VSS63 SCONN288_ADR50017P087CC-SCONN2A   I175 @S9S_MB_2U_LIB.S9S_MB_2U(SCH_1):PAGE87
    J6  151  VSS64 SCONN288_ADR50017P087CC-SCONN2A   I175 @S9S_MB_2U_LIB.S9S_MB_2U(SCH_1):PAGE87
    J6  153  VSS65 SCONN288_ADR50017P087CC-SCONN2A   I175 @S9S_MB_2U_LIB.S9S_MB_2U(SCH_1):PAGE87
    J6  155  VSS66 SCONN288_ADR50017P087CC-SCONN2A   I175 @S9S_MB_2U_LIB.S9S_MB_2U(SCH_1):PAGE87
    J6  158  VSS67 SCONN288_ADR50017P087CC-SCONN2A   I175 @S9S_MB_2U_LIB.S9S_MB_2U(SCH_1):PAGE87
    J6  160  VSS68 SCONN288_ADR50017P087CC-SCONN2A   I175 @S9S_MB_2U_LIB.S9S_MB_2U(SCH_1):PAGE87
    J6  162  VSS69 SCONN288_ADR50017P087CC-SCONN2A   I175 @S9S_MB_2U_LIB.S9S_MB_2U(SCH_1):PAGE87
    J6  164  VSS70 SCONN288_ADR50017P087CC-SCONN2A   I175 @S9S_MB_2U_LIB.S9S_MB_2U(SCH_1):PAGE87
    J6  166  VSS71 SCONN288_ADR50017P087CC-SCONN2A   I175 @S9S_MB_2U_LIB.S9S_MB_2U(SCH_1):PAGE87
    J6  169  VSS72 SCONN288_ADR50017P087CC-SCONN2A   I175 @S9S_MB_2U_LIB.S9S_MB_2U(SCH_1):PAGE87
    J6  171  VSS73 SCONN288_ADR50017P087CC-SCONN2A   I175 @S9S_MB_2U_LIB.S9S_MB_2U(SCH_1):PAGE87
    J6  173  VSS74 SCONN288_ADR50017P087CC-SCONN2A   I175 @S9S_MB_2U_LIB.S9S_MB_2U(SCH_1):PAGE87
    J6  175  VSS75 SCONN288_ADR50017P087CC-SCONN2A   I175 @S9S_MB_2U_LIB.S9S_MB_2U(SCH_1):PAGE87
    J6  177  VSS76 SCONN288_ADR50017P087CC-SCONN2A   I175 @S9S_MB_2U_LIB.S9S_MB_2U(SCH_1):PAGE87
    J6  180  VSS77 SCONN288_ADR50017P087CC-SCONN2A   I175 @S9S_MB_2U_LIB.S9S_MB_2U(SCH_1):PAGE87
    J6  182  VSS78 SCONN288_ADR50017P087CC-SCONN2A   I175 @S9S_MB_2U_LIB.S9S_MB_2U(SCH_1):PAGE87
    J6  184  VSS79 SCONN288_ADR50017P087CC-SCONN2A   I175 @S9S_MB_2U_LIB.S9S_MB_2U(SCH_1):PAGE87
    J6  186  VSS80 SCONN288_ADR50017P087CC-SCONN2A   I175 @S9S_MB_2U_LIB.S9S_MB_2U(SCH_1):PAGE87
    J6  188  VSS81 SCONN288_ADR50017P087CC-SCONN2A   I175 @S9S_MB_2U_LIB.S9S_MB_2U(SCH_1):PAGE87
    J6  191  VSS82 SCONN288_ADR50017P087CC-SCONN2A   I175 @S9S_MB_2U_LIB.S9S_MB_2U(SCH_1):PAGE87
    J6  193  VSS83 SCONN288_ADR50017P087CC-SCONN2A   I175 @S9S_MB_2U_LIB.S9S_MB_2U(SCH_1):PAGE87
    J6  195  VSS84 SCONN288_ADR50017P087CC-SCONN2A   I175 @S9S_MB_2U_LIB.S9S_MB_2U(SCH_1):PAGE87
    J6  197  VSS85 SCONN288_ADR50017P087CC-SCONN2A   I175 @S9S_MB_2U_LIB.S9S_MB_2U(SCH_1):PAGE87
    J6  199  VSS86 SCONN288_ADR50017P087CC-SCONN2A   I175 @S9S_MB_2U_LIB.S9S_MB_2U(SCH_1):PAGE87
    J6  202  VSS87 SCONN288_ADR50017P087CC-SCONN2A   I175 @S9S_MB_2U_LIB.S9S_MB_2U(SCH_1):PAGE87
    J6  204  VSS88 SCONN288_ADR50017P087CC-SCONN2A   I175 @S9S_MB_2U_LIB.S9S_MB_2U(SCH_1):PAGE87
    J6  206  VSS89 SCONN288_ADR50017P087CC-SCONN2A   I175 @S9S_MB_2U_LIB.S9S_MB_2U(SCH_1):PAGE87
    J6  208  VSS90 SCONN288_ADR50017P087CC-SCONN2A   I175 @S9S_MB_2U_LIB.S9S_MB_2U(SCH_1):PAGE87
    J6  210  VSS91 SCONN288_ADR50017P087CC-SCONN2A   I175 @S9S_MB_2U_LIB.S9S_MB_2U(SCH_1):PAGE87
    J6  212  VSS92 SCONN288_ADR50017P087CC-SCONN2A   I175 @S9S_MB_2U_LIB.S9S_MB_2U(SCH_1):PAGE87
    J6  214  VSS93 SCONN288_ADR50017P087CC-SCONN2A   I175 @S9S_MB_2U_LIB.S9S_MB_2U(SCH_1):PAGE87
    J6  216  VSS94 SCONN288_ADR50017P087CC-SCONN2A   I175 @S9S_MB_2U_LIB.S9S_MB_2U(SCH_1):PAGE87
    J6  219  VSS95 SCONN288_ADR50017P087CC-SCONN2A   I175 @S9S_MB_2U_LIB.S9S_MB_2U(SCH_1):PAGE87
    J6  222  VSS96 SCONN288_ADR50017P087CC-SCONN2A   I175 @S9S_MB_2U_LIB.S9S_MB_2U(SCH_1):PAGE87
    J6  224  VSS97 SCONN288_ADR50017P087CC-SCONN2A   I175 @S9S_MB_2U_LIB.S9S_MB_2U(SCH_1):PAGE87
    J6  226  VSS98 SCONN288_ADR50017P087CC-SCONN2A   I175 @S9S_MB_2U_LIB.S9S_MB_2U(SCH_1):PAGE87
    J6  228  VSS99 SCONN288_ADR50017P087CC-SCONN2A   I175 @S9S_MB_2U_LIB.S9S_MB_2U(SCH_1):PAGE87
    J6  230 VSS100 SCONN288_ADR50017P087CC-SCONN2A   I175 @S9S_MB_2U_LIB.S9S_MB_2U(SCH_1):PAGE87
    J6  233 VSS101 SCONN288_ADR50017P087CC-SCONN2A   I175 @S9S_MB_2U_LIB.S9S_MB_2U(SCH_1):PAGE87
    J6  235 VSS102 SCONN288_ADR50017P087CC-SCONN2A   I175 @S9S_MB_2U_LIB.S9S_MB_2U(SCH_1):PAGE87
    J6  237 VSS103 SCONN288_ADR50017P087CC-SCONN2A   I175 @S9S_MB_2U_LIB.S9S_MB_2U(SCH_1):PAGE87
    J6  240 VSS104 SCONN288_ADR50017P087CC-SCONN2A   I175 @S9S_MB_2U_LIB.S9S_MB_2U(SCH_1):PAGE87
    J6  242 VSS105 SCONN288_ADR50017P087CC-SCONN2A   I175 @S9S_MB_2U_LIB.S9S_MB_2U(SCH_1):PAGE87
    J6  244 VSS106 SCONN288_ADR50017P087CC-SCONN2A   I175 @S9S_MB_2U_LIB.S9S_MB_2U(SCH_1):PAGE87
    J6  246 VSS107 SCONN288_ADR50017P087CC-SCONN2A   I175 @S9S_MB_2U_LIB.S9S_MB_2U(SCH_1):PAGE87
    J6  248 VSS108 SCONN288_ADR50017P087CC-SCONN2A   I175 @S9S_MB_2U_LIB.S9S_MB_2U(SCH_1):PAGE87
    J6  251 VSS109 SCONN288_ADR50017P087CC-SCONN2A   I175 @S9S_MB_2U_LIB.S9S_MB_2U(SCH_1):PAGE87
    J6  253 VSS110 SCONN288_ADR50017P087CC-SCONN2A   I175 @S9S_MB_2U_LIB.S9S_MB_2U(SCH_1):PAGE87
    J6  255 VSS111 SCONN288_ADR50017P087CC-SCONN2A   I175 @S9S_MB_2U_LIB.S9S_MB_2U(SCH_1):PAGE87
    J6  257 VSS112 SCONN288_ADR50017P087CC-SCONN2A   I175 @S9S_MB_2U_LIB.S9S_MB_2U(SCH_1):PAGE87
    J6  259 VSS113 SCONN288_ADR50017P087CC-SCONN2A   I175 @S9S_MB_2U_LIB.S9S_MB_2U(SCH_1):PAGE87
    J6  262 VSS114 SCONN288_ADR50017P087CC-SCONN2A   I175 @S9S_MB_2U_LIB.S9S_MB_2U(SCH_1):PAGE87
    J6  264 VSS115 SCONN288_ADR50017P087CC-SCONN2A   I175 @S9S_MB_2U_LIB.S9S_MB_2U(SCH_1):PAGE87
    J6  266 VSS116 SCONN288_ADR50017P087CC-SCONN2A   I175 @S9S_MB_2U_LIB.S9S_MB_2U(SCH_1):PAGE87
    J6  268 VSS117 SCONN288_ADR50017P087CC-SCONN2A   I175 @S9S_MB_2U_LIB.S9S_MB_2U(SCH_1):PAGE87
    J6  270 VSS118 SCONN288_ADR50017P087CC-SCONN2A   I175 @S9S_MB_2U_LIB.S9S_MB_2U(SCH_1):PAGE87
    J6  273 VSS119 SCONN288_ADR50017P087CC-SCONN2A   I175 @S9S_MB_2U_LIB.S9S_MB_2U(SCH_1):PAGE87
    J6  275 VSS120 SCONN288_ADR50017P087CC-SCONN2A   I175 @S9S_MB_2U_LIB.S9S_MB_2U(SCH_1):PAGE87
    J6  277 VSS121 SCONN288_ADR50017P087CC-SCONN2A   I175 @S9S_MB_2U_LIB.S9S_MB_2U(SCH_1):PAGE87
    J6  279 VSS122 SCONN288_ADR50017P087CC-SCONN2A   I175 @S9S_MB_2U_LIB.S9S_MB_2U(SCH_1):PAGE87
    J6  281 VSS123 SCONN288_ADR50017P087CC-SCONN2A   I175 @S9S_MB_2U_LIB.S9S_MB_2U(SCH_1):PAGE87
    J6  284 VSS124 SCONN288_ADR50017P087CC-SCONN2A   I175 @S9S_MB_2U_LIB.S9S_MB_2U(SCH_1):PAGE87
    J6  286 VSS125 SCONN288_ADR50017P087CC-SCONN2A   I175 @S9S_MB_2U_LIB.S9S_MB_2U(SCH_1):PAGE87
    J6  288 VSS126 SCONN288_ADR50017P087CC-SCONN2A   I175 @S9S_MB_2U_LIB.S9S_MB_2U(SCH_1):PAGE87
   R32    2      B Q_RES_0402LF-127K,1%,1/16W,CHIA     I2 @S9S_MB_2U_LIB.S9S_MB_2U(SCH_1):PAGE88
   C20    2      B Q_CAP_C0402-2.2UF,6.3V,20%,X6SA   I123 @S9S_MB_2U_LIB.S9S_MB_2U(SCH_1):PAGE88
   C21    2      B Q_CAP_C0805-10UF,16V,10%,X6S,CA   I126 @S9S_MB_2U_LIB.S9S_MB_2U(SCH_1):PAGE88
   C22    2      B Q_CAP_C0805-10UF,16V,10%,X6S,CA   I166 @S9S_MB_2U_LIB.S9S_MB_2U(SCH_1):PAGE88
    J7   G1     G1 SCONN288_ADR50017P130CC-SCONN2A   I168 @S9S_MB_2U_LIB.S9S_MB_2U(SCH_1):PAGE88
    J7   G2     G2 SCONN288_ADR50017P130CC-SCONN2A   I168 @S9S_MB_2U_LIB.S9S_MB_2U(SCH_1):PAGE88
    J7   G3     G3 SCONN288_ADR50017P130CC-SCONN2A   I168 @S9S_MB_2U_LIB.S9S_MB_2U(SCH_1):PAGE88
    J7    6   VSS0 SCONN288_ADR50017P130CC-SCONN2A   I168 @S9S_MB_2U_LIB.S9S_MB_2U(SCH_1):PAGE88
    J7    8   VSS1 SCONN288_ADR50017P130CC-SCONN2A   I168 @S9S_MB_2U_LIB.S9S_MB_2U(SCH_1):PAGE88
    J7   10   VSS2 SCONN288_ADR50017P130CC-SCONN2A   I168 @S9S_MB_2U_LIB.S9S_MB_2U(SCH_1):PAGE88
    J7   13   VSS3 SCONN288_ADR50017P130CC-SCONN2A   I168 @S9S_MB_2U_LIB.S9S_MB_2U(SCH_1):PAGE88
    J7   15   VSS4 SCONN288_ADR50017P130CC-SCONN2A   I168 @S9S_MB_2U_LIB.S9S_MB_2U(SCH_1):PAGE88
    J7   17   VSS5 SCONN288_ADR50017P130CC-SCONN2A   I168 @S9S_MB_2U_LIB.S9S_MB_2U(SCH_1):PAGE88
    J7   19   VSS6 SCONN288_ADR50017P130CC-SCONN2A   I168 @S9S_MB_2U_LIB.S9S_MB_2U(SCH_1):PAGE88
    J7   21   VSS7 SCONN288_ADR50017P130CC-SCONN2A   I168 @S9S_MB_2U_LIB.S9S_MB_2U(SCH_1):PAGE88
    J7   24   VSS8 SCONN288_ADR50017P130CC-SCONN2A   I168 @S9S_MB_2U_LIB.S9S_MB_2U(SCH_1):PAGE88
    J7   26   VSS9 SCONN288_ADR50017P130CC-SCONN2A   I168 @S9S_MB_2U_LIB.S9S_MB_2U(SCH_1):PAGE88
    J7   28  VSS10 SCONN288_ADR50017P130CC-SCONN2A   I168 @S9S_MB_2U_LIB.S9S_MB_2U(SCH_1):PAGE88
    J7   30  VSS11 SCONN288_ADR50017P130CC-SCONN2A   I168 @S9S_MB_2U_LIB.S9S_MB_2U(SCH_1):PAGE88
    J7   32  VSS12 SCONN288_ADR50017P130CC-SCONN2A   I168 @S9S_MB_2U_LIB.S9S_MB_2U(SCH_1):PAGE88
    J7   35  VSS13 SCONN288_ADR50017P130CC-SCONN2A   I168 @S9S_MB_2U_LIB.S9S_MB_2U(SCH_1):PAGE88
    J7   37  VSS14 SCONN288_ADR50017P130CC-SCONN2A   I168 @S9S_MB_2U_LIB.S9S_MB_2U(SCH_1):PAGE88
    J7   39  VSS15 SCONN288_ADR50017P130CC-SCONN2A   I168 @S9S_MB_2U_LIB.S9S_MB_2U(SCH_1):PAGE88
    J7   41  VSS16 SCONN288_ADR50017P130CC-SCONN2A   I168 @S9S_MB_2U_LIB.S9S_MB_2U(SCH_1):PAGE88
    J7   43  VSS17 SCONN288_ADR50017P130CC-SCONN2A   I168 @S9S_MB_2U_LIB.S9S_MB_2U(SCH_1):PAGE88
    J7   46  VSS18 SCONN288_ADR50017P130CC-SCONN2A   I168 @S9S_MB_2U_LIB.S9S_MB_2U(SCH_1):PAGE88
    J7   48  VSS19 SCONN288_ADR50017P130CC-SCONN2A   I168 @S9S_MB_2U_LIB.S9S_MB_2U(SCH_1):PAGE88
    J7   50  VSS20 SCONN288_ADR50017P130CC-SCONN2A   I168 @S9S_MB_2U_LIB.S9S_MB_2U(SCH_1):PAGE88
    J7   52  VSS21 SCONN288_ADR50017P130CC-SCONN2A   I168 @S9S_MB_2U_LIB.S9S_MB_2U(SCH_1):PAGE88
    J7   54  VSS22 SCONN288_ADR50017P130CC-SCONN2A   I168 @S9S_MB_2U_LIB.S9S_MB_2U(SCH_1):PAGE88
    J7   57  VSS23 SCONN288_ADR50017P130CC-SCONN2A   I168 @S9S_MB_2U_LIB.S9S_MB_2U(SCH_1):PAGE88
    J7   59  VSS24 SCONN288_ADR50017P130CC-SCONN2A   I168 @S9S_MB_2U_LIB.S9S_MB_2U(SCH_1):PAGE88
    J7   61  VSS25 SCONN288_ADR50017P130CC-SCONN2A   I168 @S9S_MB_2U_LIB.S9S_MB_2U(SCH_1):PAGE88
    J7   63  VSS26 SCONN288_ADR50017P130CC-SCONN2A   I168 @S9S_MB_2U_LIB.S9S_MB_2U(SCH_1):PAGE88
    J7   65  VSS27 SCONN288_ADR50017P130CC-SCONN2A   I168 @S9S_MB_2U_LIB.S9S_MB_2U(SCH_1):PAGE88
    J7   67  VSS28 SCONN288_ADR50017P130CC-SCONN2A   I168 @S9S_MB_2U_LIB.S9S_MB_2U(SCH_1):PAGE88
    J7   69  VSS29 SCONN288_ADR50017P130CC-SCONN2A   I168 @S9S_MB_2U_LIB.S9S_MB_2U(SCH_1):PAGE88
    J7   71  VSS30 SCONN288_ADR50017P130CC-SCONN2A   I168 @S9S_MB_2U_LIB.S9S_MB_2U(SCH_1):PAGE88
    J7   73  VSS31 SCONN288_ADR50017P130CC-SCONN2A   I168 @S9S_MB_2U_LIB.S9S_MB_2U(SCH_1):PAGE88
    J7   75  VSS32 SCONN288_ADR50017P130CC-SCONN2A   I168 @S9S_MB_2U_LIB.S9S_MB_2U(SCH_1):PAGE88
    J7   77  VSS33 SCONN288_ADR50017P130CC-SCONN2A   I168 @S9S_MB_2U_LIB.S9S_MB_2U(SCH_1):PAGE88
    J7   79  VSS34 SCONN288_ADR50017P130CC-SCONN2A   I168 @S9S_MB_2U_LIB.S9S_MB_2U(SCH_1):PAGE88
    J7   81  VSS35 SCONN288_ADR50017P130CC-SCONN2A   I168 @S9S_MB_2U_LIB.S9S_MB_2U(SCH_1):PAGE88
    J7   83  VSS36 SCONN288_ADR50017P130CC-SCONN2A   I168 @S9S_MB_2U_LIB.S9S_MB_2U(SCH_1):PAGE88
    J7   85  VSS37 SCONN288_ADR50017P130CC-SCONN2A   I168 @S9S_MB_2U_LIB.S9S_MB_2U(SCH_1):PAGE88
    J7   88  VSS38 SCONN288_ADR50017P130CC-SCONN2A   I168 @S9S_MB_2U_LIB.S9S_MB_2U(SCH_1):PAGE88
    J7   90  VSS39 SCONN288_ADR50017P130CC-SCONN2A   I168 @S9S_MB_2U_LIB.S9S_MB_2U(SCH_1):PAGE88
    J7   92  VSS40 SCONN288_ADR50017P130CC-SCONN2A   I168 @S9S_MB_2U_LIB.S9S_MB_2U(SCH_1):PAGE88
    J7   95  VSS41 SCONN288_ADR50017P130CC-SCONN2A   I168 @S9S_MB_2U_LIB.S9S_MB_2U(SCH_1):PAGE88
    J7   97  VSS42 SCONN288_ADR50017P130CC-SCONN2A   I168 @S9S_MB_2U_LIB.S9S_MB_2U(SCH_1):PAGE88
    J7   99  VSS43 SCONN288_ADR50017P130CC-SCONN2A   I168 @S9S_MB_2U_LIB.S9S_MB_2U(SCH_1):PAGE88
    J7  101  VSS44 SCONN288_ADR50017P130CC-SCONN2A   I168 @S9S_MB_2U_LIB.S9S_MB_2U(SCH_1):PAGE88
    J7  103  VSS45 SCONN288_ADR50017P130CC-SCONN2A   I168 @S9S_MB_2U_LIB.S9S_MB_2U(SCH_1):PAGE88
    J7  106  VSS46 SCONN288_ADR50017P130CC-SCONN2A   I168 @S9S_MB_2U_LIB.S9S_MB_2U(SCH_1):PAGE88
    J7  108  VSS47 SCONN288_ADR50017P130CC-SCONN2A   I168 @S9S_MB_2U_LIB.S9S_MB_2U(SCH_1):PAGE88
    J7  110  VSS48 SCONN288_ADR50017P130CC-SCONN2A   I168 @S9S_MB_2U_LIB.S9S_MB_2U(SCH_1):PAGE88
    J7  112  VSS49 SCONN288_ADR50017P130CC-SCONN2A   I168 @S9S_MB_2U_LIB.S9S_MB_2U(SCH_1):PAGE88
    J7  114  VSS50 SCONN288_ADR50017P130CC-SCONN2A   I168 @S9S_MB_2U_LIB.S9S_MB_2U(SCH_1):PAGE88
    J7  117  VSS51 SCONN288_ADR50017P130CC-SCONN2A   I168 @S9S_MB_2U_LIB.S9S_MB_2U(SCH_1):PAGE88
    J7  119  VSS52 SCONN288_ADR50017P130CC-SCONN2A   I168 @S9S_MB_2U_LIB.S9S_MB_2U(SCH_1):PAGE88
    J7  121  VSS53 SCONN288_ADR50017P130CC-SCONN2A   I168 @S9S_MB_2U_LIB.S9S_MB_2U(SCH_1):PAGE88
    J7  123  VSS54 SCONN288_ADR50017P130CC-SCONN2A   I168 @S9S_MB_2U_LIB.S9S_MB_2U(SCH_1):PAGE88
    J7  125  VSS55 SCONN288_ADR50017P130CC-SCONN2A   I168 @S9S_MB_2U_LIB.S9S_MB_2U(SCH_1):PAGE88
    J7  128  VSS56 SCONN288_ADR50017P130CC-SCONN2A   I168 @S9S_MB_2U_LIB.S9S_MB_2U(SCH_1):PAGE88
    J7  130  VSS57 SCONN288_ADR50017P130CC-SCONN2A   I168 @S9S_MB_2U_LIB.S9S_MB_2U(SCH_1):PAGE88
    J7  132  VSS58 SCONN288_ADR50017P130CC-SCONN2A   I168 @S9S_MB_2U_LIB.S9S_MB_2U(SCH_1):PAGE88
    J7  134  VSS59 SCONN288_ADR50017P130CC-SCONN2A   I168 @S9S_MB_2U_LIB.S9S_MB_2U(SCH_1):PAGE88
    J7  136  VSS60 SCONN288_ADR50017P130CC-SCONN2A   I168 @S9S_MB_2U_LIB.S9S_MB_2U(SCH_1):PAGE88
    J7  139  VSS61 SCONN288_ADR50017P130CC-SCONN2A   I168 @S9S_MB_2U_LIB.S9S_MB_2U(SCH_1):PAGE88
    J7  141  VSS62 SCONN288_ADR50017P130CC-SCONN2A   I168 @S9S_MB_2U_LIB.S9S_MB_2U(SCH_1):PAGE88
    J7  143  VSS63 SCONN288_ADR50017P130CC-SCONN2A   I168 @S9S_MB_2U_LIB.S9S_MB_2U(SCH_1):PAGE88
    J7  151  VSS64 SCONN288_ADR50017P130CC-SCONN2A   I168 @S9S_MB_2U_LIB.S9S_MB_2U(SCH_1):PAGE88
    J7  153  VSS65 SCONN288_ADR50017P130CC-SCONN2A   I168 @S9S_MB_2U_LIB.S9S_MB_2U(SCH_1):PAGE88
    J7  155  VSS66 SCONN288_ADR50017P130CC-SCONN2A   I168 @S9S_MB_2U_LIB.S9S_MB_2U(SCH_1):PAGE88
    J7  158  VSS67 SCONN288_ADR50017P130CC-SCONN2A   I168 @S9S_MB_2U_LIB.S9S_MB_2U(SCH_1):PAGE88
    J7  160  VSS68 SCONN288_ADR50017P130CC-SCONN2A   I168 @S9S_MB_2U_LIB.S9S_MB_2U(SCH_1):PAGE88
    J7  162  VSS69 SCONN288_ADR50017P130CC-SCONN2A   I168 @S9S_MB_2U_LIB.S9S_MB_2U(SCH_1):PAGE88
    J7  164  VSS70 SCONN288_ADR50017P130CC-SCONN2A   I168 @S9S_MB_2U_LIB.S9S_MB_2U(SCH_1):PAGE88
    J7  166  VSS71 SCONN288_ADR50017P130CC-SCONN2A   I168 @S9S_MB_2U_LIB.S9S_MB_2U(SCH_1):PAGE88
    J7  169  VSS72 SCONN288_ADR50017P130CC-SCONN2A   I168 @S9S_MB_2U_LIB.S9S_MB_2U(SCH_1):PAGE88
    J7  171  VSS73 SCONN288_ADR50017P130CC-SCONN2A   I168 @S9S_MB_2U_LIB.S9S_MB_2U(SCH_1):PAGE88
    J7  173  VSS74 SCONN288_ADR50017P130CC-SCONN2A   I168 @S9S_MB_2U_LIB.S9S_MB_2U(SCH_1):PAGE88
    J7  175  VSS75 SCONN288_ADR50017P130CC-SCONN2A   I168 @S9S_MB_2U_LIB.S9S_MB_2U(SCH_1):PAGE88
    J7  177  VSS76 SCONN288_ADR50017P130CC-SCONN2A   I168 @S9S_MB_2U_LIB.S9S_MB_2U(SCH_1):PAGE88
    J7  180  VSS77 SCONN288_ADR50017P130CC-SCONN2A   I168 @S9S_MB_2U_LIB.S9S_MB_2U(SCH_1):PAGE88
    J7  182  VSS78 SCONN288_ADR50017P130CC-SCONN2A   I168 @S9S_MB_2U_LIB.S9S_MB_2U(SCH_1):PAGE88
    J7  184  VSS79 SCONN288_ADR50017P130CC-SCONN2A   I168 @S9S_MB_2U_LIB.S9S_MB_2U(SCH_1):PAGE88
    J7  186  VSS80 SCONN288_ADR50017P130CC-SCONN2A   I168 @S9S_MB_2U_LIB.S9S_MB_2U(SCH_1):PAGE88
    J7  188  VSS81 SCONN288_ADR50017P130CC-SCONN2A   I168 @S9S_MB_2U_LIB.S9S_MB_2U(SCH_1):PAGE88
    J7  191  VSS82 SCONN288_ADR50017P130CC-SCONN2A   I168 @S9S_MB_2U_LIB.S9S_MB_2U(SCH_1):PAGE88
    J7  193  VSS83 SCONN288_ADR50017P130CC-SCONN2A   I168 @S9S_MB_2U_LIB.S9S_MB_2U(SCH_1):PAGE88
    J7  195  VSS84 SCONN288_ADR50017P130CC-SCONN2A   I168 @S9S_MB_2U_LIB.S9S_MB_2U(SCH_1):PAGE88
    J7  197  VSS85 SCONN288_ADR50017P130CC-SCONN2A   I168 @S9S_MB_2U_LIB.S9S_MB_2U(SCH_1):PAGE88
    J7  199  VSS86 SCONN288_ADR50017P130CC-SCONN2A   I168 @S9S_MB_2U_LIB.S9S_MB_2U(SCH_1):PAGE88
    J7  202  VSS87 SCONN288_ADR50017P130CC-SCONN2A   I168 @S9S_MB_2U_LIB.S9S_MB_2U(SCH_1):PAGE88
    J7  204  VSS88 SCONN288_ADR50017P130CC-SCONN2A   I168 @S9S_MB_2U_LIB.S9S_MB_2U(SCH_1):PAGE88
    J7  206  VSS89 SCONN288_ADR50017P130CC-SCONN2A   I168 @S9S_MB_2U_LIB.S9S_MB_2U(SCH_1):PAGE88
    J7  208  VSS90 SCONN288_ADR50017P130CC-SCONN2A   I168 @S9S_MB_2U_LIB.S9S_MB_2U(SCH_1):PAGE88
    J7  210  VSS91 SCONN288_ADR50017P130CC-SCONN2A   I168 @S9S_MB_2U_LIB.S9S_MB_2U(SCH_1):PAGE88
    J7  212  VSS92 SCONN288_ADR50017P130CC-SCONN2A   I168 @S9S_MB_2U_LIB.S9S_MB_2U(SCH_1):PAGE88
    J7  214  VSS93 SCONN288_ADR50017P130CC-SCONN2A   I168 @S9S_MB_2U_LIB.S9S_MB_2U(SCH_1):PAGE88
    J7  216  VSS94 SCONN288_ADR50017P130CC-SCONN2A   I168 @S9S_MB_2U_LIB.S9S_MB_2U(SCH_1):PAGE88
    J7  219  VSS95 SCONN288_ADR50017P130CC-SCONN2A   I168 @S9S_MB_2U_LIB.S9S_MB_2U(SCH_1):PAGE88
    J7  222  VSS96 SCONN288_ADR50017P130CC-SCONN2A   I168 @S9S_MB_2U_LIB.S9S_MB_2U(SCH_1):PAGE88
    J7  224  VSS97 SCONN288_ADR50017P130CC-SCONN2A   I168 @S9S_MB_2U_LIB.S9S_MB_2U(SCH_1):PAGE88
    J7  226  VSS98 SCONN288_ADR50017P130CC-SCONN2A   I168 @S9S_MB_2U_LIB.S9S_MB_2U(SCH_1):PAGE88
    J7  228  VSS99 SCONN288_ADR50017P130CC-SCONN2A   I168 @S9S_MB_2U_LIB.S9S_MB_2U(SCH_1):PAGE88
    J7  230 VSS100 SCONN288_ADR50017P130CC-SCONN2A   I168 @S9S_MB_2U_LIB.S9S_MB_2U(SCH_1):PAGE88
    J7  233 VSS101 SCONN288_ADR50017P130CC-SCONN2A   I168 @S9S_MB_2U_LIB.S9S_MB_2U(SCH_1):PAGE88
    J7  235 VSS102 SCONN288_ADR50017P130CC-SCONN2A   I168 @S9S_MB_2U_LIB.S9S_MB_2U(SCH_1):PAGE88
    J7  237 VSS103 SCONN288_ADR50017P130CC-SCONN2A   I168 @S9S_MB_2U_LIB.S9S_MB_2U(SCH_1):PAGE88
    J7  240 VSS104 SCONN288_ADR50017P130CC-SCONN2A   I168 @S9S_MB_2U_LIB.S9S_MB_2U(SCH_1):PAGE88
    J7  242 VSS105 SCONN288_ADR50017P130CC-SCONN2A   I168 @S9S_MB_2U_LIB.S9S_MB_2U(SCH_1):PAGE88
    J7  244 VSS106 SCONN288_ADR50017P130CC-SCONN2A   I168 @S9S_MB_2U_LIB.S9S_MB_2U(SCH_1):PAGE88
    J7  246 VSS107 SCONN288_ADR50017P130CC-SCONN2A   I168 @S9S_MB_2U_LIB.S9S_MB_2U(SCH_1):PAGE88
    J7  248 VSS108 SCONN288_ADR50017P130CC-SCONN2A   I168 @S9S_MB_2U_LIB.S9S_MB_2U(SCH_1):PAGE88
    J7  251 VSS109 SCONN288_ADR50017P130CC-SCONN2A   I168 @S9S_MB_2U_LIB.S9S_MB_2U(SCH_1):PAGE88
    J7  253 VSS110 SCONN288_ADR50017P130CC-SCONN2A   I168 @S9S_MB_2U_LIB.S9S_MB_2U(SCH_1):PAGE88
    J7  255 VSS111 SCONN288_ADR50017P130CC-SCONN2A   I168 @S9S_MB_2U_LIB.S9S_MB_2U(SCH_1):PAGE88
    J7  257 VSS112 SCONN288_ADR50017P130CC-SCONN2A   I168 @S9S_MB_2U_LIB.S9S_MB_2U(SCH_1):PAGE88
    J7  259 VSS113 SCONN288_ADR50017P130CC-SCONN2A   I168 @S9S_MB_2U_LIB.S9S_MB_2U(SCH_1):PAGE88
    J7  262 VSS114 SCONN288_ADR50017P130CC-SCONN2A   I168 @S9S_MB_2U_LIB.S9S_MB_2U(SCH_1):PAGE88
    J7  264 VSS115 SCONN288_ADR50017P130CC-SCONN2A   I168 @S9S_MB_2U_LIB.S9S_MB_2U(SCH_1):PAGE88
    J7  266 VSS116 SCONN288_ADR50017P130CC-SCONN2A   I168 @S9S_MB_2U_LIB.S9S_MB_2U(SCH_1):PAGE88
    J7  268 VSS117 SCONN288_ADR50017P130CC-SCONN2A   I168 @S9S_MB_2U_LIB.S9S_MB_2U(SCH_1):PAGE88
    J7  270 VSS118 SCONN288_ADR50017P130CC-SCONN2A   I168 @S9S_MB_2U_LIB.S9S_MB_2U(SCH_1):PAGE88
    J7  273 VSS119 SCONN288_ADR50017P130CC-SCONN2A   I168 @S9S_MB_2U_LIB.S9S_MB_2U(SCH_1):PAGE88
    J7  275 VSS120 SCONN288_ADR50017P130CC-SCONN2A   I168 @S9S_MB_2U_LIB.S9S_MB_2U(SCH_1):PAGE88
    J7  277 VSS121 SCONN288_ADR50017P130CC-SCONN2A   I168 @S9S_MB_2U_LIB.S9S_MB_2U(SCH_1):PAGE88
    J7  279 VSS122 SCONN288_ADR50017P130CC-SCONN2A   I168 @S9S_MB_2U_LIB.S9S_MB_2U(SCH_1):PAGE88
    J7  281 VSS123 SCONN288_ADR50017P130CC-SCONN2A   I168 @S9S_MB_2U_LIB.S9S_MB_2U(SCH_1):PAGE88
    J7  284 VSS124 SCONN288_ADR50017P130CC-SCONN2A   I168 @S9S_MB_2U_LIB.S9S_MB_2U(SCH_1):PAGE88
    J7  286 VSS125 SCONN288_ADR50017P130CC-SCONN2A   I168 @S9S_MB_2U_LIB.S9S_MB_2U(SCH_1):PAGE88
    J7  288 VSS126 SCONN288_ADR50017P130CC-SCONN2A   I168 @S9S_MB_2U_LIB.S9S_MB_2U(SCH_1):PAGE88
   R33    2      B Q_RES_0402LF-196K,1%,1/16W,CHIA     I2 @S9S_MB_2U_LIB.S9S_MB_2U(SCH_1):PAGE89
   C23    2      B Q_CAP_C0402-2.2UF,6.3V,20%,X6SA   I121 @S9S_MB_2U_LIB.S9S_MB_2U(SCH_1):PAGE89
   C24    2      B Q_CAP_C0805-10UF,16V,10%,X6S,CA   I125 @S9S_MB_2U_LIB.S9S_MB_2U(SCH_1):PAGE89
   C25    2      B Q_CAP_C0805-10UF,16V,10%,X6S,CA   I127 @S9S_MB_2U_LIB.S9S_MB_2U(SCH_1):PAGE89
    J8   G1     G1 SCONN288_ADR50017P087CC-SCONN2A   I175 @S9S_MB_2U_LIB.S9S_MB_2U(SCH_1):PAGE89
    J8   G2     G2 SCONN288_ADR50017P087CC-SCONN2A   I175 @S9S_MB_2U_LIB.S9S_MB_2U(SCH_1):PAGE89
    J8   G3     G3 SCONN288_ADR50017P087CC-SCONN2A   I175 @S9S_MB_2U_LIB.S9S_MB_2U(SCH_1):PAGE89
    J8    6   VSS0 SCONN288_ADR50017P087CC-SCONN2A   I175 @S9S_MB_2U_LIB.S9S_MB_2U(SCH_1):PAGE89
    J8    8   VSS1 SCONN288_ADR50017P087CC-SCONN2A   I175 @S9S_MB_2U_LIB.S9S_MB_2U(SCH_1):PAGE89
    J8   10   VSS2 SCONN288_ADR50017P087CC-SCONN2A   I175 @S9S_MB_2U_LIB.S9S_MB_2U(SCH_1):PAGE89
    J8   13   VSS3 SCONN288_ADR50017P087CC-SCONN2A   I175 @S9S_MB_2U_LIB.S9S_MB_2U(SCH_1):PAGE89
    J8   15   VSS4 SCONN288_ADR50017P087CC-SCONN2A   I175 @S9S_MB_2U_LIB.S9S_MB_2U(SCH_1):PAGE89
    J8   17   VSS5 SCONN288_ADR50017P087CC-SCONN2A   I175 @S9S_MB_2U_LIB.S9S_MB_2U(SCH_1):PAGE89
    J8   19   VSS6 SCONN288_ADR50017P087CC-SCONN2A   I175 @S9S_MB_2U_LIB.S9S_MB_2U(SCH_1):PAGE89
    J8   21   VSS7 SCONN288_ADR50017P087CC-SCONN2A   I175 @S9S_MB_2U_LIB.S9S_MB_2U(SCH_1):PAGE89
    J8   24   VSS8 SCONN288_ADR50017P087CC-SCONN2A   I175 @S9S_MB_2U_LIB.S9S_MB_2U(SCH_1):PAGE89
    J8   26   VSS9 SCONN288_ADR50017P087CC-SCONN2A   I175 @S9S_MB_2U_LIB.S9S_MB_2U(SCH_1):PAGE89
    J8   28  VSS10 SCONN288_ADR50017P087CC-SCONN2A   I175 @S9S_MB_2U_LIB.S9S_MB_2U(SCH_1):PAGE89
    J8   30  VSS11 SCONN288_ADR50017P087CC-SCONN2A   I175 @S9S_MB_2U_LIB.S9S_MB_2U(SCH_1):PAGE89
    J8   32  VSS12 SCONN288_ADR50017P087CC-SCONN2A   I175 @S9S_MB_2U_LIB.S9S_MB_2U(SCH_1):PAGE89
    J8   35  VSS13 SCONN288_ADR50017P087CC-SCONN2A   I175 @S9S_MB_2U_LIB.S9S_MB_2U(SCH_1):PAGE89
    J8   37  VSS14 SCONN288_ADR50017P087CC-SCONN2A   I175 @S9S_MB_2U_LIB.S9S_MB_2U(SCH_1):PAGE89
    J8   39  VSS15 SCONN288_ADR50017P087CC-SCONN2A   I175 @S9S_MB_2U_LIB.S9S_MB_2U(SCH_1):PAGE89
    J8   41  VSS16 SCONN288_ADR50017P087CC-SCONN2A   I175 @S9S_MB_2U_LIB.S9S_MB_2U(SCH_1):PAGE89
    J8   43  VSS17 SCONN288_ADR50017P087CC-SCONN2A   I175 @S9S_MB_2U_LIB.S9S_MB_2U(SCH_1):PAGE89
    J8   46  VSS18 SCONN288_ADR50017P087CC-SCONN2A   I175 @S9S_MB_2U_LIB.S9S_MB_2U(SCH_1):PAGE89
    J8   48  VSS19 SCONN288_ADR50017P087CC-SCONN2A   I175 @S9S_MB_2U_LIB.S9S_MB_2U(SCH_1):PAGE89
    J8   50  VSS20 SCONN288_ADR50017P087CC-SCONN2A   I175 @S9S_MB_2U_LIB.S9S_MB_2U(SCH_1):PAGE89
    J8   52  VSS21 SCONN288_ADR50017P087CC-SCONN2A   I175 @S9S_MB_2U_LIB.S9S_MB_2U(SCH_1):PAGE89
    J8   54  VSS22 SCONN288_ADR50017P087CC-SCONN2A   I175 @S9S_MB_2U_LIB.S9S_MB_2U(SCH_1):PAGE89
    J8   57  VSS23 SCONN288_ADR50017P087CC-SCONN2A   I175 @S9S_MB_2U_LIB.S9S_MB_2U(SCH_1):PAGE89
    J8   59  VSS24 SCONN288_ADR50017P087CC-SCONN2A   I175 @S9S_MB_2U_LIB.S9S_MB_2U(SCH_1):PAGE89
    J8   61  VSS25 SCONN288_ADR50017P087CC-SCONN2A   I175 @S9S_MB_2U_LIB.S9S_MB_2U(SCH_1):PAGE89
    J8   63  VSS26 SCONN288_ADR50017P087CC-SCONN2A   I175 @S9S_MB_2U_LIB.S9S_MB_2U(SCH_1):PAGE89
    J8   65  VSS27 SCONN288_ADR50017P087CC-SCONN2A   I175 @S9S_MB_2U_LIB.S9S_MB_2U(SCH_1):PAGE89
    J8   67  VSS28 SCONN288_ADR50017P087CC-SCONN2A   I175 @S9S_MB_2U_LIB.S9S_MB_2U(SCH_1):PAGE89
    J8   69  VSS29 SCONN288_ADR50017P087CC-SCONN2A   I175 @S9S_MB_2U_LIB.S9S_MB_2U(SCH_1):PAGE89
    J8   71  VSS30 SCONN288_ADR50017P087CC-SCONN2A   I175 @S9S_MB_2U_LIB.S9S_MB_2U(SCH_1):PAGE89
    J8   73  VSS31 SCONN288_ADR50017P087CC-SCONN2A   I175 @S9S_MB_2U_LIB.S9S_MB_2U(SCH_1):PAGE89
    J8   75  VSS32 SCONN288_ADR50017P087CC-SCONN2A   I175 @S9S_MB_2U_LIB.S9S_MB_2U(SCH_1):PAGE89
    J8   77  VSS33 SCONN288_ADR50017P087CC-SCONN2A   I175 @S9S_MB_2U_LIB.S9S_MB_2U(SCH_1):PAGE89
    J8   79  VSS34 SCONN288_ADR50017P087CC-SCONN2A   I175 @S9S_MB_2U_LIB.S9S_MB_2U(SCH_1):PAGE89
    J8   81  VSS35 SCONN288_ADR50017P087CC-SCONN2A   I175 @S9S_MB_2U_LIB.S9S_MB_2U(SCH_1):PAGE89
    J8   83  VSS36 SCONN288_ADR50017P087CC-SCONN2A   I175 @S9S_MB_2U_LIB.S9S_MB_2U(SCH_1):PAGE89
    J8   85  VSS37 SCONN288_ADR50017P087CC-SCONN2A   I175 @S9S_MB_2U_LIB.S9S_MB_2U(SCH_1):PAGE89
    J8   88  VSS38 SCONN288_ADR50017P087CC-SCONN2A   I175 @S9S_MB_2U_LIB.S9S_MB_2U(SCH_1):PAGE89
    J8   90  VSS39 SCONN288_ADR50017P087CC-SCONN2A   I175 @S9S_MB_2U_LIB.S9S_MB_2U(SCH_1):PAGE89
    J8   92  VSS40 SCONN288_ADR50017P087CC-SCONN2A   I175 @S9S_MB_2U_LIB.S9S_MB_2U(SCH_1):PAGE89
    J8   95  VSS41 SCONN288_ADR50017P087CC-SCONN2A   I175 @S9S_MB_2U_LIB.S9S_MB_2U(SCH_1):PAGE89
    J8   97  VSS42 SCONN288_ADR50017P087CC-SCONN2A   I175 @S9S_MB_2U_LIB.S9S_MB_2U(SCH_1):PAGE89
    J8   99  VSS43 SCONN288_ADR50017P087CC-SCONN2A   I175 @S9S_MB_2U_LIB.S9S_MB_2U(SCH_1):PAGE89
    J8  101  VSS44 SCONN288_ADR50017P087CC-SCONN2A   I175 @S9S_MB_2U_LIB.S9S_MB_2U(SCH_1):PAGE89
    J8  103  VSS45 SCONN288_ADR50017P087CC-SCONN2A   I175 @S9S_MB_2U_LIB.S9S_MB_2U(SCH_1):PAGE89
    J8  106  VSS46 SCONN288_ADR50017P087CC-SCONN2A   I175 @S9S_MB_2U_LIB.S9S_MB_2U(SCH_1):PAGE89
    J8  108  VSS47 SCONN288_ADR50017P087CC-SCONN2A   I175 @S9S_MB_2U_LIB.S9S_MB_2U(SCH_1):PAGE89
    J8  110  VSS48 SCONN288_ADR50017P087CC-SCONN2A   I175 @S9S_MB_2U_LIB.S9S_MB_2U(SCH_1):PAGE89
    J8  112  VSS49 SCONN288_ADR50017P087CC-SCONN2A   I175 @S9S_MB_2U_LIB.S9S_MB_2U(SCH_1):PAGE89
    J8  114  VSS50 SCONN288_ADR50017P087CC-SCONN2A   I175 @S9S_MB_2U_LIB.S9S_MB_2U(SCH_1):PAGE89
    J8  117  VSS51 SCONN288_ADR50017P087CC-SCONN2A   I175 @S9S_MB_2U_LIB.S9S_MB_2U(SCH_1):PAGE89
    J8  119  VSS52 SCONN288_ADR50017P087CC-SCONN2A   I175 @S9S_MB_2U_LIB.S9S_MB_2U(SCH_1):PAGE89
    J8  121  VSS53 SCONN288_ADR50017P087CC-SCONN2A   I175 @S9S_MB_2U_LIB.S9S_MB_2U(SCH_1):PAGE89
    J8  123  VSS54 SCONN288_ADR50017P087CC-SCONN2A   I175 @S9S_MB_2U_LIB.S9S_MB_2U(SCH_1):PAGE89
    J8  125  VSS55 SCONN288_ADR50017P087CC-SCONN2A   I175 @S9S_MB_2U_LIB.S9S_MB_2U(SCH_1):PAGE89
    J8  128  VSS56 SCONN288_ADR50017P087CC-SCONN2A   I175 @S9S_MB_2U_LIB.S9S_MB_2U(SCH_1):PAGE89
    J8  130  VSS57 SCONN288_ADR50017P087CC-SCONN2A   I175 @S9S_MB_2U_LIB.S9S_MB_2U(SCH_1):PAGE89
    J8  132  VSS58 SCONN288_ADR50017P087CC-SCONN2A   I175 @S9S_MB_2U_LIB.S9S_MB_2U(SCH_1):PAGE89
    J8  134  VSS59 SCONN288_ADR50017P087CC-SCONN2A   I175 @S9S_MB_2U_LIB.S9S_MB_2U(SCH_1):PAGE89
    J8  136  VSS60 SCONN288_ADR50017P087CC-SCONN2A   I175 @S9S_MB_2U_LIB.S9S_MB_2U(SCH_1):PAGE89
    J8  139  VSS61 SCONN288_ADR50017P087CC-SCONN2A   I175 @S9S_MB_2U_LIB.S9S_MB_2U(SCH_1):PAGE89
    J8  141  VSS62 SCONN288_ADR50017P087CC-SCONN2A   I175 @S9S_MB_2U_LIB.S9S_MB_2U(SCH_1):PAGE89
    J8  143  VSS63 SCONN288_ADR50017P087CC-SCONN2A   I175 @S9S_MB_2U_LIB.S9S_MB_2U(SCH_1):PAGE89
    J8  151  VSS64 SCONN288_ADR50017P087CC-SCONN2A   I175 @S9S_MB_2U_LIB.S9S_MB_2U(SCH_1):PAGE89
    J8  153  VSS65 SCONN288_ADR50017P087CC-SCONN2A   I175 @S9S_MB_2U_LIB.S9S_MB_2U(SCH_1):PAGE89
    J8  155  VSS66 SCONN288_ADR50017P087CC-SCONN2A   I175 @S9S_MB_2U_LIB.S9S_MB_2U(SCH_1):PAGE89
    J8  158  VSS67 SCONN288_ADR50017P087CC-SCONN2A   I175 @S9S_MB_2U_LIB.S9S_MB_2U(SCH_1):PAGE89
    J8  160  VSS68 SCONN288_ADR50017P087CC-SCONN2A   I175 @S9S_MB_2U_LIB.S9S_MB_2U(SCH_1):PAGE89
    J8  162  VSS69 SCONN288_ADR50017P087CC-SCONN2A   I175 @S9S_MB_2U_LIB.S9S_MB_2U(SCH_1):PAGE89
    J8  164  VSS70 SCONN288_ADR50017P087CC-SCONN2A   I175 @S9S_MB_2U_LIB.S9S_MB_2U(SCH_1):PAGE89
    J8  166  VSS71 SCONN288_ADR50017P087CC-SCONN2A   I175 @S9S_MB_2U_LIB.S9S_MB_2U(SCH_1):PAGE89
    J8  169  VSS72 SCONN288_ADR50017P087CC-SCONN2A   I175 @S9S_MB_2U_LIB.S9S_MB_2U(SCH_1):PAGE89
    J8  171  VSS73 SCONN288_ADR50017P087CC-SCONN2A   I175 @S9S_MB_2U_LIB.S9S_MB_2U(SCH_1):PAGE89
    J8  173  VSS74 SCONN288_ADR50017P087CC-SCONN2A   I175 @S9S_MB_2U_LIB.S9S_MB_2U(SCH_1):PAGE89
    J8  175  VSS75 SCONN288_ADR50017P087CC-SCONN2A   I175 @S9S_MB_2U_LIB.S9S_MB_2U(SCH_1):PAGE89
    J8  177  VSS76 SCONN288_ADR50017P087CC-SCONN2A   I175 @S9S_MB_2U_LIB.S9S_MB_2U(SCH_1):PAGE89
    J8  180  VSS77 SCONN288_ADR50017P087CC-SCONN2A   I175 @S9S_MB_2U_LIB.S9S_MB_2U(SCH_1):PAGE89
    J8  182  VSS78 SCONN288_ADR50017P087CC-SCONN2A   I175 @S9S_MB_2U_LIB.S9S_MB_2U(SCH_1):PAGE89
    J8  184  VSS79 SCONN288_ADR50017P087CC-SCONN2A   I175 @S9S_MB_2U_LIB.S9S_MB_2U(SCH_1):PAGE89
    J8  186  VSS80 SCONN288_ADR50017P087CC-SCONN2A   I175 @S9S_MB_2U_LIB.S9S_MB_2U(SCH_1):PAGE89
    J8  188  VSS81 SCONN288_ADR50017P087CC-SCONN2A   I175 @S9S_MB_2U_LIB.S9S_MB_2U(SCH_1):PAGE89
    J8  191  VSS82 SCONN288_ADR50017P087CC-SCONN2A   I175 @S9S_MB_2U_LIB.S9S_MB_2U(SCH_1):PAGE89
    J8  193  VSS83 SCONN288_ADR50017P087CC-SCONN2A   I175 @S9S_MB_2U_LIB.S9S_MB_2U(SCH_1):PAGE89
    J8  195  VSS84 SCONN288_ADR50017P087CC-SCONN2A   I175 @S9S_MB_2U_LIB.S9S_MB_2U(SCH_1):PAGE89
    J8  197  VSS85 SCONN288_ADR50017P087CC-SCONN2A   I175 @S9S_MB_2U_LIB.S9S_MB_2U(SCH_1):PAGE89
    J8  199  VSS86 SCONN288_ADR50017P087CC-SCONN2A   I175 @S9S_MB_2U_LIB.S9S_MB_2U(SCH_1):PAGE89
    J8  202  VSS87 SCONN288_ADR50017P087CC-SCONN2A   I175 @S9S_MB_2U_LIB.S9S_MB_2U(SCH_1):PAGE89
    J8  204  VSS88 SCONN288_ADR50017P087CC-SCONN2A   I175 @S9S_MB_2U_LIB.S9S_MB_2U(SCH_1):PAGE89
    J8  206  VSS89 SCONN288_ADR50017P087CC-SCONN2A   I175 @S9S_MB_2U_LIB.S9S_MB_2U(SCH_1):PAGE89
    J8  208  VSS90 SCONN288_ADR50017P087CC-SCONN2A   I175 @S9S_MB_2U_LIB.S9S_MB_2U(SCH_1):PAGE89
    J8  210  VSS91 SCONN288_ADR50017P087CC-SCONN2A   I175 @S9S_MB_2U_LIB.S9S_MB_2U(SCH_1):PAGE89
    J8  212  VSS92 SCONN288_ADR50017P087CC-SCONN2A   I175 @S9S_MB_2U_LIB.S9S_MB_2U(SCH_1):PAGE89
    J8  214  VSS93 SCONN288_ADR50017P087CC-SCONN2A   I175 @S9S_MB_2U_LIB.S9S_MB_2U(SCH_1):PAGE89
    J8  216  VSS94 SCONN288_ADR50017P087CC-SCONN2A   I175 @S9S_MB_2U_LIB.S9S_MB_2U(SCH_1):PAGE89
    J8  219  VSS95 SCONN288_ADR50017P087CC-SCONN2A   I175 @S9S_MB_2U_LIB.S9S_MB_2U(SCH_1):PAGE89
    J8  222  VSS96 SCONN288_ADR50017P087CC-SCONN2A   I175 @S9S_MB_2U_LIB.S9S_MB_2U(SCH_1):PAGE89
    J8  224  VSS97 SCONN288_ADR50017P087CC-SCONN2A   I175 @S9S_MB_2U_LIB.S9S_MB_2U(SCH_1):PAGE89
    J8  226  VSS98 SCONN288_ADR50017P087CC-SCONN2A   I175 @S9S_MB_2U_LIB.S9S_MB_2U(SCH_1):PAGE89
    J8  228  VSS99 SCONN288_ADR50017P087CC-SCONN2A   I175 @S9S_MB_2U_LIB.S9S_MB_2U(SCH_1):PAGE89
    J8  230 VSS100 SCONN288_ADR50017P087CC-SCONN2A   I175 @S9S_MB_2U_LIB.S9S_MB_2U(SCH_1):PAGE89
    J8  233 VSS101 SCONN288_ADR50017P087CC-SCONN2A   I175 @S9S_MB_2U_LIB.S9S_MB_2U(SCH_1):PAGE89
    J8  235 VSS102 SCONN288_ADR50017P087CC-SCONN2A   I175 @S9S_MB_2U_LIB.S9S_MB_2U(SCH_1):PAGE89
    J8  237 VSS103 SCONN288_ADR50017P087CC-SCONN2A   I175 @S9S_MB_2U_LIB.S9S_MB_2U(SCH_1):PAGE89
    J8  240 VSS104 SCONN288_ADR50017P087CC-SCONN2A   I175 @S9S_MB_2U_LIB.S9S_MB_2U(SCH_1):PAGE89
    J8  242 VSS105 SCONN288_ADR50017P087CC-SCONN2A   I175 @S9S_MB_2U_LIB.S9S_MB_2U(SCH_1):PAGE89
    J8  244 VSS106 SCONN288_ADR50017P087CC-SCONN2A   I175 @S9S_MB_2U_LIB.S9S_MB_2U(SCH_1):PAGE89
    J8  246 VSS107 SCONN288_ADR50017P087CC-SCONN2A   I175 @S9S_MB_2U_LIB.S9S_MB_2U(SCH_1):PAGE89
    J8  248 VSS108 SCONN288_ADR50017P087CC-SCONN2A   I175 @S9S_MB_2U_LIB.S9S_MB_2U(SCH_1):PAGE89
    J8  251 VSS109 SCONN288_ADR50017P087CC-SCONN2A   I175 @S9S_MB_2U_LIB.S9S_MB_2U(SCH_1):PAGE89
    J8  253 VSS110 SCONN288_ADR50017P087CC-SCONN2A   I175 @S9S_MB_2U_LIB.S9S_MB_2U(SCH_1):PAGE89
    J8  255 VSS111 SCONN288_ADR50017P087CC-SCONN2A   I175 @S9S_MB_2U_LIB.S9S_MB_2U(SCH_1):PAGE89
    J8  257 VSS112 SCONN288_ADR50017P087CC-SCONN2A   I175 @S9S_MB_2U_LIB.S9S_MB_2U(SCH_1):PAGE89
    J8  259 VSS113 SCONN288_ADR50017P087CC-SCONN2A   I175 @S9S_MB_2U_LIB.S9S_MB_2U(SCH_1):PAGE89
    J8  262 VSS114 SCONN288_ADR50017P087CC-SCONN2A   I175 @S9S_MB_2U_LIB.S9S_MB_2U(SCH_1):PAGE89
    J8  264 VSS115 SCONN288_ADR50017P087CC-SCONN2A   I175 @S9S_MB_2U_LIB.S9S_MB_2U(SCH_1):PAGE89
    J8  266 VSS116 SCONN288_ADR50017P087CC-SCONN2A   I175 @S9S_MB_2U_LIB.S9S_MB_2U(SCH_1):PAGE89
    J8  268 VSS117 SCONN288_ADR50017P087CC-SCONN2A   I175 @S9S_MB_2U_LIB.S9S_MB_2U(SCH_1):PAGE89
    J8  270 VSS118 SCONN288_ADR50017P087CC-SCONN2A   I175 @S9S_MB_2U_LIB.S9S_MB_2U(SCH_1):PAGE89
    J8  273 VSS119 SCONN288_ADR50017P087CC-SCONN2A   I175 @S9S_MB_2U_LIB.S9S_MB_2U(SCH_1):PAGE89
    J8  275 VSS120 SCONN288_ADR50017P087CC-SCONN2A   I175 @S9S_MB_2U_LIB.S9S_MB_2U(SCH_1):PAGE89
    J8  277 VSS121 SCONN288_ADR50017P087CC-SCONN2A   I175 @S9S_MB_2U_LIB.S9S_MB_2U(SCH_1):PAGE89
    J8  279 VSS122 SCONN288_ADR50017P087CC-SCONN2A   I175 @S9S_MB_2U_LIB.S9S_MB_2U(SCH_1):PAGE89
    J8  281 VSS123 SCONN288_ADR50017P087CC-SCONN2A   I175 @S9S_MB_2U_LIB.S9S_MB_2U(SCH_1):PAGE89
    J8  284 VSS124 SCONN288_ADR50017P087CC-SCONN2A   I175 @S9S_MB_2U_LIB.S9S_MB_2U(SCH_1):PAGE89
    J8  286 VSS125 SCONN288_ADR50017P087CC-SCONN2A   I175 @S9S_MB_2U_LIB.S9S_MB_2U(SCH_1):PAGE89
    J8  288 VSS126 SCONN288_ADR50017P087CC-SCONN2A   I175 @S9S_MB_2U_LIB.S9S_MB_2U(SCH_1):PAGE89
   R34    2      B Q_RES_0402LF-10K,1%,1/16W,CHIPA    I11 @S9S_MB_2U_LIB.S9S_MB_2U(SCH_1):PAGE90
   C26    2      B Q_CAP_C0402-2.2UF,6.3V,20%,X6SA   I122 @S9S_MB_2U_LIB.S9S_MB_2U(SCH_1):PAGE90
   C27    2      B Q_CAP_C0805-10UF,16V,10%,X6S,CA   I123 @S9S_MB_2U_LIB.S9S_MB_2U(SCH_1):PAGE90
   C28    2      B Q_CAP_C0805-10UF,16V,10%,X6S,CA   I145 @S9S_MB_2U_LIB.S9S_MB_2U(SCH_1):PAGE90
    J9   G1     G1 SCONN288_ADR50017P130CC-SCONN2A   I147 @S9S_MB_2U_LIB.S9S_MB_2U(SCH_1):PAGE90
    J9   G2     G2 SCONN288_ADR50017P130CC-SCONN2A   I147 @S9S_MB_2U_LIB.S9S_MB_2U(SCH_1):PAGE90
    J9   G3     G3 SCONN288_ADR50017P130CC-SCONN2A   I147 @S9S_MB_2U_LIB.S9S_MB_2U(SCH_1):PAGE90
    J9    6   VSS0 SCONN288_ADR50017P130CC-SCONN2A   I147 @S9S_MB_2U_LIB.S9S_MB_2U(SCH_1):PAGE90
    J9    8   VSS1 SCONN288_ADR50017P130CC-SCONN2A   I147 @S9S_MB_2U_LIB.S9S_MB_2U(SCH_1):PAGE90
    J9   10   VSS2 SCONN288_ADR50017P130CC-SCONN2A   I147 @S9S_MB_2U_LIB.S9S_MB_2U(SCH_1):PAGE90
    J9   13   VSS3 SCONN288_ADR50017P130CC-SCONN2A   I147 @S9S_MB_2U_LIB.S9S_MB_2U(SCH_1):PAGE90
    J9   15   VSS4 SCONN288_ADR50017P130CC-SCONN2A   I147 @S9S_MB_2U_LIB.S9S_MB_2U(SCH_1):PAGE90
    J9   17   VSS5 SCONN288_ADR50017P130CC-SCONN2A   I147 @S9S_MB_2U_LIB.S9S_MB_2U(SCH_1):PAGE90
    J9   19   VSS6 SCONN288_ADR50017P130CC-SCONN2A   I147 @S9S_MB_2U_LIB.S9S_MB_2U(SCH_1):PAGE90
    J9   21   VSS7 SCONN288_ADR50017P130CC-SCONN2A   I147 @S9S_MB_2U_LIB.S9S_MB_2U(SCH_1):PAGE90
    J9   24   VSS8 SCONN288_ADR50017P130CC-SCONN2A   I147 @S9S_MB_2U_LIB.S9S_MB_2U(SCH_1):PAGE90
    J9   26   VSS9 SCONN288_ADR50017P130CC-SCONN2A   I147 @S9S_MB_2U_LIB.S9S_MB_2U(SCH_1):PAGE90
    J9   28  VSS10 SCONN288_ADR50017P130CC-SCONN2A   I147 @S9S_MB_2U_LIB.S9S_MB_2U(SCH_1):PAGE90
    J9   30  VSS11 SCONN288_ADR50017P130CC-SCONN2A   I147 @S9S_MB_2U_LIB.S9S_MB_2U(SCH_1):PAGE90
    J9   32  VSS12 SCONN288_ADR50017P130CC-SCONN2A   I147 @S9S_MB_2U_LIB.S9S_MB_2U(SCH_1):PAGE90
    J9   35  VSS13 SCONN288_ADR50017P130CC-SCONN2A   I147 @S9S_MB_2U_LIB.S9S_MB_2U(SCH_1):PAGE90
    J9   37  VSS14 SCONN288_ADR50017P130CC-SCONN2A   I147 @S9S_MB_2U_LIB.S9S_MB_2U(SCH_1):PAGE90
    J9   39  VSS15 SCONN288_ADR50017P130CC-SCONN2A   I147 @S9S_MB_2U_LIB.S9S_MB_2U(SCH_1):PAGE90
    J9   41  VSS16 SCONN288_ADR50017P130CC-SCONN2A   I147 @S9S_MB_2U_LIB.S9S_MB_2U(SCH_1):PAGE90
    J9   43  VSS17 SCONN288_ADR50017P130CC-SCONN2A   I147 @S9S_MB_2U_LIB.S9S_MB_2U(SCH_1):PAGE90
    J9   46  VSS18 SCONN288_ADR50017P130CC-SCONN2A   I147 @S9S_MB_2U_LIB.S9S_MB_2U(SCH_1):PAGE90
    J9   48  VSS19 SCONN288_ADR50017P130CC-SCONN2A   I147 @S9S_MB_2U_LIB.S9S_MB_2U(SCH_1):PAGE90
    J9   50  VSS20 SCONN288_ADR50017P130CC-SCONN2A   I147 @S9S_MB_2U_LIB.S9S_MB_2U(SCH_1):PAGE90
    J9   52  VSS21 SCONN288_ADR50017P130CC-SCONN2A   I147 @S9S_MB_2U_LIB.S9S_MB_2U(SCH_1):PAGE90
    J9   54  VSS22 SCONN288_ADR50017P130CC-SCONN2A   I147 @S9S_MB_2U_LIB.S9S_MB_2U(SCH_1):PAGE90
    J9   57  VSS23 SCONN288_ADR50017P130CC-SCONN2A   I147 @S9S_MB_2U_LIB.S9S_MB_2U(SCH_1):PAGE90
    J9   59  VSS24 SCONN288_ADR50017P130CC-SCONN2A   I147 @S9S_MB_2U_LIB.S9S_MB_2U(SCH_1):PAGE90
    J9   61  VSS25 SCONN288_ADR50017P130CC-SCONN2A   I147 @S9S_MB_2U_LIB.S9S_MB_2U(SCH_1):PAGE90
    J9   63  VSS26 SCONN288_ADR50017P130CC-SCONN2A   I147 @S9S_MB_2U_LIB.S9S_MB_2U(SCH_1):PAGE90
    J9   65  VSS27 SCONN288_ADR50017P130CC-SCONN2A   I147 @S9S_MB_2U_LIB.S9S_MB_2U(SCH_1):PAGE90
    J9   67  VSS28 SCONN288_ADR50017P130CC-SCONN2A   I147 @S9S_MB_2U_LIB.S9S_MB_2U(SCH_1):PAGE90
    J9   69  VSS29 SCONN288_ADR50017P130CC-SCONN2A   I147 @S9S_MB_2U_LIB.S9S_MB_2U(SCH_1):PAGE90
    J9   71  VSS30 SCONN288_ADR50017P130CC-SCONN2A   I147 @S9S_MB_2U_LIB.S9S_MB_2U(SCH_1):PAGE90
    J9   73  VSS31 SCONN288_ADR50017P130CC-SCONN2A   I147 @S9S_MB_2U_LIB.S9S_MB_2U(SCH_1):PAGE90
    J9   75  VSS32 SCONN288_ADR50017P130CC-SCONN2A   I147 @S9S_MB_2U_LIB.S9S_MB_2U(SCH_1):PAGE90
    J9   77  VSS33 SCONN288_ADR50017P130CC-SCONN2A   I147 @S9S_MB_2U_LIB.S9S_MB_2U(SCH_1):PAGE90
    J9   79  VSS34 SCONN288_ADR50017P130CC-SCONN2A   I147 @S9S_MB_2U_LIB.S9S_MB_2U(SCH_1):PAGE90
    J9   81  VSS35 SCONN288_ADR50017P130CC-SCONN2A   I147 @S9S_MB_2U_LIB.S9S_MB_2U(SCH_1):PAGE90
    J9   83  VSS36 SCONN288_ADR50017P130CC-SCONN2A   I147 @S9S_MB_2U_LIB.S9S_MB_2U(SCH_1):PAGE90
    J9   85  VSS37 SCONN288_ADR50017P130CC-SCONN2A   I147 @S9S_MB_2U_LIB.S9S_MB_2U(SCH_1):PAGE90
    J9   88  VSS38 SCONN288_ADR50017P130CC-SCONN2A   I147 @S9S_MB_2U_LIB.S9S_MB_2U(SCH_1):PAGE90
    J9   90  VSS39 SCONN288_ADR50017P130CC-SCONN2A   I147 @S9S_MB_2U_LIB.S9S_MB_2U(SCH_1):PAGE90
    J9   92  VSS40 SCONN288_ADR50017P130CC-SCONN2A   I147 @S9S_MB_2U_LIB.S9S_MB_2U(SCH_1):PAGE90
    J9   95  VSS41 SCONN288_ADR50017P130CC-SCONN2A   I147 @S9S_MB_2U_LIB.S9S_MB_2U(SCH_1):PAGE90
    J9   97  VSS42 SCONN288_ADR50017P130CC-SCONN2A   I147 @S9S_MB_2U_LIB.S9S_MB_2U(SCH_1):PAGE90
    J9   99  VSS43 SCONN288_ADR50017P130CC-SCONN2A   I147 @S9S_MB_2U_LIB.S9S_MB_2U(SCH_1):PAGE90
    J9  101  VSS44 SCONN288_ADR50017P130CC-SCONN2A   I147 @S9S_MB_2U_LIB.S9S_MB_2U(SCH_1):PAGE90
    J9  103  VSS45 SCONN288_ADR50017P130CC-SCONN2A   I147 @S9S_MB_2U_LIB.S9S_MB_2U(SCH_1):PAGE90
    J9  106  VSS46 SCONN288_ADR50017P130CC-SCONN2A   I147 @S9S_MB_2U_LIB.S9S_MB_2U(SCH_1):PAGE90
    J9  108  VSS47 SCONN288_ADR50017P130CC-SCONN2A   I147 @S9S_MB_2U_LIB.S9S_MB_2U(SCH_1):PAGE90
    J9  110  VSS48 SCONN288_ADR50017P130CC-SCONN2A   I147 @S9S_MB_2U_LIB.S9S_MB_2U(SCH_1):PAGE90
    J9  112  VSS49 SCONN288_ADR50017P130CC-SCONN2A   I147 @S9S_MB_2U_LIB.S9S_MB_2U(SCH_1):PAGE90
    J9  114  VSS50 SCONN288_ADR50017P130CC-SCONN2A   I147 @S9S_MB_2U_LIB.S9S_MB_2U(SCH_1):PAGE90
    J9  117  VSS51 SCONN288_ADR50017P130CC-SCONN2A   I147 @S9S_MB_2U_LIB.S9S_MB_2U(SCH_1):PAGE90
    J9  119  VSS52 SCONN288_ADR50017P130CC-SCONN2A   I147 @S9S_MB_2U_LIB.S9S_MB_2U(SCH_1):PAGE90
    J9  121  VSS53 SCONN288_ADR50017P130CC-SCONN2A   I147 @S9S_MB_2U_LIB.S9S_MB_2U(SCH_1):PAGE90
    J9  123  VSS54 SCONN288_ADR50017P130CC-SCONN2A   I147 @S9S_MB_2U_LIB.S9S_MB_2U(SCH_1):PAGE90
    J9  125  VSS55 SCONN288_ADR50017P130CC-SCONN2A   I147 @S9S_MB_2U_LIB.S9S_MB_2U(SCH_1):PAGE90
    J9  128  VSS56 SCONN288_ADR50017P130CC-SCONN2A   I147 @S9S_MB_2U_LIB.S9S_MB_2U(SCH_1):PAGE90
    J9  130  VSS57 SCONN288_ADR50017P130CC-SCONN2A   I147 @S9S_MB_2U_LIB.S9S_MB_2U(SCH_1):PAGE90
    J9  132  VSS58 SCONN288_ADR50017P130CC-SCONN2A   I147 @S9S_MB_2U_LIB.S9S_MB_2U(SCH_1):PAGE90
    J9  134  VSS59 SCONN288_ADR50017P130CC-SCONN2A   I147 @S9S_MB_2U_LIB.S9S_MB_2U(SCH_1):PAGE90
    J9  136  VSS60 SCONN288_ADR50017P130CC-SCONN2A   I147 @S9S_MB_2U_LIB.S9S_MB_2U(SCH_1):PAGE90
    J9  139  VSS61 SCONN288_ADR50017P130CC-SCONN2A   I147 @S9S_MB_2U_LIB.S9S_MB_2U(SCH_1):PAGE90
    J9  141  VSS62 SCONN288_ADR50017P130CC-SCONN2A   I147 @S9S_MB_2U_LIB.S9S_MB_2U(SCH_1):PAGE90
    J9  143  VSS63 SCONN288_ADR50017P130CC-SCONN2A   I147 @S9S_MB_2U_LIB.S9S_MB_2U(SCH_1):PAGE90
    J9  151  VSS64 SCONN288_ADR50017P130CC-SCONN2A   I147 @S9S_MB_2U_LIB.S9S_MB_2U(SCH_1):PAGE90
    J9  153  VSS65 SCONN288_ADR50017P130CC-SCONN2A   I147 @S9S_MB_2U_LIB.S9S_MB_2U(SCH_1):PAGE90
    J9  155  VSS66 SCONN288_ADR50017P130CC-SCONN2A   I147 @S9S_MB_2U_LIB.S9S_MB_2U(SCH_1):PAGE90
    J9  158  VSS67 SCONN288_ADR50017P130CC-SCONN2A   I147 @S9S_MB_2U_LIB.S9S_MB_2U(SCH_1):PAGE90
    J9  160  VSS68 SCONN288_ADR50017P130CC-SCONN2A   I147 @S9S_MB_2U_LIB.S9S_MB_2U(SCH_1):PAGE90
    J9  162  VSS69 SCONN288_ADR50017P130CC-SCONN2A   I147 @S9S_MB_2U_LIB.S9S_MB_2U(SCH_1):PAGE90
    J9  164  VSS70 SCONN288_ADR50017P130CC-SCONN2A   I147 @S9S_MB_2U_LIB.S9S_MB_2U(SCH_1):PAGE90
    J9  166  VSS71 SCONN288_ADR50017P130CC-SCONN2A   I147 @S9S_MB_2U_LIB.S9S_MB_2U(SCH_1):PAGE90
    J9  169  VSS72 SCONN288_ADR50017P130CC-SCONN2A   I147 @S9S_MB_2U_LIB.S9S_MB_2U(SCH_1):PAGE90
    J9  171  VSS73 SCONN288_ADR50017P130CC-SCONN2A   I147 @S9S_MB_2U_LIB.S9S_MB_2U(SCH_1):PAGE90
    J9  173  VSS74 SCONN288_ADR50017P130CC-SCONN2A   I147 @S9S_MB_2U_LIB.S9S_MB_2U(SCH_1):PAGE90
    J9  175  VSS75 SCONN288_ADR50017P130CC-SCONN2A   I147 @S9S_MB_2U_LIB.S9S_MB_2U(SCH_1):PAGE90
    J9  177  VSS76 SCONN288_ADR50017P130CC-SCONN2A   I147 @S9S_MB_2U_LIB.S9S_MB_2U(SCH_1):PAGE90
    J9  180  VSS77 SCONN288_ADR50017P130CC-SCONN2A   I147 @S9S_MB_2U_LIB.S9S_MB_2U(SCH_1):PAGE90
    J9  182  VSS78 SCONN288_ADR50017P130CC-SCONN2A   I147 @S9S_MB_2U_LIB.S9S_MB_2U(SCH_1):PAGE90
    J9  184  VSS79 SCONN288_ADR50017P130CC-SCONN2A   I147 @S9S_MB_2U_LIB.S9S_MB_2U(SCH_1):PAGE90
    J9  186  VSS80 SCONN288_ADR50017P130CC-SCONN2A   I147 @S9S_MB_2U_LIB.S9S_MB_2U(SCH_1):PAGE90
    J9  188  VSS81 SCONN288_ADR50017P130CC-SCONN2A   I147 @S9S_MB_2U_LIB.S9S_MB_2U(SCH_1):PAGE90
    J9  191  VSS82 SCONN288_ADR50017P130CC-SCONN2A   I147 @S9S_MB_2U_LIB.S9S_MB_2U(SCH_1):PAGE90
    J9  193  VSS83 SCONN288_ADR50017P130CC-SCONN2A   I147 @S9S_MB_2U_LIB.S9S_MB_2U(SCH_1):PAGE90
    J9  195  VSS84 SCONN288_ADR50017P130CC-SCONN2A   I147 @S9S_MB_2U_LIB.S9S_MB_2U(SCH_1):PAGE90
    J9  197  VSS85 SCONN288_ADR50017P130CC-SCONN2A   I147 @S9S_MB_2U_LIB.S9S_MB_2U(SCH_1):PAGE90
    J9  199  VSS86 SCONN288_ADR50017P130CC-SCONN2A   I147 @S9S_MB_2U_LIB.S9S_MB_2U(SCH_1):PAGE90
    J9  202  VSS87 SCONN288_ADR50017P130CC-SCONN2A   I147 @S9S_MB_2U_LIB.S9S_MB_2U(SCH_1):PAGE90
    J9  204  VSS88 SCONN288_ADR50017P130CC-SCONN2A   I147 @S9S_MB_2U_LIB.S9S_MB_2U(SCH_1):PAGE90
    J9  206  VSS89 SCONN288_ADR50017P130CC-SCONN2A   I147 @S9S_MB_2U_LIB.S9S_MB_2U(SCH_1):PAGE90
    J9  208  VSS90 SCONN288_ADR50017P130CC-SCONN2A   I147 @S9S_MB_2U_LIB.S9S_MB_2U(SCH_1):PAGE90
    J9  210  VSS91 SCONN288_ADR50017P130CC-SCONN2A   I147 @S9S_MB_2U_LIB.S9S_MB_2U(SCH_1):PAGE90
    J9  212  VSS92 SCONN288_ADR50017P130CC-SCONN2A   I147 @S9S_MB_2U_LIB.S9S_MB_2U(SCH_1):PAGE90
    J9  214  VSS93 SCONN288_ADR50017P130CC-SCONN2A   I147 @S9S_MB_2U_LIB.S9S_MB_2U(SCH_1):PAGE90
    J9  216  VSS94 SCONN288_ADR50017P130CC-SCONN2A   I147 @S9S_MB_2U_LIB.S9S_MB_2U(SCH_1):PAGE90
    J9  219  VSS95 SCONN288_ADR50017P130CC-SCONN2A   I147 @S9S_MB_2U_LIB.S9S_MB_2U(SCH_1):PAGE90
    J9  222  VSS96 SCONN288_ADR50017P130CC-SCONN2A   I147 @S9S_MB_2U_LIB.S9S_MB_2U(SCH_1):PAGE90
    J9  224  VSS97 SCONN288_ADR50017P130CC-SCONN2A   I147 @S9S_MB_2U_LIB.S9S_MB_2U(SCH_1):PAGE90
    J9  226  VSS98 SCONN288_ADR50017P130CC-SCONN2A   I147 @S9S_MB_2U_LIB.S9S_MB_2U(SCH_1):PAGE90
    J9  228  VSS99 SCONN288_ADR50017P130CC-SCONN2A   I147 @S9S_MB_2U_LIB.S9S_MB_2U(SCH_1):PAGE90
    J9  230 VSS100 SCONN288_ADR50017P130CC-SCONN2A   I147 @S9S_MB_2U_LIB.S9S_MB_2U(SCH_1):PAGE90
    J9  233 VSS101 SCONN288_ADR50017P130CC-SCONN2A   I147 @S9S_MB_2U_LIB.S9S_MB_2U(SCH_1):PAGE90
    J9  235 VSS102 SCONN288_ADR50017P130CC-SCONN2A   I147 @S9S_MB_2U_LIB.S9S_MB_2U(SCH_1):PAGE90
    J9  237 VSS103 SCONN288_ADR50017P130CC-SCONN2A   I147 @S9S_MB_2U_LIB.S9S_MB_2U(SCH_1):PAGE90
    J9  240 VSS104 SCONN288_ADR50017P130CC-SCONN2A   I147 @S9S_MB_2U_LIB.S9S_MB_2U(SCH_1):PAGE90
    J9  242 VSS105 SCONN288_ADR50017P130CC-SCONN2A   I147 @S9S_MB_2U_LIB.S9S_MB_2U(SCH_1):PAGE90
    J9  244 VSS106 SCONN288_ADR50017P130CC-SCONN2A   I147 @S9S_MB_2U_LIB.S9S_MB_2U(SCH_1):PAGE90
    J9  246 VSS107 SCONN288_ADR50017P130CC-SCONN2A   I147 @S9S_MB_2U_LIB.S9S_MB_2U(SCH_1):PAGE90
    J9  248 VSS108 SCONN288_ADR50017P130CC-SCONN2A   I147 @S9S_MB_2U_LIB.S9S_MB_2U(SCH_1):PAGE90
    J9  251 VSS109 SCONN288_ADR50017P130CC-SCONN2A   I147 @S9S_MB_2U_LIB.S9S_MB_2U(SCH_1):PAGE90
    J9  253 VSS110 SCONN288_ADR50017P130CC-SCONN2A   I147 @S9S_MB_2U_LIB.S9S_MB_2U(SCH_1):PAGE90
    J9  255 VSS111 SCONN288_ADR50017P130CC-SCONN2A   I147 @S9S_MB_2U_LIB.S9S_MB_2U(SCH_1):PAGE90
    J9  257 VSS112 SCONN288_ADR50017P130CC-SCONN2A   I147 @S9S_MB_2U_LIB.S9S_MB_2U(SCH_1):PAGE90
    J9  259 VSS113 SCONN288_ADR50017P130CC-SCONN2A   I147 @S9S_MB_2U_LIB.S9S_MB_2U(SCH_1):PAGE90
    J9  262 VSS114 SCONN288_ADR50017P130CC-SCONN2A   I147 @S9S_MB_2U_LIB.S9S_MB_2U(SCH_1):PAGE90
    J9  264 VSS115 SCONN288_ADR50017P130CC-SCONN2A   I147 @S9S_MB_2U_LIB.S9S_MB_2U(SCH_1):PAGE90
    J9  266 VSS116 SCONN288_ADR50017P130CC-SCONN2A   I147 @S9S_MB_2U_LIB.S9S_MB_2U(SCH_1):PAGE90
    J9  268 VSS117 SCONN288_ADR50017P130CC-SCONN2A   I147 @S9S_MB_2U_LIB.S9S_MB_2U(SCH_1):PAGE90
    J9  270 VSS118 SCONN288_ADR50017P130CC-SCONN2A   I147 @S9S_MB_2U_LIB.S9S_MB_2U(SCH_1):PAGE90
    J9  273 VSS119 SCONN288_ADR50017P130CC-SCONN2A   I147 @S9S_MB_2U_LIB.S9S_MB_2U(SCH_1):PAGE90
    J9  275 VSS120 SCONN288_ADR50017P130CC-SCONN2A   I147 @S9S_MB_2U_LIB.S9S_MB_2U(SCH_1):PAGE90
    J9  277 VSS121 SCONN288_ADR50017P130CC-SCONN2A   I147 @S9S_MB_2U_LIB.S9S_MB_2U(SCH_1):PAGE90
    J9  279 VSS122 SCONN288_ADR50017P130CC-SCONN2A   I147 @S9S_MB_2U_LIB.S9S_MB_2U(SCH_1):PAGE90
    J9  281 VSS123 SCONN288_ADR50017P130CC-SCONN2A   I147 @S9S_MB_2U_LIB.S9S_MB_2U(SCH_1):PAGE90
    J9  284 VSS124 SCONN288_ADR50017P130CC-SCONN2A   I147 @S9S_MB_2U_LIB.S9S_MB_2U(SCH_1):PAGE90
    J9  286 VSS125 SCONN288_ADR50017P130CC-SCONN2A   I147 @S9S_MB_2U_LIB.S9S_MB_2U(SCH_1):PAGE90
    J9  288 VSS126 SCONN288_ADR50017P130CC-SCONN2A   I147 @S9S_MB_2U_LIB.S9S_MB_2U(SCH_1):PAGE90
   R35    2      B Q_RES_0402LF-15.4K,1%,1/16W,CHA     I2 @S9S_MB_2U_LIB.S9S_MB_2U(SCH_1):PAGE91
   C29    2      B Q_CAP_C0402-2.2UF,6.3V,20%,X6SA   I123 @S9S_MB_2U_LIB.S9S_MB_2U(SCH_1):PAGE91
   C30    2      B Q_CAP_C0805-10UF,16V,10%,X6S,CA   I124 @S9S_MB_2U_LIB.S9S_MB_2U(SCH_1):PAGE91
   C31    2      B Q_CAP_C0805-10UF,16V,10%,X6S,CA   I146 @S9S_MB_2U_LIB.S9S_MB_2U(SCH_1):PAGE91
   J10   G1     G1 SCONN288_ADR50017P087CC-SCONN2A   I148 @S9S_MB_2U_LIB.S9S_MB_2U(SCH_1):PAGE91
   J10   G2     G2 SCONN288_ADR50017P087CC-SCONN2A   I148 @S9S_MB_2U_LIB.S9S_MB_2U(SCH_1):PAGE91
   J10   G3     G3 SCONN288_ADR50017P087CC-SCONN2A   I148 @S9S_MB_2U_LIB.S9S_MB_2U(SCH_1):PAGE91
   J10    6   VSS0 SCONN288_ADR50017P087CC-SCONN2A   I148 @S9S_MB_2U_LIB.S9S_MB_2U(SCH_1):PAGE91
   J10    8   VSS1 SCONN288_ADR50017P087CC-SCONN2A   I148 @S9S_MB_2U_LIB.S9S_MB_2U(SCH_1):PAGE91
   J10   10   VSS2 SCONN288_ADR50017P087CC-SCONN2A   I148 @S9S_MB_2U_LIB.S9S_MB_2U(SCH_1):PAGE91
   J10   13   VSS3 SCONN288_ADR50017P087CC-SCONN2A   I148 @S9S_MB_2U_LIB.S9S_MB_2U(SCH_1):PAGE91
   J10   15   VSS4 SCONN288_ADR50017P087CC-SCONN2A   I148 @S9S_MB_2U_LIB.S9S_MB_2U(SCH_1):PAGE91
   J10   17   VSS5 SCONN288_ADR50017P087CC-SCONN2A   I148 @S9S_MB_2U_LIB.S9S_MB_2U(SCH_1):PAGE91
   J10   19   VSS6 SCONN288_ADR50017P087CC-SCONN2A   I148 @S9S_MB_2U_LIB.S9S_MB_2U(SCH_1):PAGE91
   J10   21   VSS7 SCONN288_ADR50017P087CC-SCONN2A   I148 @S9S_MB_2U_LIB.S9S_MB_2U(SCH_1):PAGE91
   J10   24   VSS8 SCONN288_ADR50017P087CC-SCONN2A   I148 @S9S_MB_2U_LIB.S9S_MB_2U(SCH_1):PAGE91
   J10   26   VSS9 SCONN288_ADR50017P087CC-SCONN2A   I148 @S9S_MB_2U_LIB.S9S_MB_2U(SCH_1):PAGE91
   J10   28  VSS10 SCONN288_ADR50017P087CC-SCONN2A   I148 @S9S_MB_2U_LIB.S9S_MB_2U(SCH_1):PAGE91
   J10   30  VSS11 SCONN288_ADR50017P087CC-SCONN2A   I148 @S9S_MB_2U_LIB.S9S_MB_2U(SCH_1):PAGE91
   J10   32  VSS12 SCONN288_ADR50017P087CC-SCONN2A   I148 @S9S_MB_2U_LIB.S9S_MB_2U(SCH_1):PAGE91
   J10   35  VSS13 SCONN288_ADR50017P087CC-SCONN2A   I148 @S9S_MB_2U_LIB.S9S_MB_2U(SCH_1):PAGE91
   J10   37  VSS14 SCONN288_ADR50017P087CC-SCONN2A   I148 @S9S_MB_2U_LIB.S9S_MB_2U(SCH_1):PAGE91
   J10   39  VSS15 SCONN288_ADR50017P087CC-SCONN2A   I148 @S9S_MB_2U_LIB.S9S_MB_2U(SCH_1):PAGE91
   J10   41  VSS16 SCONN288_ADR50017P087CC-SCONN2A   I148 @S9S_MB_2U_LIB.S9S_MB_2U(SCH_1):PAGE91
   J10   43  VSS17 SCONN288_ADR50017P087CC-SCONN2A   I148 @S9S_MB_2U_LIB.S9S_MB_2U(SCH_1):PAGE91
   J10   46  VSS18 SCONN288_ADR50017P087CC-SCONN2A   I148 @S9S_MB_2U_LIB.S9S_MB_2U(SCH_1):PAGE91
   J10   48  VSS19 SCONN288_ADR50017P087CC-SCONN2A   I148 @S9S_MB_2U_LIB.S9S_MB_2U(SCH_1):PAGE91
   J10   50  VSS20 SCONN288_ADR50017P087CC-SCONN2A   I148 @S9S_MB_2U_LIB.S9S_MB_2U(SCH_1):PAGE91
   J10   52  VSS21 SCONN288_ADR50017P087CC-SCONN2A   I148 @S9S_MB_2U_LIB.S9S_MB_2U(SCH_1):PAGE91
   J10   54  VSS22 SCONN288_ADR50017P087CC-SCONN2A   I148 @S9S_MB_2U_LIB.S9S_MB_2U(SCH_1):PAGE91
   J10   57  VSS23 SCONN288_ADR50017P087CC-SCONN2A   I148 @S9S_MB_2U_LIB.S9S_MB_2U(SCH_1):PAGE91
   J10   59  VSS24 SCONN288_ADR50017P087CC-SCONN2A   I148 @S9S_MB_2U_LIB.S9S_MB_2U(SCH_1):PAGE91
   J10   61  VSS25 SCONN288_ADR50017P087CC-SCONN2A   I148 @S9S_MB_2U_LIB.S9S_MB_2U(SCH_1):PAGE91
   J10   63  VSS26 SCONN288_ADR50017P087CC-SCONN2A   I148 @S9S_MB_2U_LIB.S9S_MB_2U(SCH_1):PAGE91
   J10   65  VSS27 SCONN288_ADR50017P087CC-SCONN2A   I148 @S9S_MB_2U_LIB.S9S_MB_2U(SCH_1):PAGE91
   J10   67  VSS28 SCONN288_ADR50017P087CC-SCONN2A   I148 @S9S_MB_2U_LIB.S9S_MB_2U(SCH_1):PAGE91
   J10   69  VSS29 SCONN288_ADR50017P087CC-SCONN2A   I148 @S9S_MB_2U_LIB.S9S_MB_2U(SCH_1):PAGE91
   J10   71  VSS30 SCONN288_ADR50017P087CC-SCONN2A   I148 @S9S_MB_2U_LIB.S9S_MB_2U(SCH_1):PAGE91
   J10   73  VSS31 SCONN288_ADR50017P087CC-SCONN2A   I148 @S9S_MB_2U_LIB.S9S_MB_2U(SCH_1):PAGE91
   J10   75  VSS32 SCONN288_ADR50017P087CC-SCONN2A   I148 @S9S_MB_2U_LIB.S9S_MB_2U(SCH_1):PAGE91
   J10   77  VSS33 SCONN288_ADR50017P087CC-SCONN2A   I148 @S9S_MB_2U_LIB.S9S_MB_2U(SCH_1):PAGE91
   J10   79  VSS34 SCONN288_ADR50017P087CC-SCONN2A   I148 @S9S_MB_2U_LIB.S9S_MB_2U(SCH_1):PAGE91
   J10   81  VSS35 SCONN288_ADR50017P087CC-SCONN2A   I148 @S9S_MB_2U_LIB.S9S_MB_2U(SCH_1):PAGE91
   J10   83  VSS36 SCONN288_ADR50017P087CC-SCONN2A   I148 @S9S_MB_2U_LIB.S9S_MB_2U(SCH_1):PAGE91
   J10   85  VSS37 SCONN288_ADR50017P087CC-SCONN2A   I148 @S9S_MB_2U_LIB.S9S_MB_2U(SCH_1):PAGE91
   J10   88  VSS38 SCONN288_ADR50017P087CC-SCONN2A   I148 @S9S_MB_2U_LIB.S9S_MB_2U(SCH_1):PAGE91
   J10   90  VSS39 SCONN288_ADR50017P087CC-SCONN2A   I148 @S9S_MB_2U_LIB.S9S_MB_2U(SCH_1):PAGE91
   J10   92  VSS40 SCONN288_ADR50017P087CC-SCONN2A   I148 @S9S_MB_2U_LIB.S9S_MB_2U(SCH_1):PAGE91
   J10   95  VSS41 SCONN288_ADR50017P087CC-SCONN2A   I148 @S9S_MB_2U_LIB.S9S_MB_2U(SCH_1):PAGE91
   J10   97  VSS42 SCONN288_ADR50017P087CC-SCONN2A   I148 @S9S_MB_2U_LIB.S9S_MB_2U(SCH_1):PAGE91
   J10   99  VSS43 SCONN288_ADR50017P087CC-SCONN2A   I148 @S9S_MB_2U_LIB.S9S_MB_2U(SCH_1):PAGE91
   J10  101  VSS44 SCONN288_ADR50017P087CC-SCONN2A   I148 @S9S_MB_2U_LIB.S9S_MB_2U(SCH_1):PAGE91
   J10  103  VSS45 SCONN288_ADR50017P087CC-SCONN2A   I148 @S9S_MB_2U_LIB.S9S_MB_2U(SCH_1):PAGE91
   J10  106  VSS46 SCONN288_ADR50017P087CC-SCONN2A   I148 @S9S_MB_2U_LIB.S9S_MB_2U(SCH_1):PAGE91
   J10  108  VSS47 SCONN288_ADR50017P087CC-SCONN2A   I148 @S9S_MB_2U_LIB.S9S_MB_2U(SCH_1):PAGE91
   J10  110  VSS48 SCONN288_ADR50017P087CC-SCONN2A   I148 @S9S_MB_2U_LIB.S9S_MB_2U(SCH_1):PAGE91
   J10  112  VSS49 SCONN288_ADR50017P087CC-SCONN2A   I148 @S9S_MB_2U_LIB.S9S_MB_2U(SCH_1):PAGE91
   J10  114  VSS50 SCONN288_ADR50017P087CC-SCONN2A   I148 @S9S_MB_2U_LIB.S9S_MB_2U(SCH_1):PAGE91
   J10  117  VSS51 SCONN288_ADR50017P087CC-SCONN2A   I148 @S9S_MB_2U_LIB.S9S_MB_2U(SCH_1):PAGE91
   J10  119  VSS52 SCONN288_ADR50017P087CC-SCONN2A   I148 @S9S_MB_2U_LIB.S9S_MB_2U(SCH_1):PAGE91
   J10  121  VSS53 SCONN288_ADR50017P087CC-SCONN2A   I148 @S9S_MB_2U_LIB.S9S_MB_2U(SCH_1):PAGE91
   J10  123  VSS54 SCONN288_ADR50017P087CC-SCONN2A   I148 @S9S_MB_2U_LIB.S9S_MB_2U(SCH_1):PAGE91
   J10  125  VSS55 SCONN288_ADR50017P087CC-SCONN2A   I148 @S9S_MB_2U_LIB.S9S_MB_2U(SCH_1):PAGE91
   J10  128  VSS56 SCONN288_ADR50017P087CC-SCONN2A   I148 @S9S_MB_2U_LIB.S9S_MB_2U(SCH_1):PAGE91
   J10  130  VSS57 SCONN288_ADR50017P087CC-SCONN2A   I148 @S9S_MB_2U_LIB.S9S_MB_2U(SCH_1):PAGE91
   J10  132  VSS58 SCONN288_ADR50017P087CC-SCONN2A   I148 @S9S_MB_2U_LIB.S9S_MB_2U(SCH_1):PAGE91
   J10  134  VSS59 SCONN288_ADR50017P087CC-SCONN2A   I148 @S9S_MB_2U_LIB.S9S_MB_2U(SCH_1):PAGE91
   J10  136  VSS60 SCONN288_ADR50017P087CC-SCONN2A   I148 @S9S_MB_2U_LIB.S9S_MB_2U(SCH_1):PAGE91
   J10  139  VSS61 SCONN288_ADR50017P087CC-SCONN2A   I148 @S9S_MB_2U_LIB.S9S_MB_2U(SCH_1):PAGE91
   J10  141  VSS62 SCONN288_ADR50017P087CC-SCONN2A   I148 @S9S_MB_2U_LIB.S9S_MB_2U(SCH_1):PAGE91
   J10  143  VSS63 SCONN288_ADR50017P087CC-SCONN2A   I148 @S9S_MB_2U_LIB.S9S_MB_2U(SCH_1):PAGE91
   J10  151  VSS64 SCONN288_ADR50017P087CC-SCONN2A   I148 @S9S_MB_2U_LIB.S9S_MB_2U(SCH_1):PAGE91
   J10  153  VSS65 SCONN288_ADR50017P087CC-SCONN2A   I148 @S9S_MB_2U_LIB.S9S_MB_2U(SCH_1):PAGE91
   J10  155  VSS66 SCONN288_ADR50017P087CC-SCONN2A   I148 @S9S_MB_2U_LIB.S9S_MB_2U(SCH_1):PAGE91
   J10  158  VSS67 SCONN288_ADR50017P087CC-SCONN2A   I148 @S9S_MB_2U_LIB.S9S_MB_2U(SCH_1):PAGE91
   J10  160  VSS68 SCONN288_ADR50017P087CC-SCONN2A   I148 @S9S_MB_2U_LIB.S9S_MB_2U(SCH_1):PAGE91
   J10  162  VSS69 SCONN288_ADR50017P087CC-SCONN2A   I148 @S9S_MB_2U_LIB.S9S_MB_2U(SCH_1):PAGE91
   J10  164  VSS70 SCONN288_ADR50017P087CC-SCONN2A   I148 @S9S_MB_2U_LIB.S9S_MB_2U(SCH_1):PAGE91
   J10  166  VSS71 SCONN288_ADR50017P087CC-SCONN2A   I148 @S9S_MB_2U_LIB.S9S_MB_2U(SCH_1):PAGE91
   J10  169  VSS72 SCONN288_ADR50017P087CC-SCONN2A   I148 @S9S_MB_2U_LIB.S9S_MB_2U(SCH_1):PAGE91
   J10  171  VSS73 SCONN288_ADR50017P087CC-SCONN2A   I148 @S9S_MB_2U_LIB.S9S_MB_2U(SCH_1):PAGE91
   J10  173  VSS74 SCONN288_ADR50017P087CC-SCONN2A   I148 @S9S_MB_2U_LIB.S9S_MB_2U(SCH_1):PAGE91
   J10  175  VSS75 SCONN288_ADR50017P087CC-SCONN2A   I148 @S9S_MB_2U_LIB.S9S_MB_2U(SCH_1):PAGE91
   J10  177  VSS76 SCONN288_ADR50017P087CC-SCONN2A   I148 @S9S_MB_2U_LIB.S9S_MB_2U(SCH_1):PAGE91
   J10  180  VSS77 SCONN288_ADR50017P087CC-SCONN2A   I148 @S9S_MB_2U_LIB.S9S_MB_2U(SCH_1):PAGE91
   J10  182  VSS78 SCONN288_ADR50017P087CC-SCONN2A   I148 @S9S_MB_2U_LIB.S9S_MB_2U(SCH_1):PAGE91
   J10  184  VSS79 SCONN288_ADR50017P087CC-SCONN2A   I148 @S9S_MB_2U_LIB.S9S_MB_2U(SCH_1):PAGE91
   J10  186  VSS80 SCONN288_ADR50017P087CC-SCONN2A   I148 @S9S_MB_2U_LIB.S9S_MB_2U(SCH_1):PAGE91
   J10  188  VSS81 SCONN288_ADR50017P087CC-SCONN2A   I148 @S9S_MB_2U_LIB.S9S_MB_2U(SCH_1):PAGE91
   J10  191  VSS82 SCONN288_ADR50017P087CC-SCONN2A   I148 @S9S_MB_2U_LIB.S9S_MB_2U(SCH_1):PAGE91
   J10  193  VSS83 SCONN288_ADR50017P087CC-SCONN2A   I148 @S9S_MB_2U_LIB.S9S_MB_2U(SCH_1):PAGE91
   J10  195  VSS84 SCONN288_ADR50017P087CC-SCONN2A   I148 @S9S_MB_2U_LIB.S9S_MB_2U(SCH_1):PAGE91
   J10  197  VSS85 SCONN288_ADR50017P087CC-SCONN2A   I148 @S9S_MB_2U_LIB.S9S_MB_2U(SCH_1):PAGE91
   J10  199  VSS86 SCONN288_ADR50017P087CC-SCONN2A   I148 @S9S_MB_2U_LIB.S9S_MB_2U(SCH_1):PAGE91
   J10  202  VSS87 SCONN288_ADR50017P087CC-SCONN2A   I148 @S9S_MB_2U_LIB.S9S_MB_2U(SCH_1):PAGE91
   J10  204  VSS88 SCONN288_ADR50017P087CC-SCONN2A   I148 @S9S_MB_2U_LIB.S9S_MB_2U(SCH_1):PAGE91
   J10  206  VSS89 SCONN288_ADR50017P087CC-SCONN2A   I148 @S9S_MB_2U_LIB.S9S_MB_2U(SCH_1):PAGE91
   J10  208  VSS90 SCONN288_ADR50017P087CC-SCONN2A   I148 @S9S_MB_2U_LIB.S9S_MB_2U(SCH_1):PAGE91
   J10  210  VSS91 SCONN288_ADR50017P087CC-SCONN2A   I148 @S9S_MB_2U_LIB.S9S_MB_2U(SCH_1):PAGE91
   J10  212  VSS92 SCONN288_ADR50017P087CC-SCONN2A   I148 @S9S_MB_2U_LIB.S9S_MB_2U(SCH_1):PAGE91
   J10  214  VSS93 SCONN288_ADR50017P087CC-SCONN2A   I148 @S9S_MB_2U_LIB.S9S_MB_2U(SCH_1):PAGE91
   J10  216  VSS94 SCONN288_ADR50017P087CC-SCONN2A   I148 @S9S_MB_2U_LIB.S9S_MB_2U(SCH_1):PAGE91
   J10  219  VSS95 SCONN288_ADR50017P087CC-SCONN2A   I148 @S9S_MB_2U_LIB.S9S_MB_2U(SCH_1):PAGE91
   J10  222  VSS96 SCONN288_ADR50017P087CC-SCONN2A   I148 @S9S_MB_2U_LIB.S9S_MB_2U(SCH_1):PAGE91
   J10  224  VSS97 SCONN288_ADR50017P087CC-SCONN2A   I148 @S9S_MB_2U_LIB.S9S_MB_2U(SCH_1):PAGE91
   J10  226  VSS98 SCONN288_ADR50017P087CC-SCONN2A   I148 @S9S_MB_2U_LIB.S9S_MB_2U(SCH_1):PAGE91
   J10  228  VSS99 SCONN288_ADR50017P087CC-SCONN2A   I148 @S9S_MB_2U_LIB.S9S_MB_2U(SCH_1):PAGE91
   J10  230 VSS100 SCONN288_ADR50017P087CC-SCONN2A   I148 @S9S_MB_2U_LIB.S9S_MB_2U(SCH_1):PAGE91
   J10  233 VSS101 SCONN288_ADR50017P087CC-SCONN2A   I148 @S9S_MB_2U_LIB.S9S_MB_2U(SCH_1):PAGE91
   J10  235 VSS102 SCONN288_ADR50017P087CC-SCONN2A   I148 @S9S_MB_2U_LIB.S9S_MB_2U(SCH_1):PAGE91
   J10  237 VSS103 SCONN288_ADR50017P087CC-SCONN2A   I148 @S9S_MB_2U_LIB.S9S_MB_2U(SCH_1):PAGE91
   J10  240 VSS104 SCONN288_ADR50017P087CC-SCONN2A   I148 @S9S_MB_2U_LIB.S9S_MB_2U(SCH_1):PAGE91
   J10  242 VSS105 SCONN288_ADR50017P087CC-SCONN2A   I148 @S9S_MB_2U_LIB.S9S_MB_2U(SCH_1):PAGE91
   J10  244 VSS106 SCONN288_ADR50017P087CC-SCONN2A   I148 @S9S_MB_2U_LIB.S9S_MB_2U(SCH_1):PAGE91
   J10  246 VSS107 SCONN288_ADR50017P087CC-SCONN2A   I148 @S9S_MB_2U_LIB.S9S_MB_2U(SCH_1):PAGE91
   J10  248 VSS108 SCONN288_ADR50017P087CC-SCONN2A   I148 @S9S_MB_2U_LIB.S9S_MB_2U(SCH_1):PAGE91
   J10  251 VSS109 SCONN288_ADR50017P087CC-SCONN2A   I148 @S9S_MB_2U_LIB.S9S_MB_2U(SCH_1):PAGE91
   J10  253 VSS110 SCONN288_ADR50017P087CC-SCONN2A   I148 @S9S_MB_2U_LIB.S9S_MB_2U(SCH_1):PAGE91
   J10  255 VSS111 SCONN288_ADR50017P087CC-SCONN2A   I148 @S9S_MB_2U_LIB.S9S_MB_2U(SCH_1):PAGE91
   J10  257 VSS112 SCONN288_ADR50017P087CC-SCONN2A   I148 @S9S_MB_2U_LIB.S9S_MB_2U(SCH_1):PAGE91
   J10  259 VSS113 SCONN288_ADR50017P087CC-SCONN2A   I148 @S9S_MB_2U_LIB.S9S_MB_2U(SCH_1):PAGE91
   J10  262 VSS114 SCONN288_ADR50017P087CC-SCONN2A   I148 @S9S_MB_2U_LIB.S9S_MB_2U(SCH_1):PAGE91
   J10  264 VSS115 SCONN288_ADR50017P087CC-SCONN2A   I148 @S9S_MB_2U_LIB.S9S_MB_2U(SCH_1):PAGE91
   J10  266 VSS116 SCONN288_ADR50017P087CC-SCONN2A   I148 @S9S_MB_2U_LIB.S9S_MB_2U(SCH_1):PAGE91
   J10  268 VSS117 SCONN288_ADR50017P087CC-SCONN2A   I148 @S9S_MB_2U_LIB.S9S_MB_2U(SCH_1):PAGE91
   J10  270 VSS118 SCONN288_ADR50017P087CC-SCONN2A   I148 @S9S_MB_2U_LIB.S9S_MB_2U(SCH_1):PAGE91
   J10  273 VSS119 SCONN288_ADR50017P087CC-SCONN2A   I148 @S9S_MB_2U_LIB.S9S_MB_2U(SCH_1):PAGE91
   J10  275 VSS120 SCONN288_ADR50017P087CC-SCONN2A   I148 @S9S_MB_2U_LIB.S9S_MB_2U(SCH_1):PAGE91
   J10  277 VSS121 SCONN288_ADR50017P087CC-SCONN2A   I148 @S9S_MB_2U_LIB.S9S_MB_2U(SCH_1):PAGE91
   J10  279 VSS122 SCONN288_ADR50017P087CC-SCONN2A   I148 @S9S_MB_2U_LIB.S9S_MB_2U(SCH_1):PAGE91
   J10  281 VSS123 SCONN288_ADR50017P087CC-SCONN2A   I148 @S9S_MB_2U_LIB.S9S_MB_2U(SCH_1):PAGE91
   J10  284 VSS124 SCONN288_ADR50017P087CC-SCONN2A   I148 @S9S_MB_2U_LIB.S9S_MB_2U(SCH_1):PAGE91
   J10  286 VSS125 SCONN288_ADR50017P087CC-SCONN2A   I148 @S9S_MB_2U_LIB.S9S_MB_2U(SCH_1):PAGE91
   J10  288 VSS126 SCONN288_ADR50017P087CC-SCONN2A   I148 @S9S_MB_2U_LIB.S9S_MB_2U(SCH_1):PAGE91
   R36    2      B Q_RES_0402LF-23.2K,1%,1/16W,CHA     I2 @S9S_MB_2U_LIB.S9S_MB_2U(SCH_1):PAGE92
   C32    2      B Q_CAP_C0402-2.2UF,6.3V,20%,X6SA   I122 @S9S_MB_2U_LIB.S9S_MB_2U(SCH_1):PAGE92
   C33    2      B Q_CAP_C0805-10UF,16V,10%,X6S,CA   I127 @S9S_MB_2U_LIB.S9S_MB_2U(SCH_1):PAGE92
   C34    2      B Q_CAP_C0805-10UF,16V,10%,X6S,CA   I130 @S9S_MB_2U_LIB.S9S_MB_2U(SCH_1):PAGE92
   J11   G1     G1 SCONN288_ADR50017P130CC-SCONN2A   I175 @S9S_MB_2U_LIB.S9S_MB_2U(SCH_1):PAGE92
   J11   G2     G2 SCONN288_ADR50017P130CC-SCONN2A   I175 @S9S_MB_2U_LIB.S9S_MB_2U(SCH_1):PAGE92
   J11   G3     G3 SCONN288_ADR50017P130CC-SCONN2A   I175 @S9S_MB_2U_LIB.S9S_MB_2U(SCH_1):PAGE92
   J11    6   VSS0 SCONN288_ADR50017P130CC-SCONN2A   I175 @S9S_MB_2U_LIB.S9S_MB_2U(SCH_1):PAGE92
   J11    8   VSS1 SCONN288_ADR50017P130CC-SCONN2A   I175 @S9S_MB_2U_LIB.S9S_MB_2U(SCH_1):PAGE92
   J11   10   VSS2 SCONN288_ADR50017P130CC-SCONN2A   I175 @S9S_MB_2U_LIB.S9S_MB_2U(SCH_1):PAGE92
   J11   13   VSS3 SCONN288_ADR50017P130CC-SCONN2A   I175 @S9S_MB_2U_LIB.S9S_MB_2U(SCH_1):PAGE92
   J11   15   VSS4 SCONN288_ADR50017P130CC-SCONN2A   I175 @S9S_MB_2U_LIB.S9S_MB_2U(SCH_1):PAGE92
   J11   17   VSS5 SCONN288_ADR50017P130CC-SCONN2A   I175 @S9S_MB_2U_LIB.S9S_MB_2U(SCH_1):PAGE92
   J11   19   VSS6 SCONN288_ADR50017P130CC-SCONN2A   I175 @S9S_MB_2U_LIB.S9S_MB_2U(SCH_1):PAGE92
   J11   21   VSS7 SCONN288_ADR50017P130CC-SCONN2A   I175 @S9S_MB_2U_LIB.S9S_MB_2U(SCH_1):PAGE92
   J11   24   VSS8 SCONN288_ADR50017P130CC-SCONN2A   I175 @S9S_MB_2U_LIB.S9S_MB_2U(SCH_1):PAGE92
   J11   26   VSS9 SCONN288_ADR50017P130CC-SCONN2A   I175 @S9S_MB_2U_LIB.S9S_MB_2U(SCH_1):PAGE92
   J11   28  VSS10 SCONN288_ADR50017P130CC-SCONN2A   I175 @S9S_MB_2U_LIB.S9S_MB_2U(SCH_1):PAGE92
   J11   30  VSS11 SCONN288_ADR50017P130CC-SCONN2A   I175 @S9S_MB_2U_LIB.S9S_MB_2U(SCH_1):PAGE92
   J11   32  VSS12 SCONN288_ADR50017P130CC-SCONN2A   I175 @S9S_MB_2U_LIB.S9S_MB_2U(SCH_1):PAGE92
   J11   35  VSS13 SCONN288_ADR50017P130CC-SCONN2A   I175 @S9S_MB_2U_LIB.S9S_MB_2U(SCH_1):PAGE92
   J11   37  VSS14 SCONN288_ADR50017P130CC-SCONN2A   I175 @S9S_MB_2U_LIB.S9S_MB_2U(SCH_1):PAGE92
   J11   39  VSS15 SCONN288_ADR50017P130CC-SCONN2A   I175 @S9S_MB_2U_LIB.S9S_MB_2U(SCH_1):PAGE92
   J11   41  VSS16 SCONN288_ADR50017P130CC-SCONN2A   I175 @S9S_MB_2U_LIB.S9S_MB_2U(SCH_1):PAGE92
   J11   43  VSS17 SCONN288_ADR50017P130CC-SCONN2A   I175 @S9S_MB_2U_LIB.S9S_MB_2U(SCH_1):PAGE92
   J11   46  VSS18 SCONN288_ADR50017P130CC-SCONN2A   I175 @S9S_MB_2U_LIB.S9S_MB_2U(SCH_1):PAGE92
   J11   48  VSS19 SCONN288_ADR50017P130CC-SCONN2A   I175 @S9S_MB_2U_LIB.S9S_MB_2U(SCH_1):PAGE92
   J11   50  VSS20 SCONN288_ADR50017P130CC-SCONN2A   I175 @S9S_MB_2U_LIB.S9S_MB_2U(SCH_1):PAGE92
   J11   52  VSS21 SCONN288_ADR50017P130CC-SCONN2A   I175 @S9S_MB_2U_LIB.S9S_MB_2U(SCH_1):PAGE92
   J11   54  VSS22 SCONN288_ADR50017P130CC-SCONN2A   I175 @S9S_MB_2U_LIB.S9S_MB_2U(SCH_1):PAGE92
   J11   57  VSS23 SCONN288_ADR50017P130CC-SCONN2A   I175 @S9S_MB_2U_LIB.S9S_MB_2U(SCH_1):PAGE92
   J11   59  VSS24 SCONN288_ADR50017P130CC-SCONN2A   I175 @S9S_MB_2U_LIB.S9S_MB_2U(SCH_1):PAGE92
   J11   61  VSS25 SCONN288_ADR50017P130CC-SCONN2A   I175 @S9S_MB_2U_LIB.S9S_MB_2U(SCH_1):PAGE92
   J11   63  VSS26 SCONN288_ADR50017P130CC-SCONN2A   I175 @S9S_MB_2U_LIB.S9S_MB_2U(SCH_1):PAGE92
   J11   65  VSS27 SCONN288_ADR50017P130CC-SCONN2A   I175 @S9S_MB_2U_LIB.S9S_MB_2U(SCH_1):PAGE92
   J11   67  VSS28 SCONN288_ADR50017P130CC-SCONN2A   I175 @S9S_MB_2U_LIB.S9S_MB_2U(SCH_1):PAGE92
   J11   69  VSS29 SCONN288_ADR50017P130CC-SCONN2A   I175 @S9S_MB_2U_LIB.S9S_MB_2U(SCH_1):PAGE92
   J11   71  VSS30 SCONN288_ADR50017P130CC-SCONN2A   I175 @S9S_MB_2U_LIB.S9S_MB_2U(SCH_1):PAGE92
   J11   73  VSS31 SCONN288_ADR50017P130CC-SCONN2A   I175 @S9S_MB_2U_LIB.S9S_MB_2U(SCH_1):PAGE92
   J11   75  VSS32 SCONN288_ADR50017P130CC-SCONN2A   I175 @S9S_MB_2U_LIB.S9S_MB_2U(SCH_1):PAGE92
   J11   77  VSS33 SCONN288_ADR50017P130CC-SCONN2A   I175 @S9S_MB_2U_LIB.S9S_MB_2U(SCH_1):PAGE92
   J11   79  VSS34 SCONN288_ADR50017P130CC-SCONN2A   I175 @S9S_MB_2U_LIB.S9S_MB_2U(SCH_1):PAGE92
   J11   81  VSS35 SCONN288_ADR50017P130CC-SCONN2A   I175 @S9S_MB_2U_LIB.S9S_MB_2U(SCH_1):PAGE92
   J11   83  VSS36 SCONN288_ADR50017P130CC-SCONN2A   I175 @S9S_MB_2U_LIB.S9S_MB_2U(SCH_1):PAGE92
   J11   85  VSS37 SCONN288_ADR50017P130CC-SCONN2A   I175 @S9S_MB_2U_LIB.S9S_MB_2U(SCH_1):PAGE92
   J11   88  VSS38 SCONN288_ADR50017P130CC-SCONN2A   I175 @S9S_MB_2U_LIB.S9S_MB_2U(SCH_1):PAGE92
   J11   90  VSS39 SCONN288_ADR50017P130CC-SCONN2A   I175 @S9S_MB_2U_LIB.S9S_MB_2U(SCH_1):PAGE92
   J11   92  VSS40 SCONN288_ADR50017P130CC-SCONN2A   I175 @S9S_MB_2U_LIB.S9S_MB_2U(SCH_1):PAGE92
   J11   95  VSS41 SCONN288_ADR50017P130CC-SCONN2A   I175 @S9S_MB_2U_LIB.S9S_MB_2U(SCH_1):PAGE92
   J11   97  VSS42 SCONN288_ADR50017P130CC-SCONN2A   I175 @S9S_MB_2U_LIB.S9S_MB_2U(SCH_1):PAGE92
   J11   99  VSS43 SCONN288_ADR50017P130CC-SCONN2A   I175 @S9S_MB_2U_LIB.S9S_MB_2U(SCH_1):PAGE92
   J11  101  VSS44 SCONN288_ADR50017P130CC-SCONN2A   I175 @S9S_MB_2U_LIB.S9S_MB_2U(SCH_1):PAGE92
   J11  103  VSS45 SCONN288_ADR50017P130CC-SCONN2A   I175 @S9S_MB_2U_LIB.S9S_MB_2U(SCH_1):PAGE92
   J11  106  VSS46 SCONN288_ADR50017P130CC-SCONN2A   I175 @S9S_MB_2U_LIB.S9S_MB_2U(SCH_1):PAGE92
   J11  108  VSS47 SCONN288_ADR50017P130CC-SCONN2A   I175 @S9S_MB_2U_LIB.S9S_MB_2U(SCH_1):PAGE92
   J11  110  VSS48 SCONN288_ADR50017P130CC-SCONN2A   I175 @S9S_MB_2U_LIB.S9S_MB_2U(SCH_1):PAGE92
   J11  112  VSS49 SCONN288_ADR50017P130CC-SCONN2A   I175 @S9S_MB_2U_LIB.S9S_MB_2U(SCH_1):PAGE92
   J11  114  VSS50 SCONN288_ADR50017P130CC-SCONN2A   I175 @S9S_MB_2U_LIB.S9S_MB_2U(SCH_1):PAGE92
   J11  117  VSS51 SCONN288_ADR50017P130CC-SCONN2A   I175 @S9S_MB_2U_LIB.S9S_MB_2U(SCH_1):PAGE92
   J11  119  VSS52 SCONN288_ADR50017P130CC-SCONN2A   I175 @S9S_MB_2U_LIB.S9S_MB_2U(SCH_1):PAGE92
   J11  121  VSS53 SCONN288_ADR50017P130CC-SCONN2A   I175 @S9S_MB_2U_LIB.S9S_MB_2U(SCH_1):PAGE92
   J11  123  VSS54 SCONN288_ADR50017P130CC-SCONN2A   I175 @S9S_MB_2U_LIB.S9S_MB_2U(SCH_1):PAGE92
   J11  125  VSS55 SCONN288_ADR50017P130CC-SCONN2A   I175 @S9S_MB_2U_LIB.S9S_MB_2U(SCH_1):PAGE92
   J11  128  VSS56 SCONN288_ADR50017P130CC-SCONN2A   I175 @S9S_MB_2U_LIB.S9S_MB_2U(SCH_1):PAGE92
   J11  130  VSS57 SCONN288_ADR50017P130CC-SCONN2A   I175 @S9S_MB_2U_LIB.S9S_MB_2U(SCH_1):PAGE92
   J11  132  VSS58 SCONN288_ADR50017P130CC-SCONN2A   I175 @S9S_MB_2U_LIB.S9S_MB_2U(SCH_1):PAGE92
   J11  134  VSS59 SCONN288_ADR50017P130CC-SCONN2A   I175 @S9S_MB_2U_LIB.S9S_MB_2U(SCH_1):PAGE92
   J11  136  VSS60 SCONN288_ADR50017P130CC-SCONN2A   I175 @S9S_MB_2U_LIB.S9S_MB_2U(SCH_1):PAGE92
   J11  139  VSS61 SCONN288_ADR50017P130CC-SCONN2A   I175 @S9S_MB_2U_LIB.S9S_MB_2U(SCH_1):PAGE92
   J11  141  VSS62 SCONN288_ADR50017P130CC-SCONN2A   I175 @S9S_MB_2U_LIB.S9S_MB_2U(SCH_1):PAGE92
   J11  143  VSS63 SCONN288_ADR50017P130CC-SCONN2A   I175 @S9S_MB_2U_LIB.S9S_MB_2U(SCH_1):PAGE92
   J11  151  VSS64 SCONN288_ADR50017P130CC-SCONN2A   I175 @S9S_MB_2U_LIB.S9S_MB_2U(SCH_1):PAGE92
   J11  153  VSS65 SCONN288_ADR50017P130CC-SCONN2A   I175 @S9S_MB_2U_LIB.S9S_MB_2U(SCH_1):PAGE92
   J11  155  VSS66 SCONN288_ADR50017P130CC-SCONN2A   I175 @S9S_MB_2U_LIB.S9S_MB_2U(SCH_1):PAGE92
   J11  158  VSS67 SCONN288_ADR50017P130CC-SCONN2A   I175 @S9S_MB_2U_LIB.S9S_MB_2U(SCH_1):PAGE92
   J11  160  VSS68 SCONN288_ADR50017P130CC-SCONN2A   I175 @S9S_MB_2U_LIB.S9S_MB_2U(SCH_1):PAGE92
   J11  162  VSS69 SCONN288_ADR50017P130CC-SCONN2A   I175 @S9S_MB_2U_LIB.S9S_MB_2U(SCH_1):PAGE92
   J11  164  VSS70 SCONN288_ADR50017P130CC-SCONN2A   I175 @S9S_MB_2U_LIB.S9S_MB_2U(SCH_1):PAGE92
   J11  166  VSS71 SCONN288_ADR50017P130CC-SCONN2A   I175 @S9S_MB_2U_LIB.S9S_MB_2U(SCH_1):PAGE92
   J11  169  VSS72 SCONN288_ADR50017P130CC-SCONN2A   I175 @S9S_MB_2U_LIB.S9S_MB_2U(SCH_1):PAGE92
   J11  171  VSS73 SCONN288_ADR50017P130CC-SCONN2A   I175 @S9S_MB_2U_LIB.S9S_MB_2U(SCH_1):PAGE92
   J11  173  VSS74 SCONN288_ADR50017P130CC-SCONN2A   I175 @S9S_MB_2U_LIB.S9S_MB_2U(SCH_1):PAGE92
   J11  175  VSS75 SCONN288_ADR50017P130CC-SCONN2A   I175 @S9S_MB_2U_LIB.S9S_MB_2U(SCH_1):PAGE92
   J11  177  VSS76 SCONN288_ADR50017P130CC-SCONN2A   I175 @S9S_MB_2U_LIB.S9S_MB_2U(SCH_1):PAGE92
   J11  180  VSS77 SCONN288_ADR50017P130CC-SCONN2A   I175 @S9S_MB_2U_LIB.S9S_MB_2U(SCH_1):PAGE92
   J11  182  VSS78 SCONN288_ADR50017P130CC-SCONN2A   I175 @S9S_MB_2U_LIB.S9S_MB_2U(SCH_1):PAGE92
   J11  184  VSS79 SCONN288_ADR50017P130CC-SCONN2A   I175 @S9S_MB_2U_LIB.S9S_MB_2U(SCH_1):PAGE92
   J11  186  VSS80 SCONN288_ADR50017P130CC-SCONN2A   I175 @S9S_MB_2U_LIB.S9S_MB_2U(SCH_1):PAGE92
   J11  188  VSS81 SCONN288_ADR50017P130CC-SCONN2A   I175 @S9S_MB_2U_LIB.S9S_MB_2U(SCH_1):PAGE92
   J11  191  VSS82 SCONN288_ADR50017P130CC-SCONN2A   I175 @S9S_MB_2U_LIB.S9S_MB_2U(SCH_1):PAGE92
   J11  193  VSS83 SCONN288_ADR50017P130CC-SCONN2A   I175 @S9S_MB_2U_LIB.S9S_MB_2U(SCH_1):PAGE92
   J11  195  VSS84 SCONN288_ADR50017P130CC-SCONN2A   I175 @S9S_MB_2U_LIB.S9S_MB_2U(SCH_1):PAGE92
   J11  197  VSS85 SCONN288_ADR50017P130CC-SCONN2A   I175 @S9S_MB_2U_LIB.S9S_MB_2U(SCH_1):PAGE92
   J11  199  VSS86 SCONN288_ADR50017P130CC-SCONN2A   I175 @S9S_MB_2U_LIB.S9S_MB_2U(SCH_1):PAGE92
   J11  202  VSS87 SCONN288_ADR50017P130CC-SCONN2A   I175 @S9S_MB_2U_LIB.S9S_MB_2U(SCH_1):PAGE92
   J11  204  VSS88 SCONN288_ADR50017P130CC-SCONN2A   I175 @S9S_MB_2U_LIB.S9S_MB_2U(SCH_1):PAGE92
   J11  206  VSS89 SCONN288_ADR50017P130CC-SCONN2A   I175 @S9S_MB_2U_LIB.S9S_MB_2U(SCH_1):PAGE92
   J11  208  VSS90 SCONN288_ADR50017P130CC-SCONN2A   I175 @S9S_MB_2U_LIB.S9S_MB_2U(SCH_1):PAGE92
   J11  210  VSS91 SCONN288_ADR50017P130CC-SCONN2A   I175 @S9S_MB_2U_LIB.S9S_MB_2U(SCH_1):PAGE92
   J11  212  VSS92 SCONN288_ADR50017P130CC-SCONN2A   I175 @S9S_MB_2U_LIB.S9S_MB_2U(SCH_1):PAGE92
   J11  214  VSS93 SCONN288_ADR50017P130CC-SCONN2A   I175 @S9S_MB_2U_LIB.S9S_MB_2U(SCH_1):PAGE92
   J11  216  VSS94 SCONN288_ADR50017P130CC-SCONN2A   I175 @S9S_MB_2U_LIB.S9S_MB_2U(SCH_1):PAGE92
   J11  219  VSS95 SCONN288_ADR50017P130CC-SCONN2A   I175 @S9S_MB_2U_LIB.S9S_MB_2U(SCH_1):PAGE92
   J11  222  VSS96 SCONN288_ADR50017P130CC-SCONN2A   I175 @S9S_MB_2U_LIB.S9S_MB_2U(SCH_1):PAGE92
   J11  224  VSS97 SCONN288_ADR50017P130CC-SCONN2A   I175 @S9S_MB_2U_LIB.S9S_MB_2U(SCH_1):PAGE92
   J11  226  VSS98 SCONN288_ADR50017P130CC-SCONN2A   I175 @S9S_MB_2U_LIB.S9S_MB_2U(SCH_1):PAGE92
   J11  228  VSS99 SCONN288_ADR50017P130CC-SCONN2A   I175 @S9S_MB_2U_LIB.S9S_MB_2U(SCH_1):PAGE92
   J11  230 VSS100 SCONN288_ADR50017P130CC-SCONN2A   I175 @S9S_MB_2U_LIB.S9S_MB_2U(SCH_1):PAGE92
   J11  233 VSS101 SCONN288_ADR50017P130CC-SCONN2A   I175 @S9S_MB_2U_LIB.S9S_MB_2U(SCH_1):PAGE92
   J11  235 VSS102 SCONN288_ADR50017P130CC-SCONN2A   I175 @S9S_MB_2U_LIB.S9S_MB_2U(SCH_1):PAGE92
   J11  237 VSS103 SCONN288_ADR50017P130CC-SCONN2A   I175 @S9S_MB_2U_LIB.S9S_MB_2U(SCH_1):PAGE92
   J11  240 VSS104 SCONN288_ADR50017P130CC-SCONN2A   I175 @S9S_MB_2U_LIB.S9S_MB_2U(SCH_1):PAGE92
   J11  242 VSS105 SCONN288_ADR50017P130CC-SCONN2A   I175 @S9S_MB_2U_LIB.S9S_MB_2U(SCH_1):PAGE92
   J11  244 VSS106 SCONN288_ADR50017P130CC-SCONN2A   I175 @S9S_MB_2U_LIB.S9S_MB_2U(SCH_1):PAGE92
   J11  246 VSS107 SCONN288_ADR50017P130CC-SCONN2A   I175 @S9S_MB_2U_LIB.S9S_MB_2U(SCH_1):PAGE92
   J11  248 VSS108 SCONN288_ADR50017P130CC-SCONN2A   I175 @S9S_MB_2U_LIB.S9S_MB_2U(SCH_1):PAGE92
   J11  251 VSS109 SCONN288_ADR50017P130CC-SCONN2A   I175 @S9S_MB_2U_LIB.S9S_MB_2U(SCH_1):PAGE92
   J11  253 VSS110 SCONN288_ADR50017P130CC-SCONN2A   I175 @S9S_MB_2U_LIB.S9S_MB_2U(SCH_1):PAGE92
   J11  255 VSS111 SCONN288_ADR50017P130CC-SCONN2A   I175 @S9S_MB_2U_LIB.S9S_MB_2U(SCH_1):PAGE92
   J11  257 VSS112 SCONN288_ADR50017P130CC-SCONN2A   I175 @S9S_MB_2U_LIB.S9S_MB_2U(SCH_1):PAGE92
   J11  259 VSS113 SCONN288_ADR50017P130CC-SCONN2A   I175 @S9S_MB_2U_LIB.S9S_MB_2U(SCH_1):PAGE92
   J11  262 VSS114 SCONN288_ADR50017P130CC-SCONN2A   I175 @S9S_MB_2U_LIB.S9S_MB_2U(SCH_1):PAGE92
   J11  264 VSS115 SCONN288_ADR50017P130CC-SCONN2A   I175 @S9S_MB_2U_LIB.S9S_MB_2U(SCH_1):PAGE92
   J11  266 VSS116 SCONN288_ADR50017P130CC-SCONN2A   I175 @S9S_MB_2U_LIB.S9S_MB_2U(SCH_1):PAGE92
   J11  268 VSS117 SCONN288_ADR50017P130CC-SCONN2A   I175 @S9S_MB_2U_LIB.S9S_MB_2U(SCH_1):PAGE92
   J11  270 VSS118 SCONN288_ADR50017P130CC-SCONN2A   I175 @S9S_MB_2U_LIB.S9S_MB_2U(SCH_1):PAGE92
   J11  273 VSS119 SCONN288_ADR50017P130CC-SCONN2A   I175 @S9S_MB_2U_LIB.S9S_MB_2U(SCH_1):PAGE92
   J11  275 VSS120 SCONN288_ADR50017P130CC-SCONN2A   I175 @S9S_MB_2U_LIB.S9S_MB_2U(SCH_1):PAGE92
   J11  277 VSS121 SCONN288_ADR50017P130CC-SCONN2A   I175 @S9S_MB_2U_LIB.S9S_MB_2U(SCH_1):PAGE92
   J11  279 VSS122 SCONN288_ADR50017P130CC-SCONN2A   I175 @S9S_MB_2U_LIB.S9S_MB_2U(SCH_1):PAGE92
   J11  281 VSS123 SCONN288_ADR50017P130CC-SCONN2A   I175 @S9S_MB_2U_LIB.S9S_MB_2U(SCH_1):PAGE92
   J11  284 VSS124 SCONN288_ADR50017P130CC-SCONN2A   I175 @S9S_MB_2U_LIB.S9S_MB_2U(SCH_1):PAGE92
   J11  286 VSS125 SCONN288_ADR50017P130CC-SCONN2A   I175 @S9S_MB_2U_LIB.S9S_MB_2U(SCH_1):PAGE92
   J11  288 VSS126 SCONN288_ADR50017P130CC-SCONN2A   I175 @S9S_MB_2U_LIB.S9S_MB_2U(SCH_1):PAGE92
   R37    2      B Q_RES_0402LF-35.7K,1%,1/16W,CHA     I2 @S9S_MB_2U_LIB.S9S_MB_2U(SCH_1):PAGE93
   C35    2      B Q_CAP_C0402-2.2UF,6.3V,20%,X6SA   I122 @S9S_MB_2U_LIB.S9S_MB_2U(SCH_1):PAGE93
   C36    2      B Q_CAP_C0805-10UF,16V,10%,X6S,CA   I126 @S9S_MB_2U_LIB.S9S_MB_2U(SCH_1):PAGE93
   C37    2      B Q_CAP_C0805-10UF,16V,10%,X6S,CA   I128 @S9S_MB_2U_LIB.S9S_MB_2U(SCH_1):PAGE93
   J12   G1     G1 SCONN288_ADR50017P087CC-SCONN2A   I175 @S9S_MB_2U_LIB.S9S_MB_2U(SCH_1):PAGE93
   J12   G2     G2 SCONN288_ADR50017P087CC-SCONN2A   I175 @S9S_MB_2U_LIB.S9S_MB_2U(SCH_1):PAGE93
   J12   G3     G3 SCONN288_ADR50017P087CC-SCONN2A   I175 @S9S_MB_2U_LIB.S9S_MB_2U(SCH_1):PAGE93
   J12    6   VSS0 SCONN288_ADR50017P087CC-SCONN2A   I175 @S9S_MB_2U_LIB.S9S_MB_2U(SCH_1):PAGE93
   J12    8   VSS1 SCONN288_ADR50017P087CC-SCONN2A   I175 @S9S_MB_2U_LIB.S9S_MB_2U(SCH_1):PAGE93
   J12   10   VSS2 SCONN288_ADR50017P087CC-SCONN2A   I175 @S9S_MB_2U_LIB.S9S_MB_2U(SCH_1):PAGE93
   J12   13   VSS3 SCONN288_ADR50017P087CC-SCONN2A   I175 @S9S_MB_2U_LIB.S9S_MB_2U(SCH_1):PAGE93
   J12   15   VSS4 SCONN288_ADR50017P087CC-SCONN2A   I175 @S9S_MB_2U_LIB.S9S_MB_2U(SCH_1):PAGE93
   J12   17   VSS5 SCONN288_ADR50017P087CC-SCONN2A   I175 @S9S_MB_2U_LIB.S9S_MB_2U(SCH_1):PAGE93
   J12   19   VSS6 SCONN288_ADR50017P087CC-SCONN2A   I175 @S9S_MB_2U_LIB.S9S_MB_2U(SCH_1):PAGE93
   J12   21   VSS7 SCONN288_ADR50017P087CC-SCONN2A   I175 @S9S_MB_2U_LIB.S9S_MB_2U(SCH_1):PAGE93
   J12   24   VSS8 SCONN288_ADR50017P087CC-SCONN2A   I175 @S9S_MB_2U_LIB.S9S_MB_2U(SCH_1):PAGE93
   J12   26   VSS9 SCONN288_ADR50017P087CC-SCONN2A   I175 @S9S_MB_2U_LIB.S9S_MB_2U(SCH_1):PAGE93
   J12   28  VSS10 SCONN288_ADR50017P087CC-SCONN2A   I175 @S9S_MB_2U_LIB.S9S_MB_2U(SCH_1):PAGE93
   J12   30  VSS11 SCONN288_ADR50017P087CC-SCONN2A   I175 @S9S_MB_2U_LIB.S9S_MB_2U(SCH_1):PAGE93
   J12   32  VSS12 SCONN288_ADR50017P087CC-SCONN2A   I175 @S9S_MB_2U_LIB.S9S_MB_2U(SCH_1):PAGE93
   J12   35  VSS13 SCONN288_ADR50017P087CC-SCONN2A   I175 @S9S_MB_2U_LIB.S9S_MB_2U(SCH_1):PAGE93
   J12   37  VSS14 SCONN288_ADR50017P087CC-SCONN2A   I175 @S9S_MB_2U_LIB.S9S_MB_2U(SCH_1):PAGE93
   J12   39  VSS15 SCONN288_ADR50017P087CC-SCONN2A   I175 @S9S_MB_2U_LIB.S9S_MB_2U(SCH_1):PAGE93
   J12   41  VSS16 SCONN288_ADR50017P087CC-SCONN2A   I175 @S9S_MB_2U_LIB.S9S_MB_2U(SCH_1):PAGE93
   J12   43  VSS17 SCONN288_ADR50017P087CC-SCONN2A   I175 @S9S_MB_2U_LIB.S9S_MB_2U(SCH_1):PAGE93
   J12   46  VSS18 SCONN288_ADR50017P087CC-SCONN2A   I175 @S9S_MB_2U_LIB.S9S_MB_2U(SCH_1):PAGE93
   J12   48  VSS19 SCONN288_ADR50017P087CC-SCONN2A   I175 @S9S_MB_2U_LIB.S9S_MB_2U(SCH_1):PAGE93
   J12   50  VSS20 SCONN288_ADR50017P087CC-SCONN2A   I175 @S9S_MB_2U_LIB.S9S_MB_2U(SCH_1):PAGE93
   J12   52  VSS21 SCONN288_ADR50017P087CC-SCONN2A   I175 @S9S_MB_2U_LIB.S9S_MB_2U(SCH_1):PAGE93
   J12   54  VSS22 SCONN288_ADR50017P087CC-SCONN2A   I175 @S9S_MB_2U_LIB.S9S_MB_2U(SCH_1):PAGE93
   J12   57  VSS23 SCONN288_ADR50017P087CC-SCONN2A   I175 @S9S_MB_2U_LIB.S9S_MB_2U(SCH_1):PAGE93
   J12   59  VSS24 SCONN288_ADR50017P087CC-SCONN2A   I175 @S9S_MB_2U_LIB.S9S_MB_2U(SCH_1):PAGE93
   J12   61  VSS25 SCONN288_ADR50017P087CC-SCONN2A   I175 @S9S_MB_2U_LIB.S9S_MB_2U(SCH_1):PAGE93
   J12   63  VSS26 SCONN288_ADR50017P087CC-SCONN2A   I175 @S9S_MB_2U_LIB.S9S_MB_2U(SCH_1):PAGE93
   J12   65  VSS27 SCONN288_ADR50017P087CC-SCONN2A   I175 @S9S_MB_2U_LIB.S9S_MB_2U(SCH_1):PAGE93
   J12   67  VSS28 SCONN288_ADR50017P087CC-SCONN2A   I175 @S9S_MB_2U_LIB.S9S_MB_2U(SCH_1):PAGE93
   J12   69  VSS29 SCONN288_ADR50017P087CC-SCONN2A   I175 @S9S_MB_2U_LIB.S9S_MB_2U(SCH_1):PAGE93
   J12   71  VSS30 SCONN288_ADR50017P087CC-SCONN2A   I175 @S9S_MB_2U_LIB.S9S_MB_2U(SCH_1):PAGE93
   J12   73  VSS31 SCONN288_ADR50017P087CC-SCONN2A   I175 @S9S_MB_2U_LIB.S9S_MB_2U(SCH_1):PAGE93
   J12   75  VSS32 SCONN288_ADR50017P087CC-SCONN2A   I175 @S9S_MB_2U_LIB.S9S_MB_2U(SCH_1):PAGE93
   J12   77  VSS33 SCONN288_ADR50017P087CC-SCONN2A   I175 @S9S_MB_2U_LIB.S9S_MB_2U(SCH_1):PAGE93
   J12   79  VSS34 SCONN288_ADR50017P087CC-SCONN2A   I175 @S9S_MB_2U_LIB.S9S_MB_2U(SCH_1):PAGE93
   J12   81  VSS35 SCONN288_ADR50017P087CC-SCONN2A   I175 @S9S_MB_2U_LIB.S9S_MB_2U(SCH_1):PAGE93
   J12   83  VSS36 SCONN288_ADR50017P087CC-SCONN2A   I175 @S9S_MB_2U_LIB.S9S_MB_2U(SCH_1):PAGE93
   J12   85  VSS37 SCONN288_ADR50017P087CC-SCONN2A   I175 @S9S_MB_2U_LIB.S9S_MB_2U(SCH_1):PAGE93
   J12   88  VSS38 SCONN288_ADR50017P087CC-SCONN2A   I175 @S9S_MB_2U_LIB.S9S_MB_2U(SCH_1):PAGE93
   J12   90  VSS39 SCONN288_ADR50017P087CC-SCONN2A   I175 @S9S_MB_2U_LIB.S9S_MB_2U(SCH_1):PAGE93
   J12   92  VSS40 SCONN288_ADR50017P087CC-SCONN2A   I175 @S9S_MB_2U_LIB.S9S_MB_2U(SCH_1):PAGE93
   J12   95  VSS41 SCONN288_ADR50017P087CC-SCONN2A   I175 @S9S_MB_2U_LIB.S9S_MB_2U(SCH_1):PAGE93
   J12   97  VSS42 SCONN288_ADR50017P087CC-SCONN2A   I175 @S9S_MB_2U_LIB.S9S_MB_2U(SCH_1):PAGE93
   J12   99  VSS43 SCONN288_ADR50017P087CC-SCONN2A   I175 @S9S_MB_2U_LIB.S9S_MB_2U(SCH_1):PAGE93
   J12  101  VSS44 SCONN288_ADR50017P087CC-SCONN2A   I175 @S9S_MB_2U_LIB.S9S_MB_2U(SCH_1):PAGE93
   J12  103  VSS45 SCONN288_ADR50017P087CC-SCONN2A   I175 @S9S_MB_2U_LIB.S9S_MB_2U(SCH_1):PAGE93
   J12  106  VSS46 SCONN288_ADR50017P087CC-SCONN2A   I175 @S9S_MB_2U_LIB.S9S_MB_2U(SCH_1):PAGE93
   J12  108  VSS47 SCONN288_ADR50017P087CC-SCONN2A   I175 @S9S_MB_2U_LIB.S9S_MB_2U(SCH_1):PAGE93
   J12  110  VSS48 SCONN288_ADR50017P087CC-SCONN2A   I175 @S9S_MB_2U_LIB.S9S_MB_2U(SCH_1):PAGE93
   J12  112  VSS49 SCONN288_ADR50017P087CC-SCONN2A   I175 @S9S_MB_2U_LIB.S9S_MB_2U(SCH_1):PAGE93
   J12  114  VSS50 SCONN288_ADR50017P087CC-SCONN2A   I175 @S9S_MB_2U_LIB.S9S_MB_2U(SCH_1):PAGE93
   J12  117  VSS51 SCONN288_ADR50017P087CC-SCONN2A   I175 @S9S_MB_2U_LIB.S9S_MB_2U(SCH_1):PAGE93
   J12  119  VSS52 SCONN288_ADR50017P087CC-SCONN2A   I175 @S9S_MB_2U_LIB.S9S_MB_2U(SCH_1):PAGE93
   J12  121  VSS53 SCONN288_ADR50017P087CC-SCONN2A   I175 @S9S_MB_2U_LIB.S9S_MB_2U(SCH_1):PAGE93
   J12  123  VSS54 SCONN288_ADR50017P087CC-SCONN2A   I175 @S9S_MB_2U_LIB.S9S_MB_2U(SCH_1):PAGE93
   J12  125  VSS55 SCONN288_ADR50017P087CC-SCONN2A   I175 @S9S_MB_2U_LIB.S9S_MB_2U(SCH_1):PAGE93
   J12  128  VSS56 SCONN288_ADR50017P087CC-SCONN2A   I175 @S9S_MB_2U_LIB.S9S_MB_2U(SCH_1):PAGE93
   J12  130  VSS57 SCONN288_ADR50017P087CC-SCONN2A   I175 @S9S_MB_2U_LIB.S9S_MB_2U(SCH_1):PAGE93
   J12  132  VSS58 SCONN288_ADR50017P087CC-SCONN2A   I175 @S9S_MB_2U_LIB.S9S_MB_2U(SCH_1):PAGE93
   J12  134  VSS59 SCONN288_ADR50017P087CC-SCONN2A   I175 @S9S_MB_2U_LIB.S9S_MB_2U(SCH_1):PAGE93
   J12  136  VSS60 SCONN288_ADR50017P087CC-SCONN2A   I175 @S9S_MB_2U_LIB.S9S_MB_2U(SCH_1):PAGE93
   J12  139  VSS61 SCONN288_ADR50017P087CC-SCONN2A   I175 @S9S_MB_2U_LIB.S9S_MB_2U(SCH_1):PAGE93
   J12  141  VSS62 SCONN288_ADR50017P087CC-SCONN2A   I175 @S9S_MB_2U_LIB.S9S_MB_2U(SCH_1):PAGE93
   J12  143  VSS63 SCONN288_ADR50017P087CC-SCONN2A   I175 @S9S_MB_2U_LIB.S9S_MB_2U(SCH_1):PAGE93
   J12  151  VSS64 SCONN288_ADR50017P087CC-SCONN2A   I175 @S9S_MB_2U_LIB.S9S_MB_2U(SCH_1):PAGE93
   J12  153  VSS65 SCONN288_ADR50017P087CC-SCONN2A   I175 @S9S_MB_2U_LIB.S9S_MB_2U(SCH_1):PAGE93
   J12  155  VSS66 SCONN288_ADR50017P087CC-SCONN2A   I175 @S9S_MB_2U_LIB.S9S_MB_2U(SCH_1):PAGE93
   J12  158  VSS67 SCONN288_ADR50017P087CC-SCONN2A   I175 @S9S_MB_2U_LIB.S9S_MB_2U(SCH_1):PAGE93
   J12  160  VSS68 SCONN288_ADR50017P087CC-SCONN2A   I175 @S9S_MB_2U_LIB.S9S_MB_2U(SCH_1):PAGE93
   J12  162  VSS69 SCONN288_ADR50017P087CC-SCONN2A   I175 @S9S_MB_2U_LIB.S9S_MB_2U(SCH_1):PAGE93
   J12  164  VSS70 SCONN288_ADR50017P087CC-SCONN2A   I175 @S9S_MB_2U_LIB.S9S_MB_2U(SCH_1):PAGE93
   J12  166  VSS71 SCONN288_ADR50017P087CC-SCONN2A   I175 @S9S_MB_2U_LIB.S9S_MB_2U(SCH_1):PAGE93
   J12  169  VSS72 SCONN288_ADR50017P087CC-SCONN2A   I175 @S9S_MB_2U_LIB.S9S_MB_2U(SCH_1):PAGE93
   J12  171  VSS73 SCONN288_ADR50017P087CC-SCONN2A   I175 @S9S_MB_2U_LIB.S9S_MB_2U(SCH_1):PAGE93
   J12  173  VSS74 SCONN288_ADR50017P087CC-SCONN2A   I175 @S9S_MB_2U_LIB.S9S_MB_2U(SCH_1):PAGE93
   J12  175  VSS75 SCONN288_ADR50017P087CC-SCONN2A   I175 @S9S_MB_2U_LIB.S9S_MB_2U(SCH_1):PAGE93
   J12  177  VSS76 SCONN288_ADR50017P087CC-SCONN2A   I175 @S9S_MB_2U_LIB.S9S_MB_2U(SCH_1):PAGE93
   J12  180  VSS77 SCONN288_ADR50017P087CC-SCONN2A   I175 @S9S_MB_2U_LIB.S9S_MB_2U(SCH_1):PAGE93
   J12  182  VSS78 SCONN288_ADR50017P087CC-SCONN2A   I175 @S9S_MB_2U_LIB.S9S_MB_2U(SCH_1):PAGE93
   J12  184  VSS79 SCONN288_ADR50017P087CC-SCONN2A   I175 @S9S_MB_2U_LIB.S9S_MB_2U(SCH_1):PAGE93
   J12  186  VSS80 SCONN288_ADR50017P087CC-SCONN2A   I175 @S9S_MB_2U_LIB.S9S_MB_2U(SCH_1):PAGE93
   J12  188  VSS81 SCONN288_ADR50017P087CC-SCONN2A   I175 @S9S_MB_2U_LIB.S9S_MB_2U(SCH_1):PAGE93
   J12  191  VSS82 SCONN288_ADR50017P087CC-SCONN2A   I175 @S9S_MB_2U_LIB.S9S_MB_2U(SCH_1):PAGE93
   J12  193  VSS83 SCONN288_ADR50017P087CC-SCONN2A   I175 @S9S_MB_2U_LIB.S9S_MB_2U(SCH_1):PAGE93
   J12  195  VSS84 SCONN288_ADR50017P087CC-SCONN2A   I175 @S9S_MB_2U_LIB.S9S_MB_2U(SCH_1):PAGE93
   J12  197  VSS85 SCONN288_ADR50017P087CC-SCONN2A   I175 @S9S_MB_2U_LIB.S9S_MB_2U(SCH_1):PAGE93
   J12  199  VSS86 SCONN288_ADR50017P087CC-SCONN2A   I175 @S9S_MB_2U_LIB.S9S_MB_2U(SCH_1):PAGE93
   J12  202  VSS87 SCONN288_ADR50017P087CC-SCONN2A   I175 @S9S_MB_2U_LIB.S9S_MB_2U(SCH_1):PAGE93
   J12  204  VSS88 SCONN288_ADR50017P087CC-SCONN2A   I175 @S9S_MB_2U_LIB.S9S_MB_2U(SCH_1):PAGE93
   J12  206  VSS89 SCONN288_ADR50017P087CC-SCONN2A   I175 @S9S_MB_2U_LIB.S9S_MB_2U(SCH_1):PAGE93
   J12  208  VSS90 SCONN288_ADR50017P087CC-SCONN2A   I175 @S9S_MB_2U_LIB.S9S_MB_2U(SCH_1):PAGE93
   J12  210  VSS91 SCONN288_ADR50017P087CC-SCONN2A   I175 @S9S_MB_2U_LIB.S9S_MB_2U(SCH_1):PAGE93
   J12  212  VSS92 SCONN288_ADR50017P087CC-SCONN2A   I175 @S9S_MB_2U_LIB.S9S_MB_2U(SCH_1):PAGE93
   J12  214  VSS93 SCONN288_ADR50017P087CC-SCONN2A   I175 @S9S_MB_2U_LIB.S9S_MB_2U(SCH_1):PAGE93
   J12  216  VSS94 SCONN288_ADR50017P087CC-SCONN2A   I175 @S9S_MB_2U_LIB.S9S_MB_2U(SCH_1):PAGE93
   J12  219  VSS95 SCONN288_ADR50017P087CC-SCONN2A   I175 @S9S_MB_2U_LIB.S9S_MB_2U(SCH_1):PAGE93
   J12  222  VSS96 SCONN288_ADR50017P087CC-SCONN2A   I175 @S9S_MB_2U_LIB.S9S_MB_2U(SCH_1):PAGE93
   J12  224  VSS97 SCONN288_ADR50017P087CC-SCONN2A   I175 @S9S_MB_2U_LIB.S9S_MB_2U(SCH_1):PAGE93
   J12  226  VSS98 SCONN288_ADR50017P087CC-SCONN2A   I175 @S9S_MB_2U_LIB.S9S_MB_2U(SCH_1):PAGE93
   J12  228  VSS99 SCONN288_ADR50017P087CC-SCONN2A   I175 @S9S_MB_2U_LIB.S9S_MB_2U(SCH_1):PAGE93
   J12  230 VSS100 SCONN288_ADR50017P087CC-SCONN2A   I175 @S9S_MB_2U_LIB.S9S_MB_2U(SCH_1):PAGE93
   J12  233 VSS101 SCONN288_ADR50017P087CC-SCONN2A   I175 @S9S_MB_2U_LIB.S9S_MB_2U(SCH_1):PAGE93
   J12  235 VSS102 SCONN288_ADR50017P087CC-SCONN2A   I175 @S9S_MB_2U_LIB.S9S_MB_2U(SCH_1):PAGE93
   J12  237 VSS103 SCONN288_ADR50017P087CC-SCONN2A   I175 @S9S_MB_2U_LIB.S9S_MB_2U(SCH_1):PAGE93
   J12  240 VSS104 SCONN288_ADR50017P087CC-SCONN2A   I175 @S9S_MB_2U_LIB.S9S_MB_2U(SCH_1):PAGE93
   J12  242 VSS105 SCONN288_ADR50017P087CC-SCONN2A   I175 @S9S_MB_2U_LIB.S9S_MB_2U(SCH_1):PAGE93
   J12  244 VSS106 SCONN288_ADR50017P087CC-SCONN2A   I175 @S9S_MB_2U_LIB.S9S_MB_2U(SCH_1):PAGE93
   J12  246 VSS107 SCONN288_ADR50017P087CC-SCONN2A   I175 @S9S_MB_2U_LIB.S9S_MB_2U(SCH_1):PAGE93
   J12  248 VSS108 SCONN288_ADR50017P087CC-SCONN2A   I175 @S9S_MB_2U_LIB.S9S_MB_2U(SCH_1):PAGE93
   J12  251 VSS109 SCONN288_ADR50017P087CC-SCONN2A   I175 @S9S_MB_2U_LIB.S9S_MB_2U(SCH_1):PAGE93
   J12  253 VSS110 SCONN288_ADR50017P087CC-SCONN2A   I175 @S9S_MB_2U_LIB.S9S_MB_2U(SCH_1):PAGE93
   J12  255 VSS111 SCONN288_ADR50017P087CC-SCONN2A   I175 @S9S_MB_2U_LIB.S9S_MB_2U(SCH_1):PAGE93
   J12  257 VSS112 SCONN288_ADR50017P087CC-SCONN2A   I175 @S9S_MB_2U_LIB.S9S_MB_2U(SCH_1):PAGE93
   J12  259 VSS113 SCONN288_ADR50017P087CC-SCONN2A   I175 @S9S_MB_2U_LIB.S9S_MB_2U(SCH_1):PAGE93
   J12  262 VSS114 SCONN288_ADR50017P087CC-SCONN2A   I175 @S9S_MB_2U_LIB.S9S_MB_2U(SCH_1):PAGE93
   J12  264 VSS115 SCONN288_ADR50017P087CC-SCONN2A   I175 @S9S_MB_2U_LIB.S9S_MB_2U(SCH_1):PAGE93
   J12  266 VSS116 SCONN288_ADR50017P087CC-SCONN2A   I175 @S9S_MB_2U_LIB.S9S_MB_2U(SCH_1):PAGE93
   J12  268 VSS117 SCONN288_ADR50017P087CC-SCONN2A   I175 @S9S_MB_2U_LIB.S9S_MB_2U(SCH_1):PAGE93
   J12  270 VSS118 SCONN288_ADR50017P087CC-SCONN2A   I175 @S9S_MB_2U_LIB.S9S_MB_2U(SCH_1):PAGE93
   J12  273 VSS119 SCONN288_ADR50017P087CC-SCONN2A   I175 @S9S_MB_2U_LIB.S9S_MB_2U(SCH_1):PAGE93
   J12  275 VSS120 SCONN288_ADR50017P087CC-SCONN2A   I175 @S9S_MB_2U_LIB.S9S_MB_2U(SCH_1):PAGE93
   J12  277 VSS121 SCONN288_ADR50017P087CC-SCONN2A   I175 @S9S_MB_2U_LIB.S9S_MB_2U(SCH_1):PAGE93
   J12  279 VSS122 SCONN288_ADR50017P087CC-SCONN2A   I175 @S9S_MB_2U_LIB.S9S_MB_2U(SCH_1):PAGE93
   J12  281 VSS123 SCONN288_ADR50017P087CC-SCONN2A   I175 @S9S_MB_2U_LIB.S9S_MB_2U(SCH_1):PAGE93
   J12  284 VSS124 SCONN288_ADR50017P087CC-SCONN2A   I175 @S9S_MB_2U_LIB.S9S_MB_2U(SCH_1):PAGE93
   J12  286 VSS125 SCONN288_ADR50017P087CC-SCONN2A   I175 @S9S_MB_2U_LIB.S9S_MB_2U(SCH_1):PAGE93
   J12  288 VSS126 SCONN288_ADR50017P087CC-SCONN2A   I175 @S9S_MB_2U_LIB.S9S_MB_2U(SCH_1):PAGE93
   R38    2      B Q_RES_0402LF-54.9K,1%,1/16W,CHA    I10 @S9S_MB_2U_LIB.S9S_MB_2U(SCH_1):PAGE94
   C38    2      B Q_CAP_C0402-2.2UF,6.3V,20%,X6SA   I123 @S9S_MB_2U_LIB.S9S_MB_2U(SCH_1):PAGE94
   C39    2      B Q_CAP_C0805-10UF,16V,10%,X6S,CA   I125 @S9S_MB_2U_LIB.S9S_MB_2U(SCH_1):PAGE94
   C40    2      B Q_CAP_C0805-10UF,16V,10%,X6S,CA   I162 @S9S_MB_2U_LIB.S9S_MB_2U(SCH_1):PAGE94
   J13   G1     G1 SCONN288_ADR50017P130CC-SCONN2A   I164 @S9S_MB_2U_LIB.S9S_MB_2U(SCH_1):PAGE94
   J13   G2     G2 SCONN288_ADR50017P130CC-SCONN2A   I164 @S9S_MB_2U_LIB.S9S_MB_2U(SCH_1):PAGE94
   J13   G3     G3 SCONN288_ADR50017P130CC-SCONN2A   I164 @S9S_MB_2U_LIB.S9S_MB_2U(SCH_1):PAGE94
   J13    6   VSS0 SCONN288_ADR50017P130CC-SCONN2A   I164 @S9S_MB_2U_LIB.S9S_MB_2U(SCH_1):PAGE94
   J13    8   VSS1 SCONN288_ADR50017P130CC-SCONN2A   I164 @S9S_MB_2U_LIB.S9S_MB_2U(SCH_1):PAGE94
   J13   10   VSS2 SCONN288_ADR50017P130CC-SCONN2A   I164 @S9S_MB_2U_LIB.S9S_MB_2U(SCH_1):PAGE94
   J13   13   VSS3 SCONN288_ADR50017P130CC-SCONN2A   I164 @S9S_MB_2U_LIB.S9S_MB_2U(SCH_1):PAGE94
   J13   15   VSS4 SCONN288_ADR50017P130CC-SCONN2A   I164 @S9S_MB_2U_LIB.S9S_MB_2U(SCH_1):PAGE94
   J13   17   VSS5 SCONN288_ADR50017P130CC-SCONN2A   I164 @S9S_MB_2U_LIB.S9S_MB_2U(SCH_1):PAGE94
   J13   19   VSS6 SCONN288_ADR50017P130CC-SCONN2A   I164 @S9S_MB_2U_LIB.S9S_MB_2U(SCH_1):PAGE94
   J13   21   VSS7 SCONN288_ADR50017P130CC-SCONN2A   I164 @S9S_MB_2U_LIB.S9S_MB_2U(SCH_1):PAGE94
   J13   24   VSS8 SCONN288_ADR50017P130CC-SCONN2A   I164 @S9S_MB_2U_LIB.S9S_MB_2U(SCH_1):PAGE94
   J13   26   VSS9 SCONN288_ADR50017P130CC-SCONN2A   I164 @S9S_MB_2U_LIB.S9S_MB_2U(SCH_1):PAGE94
   J13   28  VSS10 SCONN288_ADR50017P130CC-SCONN2A   I164 @S9S_MB_2U_LIB.S9S_MB_2U(SCH_1):PAGE94
   J13   30  VSS11 SCONN288_ADR50017P130CC-SCONN2A   I164 @S9S_MB_2U_LIB.S9S_MB_2U(SCH_1):PAGE94
   J13   32  VSS12 SCONN288_ADR50017P130CC-SCONN2A   I164 @S9S_MB_2U_LIB.S9S_MB_2U(SCH_1):PAGE94
   J13   35  VSS13 SCONN288_ADR50017P130CC-SCONN2A   I164 @S9S_MB_2U_LIB.S9S_MB_2U(SCH_1):PAGE94
   J13   37  VSS14 SCONN288_ADR50017P130CC-SCONN2A   I164 @S9S_MB_2U_LIB.S9S_MB_2U(SCH_1):PAGE94
   J13   39  VSS15 SCONN288_ADR50017P130CC-SCONN2A   I164 @S9S_MB_2U_LIB.S9S_MB_2U(SCH_1):PAGE94
   J13   41  VSS16 SCONN288_ADR50017P130CC-SCONN2A   I164 @S9S_MB_2U_LIB.S9S_MB_2U(SCH_1):PAGE94
   J13   43  VSS17 SCONN288_ADR50017P130CC-SCONN2A   I164 @S9S_MB_2U_LIB.S9S_MB_2U(SCH_1):PAGE94
   J13   46  VSS18 SCONN288_ADR50017P130CC-SCONN2A   I164 @S9S_MB_2U_LIB.S9S_MB_2U(SCH_1):PAGE94
   J13   48  VSS19 SCONN288_ADR50017P130CC-SCONN2A   I164 @S9S_MB_2U_LIB.S9S_MB_2U(SCH_1):PAGE94
   J13   50  VSS20 SCONN288_ADR50017P130CC-SCONN2A   I164 @S9S_MB_2U_LIB.S9S_MB_2U(SCH_1):PAGE94
   J13   52  VSS21 SCONN288_ADR50017P130CC-SCONN2A   I164 @S9S_MB_2U_LIB.S9S_MB_2U(SCH_1):PAGE94
   J13   54  VSS22 SCONN288_ADR50017P130CC-SCONN2A   I164 @S9S_MB_2U_LIB.S9S_MB_2U(SCH_1):PAGE94
   J13   57  VSS23 SCONN288_ADR50017P130CC-SCONN2A   I164 @S9S_MB_2U_LIB.S9S_MB_2U(SCH_1):PAGE94
   J13   59  VSS24 SCONN288_ADR50017P130CC-SCONN2A   I164 @S9S_MB_2U_LIB.S9S_MB_2U(SCH_1):PAGE94
   J13   61  VSS25 SCONN288_ADR50017P130CC-SCONN2A   I164 @S9S_MB_2U_LIB.S9S_MB_2U(SCH_1):PAGE94
   J13   63  VSS26 SCONN288_ADR50017P130CC-SCONN2A   I164 @S9S_MB_2U_LIB.S9S_MB_2U(SCH_1):PAGE94
   J13   65  VSS27 SCONN288_ADR50017P130CC-SCONN2A   I164 @S9S_MB_2U_LIB.S9S_MB_2U(SCH_1):PAGE94
   J13   67  VSS28 SCONN288_ADR50017P130CC-SCONN2A   I164 @S9S_MB_2U_LIB.S9S_MB_2U(SCH_1):PAGE94
   J13   69  VSS29 SCONN288_ADR50017P130CC-SCONN2A   I164 @S9S_MB_2U_LIB.S9S_MB_2U(SCH_1):PAGE94
   J13   71  VSS30 SCONN288_ADR50017P130CC-SCONN2A   I164 @S9S_MB_2U_LIB.S9S_MB_2U(SCH_1):PAGE94
   J13   73  VSS31 SCONN288_ADR50017P130CC-SCONN2A   I164 @S9S_MB_2U_LIB.S9S_MB_2U(SCH_1):PAGE94
   J13   75  VSS32 SCONN288_ADR50017P130CC-SCONN2A   I164 @S9S_MB_2U_LIB.S9S_MB_2U(SCH_1):PAGE94
   J13   77  VSS33 SCONN288_ADR50017P130CC-SCONN2A   I164 @S9S_MB_2U_LIB.S9S_MB_2U(SCH_1):PAGE94
   J13   79  VSS34 SCONN288_ADR50017P130CC-SCONN2A   I164 @S9S_MB_2U_LIB.S9S_MB_2U(SCH_1):PAGE94
   J13   81  VSS35 SCONN288_ADR50017P130CC-SCONN2A   I164 @S9S_MB_2U_LIB.S9S_MB_2U(SCH_1):PAGE94
   J13   83  VSS36 SCONN288_ADR50017P130CC-SCONN2A   I164 @S9S_MB_2U_LIB.S9S_MB_2U(SCH_1):PAGE94
   J13   85  VSS37 SCONN288_ADR50017P130CC-SCONN2A   I164 @S9S_MB_2U_LIB.S9S_MB_2U(SCH_1):PAGE94
   J13   88  VSS38 SCONN288_ADR50017P130CC-SCONN2A   I164 @S9S_MB_2U_LIB.S9S_MB_2U(SCH_1):PAGE94
   J13   90  VSS39 SCONN288_ADR50017P130CC-SCONN2A   I164 @S9S_MB_2U_LIB.S9S_MB_2U(SCH_1):PAGE94
   J13   92  VSS40 SCONN288_ADR50017P130CC-SCONN2A   I164 @S9S_MB_2U_LIB.S9S_MB_2U(SCH_1):PAGE94
   J13   95  VSS41 SCONN288_ADR50017P130CC-SCONN2A   I164 @S9S_MB_2U_LIB.S9S_MB_2U(SCH_1):PAGE94
   J13   97  VSS42 SCONN288_ADR50017P130CC-SCONN2A   I164 @S9S_MB_2U_LIB.S9S_MB_2U(SCH_1):PAGE94
   J13   99  VSS43 SCONN288_ADR50017P130CC-SCONN2A   I164 @S9S_MB_2U_LIB.S9S_MB_2U(SCH_1):PAGE94
   J13  101  VSS44 SCONN288_ADR50017P130CC-SCONN2A   I164 @S9S_MB_2U_LIB.S9S_MB_2U(SCH_1):PAGE94
   J13  103  VSS45 SCONN288_ADR50017P130CC-SCONN2A   I164 @S9S_MB_2U_LIB.S9S_MB_2U(SCH_1):PAGE94
   J13  106  VSS46 SCONN288_ADR50017P130CC-SCONN2A   I164 @S9S_MB_2U_LIB.S9S_MB_2U(SCH_1):PAGE94
   J13  108  VSS47 SCONN288_ADR50017P130CC-SCONN2A   I164 @S9S_MB_2U_LIB.S9S_MB_2U(SCH_1):PAGE94
   J13  110  VSS48 SCONN288_ADR50017P130CC-SCONN2A   I164 @S9S_MB_2U_LIB.S9S_MB_2U(SCH_1):PAGE94
   J13  112  VSS49 SCONN288_ADR50017P130CC-SCONN2A   I164 @S9S_MB_2U_LIB.S9S_MB_2U(SCH_1):PAGE94
   J13  114  VSS50 SCONN288_ADR50017P130CC-SCONN2A   I164 @S9S_MB_2U_LIB.S9S_MB_2U(SCH_1):PAGE94
   J13  117  VSS51 SCONN288_ADR50017P130CC-SCONN2A   I164 @S9S_MB_2U_LIB.S9S_MB_2U(SCH_1):PAGE94
   J13  119  VSS52 SCONN288_ADR50017P130CC-SCONN2A   I164 @S9S_MB_2U_LIB.S9S_MB_2U(SCH_1):PAGE94
   J13  121  VSS53 SCONN288_ADR50017P130CC-SCONN2A   I164 @S9S_MB_2U_LIB.S9S_MB_2U(SCH_1):PAGE94
   J13  123  VSS54 SCONN288_ADR50017P130CC-SCONN2A   I164 @S9S_MB_2U_LIB.S9S_MB_2U(SCH_1):PAGE94
   J13  125  VSS55 SCONN288_ADR50017P130CC-SCONN2A   I164 @S9S_MB_2U_LIB.S9S_MB_2U(SCH_1):PAGE94
   J13  128  VSS56 SCONN288_ADR50017P130CC-SCONN2A   I164 @S9S_MB_2U_LIB.S9S_MB_2U(SCH_1):PAGE94
   J13  130  VSS57 SCONN288_ADR50017P130CC-SCONN2A   I164 @S9S_MB_2U_LIB.S9S_MB_2U(SCH_1):PAGE94
   J13  132  VSS58 SCONN288_ADR50017P130CC-SCONN2A   I164 @S9S_MB_2U_LIB.S9S_MB_2U(SCH_1):PAGE94
   J13  134  VSS59 SCONN288_ADR50017P130CC-SCONN2A   I164 @S9S_MB_2U_LIB.S9S_MB_2U(SCH_1):PAGE94
   J13  136  VSS60 SCONN288_ADR50017P130CC-SCONN2A   I164 @S9S_MB_2U_LIB.S9S_MB_2U(SCH_1):PAGE94
   J13  139  VSS61 SCONN288_ADR50017P130CC-SCONN2A   I164 @S9S_MB_2U_LIB.S9S_MB_2U(SCH_1):PAGE94
   J13  141  VSS62 SCONN288_ADR50017P130CC-SCONN2A   I164 @S9S_MB_2U_LIB.S9S_MB_2U(SCH_1):PAGE94
   J13  143  VSS63 SCONN288_ADR50017P130CC-SCONN2A   I164 @S9S_MB_2U_LIB.S9S_MB_2U(SCH_1):PAGE94
   J13  151  VSS64 SCONN288_ADR50017P130CC-SCONN2A   I164 @S9S_MB_2U_LIB.S9S_MB_2U(SCH_1):PAGE94
   J13  153  VSS65 SCONN288_ADR50017P130CC-SCONN2A   I164 @S9S_MB_2U_LIB.S9S_MB_2U(SCH_1):PAGE94
   J13  155  VSS66 SCONN288_ADR50017P130CC-SCONN2A   I164 @S9S_MB_2U_LIB.S9S_MB_2U(SCH_1):PAGE94
   J13  158  VSS67 SCONN288_ADR50017P130CC-SCONN2A   I164 @S9S_MB_2U_LIB.S9S_MB_2U(SCH_1):PAGE94
   J13  160  VSS68 SCONN288_ADR50017P130CC-SCONN2A   I164 @S9S_MB_2U_LIB.S9S_MB_2U(SCH_1):PAGE94
   J13  162  VSS69 SCONN288_ADR50017P130CC-SCONN2A   I164 @S9S_MB_2U_LIB.S9S_MB_2U(SCH_1):PAGE94
   J13  164  VSS70 SCONN288_ADR50017P130CC-SCONN2A   I164 @S9S_MB_2U_LIB.S9S_MB_2U(SCH_1):PAGE94
   J13  166  VSS71 SCONN288_ADR50017P130CC-SCONN2A   I164 @S9S_MB_2U_LIB.S9S_MB_2U(SCH_1):PAGE94
   J13  169  VSS72 SCONN288_ADR50017P130CC-SCONN2A   I164 @S9S_MB_2U_LIB.S9S_MB_2U(SCH_1):PAGE94
   J13  171  VSS73 SCONN288_ADR50017P130CC-SCONN2A   I164 @S9S_MB_2U_LIB.S9S_MB_2U(SCH_1):PAGE94
   J13  173  VSS74 SCONN288_ADR50017P130CC-SCONN2A   I164 @S9S_MB_2U_LIB.S9S_MB_2U(SCH_1):PAGE94
   J13  175  VSS75 SCONN288_ADR50017P130CC-SCONN2A   I164 @S9S_MB_2U_LIB.S9S_MB_2U(SCH_1):PAGE94
   J13  177  VSS76 SCONN288_ADR50017P130CC-SCONN2A   I164 @S9S_MB_2U_LIB.S9S_MB_2U(SCH_1):PAGE94
   J13  180  VSS77 SCONN288_ADR50017P130CC-SCONN2A   I164 @S9S_MB_2U_LIB.S9S_MB_2U(SCH_1):PAGE94
   J13  182  VSS78 SCONN288_ADR50017P130CC-SCONN2A   I164 @S9S_MB_2U_LIB.S9S_MB_2U(SCH_1):PAGE94
   J13  184  VSS79 SCONN288_ADR50017P130CC-SCONN2A   I164 @S9S_MB_2U_LIB.S9S_MB_2U(SCH_1):PAGE94
   J13  186  VSS80 SCONN288_ADR50017P130CC-SCONN2A   I164 @S9S_MB_2U_LIB.S9S_MB_2U(SCH_1):PAGE94
   J13  188  VSS81 SCONN288_ADR50017P130CC-SCONN2A   I164 @S9S_MB_2U_LIB.S9S_MB_2U(SCH_1):PAGE94
   J13  191  VSS82 SCONN288_ADR50017P130CC-SCONN2A   I164 @S9S_MB_2U_LIB.S9S_MB_2U(SCH_1):PAGE94
   J13  193  VSS83 SCONN288_ADR50017P130CC-SCONN2A   I164 @S9S_MB_2U_LIB.S9S_MB_2U(SCH_1):PAGE94
   J13  195  VSS84 SCONN288_ADR50017P130CC-SCONN2A   I164 @S9S_MB_2U_LIB.S9S_MB_2U(SCH_1):PAGE94
   J13  197  VSS85 SCONN288_ADR50017P130CC-SCONN2A   I164 @S9S_MB_2U_LIB.S9S_MB_2U(SCH_1):PAGE94
   J13  199  VSS86 SCONN288_ADR50017P130CC-SCONN2A   I164 @S9S_MB_2U_LIB.S9S_MB_2U(SCH_1):PAGE94
   J13  202  VSS87 SCONN288_ADR50017P130CC-SCONN2A   I164 @S9S_MB_2U_LIB.S9S_MB_2U(SCH_1):PAGE94
   J13  204  VSS88 SCONN288_ADR50017P130CC-SCONN2A   I164 @S9S_MB_2U_LIB.S9S_MB_2U(SCH_1):PAGE94
   J13  206  VSS89 SCONN288_ADR50017P130CC-SCONN2A   I164 @S9S_MB_2U_LIB.S9S_MB_2U(SCH_1):PAGE94
   J13  208  VSS90 SCONN288_ADR50017P130CC-SCONN2A   I164 @S9S_MB_2U_LIB.S9S_MB_2U(SCH_1):PAGE94
   J13  210  VSS91 SCONN288_ADR50017P130CC-SCONN2A   I164 @S9S_MB_2U_LIB.S9S_MB_2U(SCH_1):PAGE94
   J13  212  VSS92 SCONN288_ADR50017P130CC-SCONN2A   I164 @S9S_MB_2U_LIB.S9S_MB_2U(SCH_1):PAGE94
   J13  214  VSS93 SCONN288_ADR50017P130CC-SCONN2A   I164 @S9S_MB_2U_LIB.S9S_MB_2U(SCH_1):PAGE94
   J13  216  VSS94 SCONN288_ADR50017P130CC-SCONN2A   I164 @S9S_MB_2U_LIB.S9S_MB_2U(SCH_1):PAGE94
   J13  219  VSS95 SCONN288_ADR50017P130CC-SCONN2A   I164 @S9S_MB_2U_LIB.S9S_MB_2U(SCH_1):PAGE94
   J13  222  VSS96 SCONN288_ADR50017P130CC-SCONN2A   I164 @S9S_MB_2U_LIB.S9S_MB_2U(SCH_1):PAGE94
   J13  224  VSS97 SCONN288_ADR50017P130CC-SCONN2A   I164 @S9S_MB_2U_LIB.S9S_MB_2U(SCH_1):PAGE94
   J13  226  VSS98 SCONN288_ADR50017P130CC-SCONN2A   I164 @S9S_MB_2U_LIB.S9S_MB_2U(SCH_1):PAGE94
   J13  228  VSS99 SCONN288_ADR50017P130CC-SCONN2A   I164 @S9S_MB_2U_LIB.S9S_MB_2U(SCH_1):PAGE94
   J13  230 VSS100 SCONN288_ADR50017P130CC-SCONN2A   I164 @S9S_MB_2U_LIB.S9S_MB_2U(SCH_1):PAGE94
   J13  233 VSS101 SCONN288_ADR50017P130CC-SCONN2A   I164 @S9S_MB_2U_LIB.S9S_MB_2U(SCH_1):PAGE94
   J13  235 VSS102 SCONN288_ADR50017P130CC-SCONN2A   I164 @S9S_MB_2U_LIB.S9S_MB_2U(SCH_1):PAGE94
   J13  237 VSS103 SCONN288_ADR50017P130CC-SCONN2A   I164 @S9S_MB_2U_LIB.S9S_MB_2U(SCH_1):PAGE94
   J13  240 VSS104 SCONN288_ADR50017P130CC-SCONN2A   I164 @S9S_MB_2U_LIB.S9S_MB_2U(SCH_1):PAGE94
   J13  242 VSS105 SCONN288_ADR50017P130CC-SCONN2A   I164 @S9S_MB_2U_LIB.S9S_MB_2U(SCH_1):PAGE94
   J13  244 VSS106 SCONN288_ADR50017P130CC-SCONN2A   I164 @S9S_MB_2U_LIB.S9S_MB_2U(SCH_1):PAGE94
   J13  246 VSS107 SCONN288_ADR50017P130CC-SCONN2A   I164 @S9S_MB_2U_LIB.S9S_MB_2U(SCH_1):PAGE94
   J13  248 VSS108 SCONN288_ADR50017P130CC-SCONN2A   I164 @S9S_MB_2U_LIB.S9S_MB_2U(SCH_1):PAGE94
   J13  251 VSS109 SCONN288_ADR50017P130CC-SCONN2A   I164 @S9S_MB_2U_LIB.S9S_MB_2U(SCH_1):PAGE94
   J13  253 VSS110 SCONN288_ADR50017P130CC-SCONN2A   I164 @S9S_MB_2U_LIB.S9S_MB_2U(SCH_1):PAGE94
   J13  255 VSS111 SCONN288_ADR50017P130CC-SCONN2A   I164 @S9S_MB_2U_LIB.S9S_MB_2U(SCH_1):PAGE94
   J13  257 VSS112 SCONN288_ADR50017P130CC-SCONN2A   I164 @S9S_MB_2U_LIB.S9S_MB_2U(SCH_1):PAGE94
   J13  259 VSS113 SCONN288_ADR50017P130CC-SCONN2A   I164 @S9S_MB_2U_LIB.S9S_MB_2U(SCH_1):PAGE94
   J13  262 VSS114 SCONN288_ADR50017P130CC-SCONN2A   I164 @S9S_MB_2U_LIB.S9S_MB_2U(SCH_1):PAGE94
   J13  264 VSS115 SCONN288_ADR50017P130CC-SCONN2A   I164 @S9S_MB_2U_LIB.S9S_MB_2U(SCH_1):PAGE94
   J13  266 VSS116 SCONN288_ADR50017P130CC-SCONN2A   I164 @S9S_MB_2U_LIB.S9S_MB_2U(SCH_1):PAGE94
   J13  268 VSS117 SCONN288_ADR50017P130CC-SCONN2A   I164 @S9S_MB_2U_LIB.S9S_MB_2U(SCH_1):PAGE94
   J13  270 VSS118 SCONN288_ADR50017P130CC-SCONN2A   I164 @S9S_MB_2U_LIB.S9S_MB_2U(SCH_1):PAGE94
   J13  273 VSS119 SCONN288_ADR50017P130CC-SCONN2A   I164 @S9S_MB_2U_LIB.S9S_MB_2U(SCH_1):PAGE94
   J13  275 VSS120 SCONN288_ADR50017P130CC-SCONN2A   I164 @S9S_MB_2U_LIB.S9S_MB_2U(SCH_1):PAGE94
   J13  277 VSS121 SCONN288_ADR50017P130CC-SCONN2A   I164 @S9S_MB_2U_LIB.S9S_MB_2U(SCH_1):PAGE94
   J13  279 VSS122 SCONN288_ADR50017P130CC-SCONN2A   I164 @S9S_MB_2U_LIB.S9S_MB_2U(SCH_1):PAGE94
   J13  281 VSS123 SCONN288_ADR50017P130CC-SCONN2A   I164 @S9S_MB_2U_LIB.S9S_MB_2U(SCH_1):PAGE94
   J13  284 VSS124 SCONN288_ADR50017P130CC-SCONN2A   I164 @S9S_MB_2U_LIB.S9S_MB_2U(SCH_1):PAGE94
   J13  286 VSS125 SCONN288_ADR50017P130CC-SCONN2A   I164 @S9S_MB_2U_LIB.S9S_MB_2U(SCH_1):PAGE94
   J13  288 VSS126 SCONN288_ADR50017P130CC-SCONN2A   I164 @S9S_MB_2U_LIB.S9S_MB_2U(SCH_1):PAGE94
   R39    2      B Q_RES_0402LF-84.5K,1%,1/16W,CHA    I46 @S9S_MB_2U_LIB.S9S_MB_2U(SCH_1):PAGE95
   C41    2      B Q_CAP_C0402-2.2UF,6.3V,20%,X6SA   I121 @S9S_MB_2U_LIB.S9S_MB_2U(SCH_1):PAGE95
   C42    2      B Q_CAP_C0805-10UF,16V,10%,X6S,CA   I125 @S9S_MB_2U_LIB.S9S_MB_2U(SCH_1):PAGE95
   C43    2      B Q_CAP_C0805-10UF,16V,10%,X6S,CA   I128 @S9S_MB_2U_LIB.S9S_MB_2U(SCH_1):PAGE95
   J14   G1     G1 SCONN288_ADR50017P087CC-SCONN2A   I176 @S9S_MB_2U_LIB.S9S_MB_2U(SCH_1):PAGE95
   J14   G2     G2 SCONN288_ADR50017P087CC-SCONN2A   I176 @S9S_MB_2U_LIB.S9S_MB_2U(SCH_1):PAGE95
   J14   G3     G3 SCONN288_ADR50017P087CC-SCONN2A   I176 @S9S_MB_2U_LIB.S9S_MB_2U(SCH_1):PAGE95
   J14    6   VSS0 SCONN288_ADR50017P087CC-SCONN2A   I176 @S9S_MB_2U_LIB.S9S_MB_2U(SCH_1):PAGE95
   J14    8   VSS1 SCONN288_ADR50017P087CC-SCONN2A   I176 @S9S_MB_2U_LIB.S9S_MB_2U(SCH_1):PAGE95
   J14   10   VSS2 SCONN288_ADR50017P087CC-SCONN2A   I176 @S9S_MB_2U_LIB.S9S_MB_2U(SCH_1):PAGE95
   J14   13   VSS3 SCONN288_ADR50017P087CC-SCONN2A   I176 @S9S_MB_2U_LIB.S9S_MB_2U(SCH_1):PAGE95
   J14   15   VSS4 SCONN288_ADR50017P087CC-SCONN2A   I176 @S9S_MB_2U_LIB.S9S_MB_2U(SCH_1):PAGE95
   J14   17   VSS5 SCONN288_ADR50017P087CC-SCONN2A   I176 @S9S_MB_2U_LIB.S9S_MB_2U(SCH_1):PAGE95
   J14   19   VSS6 SCONN288_ADR50017P087CC-SCONN2A   I176 @S9S_MB_2U_LIB.S9S_MB_2U(SCH_1):PAGE95
   J14   21   VSS7 SCONN288_ADR50017P087CC-SCONN2A   I176 @S9S_MB_2U_LIB.S9S_MB_2U(SCH_1):PAGE95
   J14   24   VSS8 SCONN288_ADR50017P087CC-SCONN2A   I176 @S9S_MB_2U_LIB.S9S_MB_2U(SCH_1):PAGE95
   J14   26   VSS9 SCONN288_ADR50017P087CC-SCONN2A   I176 @S9S_MB_2U_LIB.S9S_MB_2U(SCH_1):PAGE95
   J14   28  VSS10 SCONN288_ADR50017P087CC-SCONN2A   I176 @S9S_MB_2U_LIB.S9S_MB_2U(SCH_1):PAGE95
   J14   30  VSS11 SCONN288_ADR50017P087CC-SCONN2A   I176 @S9S_MB_2U_LIB.S9S_MB_2U(SCH_1):PAGE95
   J14   32  VSS12 SCONN288_ADR50017P087CC-SCONN2A   I176 @S9S_MB_2U_LIB.S9S_MB_2U(SCH_1):PAGE95
   J14   35  VSS13 SCONN288_ADR50017P087CC-SCONN2A   I176 @S9S_MB_2U_LIB.S9S_MB_2U(SCH_1):PAGE95
   J14   37  VSS14 SCONN288_ADR50017P087CC-SCONN2A   I176 @S9S_MB_2U_LIB.S9S_MB_2U(SCH_1):PAGE95
   J14   39  VSS15 SCONN288_ADR50017P087CC-SCONN2A   I176 @S9S_MB_2U_LIB.S9S_MB_2U(SCH_1):PAGE95
   J14   41  VSS16 SCONN288_ADR50017P087CC-SCONN2A   I176 @S9S_MB_2U_LIB.S9S_MB_2U(SCH_1):PAGE95
   J14   43  VSS17 SCONN288_ADR50017P087CC-SCONN2A   I176 @S9S_MB_2U_LIB.S9S_MB_2U(SCH_1):PAGE95
   J14   46  VSS18 SCONN288_ADR50017P087CC-SCONN2A   I176 @S9S_MB_2U_LIB.S9S_MB_2U(SCH_1):PAGE95
   J14   48  VSS19 SCONN288_ADR50017P087CC-SCONN2A   I176 @S9S_MB_2U_LIB.S9S_MB_2U(SCH_1):PAGE95
   J14   50  VSS20 SCONN288_ADR50017P087CC-SCONN2A   I176 @S9S_MB_2U_LIB.S9S_MB_2U(SCH_1):PAGE95
   J14   52  VSS21 SCONN288_ADR50017P087CC-SCONN2A   I176 @S9S_MB_2U_LIB.S9S_MB_2U(SCH_1):PAGE95
   J14   54  VSS22 SCONN288_ADR50017P087CC-SCONN2A   I176 @S9S_MB_2U_LIB.S9S_MB_2U(SCH_1):PAGE95
   J14   57  VSS23 SCONN288_ADR50017P087CC-SCONN2A   I176 @S9S_MB_2U_LIB.S9S_MB_2U(SCH_1):PAGE95
   J14   59  VSS24 SCONN288_ADR50017P087CC-SCONN2A   I176 @S9S_MB_2U_LIB.S9S_MB_2U(SCH_1):PAGE95
   J14   61  VSS25 SCONN288_ADR50017P087CC-SCONN2A   I176 @S9S_MB_2U_LIB.S9S_MB_2U(SCH_1):PAGE95
   J14   63  VSS26 SCONN288_ADR50017P087CC-SCONN2A   I176 @S9S_MB_2U_LIB.S9S_MB_2U(SCH_1):PAGE95
   J14   65  VSS27 SCONN288_ADR50017P087CC-SCONN2A   I176 @S9S_MB_2U_LIB.S9S_MB_2U(SCH_1):PAGE95
   J14   67  VSS28 SCONN288_ADR50017P087CC-SCONN2A   I176 @S9S_MB_2U_LIB.S9S_MB_2U(SCH_1):PAGE95
   J14   69  VSS29 SCONN288_ADR50017P087CC-SCONN2A   I176 @S9S_MB_2U_LIB.S9S_MB_2U(SCH_1):PAGE95
   J14   71  VSS30 SCONN288_ADR50017P087CC-SCONN2A   I176 @S9S_MB_2U_LIB.S9S_MB_2U(SCH_1):PAGE95
   J14   73  VSS31 SCONN288_ADR50017P087CC-SCONN2A   I176 @S9S_MB_2U_LIB.S9S_MB_2U(SCH_1):PAGE95
   J14   75  VSS32 SCONN288_ADR50017P087CC-SCONN2A   I176 @S9S_MB_2U_LIB.S9S_MB_2U(SCH_1):PAGE95
   J14   77  VSS33 SCONN288_ADR50017P087CC-SCONN2A   I176 @S9S_MB_2U_LIB.S9S_MB_2U(SCH_1):PAGE95
   J14   79  VSS34 SCONN288_ADR50017P087CC-SCONN2A   I176 @S9S_MB_2U_LIB.S9S_MB_2U(SCH_1):PAGE95
   J14   81  VSS35 SCONN288_ADR50017P087CC-SCONN2A   I176 @S9S_MB_2U_LIB.S9S_MB_2U(SCH_1):PAGE95
   J14   83  VSS36 SCONN288_ADR50017P087CC-SCONN2A   I176 @S9S_MB_2U_LIB.S9S_MB_2U(SCH_1):PAGE95
   J14   85  VSS37 SCONN288_ADR50017P087CC-SCONN2A   I176 @S9S_MB_2U_LIB.S9S_MB_2U(SCH_1):PAGE95
   J14   88  VSS38 SCONN288_ADR50017P087CC-SCONN2A   I176 @S9S_MB_2U_LIB.S9S_MB_2U(SCH_1):PAGE95
   J14   90  VSS39 SCONN288_ADR50017P087CC-SCONN2A   I176 @S9S_MB_2U_LIB.S9S_MB_2U(SCH_1):PAGE95
   J14   92  VSS40 SCONN288_ADR50017P087CC-SCONN2A   I176 @S9S_MB_2U_LIB.S9S_MB_2U(SCH_1):PAGE95
   J14   95  VSS41 SCONN288_ADR50017P087CC-SCONN2A   I176 @S9S_MB_2U_LIB.S9S_MB_2U(SCH_1):PAGE95
   J14   97  VSS42 SCONN288_ADR50017P087CC-SCONN2A   I176 @S9S_MB_2U_LIB.S9S_MB_2U(SCH_1):PAGE95
   J14   99  VSS43 SCONN288_ADR50017P087CC-SCONN2A   I176 @S9S_MB_2U_LIB.S9S_MB_2U(SCH_1):PAGE95
   J14  101  VSS44 SCONN288_ADR50017P087CC-SCONN2A   I176 @S9S_MB_2U_LIB.S9S_MB_2U(SCH_1):PAGE95
   J14  103  VSS45 SCONN288_ADR50017P087CC-SCONN2A   I176 @S9S_MB_2U_LIB.S9S_MB_2U(SCH_1):PAGE95
   J14  106  VSS46 SCONN288_ADR50017P087CC-SCONN2A   I176 @S9S_MB_2U_LIB.S9S_MB_2U(SCH_1):PAGE95
   J14  108  VSS47 SCONN288_ADR50017P087CC-SCONN2A   I176 @S9S_MB_2U_LIB.S9S_MB_2U(SCH_1):PAGE95
   J14  110  VSS48 SCONN288_ADR50017P087CC-SCONN2A   I176 @S9S_MB_2U_LIB.S9S_MB_2U(SCH_1):PAGE95
   J14  112  VSS49 SCONN288_ADR50017P087CC-SCONN2A   I176 @S9S_MB_2U_LIB.S9S_MB_2U(SCH_1):PAGE95
   J14  114  VSS50 SCONN288_ADR50017P087CC-SCONN2A   I176 @S9S_MB_2U_LIB.S9S_MB_2U(SCH_1):PAGE95
   J14  117  VSS51 SCONN288_ADR50017P087CC-SCONN2A   I176 @S9S_MB_2U_LIB.S9S_MB_2U(SCH_1):PAGE95
   J14  119  VSS52 SCONN288_ADR50017P087CC-SCONN2A   I176 @S9S_MB_2U_LIB.S9S_MB_2U(SCH_1):PAGE95
   J14  121  VSS53 SCONN288_ADR50017P087CC-SCONN2A   I176 @S9S_MB_2U_LIB.S9S_MB_2U(SCH_1):PAGE95
   J14  123  VSS54 SCONN288_ADR50017P087CC-SCONN2A   I176 @S9S_MB_2U_LIB.S9S_MB_2U(SCH_1):PAGE95
   J14  125  VSS55 SCONN288_ADR50017P087CC-SCONN2A   I176 @S9S_MB_2U_LIB.S9S_MB_2U(SCH_1):PAGE95
   J14  128  VSS56 SCONN288_ADR50017P087CC-SCONN2A   I176 @S9S_MB_2U_LIB.S9S_MB_2U(SCH_1):PAGE95
   J14  130  VSS57 SCONN288_ADR50017P087CC-SCONN2A   I176 @S9S_MB_2U_LIB.S9S_MB_2U(SCH_1):PAGE95
   J14  132  VSS58 SCONN288_ADR50017P087CC-SCONN2A   I176 @S9S_MB_2U_LIB.S9S_MB_2U(SCH_1):PAGE95
   J14  134  VSS59 SCONN288_ADR50017P087CC-SCONN2A   I176 @S9S_MB_2U_LIB.S9S_MB_2U(SCH_1):PAGE95
   J14  136  VSS60 SCONN288_ADR50017P087CC-SCONN2A   I176 @S9S_MB_2U_LIB.S9S_MB_2U(SCH_1):PAGE95
   J14  139  VSS61 SCONN288_ADR50017P087CC-SCONN2A   I176 @S9S_MB_2U_LIB.S9S_MB_2U(SCH_1):PAGE95
   J14  141  VSS62 SCONN288_ADR50017P087CC-SCONN2A   I176 @S9S_MB_2U_LIB.S9S_MB_2U(SCH_1):PAGE95
   J14  143  VSS63 SCONN288_ADR50017P087CC-SCONN2A   I176 @S9S_MB_2U_LIB.S9S_MB_2U(SCH_1):PAGE95
   J14  151  VSS64 SCONN288_ADR50017P087CC-SCONN2A   I176 @S9S_MB_2U_LIB.S9S_MB_2U(SCH_1):PAGE95
   J14  153  VSS65 SCONN288_ADR50017P087CC-SCONN2A   I176 @S9S_MB_2U_LIB.S9S_MB_2U(SCH_1):PAGE95
   J14  155  VSS66 SCONN288_ADR50017P087CC-SCONN2A   I176 @S9S_MB_2U_LIB.S9S_MB_2U(SCH_1):PAGE95
   J14  158  VSS67 SCONN288_ADR50017P087CC-SCONN2A   I176 @S9S_MB_2U_LIB.S9S_MB_2U(SCH_1):PAGE95
   J14  160  VSS68 SCONN288_ADR50017P087CC-SCONN2A   I176 @S9S_MB_2U_LIB.S9S_MB_2U(SCH_1):PAGE95
   J14  162  VSS69 SCONN288_ADR50017P087CC-SCONN2A   I176 @S9S_MB_2U_LIB.S9S_MB_2U(SCH_1):PAGE95
   J14  164  VSS70 SCONN288_ADR50017P087CC-SCONN2A   I176 @S9S_MB_2U_LIB.S9S_MB_2U(SCH_1):PAGE95
   J14  166  VSS71 SCONN288_ADR50017P087CC-SCONN2A   I176 @S9S_MB_2U_LIB.S9S_MB_2U(SCH_1):PAGE95
   J14  169  VSS72 SCONN288_ADR50017P087CC-SCONN2A   I176 @S9S_MB_2U_LIB.S9S_MB_2U(SCH_1):PAGE95
   J14  171  VSS73 SCONN288_ADR50017P087CC-SCONN2A   I176 @S9S_MB_2U_LIB.S9S_MB_2U(SCH_1):PAGE95
   J14  173  VSS74 SCONN288_ADR50017P087CC-SCONN2A   I176 @S9S_MB_2U_LIB.S9S_MB_2U(SCH_1):PAGE95
   J14  175  VSS75 SCONN288_ADR50017P087CC-SCONN2A   I176 @S9S_MB_2U_LIB.S9S_MB_2U(SCH_1):PAGE95
   J14  177  VSS76 SCONN288_ADR50017P087CC-SCONN2A   I176 @S9S_MB_2U_LIB.S9S_MB_2U(SCH_1):PAGE95
   J14  180  VSS77 SCONN288_ADR50017P087CC-SCONN2A   I176 @S9S_MB_2U_LIB.S9S_MB_2U(SCH_1):PAGE95
   J14  182  VSS78 SCONN288_ADR50017P087CC-SCONN2A   I176 @S9S_MB_2U_LIB.S9S_MB_2U(SCH_1):PAGE95
   J14  184  VSS79 SCONN288_ADR50017P087CC-SCONN2A   I176 @S9S_MB_2U_LIB.S9S_MB_2U(SCH_1):PAGE95
   J14  186  VSS80 SCONN288_ADR50017P087CC-SCONN2A   I176 @S9S_MB_2U_LIB.S9S_MB_2U(SCH_1):PAGE95
   J14  188  VSS81 SCONN288_ADR50017P087CC-SCONN2A   I176 @S9S_MB_2U_LIB.S9S_MB_2U(SCH_1):PAGE95
   J14  191  VSS82 SCONN288_ADR50017P087CC-SCONN2A   I176 @S9S_MB_2U_LIB.S9S_MB_2U(SCH_1):PAGE95
   J14  193  VSS83 SCONN288_ADR50017P087CC-SCONN2A   I176 @S9S_MB_2U_LIB.S9S_MB_2U(SCH_1):PAGE95
   J14  195  VSS84 SCONN288_ADR50017P087CC-SCONN2A   I176 @S9S_MB_2U_LIB.S9S_MB_2U(SCH_1):PAGE95
   J14  197  VSS85 SCONN288_ADR50017P087CC-SCONN2A   I176 @S9S_MB_2U_LIB.S9S_MB_2U(SCH_1):PAGE95
   J14  199  VSS86 SCONN288_ADR50017P087CC-SCONN2A   I176 @S9S_MB_2U_LIB.S9S_MB_2U(SCH_1):PAGE95
   J14  202  VSS87 SCONN288_ADR50017P087CC-SCONN2A   I176 @S9S_MB_2U_LIB.S9S_MB_2U(SCH_1):PAGE95
   J14  204  VSS88 SCONN288_ADR50017P087CC-SCONN2A   I176 @S9S_MB_2U_LIB.S9S_MB_2U(SCH_1):PAGE95
   J14  206  VSS89 SCONN288_ADR50017P087CC-SCONN2A   I176 @S9S_MB_2U_LIB.S9S_MB_2U(SCH_1):PAGE95
   J14  208  VSS90 SCONN288_ADR50017P087CC-SCONN2A   I176 @S9S_MB_2U_LIB.S9S_MB_2U(SCH_1):PAGE95
   J14  210  VSS91 SCONN288_ADR50017P087CC-SCONN2A   I176 @S9S_MB_2U_LIB.S9S_MB_2U(SCH_1):PAGE95
   J14  212  VSS92 SCONN288_ADR50017P087CC-SCONN2A   I176 @S9S_MB_2U_LIB.S9S_MB_2U(SCH_1):PAGE95
   J14  214  VSS93 SCONN288_ADR50017P087CC-SCONN2A   I176 @S9S_MB_2U_LIB.S9S_MB_2U(SCH_1):PAGE95
   J14  216  VSS94 SCONN288_ADR50017P087CC-SCONN2A   I176 @S9S_MB_2U_LIB.S9S_MB_2U(SCH_1):PAGE95
   J14  219  VSS95 SCONN288_ADR50017P087CC-SCONN2A   I176 @S9S_MB_2U_LIB.S9S_MB_2U(SCH_1):PAGE95
   J14  222  VSS96 SCONN288_ADR50017P087CC-SCONN2A   I176 @S9S_MB_2U_LIB.S9S_MB_2U(SCH_1):PAGE95
   J14  224  VSS97 SCONN288_ADR50017P087CC-SCONN2A   I176 @S9S_MB_2U_LIB.S9S_MB_2U(SCH_1):PAGE95
   J14  226  VSS98 SCONN288_ADR50017P087CC-SCONN2A   I176 @S9S_MB_2U_LIB.S9S_MB_2U(SCH_1):PAGE95
   J14  228  VSS99 SCONN288_ADR50017P087CC-SCONN2A   I176 @S9S_MB_2U_LIB.S9S_MB_2U(SCH_1):PAGE95
   J14  230 VSS100 SCONN288_ADR50017P087CC-SCONN2A   I176 @S9S_MB_2U_LIB.S9S_MB_2U(SCH_1):PAGE95
   J14  233 VSS101 SCONN288_ADR50017P087CC-SCONN2A   I176 @S9S_MB_2U_LIB.S9S_MB_2U(SCH_1):PAGE95
   J14  235 VSS102 SCONN288_ADR50017P087CC-SCONN2A   I176 @S9S_MB_2U_LIB.S9S_MB_2U(SCH_1):PAGE95
   J14  237 VSS103 SCONN288_ADR50017P087CC-SCONN2A   I176 @S9S_MB_2U_LIB.S9S_MB_2U(SCH_1):PAGE95
   J14  240 VSS104 SCONN288_ADR50017P087CC-SCONN2A   I176 @S9S_MB_2U_LIB.S9S_MB_2U(SCH_1):PAGE95
   J14  242 VSS105 SCONN288_ADR50017P087CC-SCONN2A   I176 @S9S_MB_2U_LIB.S9S_MB_2U(SCH_1):PAGE95
   J14  244 VSS106 SCONN288_ADR50017P087CC-SCONN2A   I176 @S9S_MB_2U_LIB.S9S_MB_2U(SCH_1):PAGE95
   J14  246 VSS107 SCONN288_ADR50017P087CC-SCONN2A   I176 @S9S_MB_2U_LIB.S9S_MB_2U(SCH_1):PAGE95
   J14  248 VSS108 SCONN288_ADR50017P087CC-SCONN2A   I176 @S9S_MB_2U_LIB.S9S_MB_2U(SCH_1):PAGE95
   J14  251 VSS109 SCONN288_ADR50017P087CC-SCONN2A   I176 @S9S_MB_2U_LIB.S9S_MB_2U(SCH_1):PAGE95
   J14  253 VSS110 SCONN288_ADR50017P087CC-SCONN2A   I176 @S9S_MB_2U_LIB.S9S_MB_2U(SCH_1):PAGE95
   J14  255 VSS111 SCONN288_ADR50017P087CC-SCONN2A   I176 @S9S_MB_2U_LIB.S9S_MB_2U(SCH_1):PAGE95
   J14  257 VSS112 SCONN288_ADR50017P087CC-SCONN2A   I176 @S9S_MB_2U_LIB.S9S_MB_2U(SCH_1):PAGE95
   J14  259 VSS113 SCONN288_ADR50017P087CC-SCONN2A   I176 @S9S_MB_2U_LIB.S9S_MB_2U(SCH_1):PAGE95
   J14  262 VSS114 SCONN288_ADR50017P087CC-SCONN2A   I176 @S9S_MB_2U_LIB.S9S_MB_2U(SCH_1):PAGE95
   J14  264 VSS115 SCONN288_ADR50017P087CC-SCONN2A   I176 @S9S_MB_2U_LIB.S9S_MB_2U(SCH_1):PAGE95
   J14  266 VSS116 SCONN288_ADR50017P087CC-SCONN2A   I176 @S9S_MB_2U_LIB.S9S_MB_2U(SCH_1):PAGE95
   J14  268 VSS117 SCONN288_ADR50017P087CC-SCONN2A   I176 @S9S_MB_2U_LIB.S9S_MB_2U(SCH_1):PAGE95
   J14  270 VSS118 SCONN288_ADR50017P087CC-SCONN2A   I176 @S9S_MB_2U_LIB.S9S_MB_2U(SCH_1):PAGE95
   J14  273 VSS119 SCONN288_ADR50017P087CC-SCONN2A   I176 @S9S_MB_2U_LIB.S9S_MB_2U(SCH_1):PAGE95
   J14  275 VSS120 SCONN288_ADR50017P087CC-SCONN2A   I176 @S9S_MB_2U_LIB.S9S_MB_2U(SCH_1):PAGE95
   J14  277 VSS121 SCONN288_ADR50017P087CC-SCONN2A   I176 @S9S_MB_2U_LIB.S9S_MB_2U(SCH_1):PAGE95
   J14  279 VSS122 SCONN288_ADR50017P087CC-SCONN2A   I176 @S9S_MB_2U_LIB.S9S_MB_2U(SCH_1):PAGE95
   J14  281 VSS123 SCONN288_ADR50017P087CC-SCONN2A   I176 @S9S_MB_2U_LIB.S9S_MB_2U(SCH_1):PAGE95
   J14  284 VSS124 SCONN288_ADR50017P087CC-SCONN2A   I176 @S9S_MB_2U_LIB.S9S_MB_2U(SCH_1):PAGE95
   J14  286 VSS125 SCONN288_ADR50017P087CC-SCONN2A   I176 @S9S_MB_2U_LIB.S9S_MB_2U(SCH_1):PAGE95
   J14  288 VSS126 SCONN288_ADR50017P087CC-SCONN2A   I176 @S9S_MB_2U_LIB.S9S_MB_2U(SCH_1):PAGE95
   R40    2      B Q_RES_0402LF-127K,1%,1/16W,CHIA    I47 @S9S_MB_2U_LIB.S9S_MB_2U(SCH_1):PAGE96
   C44    2      B Q_CAP_C0402-2.2UF,6.3V,20%,X6SA   I121 @S9S_MB_2U_LIB.S9S_MB_2U(SCH_1):PAGE96
   C45    2      B Q_CAP_C0805-10UF,16V,10%,X6S,CA   I125 @S9S_MB_2U_LIB.S9S_MB_2U(SCH_1):PAGE96
   C46    2      B Q_CAP_C0805-10UF,16V,10%,X6S,CA   I127 @S9S_MB_2U_LIB.S9S_MB_2U(SCH_1):PAGE96
   J15   G1     G1 SCONN288_ADR50017P130CC-SCONN2A   I176 @S9S_MB_2U_LIB.S9S_MB_2U(SCH_1):PAGE96
   J15   G2     G2 SCONN288_ADR50017P130CC-SCONN2A   I176 @S9S_MB_2U_LIB.S9S_MB_2U(SCH_1):PAGE96
   J15   G3     G3 SCONN288_ADR50017P130CC-SCONN2A   I176 @S9S_MB_2U_LIB.S9S_MB_2U(SCH_1):PAGE96
   J15    6   VSS0 SCONN288_ADR50017P130CC-SCONN2A   I176 @S9S_MB_2U_LIB.S9S_MB_2U(SCH_1):PAGE96
   J15    8   VSS1 SCONN288_ADR50017P130CC-SCONN2A   I176 @S9S_MB_2U_LIB.S9S_MB_2U(SCH_1):PAGE96
   J15   10   VSS2 SCONN288_ADR50017P130CC-SCONN2A   I176 @S9S_MB_2U_LIB.S9S_MB_2U(SCH_1):PAGE96
   J15   13   VSS3 SCONN288_ADR50017P130CC-SCONN2A   I176 @S9S_MB_2U_LIB.S9S_MB_2U(SCH_1):PAGE96
   J15   15   VSS4 SCONN288_ADR50017P130CC-SCONN2A   I176 @S9S_MB_2U_LIB.S9S_MB_2U(SCH_1):PAGE96
   J15   17   VSS5 SCONN288_ADR50017P130CC-SCONN2A   I176 @S9S_MB_2U_LIB.S9S_MB_2U(SCH_1):PAGE96
   J15   19   VSS6 SCONN288_ADR50017P130CC-SCONN2A   I176 @S9S_MB_2U_LIB.S9S_MB_2U(SCH_1):PAGE96
   J15   21   VSS7 SCONN288_ADR50017P130CC-SCONN2A   I176 @S9S_MB_2U_LIB.S9S_MB_2U(SCH_1):PAGE96
   J15   24   VSS8 SCONN288_ADR50017P130CC-SCONN2A   I176 @S9S_MB_2U_LIB.S9S_MB_2U(SCH_1):PAGE96
   J15   26   VSS9 SCONN288_ADR50017P130CC-SCONN2A   I176 @S9S_MB_2U_LIB.S9S_MB_2U(SCH_1):PAGE96
   J15   28  VSS10 SCONN288_ADR50017P130CC-SCONN2A   I176 @S9S_MB_2U_LIB.S9S_MB_2U(SCH_1):PAGE96
   J15   30  VSS11 SCONN288_ADR50017P130CC-SCONN2A   I176 @S9S_MB_2U_LIB.S9S_MB_2U(SCH_1):PAGE96
   J15   32  VSS12 SCONN288_ADR50017P130CC-SCONN2A   I176 @S9S_MB_2U_LIB.S9S_MB_2U(SCH_1):PAGE96
   J15   35  VSS13 SCONN288_ADR50017P130CC-SCONN2A   I176 @S9S_MB_2U_LIB.S9S_MB_2U(SCH_1):PAGE96
   J15   37  VSS14 SCONN288_ADR50017P130CC-SCONN2A   I176 @S9S_MB_2U_LIB.S9S_MB_2U(SCH_1):PAGE96
   J15   39  VSS15 SCONN288_ADR50017P130CC-SCONN2A   I176 @S9S_MB_2U_LIB.S9S_MB_2U(SCH_1):PAGE96
   J15   41  VSS16 SCONN288_ADR50017P130CC-SCONN2A   I176 @S9S_MB_2U_LIB.S9S_MB_2U(SCH_1):PAGE96
   J15   43  VSS17 SCONN288_ADR50017P130CC-SCONN2A   I176 @S9S_MB_2U_LIB.S9S_MB_2U(SCH_1):PAGE96
   J15   46  VSS18 SCONN288_ADR50017P130CC-SCONN2A   I176 @S9S_MB_2U_LIB.S9S_MB_2U(SCH_1):PAGE96
   J15   48  VSS19 SCONN288_ADR50017P130CC-SCONN2A   I176 @S9S_MB_2U_LIB.S9S_MB_2U(SCH_1):PAGE96
   J15   50  VSS20 SCONN288_ADR50017P130CC-SCONN2A   I176 @S9S_MB_2U_LIB.S9S_MB_2U(SCH_1):PAGE96
   J15   52  VSS21 SCONN288_ADR50017P130CC-SCONN2A   I176 @S9S_MB_2U_LIB.S9S_MB_2U(SCH_1):PAGE96
   J15   54  VSS22 SCONN288_ADR50017P130CC-SCONN2A   I176 @S9S_MB_2U_LIB.S9S_MB_2U(SCH_1):PAGE96
   J15   57  VSS23 SCONN288_ADR50017P130CC-SCONN2A   I176 @S9S_MB_2U_LIB.S9S_MB_2U(SCH_1):PAGE96
   J15   59  VSS24 SCONN288_ADR50017P130CC-SCONN2A   I176 @S9S_MB_2U_LIB.S9S_MB_2U(SCH_1):PAGE96
   J15   61  VSS25 SCONN288_ADR50017P130CC-SCONN2A   I176 @S9S_MB_2U_LIB.S9S_MB_2U(SCH_1):PAGE96
   J15   63  VSS26 SCONN288_ADR50017P130CC-SCONN2A   I176 @S9S_MB_2U_LIB.S9S_MB_2U(SCH_1):PAGE96
   J15   65  VSS27 SCONN288_ADR50017P130CC-SCONN2A   I176 @S9S_MB_2U_LIB.S9S_MB_2U(SCH_1):PAGE96
   J15   67  VSS28 SCONN288_ADR50017P130CC-SCONN2A   I176 @S9S_MB_2U_LIB.S9S_MB_2U(SCH_1):PAGE96
   J15   69  VSS29 SCONN288_ADR50017P130CC-SCONN2A   I176 @S9S_MB_2U_LIB.S9S_MB_2U(SCH_1):PAGE96
   J15   71  VSS30 SCONN288_ADR50017P130CC-SCONN2A   I176 @S9S_MB_2U_LIB.S9S_MB_2U(SCH_1):PAGE96
   J15   73  VSS31 SCONN288_ADR50017P130CC-SCONN2A   I176 @S9S_MB_2U_LIB.S9S_MB_2U(SCH_1):PAGE96
   J15   75  VSS32 SCONN288_ADR50017P130CC-SCONN2A   I176 @S9S_MB_2U_LIB.S9S_MB_2U(SCH_1):PAGE96
   J15   77  VSS33 SCONN288_ADR50017P130CC-SCONN2A   I176 @S9S_MB_2U_LIB.S9S_MB_2U(SCH_1):PAGE96
   J15   79  VSS34 SCONN288_ADR50017P130CC-SCONN2A   I176 @S9S_MB_2U_LIB.S9S_MB_2U(SCH_1):PAGE96
   J15   81  VSS35 SCONN288_ADR50017P130CC-SCONN2A   I176 @S9S_MB_2U_LIB.S9S_MB_2U(SCH_1):PAGE96
   J15   83  VSS36 SCONN288_ADR50017P130CC-SCONN2A   I176 @S9S_MB_2U_LIB.S9S_MB_2U(SCH_1):PAGE96
   J15   85  VSS37 SCONN288_ADR50017P130CC-SCONN2A   I176 @S9S_MB_2U_LIB.S9S_MB_2U(SCH_1):PAGE96
   J15   88  VSS38 SCONN288_ADR50017P130CC-SCONN2A   I176 @S9S_MB_2U_LIB.S9S_MB_2U(SCH_1):PAGE96
   J15   90  VSS39 SCONN288_ADR50017P130CC-SCONN2A   I176 @S9S_MB_2U_LIB.S9S_MB_2U(SCH_1):PAGE96
   J15   92  VSS40 SCONN288_ADR50017P130CC-SCONN2A   I176 @S9S_MB_2U_LIB.S9S_MB_2U(SCH_1):PAGE96
   J15   95  VSS41 SCONN288_ADR50017P130CC-SCONN2A   I176 @S9S_MB_2U_LIB.S9S_MB_2U(SCH_1):PAGE96
   J15   97  VSS42 SCONN288_ADR50017P130CC-SCONN2A   I176 @S9S_MB_2U_LIB.S9S_MB_2U(SCH_1):PAGE96
   J15   99  VSS43 SCONN288_ADR50017P130CC-SCONN2A   I176 @S9S_MB_2U_LIB.S9S_MB_2U(SCH_1):PAGE96
   J15  101  VSS44 SCONN288_ADR50017P130CC-SCONN2A   I176 @S9S_MB_2U_LIB.S9S_MB_2U(SCH_1):PAGE96
   J15  103  VSS45 SCONN288_ADR50017P130CC-SCONN2A   I176 @S9S_MB_2U_LIB.S9S_MB_2U(SCH_1):PAGE96
   J15  106  VSS46 SCONN288_ADR50017P130CC-SCONN2A   I176 @S9S_MB_2U_LIB.S9S_MB_2U(SCH_1):PAGE96
   J15  108  VSS47 SCONN288_ADR50017P130CC-SCONN2A   I176 @S9S_MB_2U_LIB.S9S_MB_2U(SCH_1):PAGE96
   J15  110  VSS48 SCONN288_ADR50017P130CC-SCONN2A   I176 @S9S_MB_2U_LIB.S9S_MB_2U(SCH_1):PAGE96
   J15  112  VSS49 SCONN288_ADR50017P130CC-SCONN2A   I176 @S9S_MB_2U_LIB.S9S_MB_2U(SCH_1):PAGE96
   J15  114  VSS50 SCONN288_ADR50017P130CC-SCONN2A   I176 @S9S_MB_2U_LIB.S9S_MB_2U(SCH_1):PAGE96
   J15  117  VSS51 SCONN288_ADR50017P130CC-SCONN2A   I176 @S9S_MB_2U_LIB.S9S_MB_2U(SCH_1):PAGE96
   J15  119  VSS52 SCONN288_ADR50017P130CC-SCONN2A   I176 @S9S_MB_2U_LIB.S9S_MB_2U(SCH_1):PAGE96
   J15  121  VSS53 SCONN288_ADR50017P130CC-SCONN2A   I176 @S9S_MB_2U_LIB.S9S_MB_2U(SCH_1):PAGE96
   J15  123  VSS54 SCONN288_ADR50017P130CC-SCONN2A   I176 @S9S_MB_2U_LIB.S9S_MB_2U(SCH_1):PAGE96
   J15  125  VSS55 SCONN288_ADR50017P130CC-SCONN2A   I176 @S9S_MB_2U_LIB.S9S_MB_2U(SCH_1):PAGE96
   J15  128  VSS56 SCONN288_ADR50017P130CC-SCONN2A   I176 @S9S_MB_2U_LIB.S9S_MB_2U(SCH_1):PAGE96
   J15  130  VSS57 SCONN288_ADR50017P130CC-SCONN2A   I176 @S9S_MB_2U_LIB.S9S_MB_2U(SCH_1):PAGE96
   J15  132  VSS58 SCONN288_ADR50017P130CC-SCONN2A   I176 @S9S_MB_2U_LIB.S9S_MB_2U(SCH_1):PAGE96
   J15  134  VSS59 SCONN288_ADR50017P130CC-SCONN2A   I176 @S9S_MB_2U_LIB.S9S_MB_2U(SCH_1):PAGE96
   J15  136  VSS60 SCONN288_ADR50017P130CC-SCONN2A   I176 @S9S_MB_2U_LIB.S9S_MB_2U(SCH_1):PAGE96
   J15  139  VSS61 SCONN288_ADR50017P130CC-SCONN2A   I176 @S9S_MB_2U_LIB.S9S_MB_2U(SCH_1):PAGE96
   J15  141  VSS62 SCONN288_ADR50017P130CC-SCONN2A   I176 @S9S_MB_2U_LIB.S9S_MB_2U(SCH_1):PAGE96
   J15  143  VSS63 SCONN288_ADR50017P130CC-SCONN2A   I176 @S9S_MB_2U_LIB.S9S_MB_2U(SCH_1):PAGE96
   J15  151  VSS64 SCONN288_ADR50017P130CC-SCONN2A   I176 @S9S_MB_2U_LIB.S9S_MB_2U(SCH_1):PAGE96
   J15  153  VSS65 SCONN288_ADR50017P130CC-SCONN2A   I176 @S9S_MB_2U_LIB.S9S_MB_2U(SCH_1):PAGE96
   J15  155  VSS66 SCONN288_ADR50017P130CC-SCONN2A   I176 @S9S_MB_2U_LIB.S9S_MB_2U(SCH_1):PAGE96
   J15  158  VSS67 SCONN288_ADR50017P130CC-SCONN2A   I176 @S9S_MB_2U_LIB.S9S_MB_2U(SCH_1):PAGE96
   J15  160  VSS68 SCONN288_ADR50017P130CC-SCONN2A   I176 @S9S_MB_2U_LIB.S9S_MB_2U(SCH_1):PAGE96
   J15  162  VSS69 SCONN288_ADR50017P130CC-SCONN2A   I176 @S9S_MB_2U_LIB.S9S_MB_2U(SCH_1):PAGE96
   J15  164  VSS70 SCONN288_ADR50017P130CC-SCONN2A   I176 @S9S_MB_2U_LIB.S9S_MB_2U(SCH_1):PAGE96
   J15  166  VSS71 SCONN288_ADR50017P130CC-SCONN2A   I176 @S9S_MB_2U_LIB.S9S_MB_2U(SCH_1):PAGE96
   J15  169  VSS72 SCONN288_ADR50017P130CC-SCONN2A   I176 @S9S_MB_2U_LIB.S9S_MB_2U(SCH_1):PAGE96
   J15  171  VSS73 SCONN288_ADR50017P130CC-SCONN2A   I176 @S9S_MB_2U_LIB.S9S_MB_2U(SCH_1):PAGE96
   J15  173  VSS74 SCONN288_ADR50017P130CC-SCONN2A   I176 @S9S_MB_2U_LIB.S9S_MB_2U(SCH_1):PAGE96
   J15  175  VSS75 SCONN288_ADR50017P130CC-SCONN2A   I176 @S9S_MB_2U_LIB.S9S_MB_2U(SCH_1):PAGE96
   J15  177  VSS76 SCONN288_ADR50017P130CC-SCONN2A   I176 @S9S_MB_2U_LIB.S9S_MB_2U(SCH_1):PAGE96
   J15  180  VSS77 SCONN288_ADR50017P130CC-SCONN2A   I176 @S9S_MB_2U_LIB.S9S_MB_2U(SCH_1):PAGE96
   J15  182  VSS78 SCONN288_ADR50017P130CC-SCONN2A   I176 @S9S_MB_2U_LIB.S9S_MB_2U(SCH_1):PAGE96
   J15  184  VSS79 SCONN288_ADR50017P130CC-SCONN2A   I176 @S9S_MB_2U_LIB.S9S_MB_2U(SCH_1):PAGE96
   J15  186  VSS80 SCONN288_ADR50017P130CC-SCONN2A   I176 @S9S_MB_2U_LIB.S9S_MB_2U(SCH_1):PAGE96
   J15  188  VSS81 SCONN288_ADR50017P130CC-SCONN2A   I176 @S9S_MB_2U_LIB.S9S_MB_2U(SCH_1):PAGE96
   J15  191  VSS82 SCONN288_ADR50017P130CC-SCONN2A   I176 @S9S_MB_2U_LIB.S9S_MB_2U(SCH_1):PAGE96
   J15  193  VSS83 SCONN288_ADR50017P130CC-SCONN2A   I176 @S9S_MB_2U_LIB.S9S_MB_2U(SCH_1):PAGE96
   J15  195  VSS84 SCONN288_ADR50017P130CC-SCONN2A   I176 @S9S_MB_2U_LIB.S9S_MB_2U(SCH_1):PAGE96
   J15  197  VSS85 SCONN288_ADR50017P130CC-SCONN2A   I176 @S9S_MB_2U_LIB.S9S_MB_2U(SCH_1):PAGE96
   J15  199  VSS86 SCONN288_ADR50017P130CC-SCONN2A   I176 @S9S_MB_2U_LIB.S9S_MB_2U(SCH_1):PAGE96
   J15  202  VSS87 SCONN288_ADR50017P130CC-SCONN2A   I176 @S9S_MB_2U_LIB.S9S_MB_2U(SCH_1):PAGE96
   J15  204  VSS88 SCONN288_ADR50017P130CC-SCONN2A   I176 @S9S_MB_2U_LIB.S9S_MB_2U(SCH_1):PAGE96
   J15  206  VSS89 SCONN288_ADR50017P130CC-SCONN2A   I176 @S9S_MB_2U_LIB.S9S_MB_2U(SCH_1):PAGE96
   J15  208  VSS90 SCONN288_ADR50017P130CC-SCONN2A   I176 @S9S_MB_2U_LIB.S9S_MB_2U(SCH_1):PAGE96
   J15  210  VSS91 SCONN288_ADR50017P130CC-SCONN2A   I176 @S9S_MB_2U_LIB.S9S_MB_2U(SCH_1):PAGE96
   J15  212  VSS92 SCONN288_ADR50017P130CC-SCONN2A   I176 @S9S_MB_2U_LIB.S9S_MB_2U(SCH_1):PAGE96
   J15  214  VSS93 SCONN288_ADR50017P130CC-SCONN2A   I176 @S9S_MB_2U_LIB.S9S_MB_2U(SCH_1):PAGE96
   J15  216  VSS94 SCONN288_ADR50017P130CC-SCONN2A   I176 @S9S_MB_2U_LIB.S9S_MB_2U(SCH_1):PAGE96
   J15  219  VSS95 SCONN288_ADR50017P130CC-SCONN2A   I176 @S9S_MB_2U_LIB.S9S_MB_2U(SCH_1):PAGE96
   J15  222  VSS96 SCONN288_ADR50017P130CC-SCONN2A   I176 @S9S_MB_2U_LIB.S9S_MB_2U(SCH_1):PAGE96
   J15  224  VSS97 SCONN288_ADR50017P130CC-SCONN2A   I176 @S9S_MB_2U_LIB.S9S_MB_2U(SCH_1):PAGE96
   J15  226  VSS98 SCONN288_ADR50017P130CC-SCONN2A   I176 @S9S_MB_2U_LIB.S9S_MB_2U(SCH_1):PAGE96
   J15  228  VSS99 SCONN288_ADR50017P130CC-SCONN2A   I176 @S9S_MB_2U_LIB.S9S_MB_2U(SCH_1):PAGE96
   J15  230 VSS100 SCONN288_ADR50017P130CC-SCONN2A   I176 @S9S_MB_2U_LIB.S9S_MB_2U(SCH_1):PAGE96
   J15  233 VSS101 SCONN288_ADR50017P130CC-SCONN2A   I176 @S9S_MB_2U_LIB.S9S_MB_2U(SCH_1):PAGE96
   J15  235 VSS102 SCONN288_ADR50017P130CC-SCONN2A   I176 @S9S_MB_2U_LIB.S9S_MB_2U(SCH_1):PAGE96
   J15  237 VSS103 SCONN288_ADR50017P130CC-SCONN2A   I176 @S9S_MB_2U_LIB.S9S_MB_2U(SCH_1):PAGE96
   J15  240 VSS104 SCONN288_ADR50017P130CC-SCONN2A   I176 @S9S_MB_2U_LIB.S9S_MB_2U(SCH_1):PAGE96
   J15  242 VSS105 SCONN288_ADR50017P130CC-SCONN2A   I176 @S9S_MB_2U_LIB.S9S_MB_2U(SCH_1):PAGE96
   J15  244 VSS106 SCONN288_ADR50017P130CC-SCONN2A   I176 @S9S_MB_2U_LIB.S9S_MB_2U(SCH_1):PAGE96
   J15  246 VSS107 SCONN288_ADR50017P130CC-SCONN2A   I176 @S9S_MB_2U_LIB.S9S_MB_2U(SCH_1):PAGE96
   J15  248 VSS108 SCONN288_ADR50017P130CC-SCONN2A   I176 @S9S_MB_2U_LIB.S9S_MB_2U(SCH_1):PAGE96
   J15  251 VSS109 SCONN288_ADR50017P130CC-SCONN2A   I176 @S9S_MB_2U_LIB.S9S_MB_2U(SCH_1):PAGE96
   J15  253 VSS110 SCONN288_ADR50017P130CC-SCONN2A   I176 @S9S_MB_2U_LIB.S9S_MB_2U(SCH_1):PAGE96
   J15  255 VSS111 SCONN288_ADR50017P130CC-SCONN2A   I176 @S9S_MB_2U_LIB.S9S_MB_2U(SCH_1):PAGE96
   J15  257 VSS112 SCONN288_ADR50017P130CC-SCONN2A   I176 @S9S_MB_2U_LIB.S9S_MB_2U(SCH_1):PAGE96
   J15  259 VSS113 SCONN288_ADR50017P130CC-SCONN2A   I176 @S9S_MB_2U_LIB.S9S_MB_2U(SCH_1):PAGE96
   J15  262 VSS114 SCONN288_ADR50017P130CC-SCONN2A   I176 @S9S_MB_2U_LIB.S9S_MB_2U(SCH_1):PAGE96
   J15  264 VSS115 SCONN288_ADR50017P130CC-SCONN2A   I176 @S9S_MB_2U_LIB.S9S_MB_2U(SCH_1):PAGE96
   J15  266 VSS116 SCONN288_ADR50017P130CC-SCONN2A   I176 @S9S_MB_2U_LIB.S9S_MB_2U(SCH_1):PAGE96
   J15  268 VSS117 SCONN288_ADR50017P130CC-SCONN2A   I176 @S9S_MB_2U_LIB.S9S_MB_2U(SCH_1):PAGE96
   J15  270 VSS118 SCONN288_ADR50017P130CC-SCONN2A   I176 @S9S_MB_2U_LIB.S9S_MB_2U(SCH_1):PAGE96
   J15  273 VSS119 SCONN288_ADR50017P130CC-SCONN2A   I176 @S9S_MB_2U_LIB.S9S_MB_2U(SCH_1):PAGE96
   J15  275 VSS120 SCONN288_ADR50017P130CC-SCONN2A   I176 @S9S_MB_2U_LIB.S9S_MB_2U(SCH_1):PAGE96
   J15  277 VSS121 SCONN288_ADR50017P130CC-SCONN2A   I176 @S9S_MB_2U_LIB.S9S_MB_2U(SCH_1):PAGE96
   J15  279 VSS122 SCONN288_ADR50017P130CC-SCONN2A   I176 @S9S_MB_2U_LIB.S9S_MB_2U(SCH_1):PAGE96
   J15  281 VSS123 SCONN288_ADR50017P130CC-SCONN2A   I176 @S9S_MB_2U_LIB.S9S_MB_2U(SCH_1):PAGE96
   J15  284 VSS124 SCONN288_ADR50017P130CC-SCONN2A   I176 @S9S_MB_2U_LIB.S9S_MB_2U(SCH_1):PAGE96
   J15  286 VSS125 SCONN288_ADR50017P130CC-SCONN2A   I176 @S9S_MB_2U_LIB.S9S_MB_2U(SCH_1):PAGE96
   J15  288 VSS126 SCONN288_ADR50017P130CC-SCONN2A   I176 @S9S_MB_2U_LIB.S9S_MB_2U(SCH_1):PAGE96
   R41    2      B Q_RES_0402LF-196K,1%,1/16W,CHIA     I5 @S9S_MB_2U_LIB.S9S_MB_2U(SCH_1):PAGE97
   C47    2      B Q_CAP_C0402-2.2UF,6.3V,20%,X6SA    I56 @S9S_MB_2U_LIB.S9S_MB_2U(SCH_1):PAGE97
   C48    2      B Q_CAP_C0805-10UF,16V,10%,X6S,CA    I59 @S9S_MB_2U_LIB.S9S_MB_2U(SCH_1):PAGE97
   C49    2      B Q_CAP_C0805-10UF,16V,10%,X6S,CA    I62 @S9S_MB_2U_LIB.S9S_MB_2U(SCH_1):PAGE97
   J16   G1     G1 SCONN288_ADR50017P087CC-SCONN2A    I64 @S9S_MB_2U_LIB.S9S_MB_2U(SCH_1):PAGE97
   J16   G2     G2 SCONN288_ADR50017P087CC-SCONN2A    I64 @S9S_MB_2U_LIB.S9S_MB_2U(SCH_1):PAGE97
   J16   G3     G3 SCONN288_ADR50017P087CC-SCONN2A    I64 @S9S_MB_2U_LIB.S9S_MB_2U(SCH_1):PAGE97
   J16    6   VSS0 SCONN288_ADR50017P087CC-SCONN2A    I64 @S9S_MB_2U_LIB.S9S_MB_2U(SCH_1):PAGE97
   J16    8   VSS1 SCONN288_ADR50017P087CC-SCONN2A    I64 @S9S_MB_2U_LIB.S9S_MB_2U(SCH_1):PAGE97
   J16   10   VSS2 SCONN288_ADR50017P087CC-SCONN2A    I64 @S9S_MB_2U_LIB.S9S_MB_2U(SCH_1):PAGE97
   J16   13   VSS3 SCONN288_ADR50017P087CC-SCONN2A    I64 @S9S_MB_2U_LIB.S9S_MB_2U(SCH_1):PAGE97
   J16   15   VSS4 SCONN288_ADR50017P087CC-SCONN2A    I64 @S9S_MB_2U_LIB.S9S_MB_2U(SCH_1):PAGE97
   J16   17   VSS5 SCONN288_ADR50017P087CC-SCONN2A    I64 @S9S_MB_2U_LIB.S9S_MB_2U(SCH_1):PAGE97
   J16   19   VSS6 SCONN288_ADR50017P087CC-SCONN2A    I64 @S9S_MB_2U_LIB.S9S_MB_2U(SCH_1):PAGE97
   J16   21   VSS7 SCONN288_ADR50017P087CC-SCONN2A    I64 @S9S_MB_2U_LIB.S9S_MB_2U(SCH_1):PAGE97
   J16   24   VSS8 SCONN288_ADR50017P087CC-SCONN2A    I64 @S9S_MB_2U_LIB.S9S_MB_2U(SCH_1):PAGE97
   J16   26   VSS9 SCONN288_ADR50017P087CC-SCONN2A    I64 @S9S_MB_2U_LIB.S9S_MB_2U(SCH_1):PAGE97
   J16   28  VSS10 SCONN288_ADR50017P087CC-SCONN2A    I64 @S9S_MB_2U_LIB.S9S_MB_2U(SCH_1):PAGE97
   J16   30  VSS11 SCONN288_ADR50017P087CC-SCONN2A    I64 @S9S_MB_2U_LIB.S9S_MB_2U(SCH_1):PAGE97
   J16   32  VSS12 SCONN288_ADR50017P087CC-SCONN2A    I64 @S9S_MB_2U_LIB.S9S_MB_2U(SCH_1):PAGE97
   J16   35  VSS13 SCONN288_ADR50017P087CC-SCONN2A    I64 @S9S_MB_2U_LIB.S9S_MB_2U(SCH_1):PAGE97
   J16   37  VSS14 SCONN288_ADR50017P087CC-SCONN2A    I64 @S9S_MB_2U_LIB.S9S_MB_2U(SCH_1):PAGE97
   J16   39  VSS15 SCONN288_ADR50017P087CC-SCONN2A    I64 @S9S_MB_2U_LIB.S9S_MB_2U(SCH_1):PAGE97
   J16   41  VSS16 SCONN288_ADR50017P087CC-SCONN2A    I64 @S9S_MB_2U_LIB.S9S_MB_2U(SCH_1):PAGE97
   J16   43  VSS17 SCONN288_ADR50017P087CC-SCONN2A    I64 @S9S_MB_2U_LIB.S9S_MB_2U(SCH_1):PAGE97
   J16   46  VSS18 SCONN288_ADR50017P087CC-SCONN2A    I64 @S9S_MB_2U_LIB.S9S_MB_2U(SCH_1):PAGE97
   J16   48  VSS19 SCONN288_ADR50017P087CC-SCONN2A    I64 @S9S_MB_2U_LIB.S9S_MB_2U(SCH_1):PAGE97
   J16   50  VSS20 SCONN288_ADR50017P087CC-SCONN2A    I64 @S9S_MB_2U_LIB.S9S_MB_2U(SCH_1):PAGE97
   J16   52  VSS21 SCONN288_ADR50017P087CC-SCONN2A    I64 @S9S_MB_2U_LIB.S9S_MB_2U(SCH_1):PAGE97
   J16   54  VSS22 SCONN288_ADR50017P087CC-SCONN2A    I64 @S9S_MB_2U_LIB.S9S_MB_2U(SCH_1):PAGE97
   J16   57  VSS23 SCONN288_ADR50017P087CC-SCONN2A    I64 @S9S_MB_2U_LIB.S9S_MB_2U(SCH_1):PAGE97
   J16   59  VSS24 SCONN288_ADR50017P087CC-SCONN2A    I64 @S9S_MB_2U_LIB.S9S_MB_2U(SCH_1):PAGE97
   J16   61  VSS25 SCONN288_ADR50017P087CC-SCONN2A    I64 @S9S_MB_2U_LIB.S9S_MB_2U(SCH_1):PAGE97
   J16   63  VSS26 SCONN288_ADR50017P087CC-SCONN2A    I64 @S9S_MB_2U_LIB.S9S_MB_2U(SCH_1):PAGE97
   J16   65  VSS27 SCONN288_ADR50017P087CC-SCONN2A    I64 @S9S_MB_2U_LIB.S9S_MB_2U(SCH_1):PAGE97
   J16   67  VSS28 SCONN288_ADR50017P087CC-SCONN2A    I64 @S9S_MB_2U_LIB.S9S_MB_2U(SCH_1):PAGE97
   J16   69  VSS29 SCONN288_ADR50017P087CC-SCONN2A    I64 @S9S_MB_2U_LIB.S9S_MB_2U(SCH_1):PAGE97
   J16   71  VSS30 SCONN288_ADR50017P087CC-SCONN2A    I64 @S9S_MB_2U_LIB.S9S_MB_2U(SCH_1):PAGE97
   J16   73  VSS31 SCONN288_ADR50017P087CC-SCONN2A    I64 @S9S_MB_2U_LIB.S9S_MB_2U(SCH_1):PAGE97
   J16   75  VSS32 SCONN288_ADR50017P087CC-SCONN2A    I64 @S9S_MB_2U_LIB.S9S_MB_2U(SCH_1):PAGE97
   J16   77  VSS33 SCONN288_ADR50017P087CC-SCONN2A    I64 @S9S_MB_2U_LIB.S9S_MB_2U(SCH_1):PAGE97
   J16   79  VSS34 SCONN288_ADR50017P087CC-SCONN2A    I64 @S9S_MB_2U_LIB.S9S_MB_2U(SCH_1):PAGE97
   J16   81  VSS35 SCONN288_ADR50017P087CC-SCONN2A    I64 @S9S_MB_2U_LIB.S9S_MB_2U(SCH_1):PAGE97
   J16   83  VSS36 SCONN288_ADR50017P087CC-SCONN2A    I64 @S9S_MB_2U_LIB.S9S_MB_2U(SCH_1):PAGE97
   J16   85  VSS37 SCONN288_ADR50017P087CC-SCONN2A    I64 @S9S_MB_2U_LIB.S9S_MB_2U(SCH_1):PAGE97
   J16   88  VSS38 SCONN288_ADR50017P087CC-SCONN2A    I64 @S9S_MB_2U_LIB.S9S_MB_2U(SCH_1):PAGE97
   J16   90  VSS39 SCONN288_ADR50017P087CC-SCONN2A    I64 @S9S_MB_2U_LIB.S9S_MB_2U(SCH_1):PAGE97
   J16   92  VSS40 SCONN288_ADR50017P087CC-SCONN2A    I64 @S9S_MB_2U_LIB.S9S_MB_2U(SCH_1):PAGE97
   J16   95  VSS41 SCONN288_ADR50017P087CC-SCONN2A    I64 @S9S_MB_2U_LIB.S9S_MB_2U(SCH_1):PAGE97
   J16   97  VSS42 SCONN288_ADR50017P087CC-SCONN2A    I64 @S9S_MB_2U_LIB.S9S_MB_2U(SCH_1):PAGE97
   J16   99  VSS43 SCONN288_ADR50017P087CC-SCONN2A    I64 @S9S_MB_2U_LIB.S9S_MB_2U(SCH_1):PAGE97
   J16  101  VSS44 SCONN288_ADR50017P087CC-SCONN2A    I64 @S9S_MB_2U_LIB.S9S_MB_2U(SCH_1):PAGE97
   J16  103  VSS45 SCONN288_ADR50017P087CC-SCONN2A    I64 @S9S_MB_2U_LIB.S9S_MB_2U(SCH_1):PAGE97
   J16  106  VSS46 SCONN288_ADR50017P087CC-SCONN2A    I64 @S9S_MB_2U_LIB.S9S_MB_2U(SCH_1):PAGE97
   J16  108  VSS47 SCONN288_ADR50017P087CC-SCONN2A    I64 @S9S_MB_2U_LIB.S9S_MB_2U(SCH_1):PAGE97
   J16  110  VSS48 SCONN288_ADR50017P087CC-SCONN2A    I64 @S9S_MB_2U_LIB.S9S_MB_2U(SCH_1):PAGE97
   J16  112  VSS49 SCONN288_ADR50017P087CC-SCONN2A    I64 @S9S_MB_2U_LIB.S9S_MB_2U(SCH_1):PAGE97
   J16  114  VSS50 SCONN288_ADR50017P087CC-SCONN2A    I64 @S9S_MB_2U_LIB.S9S_MB_2U(SCH_1):PAGE97
   J16  117  VSS51 SCONN288_ADR50017P087CC-SCONN2A    I64 @S9S_MB_2U_LIB.S9S_MB_2U(SCH_1):PAGE97
   J16  119  VSS52 SCONN288_ADR50017P087CC-SCONN2A    I64 @S9S_MB_2U_LIB.S9S_MB_2U(SCH_1):PAGE97
   J16  121  VSS53 SCONN288_ADR50017P087CC-SCONN2A    I64 @S9S_MB_2U_LIB.S9S_MB_2U(SCH_1):PAGE97
   J16  123  VSS54 SCONN288_ADR50017P087CC-SCONN2A    I64 @S9S_MB_2U_LIB.S9S_MB_2U(SCH_1):PAGE97
   J16  125  VSS55 SCONN288_ADR50017P087CC-SCONN2A    I64 @S9S_MB_2U_LIB.S9S_MB_2U(SCH_1):PAGE97
   J16  128  VSS56 SCONN288_ADR50017P087CC-SCONN2A    I64 @S9S_MB_2U_LIB.S9S_MB_2U(SCH_1):PAGE97
   J16  130  VSS57 SCONN288_ADR50017P087CC-SCONN2A    I64 @S9S_MB_2U_LIB.S9S_MB_2U(SCH_1):PAGE97
   J16  132  VSS58 SCONN288_ADR50017P087CC-SCONN2A    I64 @S9S_MB_2U_LIB.S9S_MB_2U(SCH_1):PAGE97
   J16  134  VSS59 SCONN288_ADR50017P087CC-SCONN2A    I64 @S9S_MB_2U_LIB.S9S_MB_2U(SCH_1):PAGE97
   J16  136  VSS60 SCONN288_ADR50017P087CC-SCONN2A    I64 @S9S_MB_2U_LIB.S9S_MB_2U(SCH_1):PAGE97
   J16  139  VSS61 SCONN288_ADR50017P087CC-SCONN2A    I64 @S9S_MB_2U_LIB.S9S_MB_2U(SCH_1):PAGE97
   J16  141  VSS62 SCONN288_ADR50017P087CC-SCONN2A    I64 @S9S_MB_2U_LIB.S9S_MB_2U(SCH_1):PAGE97
   J16  143  VSS63 SCONN288_ADR50017P087CC-SCONN2A    I64 @S9S_MB_2U_LIB.S9S_MB_2U(SCH_1):PAGE97
   J16  151  VSS64 SCONN288_ADR50017P087CC-SCONN2A    I64 @S9S_MB_2U_LIB.S9S_MB_2U(SCH_1):PAGE97
   J16  153  VSS65 SCONN288_ADR50017P087CC-SCONN2A    I64 @S9S_MB_2U_LIB.S9S_MB_2U(SCH_1):PAGE97
   J16  155  VSS66 SCONN288_ADR50017P087CC-SCONN2A    I64 @S9S_MB_2U_LIB.S9S_MB_2U(SCH_1):PAGE97
   J16  158  VSS67 SCONN288_ADR50017P087CC-SCONN2A    I64 @S9S_MB_2U_LIB.S9S_MB_2U(SCH_1):PAGE97
   J16  160  VSS68 SCONN288_ADR50017P087CC-SCONN2A    I64 @S9S_MB_2U_LIB.S9S_MB_2U(SCH_1):PAGE97
   J16  162  VSS69 SCONN288_ADR50017P087CC-SCONN2A    I64 @S9S_MB_2U_LIB.S9S_MB_2U(SCH_1):PAGE97
   J16  164  VSS70 SCONN288_ADR50017P087CC-SCONN2A    I64 @S9S_MB_2U_LIB.S9S_MB_2U(SCH_1):PAGE97
   J16  166  VSS71 SCONN288_ADR50017P087CC-SCONN2A    I64 @S9S_MB_2U_LIB.S9S_MB_2U(SCH_1):PAGE97
   J16  169  VSS72 SCONN288_ADR50017P087CC-SCONN2A    I64 @S9S_MB_2U_LIB.S9S_MB_2U(SCH_1):PAGE97
   J16  171  VSS73 SCONN288_ADR50017P087CC-SCONN2A    I64 @S9S_MB_2U_LIB.S9S_MB_2U(SCH_1):PAGE97
   J16  173  VSS74 SCONN288_ADR50017P087CC-SCONN2A    I64 @S9S_MB_2U_LIB.S9S_MB_2U(SCH_1):PAGE97
   J16  175  VSS75 SCONN288_ADR50017P087CC-SCONN2A    I64 @S9S_MB_2U_LIB.S9S_MB_2U(SCH_1):PAGE97
   J16  177  VSS76 SCONN288_ADR50017P087CC-SCONN2A    I64 @S9S_MB_2U_LIB.S9S_MB_2U(SCH_1):PAGE97
   J16  180  VSS77 SCONN288_ADR50017P087CC-SCONN2A    I64 @S9S_MB_2U_LIB.S9S_MB_2U(SCH_1):PAGE97
   J16  182  VSS78 SCONN288_ADR50017P087CC-SCONN2A    I64 @S9S_MB_2U_LIB.S9S_MB_2U(SCH_1):PAGE97
   J16  184  VSS79 SCONN288_ADR50017P087CC-SCONN2A    I64 @S9S_MB_2U_LIB.S9S_MB_2U(SCH_1):PAGE97
   J16  186  VSS80 SCONN288_ADR50017P087CC-SCONN2A    I64 @S9S_MB_2U_LIB.S9S_MB_2U(SCH_1):PAGE97
   J16  188  VSS81 SCONN288_ADR50017P087CC-SCONN2A    I64 @S9S_MB_2U_LIB.S9S_MB_2U(SCH_1):PAGE97
   J16  191  VSS82 SCONN288_ADR50017P087CC-SCONN2A    I64 @S9S_MB_2U_LIB.S9S_MB_2U(SCH_1):PAGE97
   J16  193  VSS83 SCONN288_ADR50017P087CC-SCONN2A    I64 @S9S_MB_2U_LIB.S9S_MB_2U(SCH_1):PAGE97
   J16  195  VSS84 SCONN288_ADR50017P087CC-SCONN2A    I64 @S9S_MB_2U_LIB.S9S_MB_2U(SCH_1):PAGE97
   J16  197  VSS85 SCONN288_ADR50017P087CC-SCONN2A    I64 @S9S_MB_2U_LIB.S9S_MB_2U(SCH_1):PAGE97
   J16  199  VSS86 SCONN288_ADR50017P087CC-SCONN2A    I64 @S9S_MB_2U_LIB.S9S_MB_2U(SCH_1):PAGE97
   J16  202  VSS87 SCONN288_ADR50017P087CC-SCONN2A    I64 @S9S_MB_2U_LIB.S9S_MB_2U(SCH_1):PAGE97
   J16  204  VSS88 SCONN288_ADR50017P087CC-SCONN2A    I64 @S9S_MB_2U_LIB.S9S_MB_2U(SCH_1):PAGE97
   J16  206  VSS89 SCONN288_ADR50017P087CC-SCONN2A    I64 @S9S_MB_2U_LIB.S9S_MB_2U(SCH_1):PAGE97
   J16  208  VSS90 SCONN288_ADR50017P087CC-SCONN2A    I64 @S9S_MB_2U_LIB.S9S_MB_2U(SCH_1):PAGE97
   J16  210  VSS91 SCONN288_ADR50017P087CC-SCONN2A    I64 @S9S_MB_2U_LIB.S9S_MB_2U(SCH_1):PAGE97
   J16  212  VSS92 SCONN288_ADR50017P087CC-SCONN2A    I64 @S9S_MB_2U_LIB.S9S_MB_2U(SCH_1):PAGE97
   J16  214  VSS93 SCONN288_ADR50017P087CC-SCONN2A    I64 @S9S_MB_2U_LIB.S9S_MB_2U(SCH_1):PAGE97
   J16  216  VSS94 SCONN288_ADR50017P087CC-SCONN2A    I64 @S9S_MB_2U_LIB.S9S_MB_2U(SCH_1):PAGE97
   J16  219  VSS95 SCONN288_ADR50017P087CC-SCONN2A    I64 @S9S_MB_2U_LIB.S9S_MB_2U(SCH_1):PAGE97
   J16  222  VSS96 SCONN288_ADR50017P087CC-SCONN2A    I64 @S9S_MB_2U_LIB.S9S_MB_2U(SCH_1):PAGE97
   J16  224  VSS97 SCONN288_ADR50017P087CC-SCONN2A    I64 @S9S_MB_2U_LIB.S9S_MB_2U(SCH_1):PAGE97
   J16  226  VSS98 SCONN288_ADR50017P087CC-SCONN2A    I64 @S9S_MB_2U_LIB.S9S_MB_2U(SCH_1):PAGE97
   J16  228  VSS99 SCONN288_ADR50017P087CC-SCONN2A    I64 @S9S_MB_2U_LIB.S9S_MB_2U(SCH_1):PAGE97
   J16  230 VSS100 SCONN288_ADR50017P087CC-SCONN2A    I64 @S9S_MB_2U_LIB.S9S_MB_2U(SCH_1):PAGE97
   J16  233 VSS101 SCONN288_ADR50017P087CC-SCONN2A    I64 @S9S_MB_2U_LIB.S9S_MB_2U(SCH_1):PAGE97
   J16  235 VSS102 SCONN288_ADR50017P087CC-SCONN2A    I64 @S9S_MB_2U_LIB.S9S_MB_2U(SCH_1):PAGE97
   J16  237 VSS103 SCONN288_ADR50017P087CC-SCONN2A    I64 @S9S_MB_2U_LIB.S9S_MB_2U(SCH_1):PAGE97
   J16  240 VSS104 SCONN288_ADR50017P087CC-SCONN2A    I64 @S9S_MB_2U_LIB.S9S_MB_2U(SCH_1):PAGE97
   J16  242 VSS105 SCONN288_ADR50017P087CC-SCONN2A    I64 @S9S_MB_2U_LIB.S9S_MB_2U(SCH_1):PAGE97
   J16  244 VSS106 SCONN288_ADR50017P087CC-SCONN2A    I64 @S9S_MB_2U_LIB.S9S_MB_2U(SCH_1):PAGE97
   J16  246 VSS107 SCONN288_ADR50017P087CC-SCONN2A    I64 @S9S_MB_2U_LIB.S9S_MB_2U(SCH_1):PAGE97
   J16  248 VSS108 SCONN288_ADR50017P087CC-SCONN2A    I64 @S9S_MB_2U_LIB.S9S_MB_2U(SCH_1):PAGE97
   J16  251 VSS109 SCONN288_ADR50017P087CC-SCONN2A    I64 @S9S_MB_2U_LIB.S9S_MB_2U(SCH_1):PAGE97
   J16  253 VSS110 SCONN288_ADR50017P087CC-SCONN2A    I64 @S9S_MB_2U_LIB.S9S_MB_2U(SCH_1):PAGE97
   J16  255 VSS111 SCONN288_ADR50017P087CC-SCONN2A    I64 @S9S_MB_2U_LIB.S9S_MB_2U(SCH_1):PAGE97
   J16  257 VSS112 SCONN288_ADR50017P087CC-SCONN2A    I64 @S9S_MB_2U_LIB.S9S_MB_2U(SCH_1):PAGE97
   J16  259 VSS113 SCONN288_ADR50017P087CC-SCONN2A    I64 @S9S_MB_2U_LIB.S9S_MB_2U(SCH_1):PAGE97
   J16  262 VSS114 SCONN288_ADR50017P087CC-SCONN2A    I64 @S9S_MB_2U_LIB.S9S_MB_2U(SCH_1):PAGE97
   J16  264 VSS115 SCONN288_ADR50017P087CC-SCONN2A    I64 @S9S_MB_2U_LIB.S9S_MB_2U(SCH_1):PAGE97
   J16  266 VSS116 SCONN288_ADR50017P087CC-SCONN2A    I64 @S9S_MB_2U_LIB.S9S_MB_2U(SCH_1):PAGE97
   J16  268 VSS117 SCONN288_ADR50017P087CC-SCONN2A    I64 @S9S_MB_2U_LIB.S9S_MB_2U(SCH_1):PAGE97
   J16  270 VSS118 SCONN288_ADR50017P087CC-SCONN2A    I64 @S9S_MB_2U_LIB.S9S_MB_2U(SCH_1):PAGE97
   J16  273 VSS119 SCONN288_ADR50017P087CC-SCONN2A    I64 @S9S_MB_2U_LIB.S9S_MB_2U(SCH_1):PAGE97
   J16  275 VSS120 SCONN288_ADR50017P087CC-SCONN2A    I64 @S9S_MB_2U_LIB.S9S_MB_2U(SCH_1):PAGE97
   J16  277 VSS121 SCONN288_ADR50017P087CC-SCONN2A    I64 @S9S_MB_2U_LIB.S9S_MB_2U(SCH_1):PAGE97
   J16  279 VSS122 SCONN288_ADR50017P087CC-SCONN2A    I64 @S9S_MB_2U_LIB.S9S_MB_2U(SCH_1):PAGE97
   J16  281 VSS123 SCONN288_ADR50017P087CC-SCONN2A    I64 @S9S_MB_2U_LIB.S9S_MB_2U(SCH_1):PAGE97
   J16  284 VSS124 SCONN288_ADR50017P087CC-SCONN2A    I64 @S9S_MB_2U_LIB.S9S_MB_2U(SCH_1):PAGE97
   J16  286 VSS125 SCONN288_ADR50017P087CC-SCONN2A    I64 @S9S_MB_2U_LIB.S9S_MB_2U(SCH_1):PAGE97
   J16  288 VSS126 SCONN288_ADR50017P087CC-SCONN2A    I64 @S9S_MB_2U_LIB.S9S_MB_2U(SCH_1):PAGE97
   R42    2      B Q_RES_0402LF-10K,1%,1/16W,CHIPA    I11 @S9S_MB_2U_LIB.S9S_MB_2U(SCH_1):PAGE98
   C50    2      B Q_CAP_C0402-2.2UF,6.3V,20%,X6SA   I122 @S9S_MB_2U_LIB.S9S_MB_2U(SCH_1):PAGE98
   C51    2      B Q_CAP_C0805-10UF,16V,10%,X6S,CA   I123 @S9S_MB_2U_LIB.S9S_MB_2U(SCH_1):PAGE98
   C52    2      B Q_CAP_C0805-10UF,16V,10%,X6S,CA   I145 @S9S_MB_2U_LIB.S9S_MB_2U(SCH_1):PAGE98
   J17   G1     G1 SCONN288_ADR50017P130CC-SCONN2A   I147 @S9S_MB_2U_LIB.S9S_MB_2U(SCH_1):PAGE98
   J17   G2     G2 SCONN288_ADR50017P130CC-SCONN2A   I147 @S9S_MB_2U_LIB.S9S_MB_2U(SCH_1):PAGE98
   J17   G3     G3 SCONN288_ADR50017P130CC-SCONN2A   I147 @S9S_MB_2U_LIB.S9S_MB_2U(SCH_1):PAGE98
   J17    6   VSS0 SCONN288_ADR50017P130CC-SCONN2A   I147 @S9S_MB_2U_LIB.S9S_MB_2U(SCH_1):PAGE98
   J17    8   VSS1 SCONN288_ADR50017P130CC-SCONN2A   I147 @S9S_MB_2U_LIB.S9S_MB_2U(SCH_1):PAGE98
   J17   10   VSS2 SCONN288_ADR50017P130CC-SCONN2A   I147 @S9S_MB_2U_LIB.S9S_MB_2U(SCH_1):PAGE98
   J17   13   VSS3 SCONN288_ADR50017P130CC-SCONN2A   I147 @S9S_MB_2U_LIB.S9S_MB_2U(SCH_1):PAGE98
   J17   15   VSS4 SCONN288_ADR50017P130CC-SCONN2A   I147 @S9S_MB_2U_LIB.S9S_MB_2U(SCH_1):PAGE98
   J17   17   VSS5 SCONN288_ADR50017P130CC-SCONN2A   I147 @S9S_MB_2U_LIB.S9S_MB_2U(SCH_1):PAGE98
   J17   19   VSS6 SCONN288_ADR50017P130CC-SCONN2A   I147 @S9S_MB_2U_LIB.S9S_MB_2U(SCH_1):PAGE98
   J17   21   VSS7 SCONN288_ADR50017P130CC-SCONN2A   I147 @S9S_MB_2U_LIB.S9S_MB_2U(SCH_1):PAGE98
   J17   24   VSS8 SCONN288_ADR50017P130CC-SCONN2A   I147 @S9S_MB_2U_LIB.S9S_MB_2U(SCH_1):PAGE98
   J17   26   VSS9 SCONN288_ADR50017P130CC-SCONN2A   I147 @S9S_MB_2U_LIB.S9S_MB_2U(SCH_1):PAGE98
   J17   28  VSS10 SCONN288_ADR50017P130CC-SCONN2A   I147 @S9S_MB_2U_LIB.S9S_MB_2U(SCH_1):PAGE98
   J17   30  VSS11 SCONN288_ADR50017P130CC-SCONN2A   I147 @S9S_MB_2U_LIB.S9S_MB_2U(SCH_1):PAGE98
   J17   32  VSS12 SCONN288_ADR50017P130CC-SCONN2A   I147 @S9S_MB_2U_LIB.S9S_MB_2U(SCH_1):PAGE98
   J17   35  VSS13 SCONN288_ADR50017P130CC-SCONN2A   I147 @S9S_MB_2U_LIB.S9S_MB_2U(SCH_1):PAGE98
   J17   37  VSS14 SCONN288_ADR50017P130CC-SCONN2A   I147 @S9S_MB_2U_LIB.S9S_MB_2U(SCH_1):PAGE98
   J17   39  VSS15 SCONN288_ADR50017P130CC-SCONN2A   I147 @S9S_MB_2U_LIB.S9S_MB_2U(SCH_1):PAGE98
   J17   41  VSS16 SCONN288_ADR50017P130CC-SCONN2A   I147 @S9S_MB_2U_LIB.S9S_MB_2U(SCH_1):PAGE98
   J17   43  VSS17 SCONN288_ADR50017P130CC-SCONN2A   I147 @S9S_MB_2U_LIB.S9S_MB_2U(SCH_1):PAGE98
   J17   46  VSS18 SCONN288_ADR50017P130CC-SCONN2A   I147 @S9S_MB_2U_LIB.S9S_MB_2U(SCH_1):PAGE98
   J17   48  VSS19 SCONN288_ADR50017P130CC-SCONN2A   I147 @S9S_MB_2U_LIB.S9S_MB_2U(SCH_1):PAGE98
   J17   50  VSS20 SCONN288_ADR50017P130CC-SCONN2A   I147 @S9S_MB_2U_LIB.S9S_MB_2U(SCH_1):PAGE98
   J17   52  VSS21 SCONN288_ADR50017P130CC-SCONN2A   I147 @S9S_MB_2U_LIB.S9S_MB_2U(SCH_1):PAGE98
   J17   54  VSS22 SCONN288_ADR50017P130CC-SCONN2A   I147 @S9S_MB_2U_LIB.S9S_MB_2U(SCH_1):PAGE98
   J17   57  VSS23 SCONN288_ADR50017P130CC-SCONN2A   I147 @S9S_MB_2U_LIB.S9S_MB_2U(SCH_1):PAGE98
   J17   59  VSS24 SCONN288_ADR50017P130CC-SCONN2A   I147 @S9S_MB_2U_LIB.S9S_MB_2U(SCH_1):PAGE98
   J17   61  VSS25 SCONN288_ADR50017P130CC-SCONN2A   I147 @S9S_MB_2U_LIB.S9S_MB_2U(SCH_1):PAGE98
   J17   63  VSS26 SCONN288_ADR50017P130CC-SCONN2A   I147 @S9S_MB_2U_LIB.S9S_MB_2U(SCH_1):PAGE98
   J17   65  VSS27 SCONN288_ADR50017P130CC-SCONN2A   I147 @S9S_MB_2U_LIB.S9S_MB_2U(SCH_1):PAGE98
   J17   67  VSS28 SCONN288_ADR50017P130CC-SCONN2A   I147 @S9S_MB_2U_LIB.S9S_MB_2U(SCH_1):PAGE98
   J17   69  VSS29 SCONN288_ADR50017P130CC-SCONN2A   I147 @S9S_MB_2U_LIB.S9S_MB_2U(SCH_1):PAGE98
   J17   71  VSS30 SCONN288_ADR50017P130CC-SCONN2A   I147 @S9S_MB_2U_LIB.S9S_MB_2U(SCH_1):PAGE98
   J17   73  VSS31 SCONN288_ADR50017P130CC-SCONN2A   I147 @S9S_MB_2U_LIB.S9S_MB_2U(SCH_1):PAGE98
   J17   75  VSS32 SCONN288_ADR50017P130CC-SCONN2A   I147 @S9S_MB_2U_LIB.S9S_MB_2U(SCH_1):PAGE98
   J17   77  VSS33 SCONN288_ADR50017P130CC-SCONN2A   I147 @S9S_MB_2U_LIB.S9S_MB_2U(SCH_1):PAGE98
   J17   79  VSS34 SCONN288_ADR50017P130CC-SCONN2A   I147 @S9S_MB_2U_LIB.S9S_MB_2U(SCH_1):PAGE98
   J17   81  VSS35 SCONN288_ADR50017P130CC-SCONN2A   I147 @S9S_MB_2U_LIB.S9S_MB_2U(SCH_1):PAGE98
   J17   83  VSS36 SCONN288_ADR50017P130CC-SCONN2A   I147 @S9S_MB_2U_LIB.S9S_MB_2U(SCH_1):PAGE98
   J17   85  VSS37 SCONN288_ADR50017P130CC-SCONN2A   I147 @S9S_MB_2U_LIB.S9S_MB_2U(SCH_1):PAGE98
   J17   88  VSS38 SCONN288_ADR50017P130CC-SCONN2A   I147 @S9S_MB_2U_LIB.S9S_MB_2U(SCH_1):PAGE98
   J17   90  VSS39 SCONN288_ADR50017P130CC-SCONN2A   I147 @S9S_MB_2U_LIB.S9S_MB_2U(SCH_1):PAGE98
   J17   92  VSS40 SCONN288_ADR50017P130CC-SCONN2A   I147 @S9S_MB_2U_LIB.S9S_MB_2U(SCH_1):PAGE98
   J17   95  VSS41 SCONN288_ADR50017P130CC-SCONN2A   I147 @S9S_MB_2U_LIB.S9S_MB_2U(SCH_1):PAGE98
   J17   97  VSS42 SCONN288_ADR50017P130CC-SCONN2A   I147 @S9S_MB_2U_LIB.S9S_MB_2U(SCH_1):PAGE98
   J17   99  VSS43 SCONN288_ADR50017P130CC-SCONN2A   I147 @S9S_MB_2U_LIB.S9S_MB_2U(SCH_1):PAGE98
   J17  101  VSS44 SCONN288_ADR50017P130CC-SCONN2A   I147 @S9S_MB_2U_LIB.S9S_MB_2U(SCH_1):PAGE98
   J17  103  VSS45 SCONN288_ADR50017P130CC-SCONN2A   I147 @S9S_MB_2U_LIB.S9S_MB_2U(SCH_1):PAGE98
   J17  106  VSS46 SCONN288_ADR50017P130CC-SCONN2A   I147 @S9S_MB_2U_LIB.S9S_MB_2U(SCH_1):PAGE98
   J17  108  VSS47 SCONN288_ADR50017P130CC-SCONN2A   I147 @S9S_MB_2U_LIB.S9S_MB_2U(SCH_1):PAGE98
   J17  110  VSS48 SCONN288_ADR50017P130CC-SCONN2A   I147 @S9S_MB_2U_LIB.S9S_MB_2U(SCH_1):PAGE98
   J17  112  VSS49 SCONN288_ADR50017P130CC-SCONN2A   I147 @S9S_MB_2U_LIB.S9S_MB_2U(SCH_1):PAGE98
   J17  114  VSS50 SCONN288_ADR50017P130CC-SCONN2A   I147 @S9S_MB_2U_LIB.S9S_MB_2U(SCH_1):PAGE98
   J17  117  VSS51 SCONN288_ADR50017P130CC-SCONN2A   I147 @S9S_MB_2U_LIB.S9S_MB_2U(SCH_1):PAGE98
   J17  119  VSS52 SCONN288_ADR50017P130CC-SCONN2A   I147 @S9S_MB_2U_LIB.S9S_MB_2U(SCH_1):PAGE98
   J17  121  VSS53 SCONN288_ADR50017P130CC-SCONN2A   I147 @S9S_MB_2U_LIB.S9S_MB_2U(SCH_1):PAGE98
   J17  123  VSS54 SCONN288_ADR50017P130CC-SCONN2A   I147 @S9S_MB_2U_LIB.S9S_MB_2U(SCH_1):PAGE98
   J17  125  VSS55 SCONN288_ADR50017P130CC-SCONN2A   I147 @S9S_MB_2U_LIB.S9S_MB_2U(SCH_1):PAGE98
   J17  128  VSS56 SCONN288_ADR50017P130CC-SCONN2A   I147 @S9S_MB_2U_LIB.S9S_MB_2U(SCH_1):PAGE98
   J17  130  VSS57 SCONN288_ADR50017P130CC-SCONN2A   I147 @S9S_MB_2U_LIB.S9S_MB_2U(SCH_1):PAGE98
   J17  132  VSS58 SCONN288_ADR50017P130CC-SCONN2A   I147 @S9S_MB_2U_LIB.S9S_MB_2U(SCH_1):PAGE98
   J17  134  VSS59 SCONN288_ADR50017P130CC-SCONN2A   I147 @S9S_MB_2U_LIB.S9S_MB_2U(SCH_1):PAGE98
   J17  136  VSS60 SCONN288_ADR50017P130CC-SCONN2A   I147 @S9S_MB_2U_LIB.S9S_MB_2U(SCH_1):PAGE98
   J17  139  VSS61 SCONN288_ADR50017P130CC-SCONN2A   I147 @S9S_MB_2U_LIB.S9S_MB_2U(SCH_1):PAGE98
   J17  141  VSS62 SCONN288_ADR50017P130CC-SCONN2A   I147 @S9S_MB_2U_LIB.S9S_MB_2U(SCH_1):PAGE98
   J17  143  VSS63 SCONN288_ADR50017P130CC-SCONN2A   I147 @S9S_MB_2U_LIB.S9S_MB_2U(SCH_1):PAGE98
   J17  151  VSS64 SCONN288_ADR50017P130CC-SCONN2A   I147 @S9S_MB_2U_LIB.S9S_MB_2U(SCH_1):PAGE98
   J17  153  VSS65 SCONN288_ADR50017P130CC-SCONN2A   I147 @S9S_MB_2U_LIB.S9S_MB_2U(SCH_1):PAGE98
   J17  155  VSS66 SCONN288_ADR50017P130CC-SCONN2A   I147 @S9S_MB_2U_LIB.S9S_MB_2U(SCH_1):PAGE98
   J17  158  VSS67 SCONN288_ADR50017P130CC-SCONN2A   I147 @S9S_MB_2U_LIB.S9S_MB_2U(SCH_1):PAGE98
   J17  160  VSS68 SCONN288_ADR50017P130CC-SCONN2A   I147 @S9S_MB_2U_LIB.S9S_MB_2U(SCH_1):PAGE98
   J17  162  VSS69 SCONN288_ADR50017P130CC-SCONN2A   I147 @S9S_MB_2U_LIB.S9S_MB_2U(SCH_1):PAGE98
   J17  164  VSS70 SCONN288_ADR50017P130CC-SCONN2A   I147 @S9S_MB_2U_LIB.S9S_MB_2U(SCH_1):PAGE98
   J17  166  VSS71 SCONN288_ADR50017P130CC-SCONN2A   I147 @S9S_MB_2U_LIB.S9S_MB_2U(SCH_1):PAGE98
   J17  169  VSS72 SCONN288_ADR50017P130CC-SCONN2A   I147 @S9S_MB_2U_LIB.S9S_MB_2U(SCH_1):PAGE98
   J17  171  VSS73 SCONN288_ADR50017P130CC-SCONN2A   I147 @S9S_MB_2U_LIB.S9S_MB_2U(SCH_1):PAGE98
   J17  173  VSS74 SCONN288_ADR50017P130CC-SCONN2A   I147 @S9S_MB_2U_LIB.S9S_MB_2U(SCH_1):PAGE98
   J17  175  VSS75 SCONN288_ADR50017P130CC-SCONN2A   I147 @S9S_MB_2U_LIB.S9S_MB_2U(SCH_1):PAGE98
   J17  177  VSS76 SCONN288_ADR50017P130CC-SCONN2A   I147 @S9S_MB_2U_LIB.S9S_MB_2U(SCH_1):PAGE98
   J17  180  VSS77 SCONN288_ADR50017P130CC-SCONN2A   I147 @S9S_MB_2U_LIB.S9S_MB_2U(SCH_1):PAGE98
   J17  182  VSS78 SCONN288_ADR50017P130CC-SCONN2A   I147 @S9S_MB_2U_LIB.S9S_MB_2U(SCH_1):PAGE98
   J17  184  VSS79 SCONN288_ADR50017P130CC-SCONN2A   I147 @S9S_MB_2U_LIB.S9S_MB_2U(SCH_1):PAGE98
   J17  186  VSS80 SCONN288_ADR50017P130CC-SCONN2A   I147 @S9S_MB_2U_LIB.S9S_MB_2U(SCH_1):PAGE98
   J17  188  VSS81 SCONN288_ADR50017P130CC-SCONN2A   I147 @S9S_MB_2U_LIB.S9S_MB_2U(SCH_1):PAGE98
   J17  191  VSS82 SCONN288_ADR50017P130CC-SCONN2A   I147 @S9S_MB_2U_LIB.S9S_MB_2U(SCH_1):PAGE98
   J17  193  VSS83 SCONN288_ADR50017P130CC-SCONN2A   I147 @S9S_MB_2U_LIB.S9S_MB_2U(SCH_1):PAGE98
   J17  195  VSS84 SCONN288_ADR50017P130CC-SCONN2A   I147 @S9S_MB_2U_LIB.S9S_MB_2U(SCH_1):PAGE98
   J17  197  VSS85 SCONN288_ADR50017P130CC-SCONN2A   I147 @S9S_MB_2U_LIB.S9S_MB_2U(SCH_1):PAGE98
   J17  199  VSS86 SCONN288_ADR50017P130CC-SCONN2A   I147 @S9S_MB_2U_LIB.S9S_MB_2U(SCH_1):PAGE98
   J17  202  VSS87 SCONN288_ADR50017P130CC-SCONN2A   I147 @S9S_MB_2U_LIB.S9S_MB_2U(SCH_1):PAGE98
   J17  204  VSS88 SCONN288_ADR50017P130CC-SCONN2A   I147 @S9S_MB_2U_LIB.S9S_MB_2U(SCH_1):PAGE98
   J17  206  VSS89 SCONN288_ADR50017P130CC-SCONN2A   I147 @S9S_MB_2U_LIB.S9S_MB_2U(SCH_1):PAGE98
   J17  208  VSS90 SCONN288_ADR50017P130CC-SCONN2A   I147 @S9S_MB_2U_LIB.S9S_MB_2U(SCH_1):PAGE98
   J17  210  VSS91 SCONN288_ADR50017P130CC-SCONN2A   I147 @S9S_MB_2U_LIB.S9S_MB_2U(SCH_1):PAGE98
   J17  212  VSS92 SCONN288_ADR50017P130CC-SCONN2A   I147 @S9S_MB_2U_LIB.S9S_MB_2U(SCH_1):PAGE98
   J17  214  VSS93 SCONN288_ADR50017P130CC-SCONN2A   I147 @S9S_MB_2U_LIB.S9S_MB_2U(SCH_1):PAGE98
   J17  216  VSS94 SCONN288_ADR50017P130CC-SCONN2A   I147 @S9S_MB_2U_LIB.S9S_MB_2U(SCH_1):PAGE98
   J17  219  VSS95 SCONN288_ADR50017P130CC-SCONN2A   I147 @S9S_MB_2U_LIB.S9S_MB_2U(SCH_1):PAGE98
   J17  222  VSS96 SCONN288_ADR50017P130CC-SCONN2A   I147 @S9S_MB_2U_LIB.S9S_MB_2U(SCH_1):PAGE98
   J17  224  VSS97 SCONN288_ADR50017P130CC-SCONN2A   I147 @S9S_MB_2U_LIB.S9S_MB_2U(SCH_1):PAGE98
   J17  226  VSS98 SCONN288_ADR50017P130CC-SCONN2A   I147 @S9S_MB_2U_LIB.S9S_MB_2U(SCH_1):PAGE98
   J17  228  VSS99 SCONN288_ADR50017P130CC-SCONN2A   I147 @S9S_MB_2U_LIB.S9S_MB_2U(SCH_1):PAGE98
   J17  230 VSS100 SCONN288_ADR50017P130CC-SCONN2A   I147 @S9S_MB_2U_LIB.S9S_MB_2U(SCH_1):PAGE98
   J17  233 VSS101 SCONN288_ADR50017P130CC-SCONN2A   I147 @S9S_MB_2U_LIB.S9S_MB_2U(SCH_1):PAGE98
   J17  235 VSS102 SCONN288_ADR50017P130CC-SCONN2A   I147 @S9S_MB_2U_LIB.S9S_MB_2U(SCH_1):PAGE98
   J17  237 VSS103 SCONN288_ADR50017P130CC-SCONN2A   I147 @S9S_MB_2U_LIB.S9S_MB_2U(SCH_1):PAGE98
   J17  240 VSS104 SCONN288_ADR50017P130CC-SCONN2A   I147 @S9S_MB_2U_LIB.S9S_MB_2U(SCH_1):PAGE98
   J17  242 VSS105 SCONN288_ADR50017P130CC-SCONN2A   I147 @S9S_MB_2U_LIB.S9S_MB_2U(SCH_1):PAGE98
   J17  244 VSS106 SCONN288_ADR50017P130CC-SCONN2A   I147 @S9S_MB_2U_LIB.S9S_MB_2U(SCH_1):PAGE98
   J17  246 VSS107 SCONN288_ADR50017P130CC-SCONN2A   I147 @S9S_MB_2U_LIB.S9S_MB_2U(SCH_1):PAGE98
   J17  248 VSS108 SCONN288_ADR50017P130CC-SCONN2A   I147 @S9S_MB_2U_LIB.S9S_MB_2U(SCH_1):PAGE98
   J17  251 VSS109 SCONN288_ADR50017P130CC-SCONN2A   I147 @S9S_MB_2U_LIB.S9S_MB_2U(SCH_1):PAGE98
   J17  253 VSS110 SCONN288_ADR50017P130CC-SCONN2A   I147 @S9S_MB_2U_LIB.S9S_MB_2U(SCH_1):PAGE98
   J17  255 VSS111 SCONN288_ADR50017P130CC-SCONN2A   I147 @S9S_MB_2U_LIB.S9S_MB_2U(SCH_1):PAGE98
   J17  257 VSS112 SCONN288_ADR50017P130CC-SCONN2A   I147 @S9S_MB_2U_LIB.S9S_MB_2U(SCH_1):PAGE98
   J17  259 VSS113 SCONN288_ADR50017P130CC-SCONN2A   I147 @S9S_MB_2U_LIB.S9S_MB_2U(SCH_1):PAGE98
   J17  262 VSS114 SCONN288_ADR50017P130CC-SCONN2A   I147 @S9S_MB_2U_LIB.S9S_MB_2U(SCH_1):PAGE98
   J17  264 VSS115 SCONN288_ADR50017P130CC-SCONN2A   I147 @S9S_MB_2U_LIB.S9S_MB_2U(SCH_1):PAGE98
   J17  266 VSS116 SCONN288_ADR50017P130CC-SCONN2A   I147 @S9S_MB_2U_LIB.S9S_MB_2U(SCH_1):PAGE98
   J17  268 VSS117 SCONN288_ADR50017P130CC-SCONN2A   I147 @S9S_MB_2U_LIB.S9S_MB_2U(SCH_1):PAGE98
   J17  270 VSS118 SCONN288_ADR50017P130CC-SCONN2A   I147 @S9S_MB_2U_LIB.S9S_MB_2U(SCH_1):PAGE98
   J17  273 VSS119 SCONN288_ADR50017P130CC-SCONN2A   I147 @S9S_MB_2U_LIB.S9S_MB_2U(SCH_1):PAGE98
   J17  275 VSS120 SCONN288_ADR50017P130CC-SCONN2A   I147 @S9S_MB_2U_LIB.S9S_MB_2U(SCH_1):PAGE98
   J17  277 VSS121 SCONN288_ADR50017P130CC-SCONN2A   I147 @S9S_MB_2U_LIB.S9S_MB_2U(SCH_1):PAGE98
   J17  279 VSS122 SCONN288_ADR50017P130CC-SCONN2A   I147 @S9S_MB_2U_LIB.S9S_MB_2U(SCH_1):PAGE98
   J17  281 VSS123 SCONN288_ADR50017P130CC-SCONN2A   I147 @S9S_MB_2U_LIB.S9S_MB_2U(SCH_1):PAGE98
   J17  284 VSS124 SCONN288_ADR50017P130CC-SCONN2A   I147 @S9S_MB_2U_LIB.S9S_MB_2U(SCH_1):PAGE98
   J17  286 VSS125 SCONN288_ADR50017P130CC-SCONN2A   I147 @S9S_MB_2U_LIB.S9S_MB_2U(SCH_1):PAGE98
   J17  288 VSS126 SCONN288_ADR50017P130CC-SCONN2A   I147 @S9S_MB_2U_LIB.S9S_MB_2U(SCH_1):PAGE98
   R43    2      B Q_RES_0402LF-15.4K,1%,1/16W,CHA     I2 @S9S_MB_2U_LIB.S9S_MB_2U(SCH_1):PAGE99
   C53    2      B Q_CAP_C0402-2.2UF,6.3V,20%,X6SA   I122 @S9S_MB_2U_LIB.S9S_MB_2U(SCH_1):PAGE99
   C54    2      B Q_CAP_C0805-10UF,16V,10%,X6S,CA   I126 @S9S_MB_2U_LIB.S9S_MB_2U(SCH_1):PAGE99
   C55    2      B Q_CAP_C0805-10UF,16V,10%,X6S,CA   I128 @S9S_MB_2U_LIB.S9S_MB_2U(SCH_1):PAGE99
   J18   G1     G1 SCONN288_ADR50017P087CC-SCONN2A   I175 @S9S_MB_2U_LIB.S9S_MB_2U(SCH_1):PAGE99
   J18   G2     G2 SCONN288_ADR50017P087CC-SCONN2A   I175 @S9S_MB_2U_LIB.S9S_MB_2U(SCH_1):PAGE99
   J18   G3     G3 SCONN288_ADR50017P087CC-SCONN2A   I175 @S9S_MB_2U_LIB.S9S_MB_2U(SCH_1):PAGE99
   J18    6   VSS0 SCONN288_ADR50017P087CC-SCONN2A   I175 @S9S_MB_2U_LIB.S9S_MB_2U(SCH_1):PAGE99
   J18    8   VSS1 SCONN288_ADR50017P087CC-SCONN2A   I175 @S9S_MB_2U_LIB.S9S_MB_2U(SCH_1):PAGE99
   J18   10   VSS2 SCONN288_ADR50017P087CC-SCONN2A   I175 @S9S_MB_2U_LIB.S9S_MB_2U(SCH_1):PAGE99
   J18   13   VSS3 SCONN288_ADR50017P087CC-SCONN2A   I175 @S9S_MB_2U_LIB.S9S_MB_2U(SCH_1):PAGE99
   J18   15   VSS4 SCONN288_ADR50017P087CC-SCONN2A   I175 @S9S_MB_2U_LIB.S9S_MB_2U(SCH_1):PAGE99
   J18   17   VSS5 SCONN288_ADR50017P087CC-SCONN2A   I175 @S9S_MB_2U_LIB.S9S_MB_2U(SCH_1):PAGE99
   J18   19   VSS6 SCONN288_ADR50017P087CC-SCONN2A   I175 @S9S_MB_2U_LIB.S9S_MB_2U(SCH_1):PAGE99
   J18   21   VSS7 SCONN288_ADR50017P087CC-SCONN2A   I175 @S9S_MB_2U_LIB.S9S_MB_2U(SCH_1):PAGE99
   J18   24   VSS8 SCONN288_ADR50017P087CC-SCONN2A   I175 @S9S_MB_2U_LIB.S9S_MB_2U(SCH_1):PAGE99
   J18   26   VSS9 SCONN288_ADR50017P087CC-SCONN2A   I175 @S9S_MB_2U_LIB.S9S_MB_2U(SCH_1):PAGE99
   J18   28  VSS10 SCONN288_ADR50017P087CC-SCONN2A   I175 @S9S_MB_2U_LIB.S9S_MB_2U(SCH_1):PAGE99
   J18   30  VSS11 SCONN288_ADR50017P087CC-SCONN2A   I175 @S9S_MB_2U_LIB.S9S_MB_2U(SCH_1):PAGE99
   J18   32  VSS12 SCONN288_ADR50017P087CC-SCONN2A   I175 @S9S_MB_2U_LIB.S9S_MB_2U(SCH_1):PAGE99
   J18   35  VSS13 SCONN288_ADR50017P087CC-SCONN2A   I175 @S9S_MB_2U_LIB.S9S_MB_2U(SCH_1):PAGE99
   J18   37  VSS14 SCONN288_ADR50017P087CC-SCONN2A   I175 @S9S_MB_2U_LIB.S9S_MB_2U(SCH_1):PAGE99
   J18   39  VSS15 SCONN288_ADR50017P087CC-SCONN2A   I175 @S9S_MB_2U_LIB.S9S_MB_2U(SCH_1):PAGE99
   J18   41  VSS16 SCONN288_ADR50017P087CC-SCONN2A   I175 @S9S_MB_2U_LIB.S9S_MB_2U(SCH_1):PAGE99
   J18   43  VSS17 SCONN288_ADR50017P087CC-SCONN2A   I175 @S9S_MB_2U_LIB.S9S_MB_2U(SCH_1):PAGE99
   J18   46  VSS18 SCONN288_ADR50017P087CC-SCONN2A   I175 @S9S_MB_2U_LIB.S9S_MB_2U(SCH_1):PAGE99
   J18   48  VSS19 SCONN288_ADR50017P087CC-SCONN2A   I175 @S9S_MB_2U_LIB.S9S_MB_2U(SCH_1):PAGE99
   J18   50  VSS20 SCONN288_ADR50017P087CC-SCONN2A   I175 @S9S_MB_2U_LIB.S9S_MB_2U(SCH_1):PAGE99
   J18   52  VSS21 SCONN288_ADR50017P087CC-SCONN2A   I175 @S9S_MB_2U_LIB.S9S_MB_2U(SCH_1):PAGE99
   J18   54  VSS22 SCONN288_ADR50017P087CC-SCONN2A   I175 @S9S_MB_2U_LIB.S9S_MB_2U(SCH_1):PAGE99
   J18   57  VSS23 SCONN288_ADR50017P087CC-SCONN2A   I175 @S9S_MB_2U_LIB.S9S_MB_2U(SCH_1):PAGE99
   J18   59  VSS24 SCONN288_ADR50017P087CC-SCONN2A   I175 @S9S_MB_2U_LIB.S9S_MB_2U(SCH_1):PAGE99
   J18   61  VSS25 SCONN288_ADR50017P087CC-SCONN2A   I175 @S9S_MB_2U_LIB.S9S_MB_2U(SCH_1):PAGE99
   J18   63  VSS26 SCONN288_ADR50017P087CC-SCONN2A   I175 @S9S_MB_2U_LIB.S9S_MB_2U(SCH_1):PAGE99
   J18   65  VSS27 SCONN288_ADR50017P087CC-SCONN2A   I175 @S9S_MB_2U_LIB.S9S_MB_2U(SCH_1):PAGE99
   J18   67  VSS28 SCONN288_ADR50017P087CC-SCONN2A   I175 @S9S_MB_2U_LIB.S9S_MB_2U(SCH_1):PAGE99
   J18   69  VSS29 SCONN288_ADR50017P087CC-SCONN2A   I175 @S9S_MB_2U_LIB.S9S_MB_2U(SCH_1):PAGE99
   J18   71  VSS30 SCONN288_ADR50017P087CC-SCONN2A   I175 @S9S_MB_2U_LIB.S9S_MB_2U(SCH_1):PAGE99
   J18   73  VSS31 SCONN288_ADR50017P087CC-SCONN2A   I175 @S9S_MB_2U_LIB.S9S_MB_2U(SCH_1):PAGE99
   J18   75  VSS32 SCONN288_ADR50017P087CC-SCONN2A   I175 @S9S_MB_2U_LIB.S9S_MB_2U(SCH_1):PAGE99
   J18   77  VSS33 SCONN288_ADR50017P087CC-SCONN2A   I175 @S9S_MB_2U_LIB.S9S_MB_2U(SCH_1):PAGE99
   J18   79  VSS34 SCONN288_ADR50017P087CC-SCONN2A   I175 @S9S_MB_2U_LIB.S9S_MB_2U(SCH_1):PAGE99
   J18   81  VSS35 SCONN288_ADR50017P087CC-SCONN2A   I175 @S9S_MB_2U_LIB.S9S_MB_2U(SCH_1):PAGE99
   J18   83  VSS36 SCONN288_ADR50017P087CC-SCONN2A   I175 @S9S_MB_2U_LIB.S9S_MB_2U(SCH_1):PAGE99
   J18   85  VSS37 SCONN288_ADR50017P087CC-SCONN2A   I175 @S9S_MB_2U_LIB.S9S_MB_2U(SCH_1):PAGE99
   J18   88  VSS38 SCONN288_ADR50017P087CC-SCONN2A   I175 @S9S_MB_2U_LIB.S9S_MB_2U(SCH_1):PAGE99
   J18   90  VSS39 SCONN288_ADR50017P087CC-SCONN2A   I175 @S9S_MB_2U_LIB.S9S_MB_2U(SCH_1):PAGE99
   J18   92  VSS40 SCONN288_ADR50017P087CC-SCONN2A   I175 @S9S_MB_2U_LIB.S9S_MB_2U(SCH_1):PAGE99
   J18   95  VSS41 SCONN288_ADR50017P087CC-SCONN2A   I175 @S9S_MB_2U_LIB.S9S_MB_2U(SCH_1):PAGE99
   J18   97  VSS42 SCONN288_ADR50017P087CC-SCONN2A   I175 @S9S_MB_2U_LIB.S9S_MB_2U(SCH_1):PAGE99
   J18   99  VSS43 SCONN288_ADR50017P087CC-SCONN2A   I175 @S9S_MB_2U_LIB.S9S_MB_2U(SCH_1):PAGE99
   J18  101  VSS44 SCONN288_ADR50017P087CC-SCONN2A   I175 @S9S_MB_2U_LIB.S9S_MB_2U(SCH_1):PAGE99
   J18  103  VSS45 SCONN288_ADR50017P087CC-SCONN2A   I175 @S9S_MB_2U_LIB.S9S_MB_2U(SCH_1):PAGE99
   J18  106  VSS46 SCONN288_ADR50017P087CC-SCONN2A   I175 @S9S_MB_2U_LIB.S9S_MB_2U(SCH_1):PAGE99
   J18  108  VSS47 SCONN288_ADR50017P087CC-SCONN2A   I175 @S9S_MB_2U_LIB.S9S_MB_2U(SCH_1):PAGE99
   J18  110  VSS48 SCONN288_ADR50017P087CC-SCONN2A   I175 @S9S_MB_2U_LIB.S9S_MB_2U(SCH_1):PAGE99
   J18  112  VSS49 SCONN288_ADR50017P087CC-SCONN2A   I175 @S9S_MB_2U_LIB.S9S_MB_2U(SCH_1):PAGE99
   J18  114  VSS50 SCONN288_ADR50017P087CC-SCONN2A   I175 @S9S_MB_2U_LIB.S9S_MB_2U(SCH_1):PAGE99
   J18  117  VSS51 SCONN288_ADR50017P087CC-SCONN2A   I175 @S9S_MB_2U_LIB.S9S_MB_2U(SCH_1):PAGE99
   J18  119  VSS52 SCONN288_ADR50017P087CC-SCONN2A   I175 @S9S_MB_2U_LIB.S9S_MB_2U(SCH_1):PAGE99
   J18  121  VSS53 SCONN288_ADR50017P087CC-SCONN2A   I175 @S9S_MB_2U_LIB.S9S_MB_2U(SCH_1):PAGE99
   J18  123  VSS54 SCONN288_ADR50017P087CC-SCONN2A   I175 @S9S_MB_2U_LIB.S9S_MB_2U(SCH_1):PAGE99
   J18  125  VSS55 SCONN288_ADR50017P087CC-SCONN2A   I175 @S9S_MB_2U_LIB.S9S_MB_2U(SCH_1):PAGE99
   J18  128  VSS56 SCONN288_ADR50017P087CC-SCONN2A   I175 @S9S_MB_2U_LIB.S9S_MB_2U(SCH_1):PAGE99
   J18  130  VSS57 SCONN288_ADR50017P087CC-SCONN2A   I175 @S9S_MB_2U_LIB.S9S_MB_2U(SCH_1):PAGE99
   J18  132  VSS58 SCONN288_ADR50017P087CC-SCONN2A   I175 @S9S_MB_2U_LIB.S9S_MB_2U(SCH_1):PAGE99
   J18  134  VSS59 SCONN288_ADR50017P087CC-SCONN2A   I175 @S9S_MB_2U_LIB.S9S_MB_2U(SCH_1):PAGE99
   J18  136  VSS60 SCONN288_ADR50017P087CC-SCONN2A   I175 @S9S_MB_2U_LIB.S9S_MB_2U(SCH_1):PAGE99
   J18  139  VSS61 SCONN288_ADR50017P087CC-SCONN2A   I175 @S9S_MB_2U_LIB.S9S_MB_2U(SCH_1):PAGE99
   J18  141  VSS62 SCONN288_ADR50017P087CC-SCONN2A   I175 @S9S_MB_2U_LIB.S9S_MB_2U(SCH_1):PAGE99
   J18  143  VSS63 SCONN288_ADR50017P087CC-SCONN2A   I175 @S9S_MB_2U_LIB.S9S_MB_2U(SCH_1):PAGE99
   J18  151  VSS64 SCONN288_ADR50017P087CC-SCONN2A   I175 @S9S_MB_2U_LIB.S9S_MB_2U(SCH_1):PAGE99
   J18  153  VSS65 SCONN288_ADR50017P087CC-SCONN2A   I175 @S9S_MB_2U_LIB.S9S_MB_2U(SCH_1):PAGE99
   J18  155  VSS66 SCONN288_ADR50017P087CC-SCONN2A   I175 @S9S_MB_2U_LIB.S9S_MB_2U(SCH_1):PAGE99
   J18  158  VSS67 SCONN288_ADR50017P087CC-SCONN2A   I175 @S9S_MB_2U_LIB.S9S_MB_2U(SCH_1):PAGE99
   J18  160  VSS68 SCONN288_ADR50017P087CC-SCONN2A   I175 @S9S_MB_2U_LIB.S9S_MB_2U(SCH_1):PAGE99
   J18  162  VSS69 SCONN288_ADR50017P087CC-SCONN2A   I175 @S9S_MB_2U_LIB.S9S_MB_2U(SCH_1):PAGE99
   J18  164  VSS70 SCONN288_ADR50017P087CC-SCONN2A   I175 @S9S_MB_2U_LIB.S9S_MB_2U(SCH_1):PAGE99
   J18  166  VSS71 SCONN288_ADR50017P087CC-SCONN2A   I175 @S9S_MB_2U_LIB.S9S_MB_2U(SCH_1):PAGE99
   J18  169  VSS72 SCONN288_ADR50017P087CC-SCONN2A   I175 @S9S_MB_2U_LIB.S9S_MB_2U(SCH_1):PAGE99
   J18  171  VSS73 SCONN288_ADR50017P087CC-SCONN2A   I175 @S9S_MB_2U_LIB.S9S_MB_2U(SCH_1):PAGE99
   J18  173  VSS74 SCONN288_ADR50017P087CC-SCONN2A   I175 @S9S_MB_2U_LIB.S9S_MB_2U(SCH_1):PAGE99
   J18  175  VSS75 SCONN288_ADR50017P087CC-SCONN2A   I175 @S9S_MB_2U_LIB.S9S_MB_2U(SCH_1):PAGE99
   J18  177  VSS76 SCONN288_ADR50017P087CC-SCONN2A   I175 @S9S_MB_2U_LIB.S9S_MB_2U(SCH_1):PAGE99
   J18  180  VSS77 SCONN288_ADR50017P087CC-SCONN2A   I175 @S9S_MB_2U_LIB.S9S_MB_2U(SCH_1):PAGE99
   J18  182  VSS78 SCONN288_ADR50017P087CC-SCONN2A   I175 @S9S_MB_2U_LIB.S9S_MB_2U(SCH_1):PAGE99
   J18  184  VSS79 SCONN288_ADR50017P087CC-SCONN2A   I175 @S9S_MB_2U_LIB.S9S_MB_2U(SCH_1):PAGE99
   J18  186  VSS80 SCONN288_ADR50017P087CC-SCONN2A   I175 @S9S_MB_2U_LIB.S9S_MB_2U(SCH_1):PAGE99
   J18  188  VSS81 SCONN288_ADR50017P087CC-SCONN2A   I175 @S9S_MB_2U_LIB.S9S_MB_2U(SCH_1):PAGE99
   J18  191  VSS82 SCONN288_ADR50017P087CC-SCONN2A   I175 @S9S_MB_2U_LIB.S9S_MB_2U(SCH_1):PAGE99
   J18  193  VSS83 SCONN288_ADR50017P087CC-SCONN2A   I175 @S9S_MB_2U_LIB.S9S_MB_2U(SCH_1):PAGE99
   J18  195  VSS84 SCONN288_ADR50017P087CC-SCONN2A   I175 @S9S_MB_2U_LIB.S9S_MB_2U(SCH_1):PAGE99
   J18  197  VSS85 SCONN288_ADR50017P087CC-SCONN2A   I175 @S9S_MB_2U_LIB.S9S_MB_2U(SCH_1):PAGE99
   J18  199  VSS86 SCONN288_ADR50017P087CC-SCONN2A   I175 @S9S_MB_2U_LIB.S9S_MB_2U(SCH_1):PAGE99
   J18  202  VSS87 SCONN288_ADR50017P087CC-SCONN2A   I175 @S9S_MB_2U_LIB.S9S_MB_2U(SCH_1):PAGE99
   J18  204  VSS88 SCONN288_ADR50017P087CC-SCONN2A   I175 @S9S_MB_2U_LIB.S9S_MB_2U(SCH_1):PAGE99
   J18  206  VSS89 SCONN288_ADR50017P087CC-SCONN2A   I175 @S9S_MB_2U_LIB.S9S_MB_2U(SCH_1):PAGE99
   J18  208  VSS90 SCONN288_ADR50017P087CC-SCONN2A   I175 @S9S_MB_2U_LIB.S9S_MB_2U(SCH_1):PAGE99
   J18  210  VSS91 SCONN288_ADR50017P087CC-SCONN2A   I175 @S9S_MB_2U_LIB.S9S_MB_2U(SCH_1):PAGE99
   J18  212  VSS92 SCONN288_ADR50017P087CC-SCONN2A   I175 @S9S_MB_2U_LIB.S9S_MB_2U(SCH_1):PAGE99
   J18  214  VSS93 SCONN288_ADR50017P087CC-SCONN2A   I175 @S9S_MB_2U_LIB.S9S_MB_2U(SCH_1):PAGE99
   J18  216  VSS94 SCONN288_ADR50017P087CC-SCONN2A   I175 @S9S_MB_2U_LIB.S9S_MB_2U(SCH_1):PAGE99
   J18  219  VSS95 SCONN288_ADR50017P087CC-SCONN2A   I175 @S9S_MB_2U_LIB.S9S_MB_2U(SCH_1):PAGE99
   J18  222  VSS96 SCONN288_ADR50017P087CC-SCONN2A   I175 @S9S_MB_2U_LIB.S9S_MB_2U(SCH_1):PAGE99
   J18  224  VSS97 SCONN288_ADR50017P087CC-SCONN2A   I175 @S9S_MB_2U_LIB.S9S_MB_2U(SCH_1):PAGE99
   J18  226  VSS98 SCONN288_ADR50017P087CC-SCONN2A   I175 @S9S_MB_2U_LIB.S9S_MB_2U(SCH_1):PAGE99
   J18  228  VSS99 SCONN288_ADR50017P087CC-SCONN2A   I175 @S9S_MB_2U_LIB.S9S_MB_2U(SCH_1):PAGE99
   J18  230 VSS100 SCONN288_ADR50017P087CC-SCONN2A   I175 @S9S_MB_2U_LIB.S9S_MB_2U(SCH_1):PAGE99
   J18  233 VSS101 SCONN288_ADR50017P087CC-SCONN2A   I175 @S9S_MB_2U_LIB.S9S_MB_2U(SCH_1):PAGE99
   J18  235 VSS102 SCONN288_ADR50017P087CC-SCONN2A   I175 @S9S_MB_2U_LIB.S9S_MB_2U(SCH_1):PAGE99
   J18  237 VSS103 SCONN288_ADR50017P087CC-SCONN2A   I175 @S9S_MB_2U_LIB.S9S_MB_2U(SCH_1):PAGE99
   J18  240 VSS104 SCONN288_ADR50017P087CC-SCONN2A   I175 @S9S_MB_2U_LIB.S9S_MB_2U(SCH_1):PAGE99
   J18  242 VSS105 SCONN288_ADR50017P087CC-SCONN2A   I175 @S9S_MB_2U_LIB.S9S_MB_2U(SCH_1):PAGE99
   J18  244 VSS106 SCONN288_ADR50017P087CC-SCONN2A   I175 @S9S_MB_2U_LIB.S9S_MB_2U(SCH_1):PAGE99
   J18  246 VSS107 SCONN288_ADR50017P087CC-SCONN2A   I175 @S9S_MB_2U_LIB.S9S_MB_2U(SCH_1):PAGE99
   J18  248 VSS108 SCONN288_ADR50017P087CC-SCONN2A   I175 @S9S_MB_2U_LIB.S9S_MB_2U(SCH_1):PAGE99
   J18  251 VSS109 SCONN288_ADR50017P087CC-SCONN2A   I175 @S9S_MB_2U_LIB.S9S_MB_2U(SCH_1):PAGE99
   J18  253 VSS110 SCONN288_ADR50017P087CC-SCONN2A   I175 @S9S_MB_2U_LIB.S9S_MB_2U(SCH_1):PAGE99
   J18  255 VSS111 SCONN288_ADR50017P087CC-SCONN2A   I175 @S9S_MB_2U_LIB.S9S_MB_2U(SCH_1):PAGE99
   J18  257 VSS112 SCONN288_ADR50017P087CC-SCONN2A   I175 @S9S_MB_2U_LIB.S9S_MB_2U(SCH_1):PAGE99
   J18  259 VSS113 SCONN288_ADR50017P087CC-SCONN2A   I175 @S9S_MB_2U_LIB.S9S_MB_2U(SCH_1):PAGE99
   J18  262 VSS114 SCONN288_ADR50017P087CC-SCONN2A   I175 @S9S_MB_2U_LIB.S9S_MB_2U(SCH_1):PAGE99
   J18  264 VSS115 SCONN288_ADR50017P087CC-SCONN2A   I175 @S9S_MB_2U_LIB.S9S_MB_2U(SCH_1):PAGE99
   J18  266 VSS116 SCONN288_ADR50017P087CC-SCONN2A   I175 @S9S_MB_2U_LIB.S9S_MB_2U(SCH_1):PAGE99
   J18  268 VSS117 SCONN288_ADR50017P087CC-SCONN2A   I175 @S9S_MB_2U_LIB.S9S_MB_2U(SCH_1):PAGE99
   J18  270 VSS118 SCONN288_ADR50017P087CC-SCONN2A   I175 @S9S_MB_2U_LIB.S9S_MB_2U(SCH_1):PAGE99
   J18  273 VSS119 SCONN288_ADR50017P087CC-SCONN2A   I175 @S9S_MB_2U_LIB.S9S_MB_2U(SCH_1):PAGE99
   J18  275 VSS120 SCONN288_ADR50017P087CC-SCONN2A   I175 @S9S_MB_2U_LIB.S9S_MB_2U(SCH_1):PAGE99
   J18  277 VSS121 SCONN288_ADR50017P087CC-SCONN2A   I175 @S9S_MB_2U_LIB.S9S_MB_2U(SCH_1):PAGE99
   J18  279 VSS122 SCONN288_ADR50017P087CC-SCONN2A   I175 @S9S_MB_2U_LIB.S9S_MB_2U(SCH_1):PAGE99
   J18  281 VSS123 SCONN288_ADR50017P087CC-SCONN2A   I175 @S9S_MB_2U_LIB.S9S_MB_2U(SCH_1):PAGE99
   J18  284 VSS124 SCONN288_ADR50017P087CC-SCONN2A   I175 @S9S_MB_2U_LIB.S9S_MB_2U(SCH_1):PAGE99
   J18  286 VSS125 SCONN288_ADR50017P087CC-SCONN2A   I175 @S9S_MB_2U_LIB.S9S_MB_2U(SCH_1):PAGE99
   J18  288 VSS126 SCONN288_ADR50017P087CC-SCONN2A   I175 @S9S_MB_2U_LIB.S9S_MB_2U(SCH_1):PAGE99
   R44    2      B Q_RES_0402LF-23.2K,1%,1/16W,CHA     I3 @S9S_MB_2U_LIB.S9S_MB_2U(SCH_1):PAGE100
   C56    2      B Q_CAP_C0402-2.2UF,6.3V,20%,X6SA   I121 @S9S_MB_2U_LIB.S9S_MB_2U(SCH_1):PAGE100
   C57    2      B Q_CAP_C0805-10UF,16V,10%,X6S,CA   I122 @S9S_MB_2U_LIB.S9S_MB_2U(SCH_1):PAGE100
   C58    2      B Q_CAP_C0805-10UF,16V,10%,X6S,CA   I124 @S9S_MB_2U_LIB.S9S_MB_2U(SCH_1):PAGE100
   J19   G1     G1 SCONN288_ADR50017P130CC-SCONN2A   I175 @S9S_MB_2U_LIB.S9S_MB_2U(SCH_1):PAGE100
   J19   G2     G2 SCONN288_ADR50017P130CC-SCONN2A   I175 @S9S_MB_2U_LIB.S9S_MB_2U(SCH_1):PAGE100
   J19   G3     G3 SCONN288_ADR50017P130CC-SCONN2A   I175 @S9S_MB_2U_LIB.S9S_MB_2U(SCH_1):PAGE100
   J19    6   VSS0 SCONN288_ADR50017P130CC-SCONN2A   I175 @S9S_MB_2U_LIB.S9S_MB_2U(SCH_1):PAGE100
   J19    8   VSS1 SCONN288_ADR50017P130CC-SCONN2A   I175 @S9S_MB_2U_LIB.S9S_MB_2U(SCH_1):PAGE100
   J19   10   VSS2 SCONN288_ADR50017P130CC-SCONN2A   I175 @S9S_MB_2U_LIB.S9S_MB_2U(SCH_1):PAGE100
   J19   13   VSS3 SCONN288_ADR50017P130CC-SCONN2A   I175 @S9S_MB_2U_LIB.S9S_MB_2U(SCH_1):PAGE100
   J19   15   VSS4 SCONN288_ADR50017P130CC-SCONN2A   I175 @S9S_MB_2U_LIB.S9S_MB_2U(SCH_1):PAGE100
   J19   17   VSS5 SCONN288_ADR50017P130CC-SCONN2A   I175 @S9S_MB_2U_LIB.S9S_MB_2U(SCH_1):PAGE100
   J19   19   VSS6 SCONN288_ADR50017P130CC-SCONN2A   I175 @S9S_MB_2U_LIB.S9S_MB_2U(SCH_1):PAGE100
   J19   21   VSS7 SCONN288_ADR50017P130CC-SCONN2A   I175 @S9S_MB_2U_LIB.S9S_MB_2U(SCH_1):PAGE100
   J19   24   VSS8 SCONN288_ADR50017P130CC-SCONN2A   I175 @S9S_MB_2U_LIB.S9S_MB_2U(SCH_1):PAGE100
   J19   26   VSS9 SCONN288_ADR50017P130CC-SCONN2A   I175 @S9S_MB_2U_LIB.S9S_MB_2U(SCH_1):PAGE100
   J19   28  VSS10 SCONN288_ADR50017P130CC-SCONN2A   I175 @S9S_MB_2U_LIB.S9S_MB_2U(SCH_1):PAGE100
   J19   30  VSS11 SCONN288_ADR50017P130CC-SCONN2A   I175 @S9S_MB_2U_LIB.S9S_MB_2U(SCH_1):PAGE100
   J19   32  VSS12 SCONN288_ADR50017P130CC-SCONN2A   I175 @S9S_MB_2U_LIB.S9S_MB_2U(SCH_1):PAGE100
   J19   35  VSS13 SCONN288_ADR50017P130CC-SCONN2A   I175 @S9S_MB_2U_LIB.S9S_MB_2U(SCH_1):PAGE100
   J19   37  VSS14 SCONN288_ADR50017P130CC-SCONN2A   I175 @S9S_MB_2U_LIB.S9S_MB_2U(SCH_1):PAGE100
   J19   39  VSS15 SCONN288_ADR50017P130CC-SCONN2A   I175 @S9S_MB_2U_LIB.S9S_MB_2U(SCH_1):PAGE100
   J19   41  VSS16 SCONN288_ADR50017P130CC-SCONN2A   I175 @S9S_MB_2U_LIB.S9S_MB_2U(SCH_1):PAGE100
   J19   43  VSS17 SCONN288_ADR50017P130CC-SCONN2A   I175 @S9S_MB_2U_LIB.S9S_MB_2U(SCH_1):PAGE100
   J19   46  VSS18 SCONN288_ADR50017P130CC-SCONN2A   I175 @S9S_MB_2U_LIB.S9S_MB_2U(SCH_1):PAGE100
   J19   48  VSS19 SCONN288_ADR50017P130CC-SCONN2A   I175 @S9S_MB_2U_LIB.S9S_MB_2U(SCH_1):PAGE100
   J19   50  VSS20 SCONN288_ADR50017P130CC-SCONN2A   I175 @S9S_MB_2U_LIB.S9S_MB_2U(SCH_1):PAGE100
   J19   52  VSS21 SCONN288_ADR50017P130CC-SCONN2A   I175 @S9S_MB_2U_LIB.S9S_MB_2U(SCH_1):PAGE100
   J19   54  VSS22 SCONN288_ADR50017P130CC-SCONN2A   I175 @S9S_MB_2U_LIB.S9S_MB_2U(SCH_1):PAGE100
   J19   57  VSS23 SCONN288_ADR50017P130CC-SCONN2A   I175 @S9S_MB_2U_LIB.S9S_MB_2U(SCH_1):PAGE100
   J19   59  VSS24 SCONN288_ADR50017P130CC-SCONN2A   I175 @S9S_MB_2U_LIB.S9S_MB_2U(SCH_1):PAGE100
   J19   61  VSS25 SCONN288_ADR50017P130CC-SCONN2A   I175 @S9S_MB_2U_LIB.S9S_MB_2U(SCH_1):PAGE100
   J19   63  VSS26 SCONN288_ADR50017P130CC-SCONN2A   I175 @S9S_MB_2U_LIB.S9S_MB_2U(SCH_1):PAGE100
   J19   65  VSS27 SCONN288_ADR50017P130CC-SCONN2A   I175 @S9S_MB_2U_LIB.S9S_MB_2U(SCH_1):PAGE100
   J19   67  VSS28 SCONN288_ADR50017P130CC-SCONN2A   I175 @S9S_MB_2U_LIB.S9S_MB_2U(SCH_1):PAGE100
   J19   69  VSS29 SCONN288_ADR50017P130CC-SCONN2A   I175 @S9S_MB_2U_LIB.S9S_MB_2U(SCH_1):PAGE100
   J19   71  VSS30 SCONN288_ADR50017P130CC-SCONN2A   I175 @S9S_MB_2U_LIB.S9S_MB_2U(SCH_1):PAGE100
   J19   73  VSS31 SCONN288_ADR50017P130CC-SCONN2A   I175 @S9S_MB_2U_LIB.S9S_MB_2U(SCH_1):PAGE100
   J19   75  VSS32 SCONN288_ADR50017P130CC-SCONN2A   I175 @S9S_MB_2U_LIB.S9S_MB_2U(SCH_1):PAGE100
   J19   77  VSS33 SCONN288_ADR50017P130CC-SCONN2A   I175 @S9S_MB_2U_LIB.S9S_MB_2U(SCH_1):PAGE100
   J19   79  VSS34 SCONN288_ADR50017P130CC-SCONN2A   I175 @S9S_MB_2U_LIB.S9S_MB_2U(SCH_1):PAGE100
   J19   81  VSS35 SCONN288_ADR50017P130CC-SCONN2A   I175 @S9S_MB_2U_LIB.S9S_MB_2U(SCH_1):PAGE100
   J19   83  VSS36 SCONN288_ADR50017P130CC-SCONN2A   I175 @S9S_MB_2U_LIB.S9S_MB_2U(SCH_1):PAGE100
   J19   85  VSS37 SCONN288_ADR50017P130CC-SCONN2A   I175 @S9S_MB_2U_LIB.S9S_MB_2U(SCH_1):PAGE100
   J19   88  VSS38 SCONN288_ADR50017P130CC-SCONN2A   I175 @S9S_MB_2U_LIB.S9S_MB_2U(SCH_1):PAGE100
   J19   90  VSS39 SCONN288_ADR50017P130CC-SCONN2A   I175 @S9S_MB_2U_LIB.S9S_MB_2U(SCH_1):PAGE100
   J19   92  VSS40 SCONN288_ADR50017P130CC-SCONN2A   I175 @S9S_MB_2U_LIB.S9S_MB_2U(SCH_1):PAGE100
   J19   95  VSS41 SCONN288_ADR50017P130CC-SCONN2A   I175 @S9S_MB_2U_LIB.S9S_MB_2U(SCH_1):PAGE100
   J19   97  VSS42 SCONN288_ADR50017P130CC-SCONN2A   I175 @S9S_MB_2U_LIB.S9S_MB_2U(SCH_1):PAGE100
   J19   99  VSS43 SCONN288_ADR50017P130CC-SCONN2A   I175 @S9S_MB_2U_LIB.S9S_MB_2U(SCH_1):PAGE100
   J19  101  VSS44 SCONN288_ADR50017P130CC-SCONN2A   I175 @S9S_MB_2U_LIB.S9S_MB_2U(SCH_1):PAGE100
   J19  103  VSS45 SCONN288_ADR50017P130CC-SCONN2A   I175 @S9S_MB_2U_LIB.S9S_MB_2U(SCH_1):PAGE100
   J19  106  VSS46 SCONN288_ADR50017P130CC-SCONN2A   I175 @S9S_MB_2U_LIB.S9S_MB_2U(SCH_1):PAGE100
   J19  108  VSS47 SCONN288_ADR50017P130CC-SCONN2A   I175 @S9S_MB_2U_LIB.S9S_MB_2U(SCH_1):PAGE100
   J19  110  VSS48 SCONN288_ADR50017P130CC-SCONN2A   I175 @S9S_MB_2U_LIB.S9S_MB_2U(SCH_1):PAGE100
   J19  112  VSS49 SCONN288_ADR50017P130CC-SCONN2A   I175 @S9S_MB_2U_LIB.S9S_MB_2U(SCH_1):PAGE100
   J19  114  VSS50 SCONN288_ADR50017P130CC-SCONN2A   I175 @S9S_MB_2U_LIB.S9S_MB_2U(SCH_1):PAGE100
   J19  117  VSS51 SCONN288_ADR50017P130CC-SCONN2A   I175 @S9S_MB_2U_LIB.S9S_MB_2U(SCH_1):PAGE100
   J19  119  VSS52 SCONN288_ADR50017P130CC-SCONN2A   I175 @S9S_MB_2U_LIB.S9S_MB_2U(SCH_1):PAGE100
   J19  121  VSS53 SCONN288_ADR50017P130CC-SCONN2A   I175 @S9S_MB_2U_LIB.S9S_MB_2U(SCH_1):PAGE100
   J19  123  VSS54 SCONN288_ADR50017P130CC-SCONN2A   I175 @S9S_MB_2U_LIB.S9S_MB_2U(SCH_1):PAGE100
   J19  125  VSS55 SCONN288_ADR50017P130CC-SCONN2A   I175 @S9S_MB_2U_LIB.S9S_MB_2U(SCH_1):PAGE100
   J19  128  VSS56 SCONN288_ADR50017P130CC-SCONN2A   I175 @S9S_MB_2U_LIB.S9S_MB_2U(SCH_1):PAGE100
   J19  130  VSS57 SCONN288_ADR50017P130CC-SCONN2A   I175 @S9S_MB_2U_LIB.S9S_MB_2U(SCH_1):PAGE100
   J19  132  VSS58 SCONN288_ADR50017P130CC-SCONN2A   I175 @S9S_MB_2U_LIB.S9S_MB_2U(SCH_1):PAGE100
   J19  134  VSS59 SCONN288_ADR50017P130CC-SCONN2A   I175 @S9S_MB_2U_LIB.S9S_MB_2U(SCH_1):PAGE100
   J19  136  VSS60 SCONN288_ADR50017P130CC-SCONN2A   I175 @S9S_MB_2U_LIB.S9S_MB_2U(SCH_1):PAGE100
   J19  139  VSS61 SCONN288_ADR50017P130CC-SCONN2A   I175 @S9S_MB_2U_LIB.S9S_MB_2U(SCH_1):PAGE100
   J19  141  VSS62 SCONN288_ADR50017P130CC-SCONN2A   I175 @S9S_MB_2U_LIB.S9S_MB_2U(SCH_1):PAGE100
   J19  143  VSS63 SCONN288_ADR50017P130CC-SCONN2A   I175 @S9S_MB_2U_LIB.S9S_MB_2U(SCH_1):PAGE100
   J19  151  VSS64 SCONN288_ADR50017P130CC-SCONN2A   I175 @S9S_MB_2U_LIB.S9S_MB_2U(SCH_1):PAGE100
   J19  153  VSS65 SCONN288_ADR50017P130CC-SCONN2A   I175 @S9S_MB_2U_LIB.S9S_MB_2U(SCH_1):PAGE100
   J19  155  VSS66 SCONN288_ADR50017P130CC-SCONN2A   I175 @S9S_MB_2U_LIB.S9S_MB_2U(SCH_1):PAGE100
   J19  158  VSS67 SCONN288_ADR50017P130CC-SCONN2A   I175 @S9S_MB_2U_LIB.S9S_MB_2U(SCH_1):PAGE100
   J19  160  VSS68 SCONN288_ADR50017P130CC-SCONN2A   I175 @S9S_MB_2U_LIB.S9S_MB_2U(SCH_1):PAGE100
   J19  162  VSS69 SCONN288_ADR50017P130CC-SCONN2A   I175 @S9S_MB_2U_LIB.S9S_MB_2U(SCH_1):PAGE100
   J19  164  VSS70 SCONN288_ADR50017P130CC-SCONN2A   I175 @S9S_MB_2U_LIB.S9S_MB_2U(SCH_1):PAGE100
   J19  166  VSS71 SCONN288_ADR50017P130CC-SCONN2A   I175 @S9S_MB_2U_LIB.S9S_MB_2U(SCH_1):PAGE100
   J19  169  VSS72 SCONN288_ADR50017P130CC-SCONN2A   I175 @S9S_MB_2U_LIB.S9S_MB_2U(SCH_1):PAGE100
   J19  171  VSS73 SCONN288_ADR50017P130CC-SCONN2A   I175 @S9S_MB_2U_LIB.S9S_MB_2U(SCH_1):PAGE100
   J19  173  VSS74 SCONN288_ADR50017P130CC-SCONN2A   I175 @S9S_MB_2U_LIB.S9S_MB_2U(SCH_1):PAGE100
   J19  175  VSS75 SCONN288_ADR50017P130CC-SCONN2A   I175 @S9S_MB_2U_LIB.S9S_MB_2U(SCH_1):PAGE100
   J19  177  VSS76 SCONN288_ADR50017P130CC-SCONN2A   I175 @S9S_MB_2U_LIB.S9S_MB_2U(SCH_1):PAGE100
   J19  180  VSS77 SCONN288_ADR50017P130CC-SCONN2A   I175 @S9S_MB_2U_LIB.S9S_MB_2U(SCH_1):PAGE100
   J19  182  VSS78 SCONN288_ADR50017P130CC-SCONN2A   I175 @S9S_MB_2U_LIB.S9S_MB_2U(SCH_1):PAGE100
   J19  184  VSS79 SCONN288_ADR50017P130CC-SCONN2A   I175 @S9S_MB_2U_LIB.S9S_MB_2U(SCH_1):PAGE100
   J19  186  VSS80 SCONN288_ADR50017P130CC-SCONN2A   I175 @S9S_MB_2U_LIB.S9S_MB_2U(SCH_1):PAGE100
   J19  188  VSS81 SCONN288_ADR50017P130CC-SCONN2A   I175 @S9S_MB_2U_LIB.S9S_MB_2U(SCH_1):PAGE100
   J19  191  VSS82 SCONN288_ADR50017P130CC-SCONN2A   I175 @S9S_MB_2U_LIB.S9S_MB_2U(SCH_1):PAGE100
   J19  193  VSS83 SCONN288_ADR50017P130CC-SCONN2A   I175 @S9S_MB_2U_LIB.S9S_MB_2U(SCH_1):PAGE100
   J19  195  VSS84 SCONN288_ADR50017P130CC-SCONN2A   I175 @S9S_MB_2U_LIB.S9S_MB_2U(SCH_1):PAGE100
   J19  197  VSS85 SCONN288_ADR50017P130CC-SCONN2A   I175 @S9S_MB_2U_LIB.S9S_MB_2U(SCH_1):PAGE100
   J19  199  VSS86 SCONN288_ADR50017P130CC-SCONN2A   I175 @S9S_MB_2U_LIB.S9S_MB_2U(SCH_1):PAGE100
   J19  202  VSS87 SCONN288_ADR50017P130CC-SCONN2A   I175 @S9S_MB_2U_LIB.S9S_MB_2U(SCH_1):PAGE100
   J19  204  VSS88 SCONN288_ADR50017P130CC-SCONN2A   I175 @S9S_MB_2U_LIB.S9S_MB_2U(SCH_1):PAGE100
   J19  206  VSS89 SCONN288_ADR50017P130CC-SCONN2A   I175 @S9S_MB_2U_LIB.S9S_MB_2U(SCH_1):PAGE100
   J19  208  VSS90 SCONN288_ADR50017P130CC-SCONN2A   I175 @S9S_MB_2U_LIB.S9S_MB_2U(SCH_1):PAGE100
   J19  210  VSS91 SCONN288_ADR50017P130CC-SCONN2A   I175 @S9S_MB_2U_LIB.S9S_MB_2U(SCH_1):PAGE100
   J19  212  VSS92 SCONN288_ADR50017P130CC-SCONN2A   I175 @S9S_MB_2U_LIB.S9S_MB_2U(SCH_1):PAGE100
   J19  214  VSS93 SCONN288_ADR50017P130CC-SCONN2A   I175 @S9S_MB_2U_LIB.S9S_MB_2U(SCH_1):PAGE100
   J19  216  VSS94 SCONN288_ADR50017P130CC-SCONN2A   I175 @S9S_MB_2U_LIB.S9S_MB_2U(SCH_1):PAGE100
   J19  219  VSS95 SCONN288_ADR50017P130CC-SCONN2A   I175 @S9S_MB_2U_LIB.S9S_MB_2U(SCH_1):PAGE100
   J19  222  VSS96 SCONN288_ADR50017P130CC-SCONN2A   I175 @S9S_MB_2U_LIB.S9S_MB_2U(SCH_1):PAGE100
   J19  224  VSS97 SCONN288_ADR50017P130CC-SCONN2A   I175 @S9S_MB_2U_LIB.S9S_MB_2U(SCH_1):PAGE100
   J19  226  VSS98 SCONN288_ADR50017P130CC-SCONN2A   I175 @S9S_MB_2U_LIB.S9S_MB_2U(SCH_1):PAGE100
   J19  228  VSS99 SCONN288_ADR50017P130CC-SCONN2A   I175 @S9S_MB_2U_LIB.S9S_MB_2U(SCH_1):PAGE100
   J19  230 VSS100 SCONN288_ADR50017P130CC-SCONN2A   I175 @S9S_MB_2U_LIB.S9S_MB_2U(SCH_1):PAGE100
   J19  233 VSS101 SCONN288_ADR50017P130CC-SCONN2A   I175 @S9S_MB_2U_LIB.S9S_MB_2U(SCH_1):PAGE100
   J19  235 VSS102 SCONN288_ADR50017P130CC-SCONN2A   I175 @S9S_MB_2U_LIB.S9S_MB_2U(SCH_1):PAGE100
   J19  237 VSS103 SCONN288_ADR50017P130CC-SCONN2A   I175 @S9S_MB_2U_LIB.S9S_MB_2U(SCH_1):PAGE100
   J19  240 VSS104 SCONN288_ADR50017P130CC-SCONN2A   I175 @S9S_MB_2U_LIB.S9S_MB_2U(SCH_1):PAGE100
   J19  242 VSS105 SCONN288_ADR50017P130CC-SCONN2A   I175 @S9S_MB_2U_LIB.S9S_MB_2U(SCH_1):PAGE100
   J19  244 VSS106 SCONN288_ADR50017P130CC-SCONN2A   I175 @S9S_MB_2U_LIB.S9S_MB_2U(SCH_1):PAGE100
   J19  246 VSS107 SCONN288_ADR50017P130CC-SCONN2A   I175 @S9S_MB_2U_LIB.S9S_MB_2U(SCH_1):PAGE100
   J19  248 VSS108 SCONN288_ADR50017P130CC-SCONN2A   I175 @S9S_MB_2U_LIB.S9S_MB_2U(SCH_1):PAGE100
   J19  251 VSS109 SCONN288_ADR50017P130CC-SCONN2A   I175 @S9S_MB_2U_LIB.S9S_MB_2U(SCH_1):PAGE100
   J19  253 VSS110 SCONN288_ADR50017P130CC-SCONN2A   I175 @S9S_MB_2U_LIB.S9S_MB_2U(SCH_1):PAGE100
   J19  255 VSS111 SCONN288_ADR50017P130CC-SCONN2A   I175 @S9S_MB_2U_LIB.S9S_MB_2U(SCH_1):PAGE100
   J19  257 VSS112 SCONN288_ADR50017P130CC-SCONN2A   I175 @S9S_MB_2U_LIB.S9S_MB_2U(SCH_1):PAGE100
   J19  259 VSS113 SCONN288_ADR50017P130CC-SCONN2A   I175 @S9S_MB_2U_LIB.S9S_MB_2U(SCH_1):PAGE100
   J19  262 VSS114 SCONN288_ADR50017P130CC-SCONN2A   I175 @S9S_MB_2U_LIB.S9S_MB_2U(SCH_1):PAGE100
   J19  264 VSS115 SCONN288_ADR50017P130CC-SCONN2A   I175 @S9S_MB_2U_LIB.S9S_MB_2U(SCH_1):PAGE100
   J19  266 VSS116 SCONN288_ADR50017P130CC-SCONN2A   I175 @S9S_MB_2U_LIB.S9S_MB_2U(SCH_1):PAGE100
   J19  268 VSS117 SCONN288_ADR50017P130CC-SCONN2A   I175 @S9S_MB_2U_LIB.S9S_MB_2U(SCH_1):PAGE100
   J19  270 VSS118 SCONN288_ADR50017P130CC-SCONN2A   I175 @S9S_MB_2U_LIB.S9S_MB_2U(SCH_1):PAGE100
   J19  273 VSS119 SCONN288_ADR50017P130CC-SCONN2A   I175 @S9S_MB_2U_LIB.S9S_MB_2U(SCH_1):PAGE100
   J19  275 VSS120 SCONN288_ADR50017P130CC-SCONN2A   I175 @S9S_MB_2U_LIB.S9S_MB_2U(SCH_1):PAGE100
   J19  277 VSS121 SCONN288_ADR50017P130CC-SCONN2A   I175 @S9S_MB_2U_LIB.S9S_MB_2U(SCH_1):PAGE100
   J19  279 VSS122 SCONN288_ADR50017P130CC-SCONN2A   I175 @S9S_MB_2U_LIB.S9S_MB_2U(SCH_1):PAGE100
   J19  281 VSS123 SCONN288_ADR50017P130CC-SCONN2A   I175 @S9S_MB_2U_LIB.S9S_MB_2U(SCH_1):PAGE100
   J19  284 VSS124 SCONN288_ADR50017P130CC-SCONN2A   I175 @S9S_MB_2U_LIB.S9S_MB_2U(SCH_1):PAGE100
   J19  286 VSS125 SCONN288_ADR50017P130CC-SCONN2A   I175 @S9S_MB_2U_LIB.S9S_MB_2U(SCH_1):PAGE100
   J19  288 VSS126 SCONN288_ADR50017P130CC-SCONN2A   I175 @S9S_MB_2U_LIB.S9S_MB_2U(SCH_1):PAGE100
   R45    2      B Q_RES_0402LF-35.7K,1%,1/16W,CHA    I46 @S9S_MB_2U_LIB.S9S_MB_2U(SCH_1):PAGE101
   C59    2      B Q_CAP_C0402-2.2UF,6.3V,20%,X6SA   I121 @S9S_MB_2U_LIB.S9S_MB_2U(SCH_1):PAGE101
   C60    2      B Q_CAP_C0805-10UF,16V,10%,X6S,CA   I125 @S9S_MB_2U_LIB.S9S_MB_2U(SCH_1):PAGE101
   C61    2      B Q_CAP_C0805-10UF,16V,10%,X6S,CA   I127 @S9S_MB_2U_LIB.S9S_MB_2U(SCH_1):PAGE101
   J20   G1     G1 SCONN288_ADR50017P087CC-SCONN2A   I176 @S9S_MB_2U_LIB.S9S_MB_2U(SCH_1):PAGE101
   J20   G2     G2 SCONN288_ADR50017P087CC-SCONN2A   I176 @S9S_MB_2U_LIB.S9S_MB_2U(SCH_1):PAGE101
   J20   G3     G3 SCONN288_ADR50017P087CC-SCONN2A   I176 @S9S_MB_2U_LIB.S9S_MB_2U(SCH_1):PAGE101
   J20    6   VSS0 SCONN288_ADR50017P087CC-SCONN2A   I176 @S9S_MB_2U_LIB.S9S_MB_2U(SCH_1):PAGE101
   J20    8   VSS1 SCONN288_ADR50017P087CC-SCONN2A   I176 @S9S_MB_2U_LIB.S9S_MB_2U(SCH_1):PAGE101
   J20   10   VSS2 SCONN288_ADR50017P087CC-SCONN2A   I176 @S9S_MB_2U_LIB.S9S_MB_2U(SCH_1):PAGE101
   J20   13   VSS3 SCONN288_ADR50017P087CC-SCONN2A   I176 @S9S_MB_2U_LIB.S9S_MB_2U(SCH_1):PAGE101
   J20   15   VSS4 SCONN288_ADR50017P087CC-SCONN2A   I176 @S9S_MB_2U_LIB.S9S_MB_2U(SCH_1):PAGE101
   J20   17   VSS5 SCONN288_ADR50017P087CC-SCONN2A   I176 @S9S_MB_2U_LIB.S9S_MB_2U(SCH_1):PAGE101
   J20   19   VSS6 SCONN288_ADR50017P087CC-SCONN2A   I176 @S9S_MB_2U_LIB.S9S_MB_2U(SCH_1):PAGE101
   J20   21   VSS7 SCONN288_ADR50017P087CC-SCONN2A   I176 @S9S_MB_2U_LIB.S9S_MB_2U(SCH_1):PAGE101
   J20   24   VSS8 SCONN288_ADR50017P087CC-SCONN2A   I176 @S9S_MB_2U_LIB.S9S_MB_2U(SCH_1):PAGE101
   J20   26   VSS9 SCONN288_ADR50017P087CC-SCONN2A   I176 @S9S_MB_2U_LIB.S9S_MB_2U(SCH_1):PAGE101
   J20   28  VSS10 SCONN288_ADR50017P087CC-SCONN2A   I176 @S9S_MB_2U_LIB.S9S_MB_2U(SCH_1):PAGE101
   J20   30  VSS11 SCONN288_ADR50017P087CC-SCONN2A   I176 @S9S_MB_2U_LIB.S9S_MB_2U(SCH_1):PAGE101
   J20   32  VSS12 SCONN288_ADR50017P087CC-SCONN2A   I176 @S9S_MB_2U_LIB.S9S_MB_2U(SCH_1):PAGE101
   J20   35  VSS13 SCONN288_ADR50017P087CC-SCONN2A   I176 @S9S_MB_2U_LIB.S9S_MB_2U(SCH_1):PAGE101
   J20   37  VSS14 SCONN288_ADR50017P087CC-SCONN2A   I176 @S9S_MB_2U_LIB.S9S_MB_2U(SCH_1):PAGE101
   J20   39  VSS15 SCONN288_ADR50017P087CC-SCONN2A   I176 @S9S_MB_2U_LIB.S9S_MB_2U(SCH_1):PAGE101
   J20   41  VSS16 SCONN288_ADR50017P087CC-SCONN2A   I176 @S9S_MB_2U_LIB.S9S_MB_2U(SCH_1):PAGE101
   J20   43  VSS17 SCONN288_ADR50017P087CC-SCONN2A   I176 @S9S_MB_2U_LIB.S9S_MB_2U(SCH_1):PAGE101
   J20   46  VSS18 SCONN288_ADR50017P087CC-SCONN2A   I176 @S9S_MB_2U_LIB.S9S_MB_2U(SCH_1):PAGE101
   J20   48  VSS19 SCONN288_ADR50017P087CC-SCONN2A   I176 @S9S_MB_2U_LIB.S9S_MB_2U(SCH_1):PAGE101
   J20   50  VSS20 SCONN288_ADR50017P087CC-SCONN2A   I176 @S9S_MB_2U_LIB.S9S_MB_2U(SCH_1):PAGE101
   J20   52  VSS21 SCONN288_ADR50017P087CC-SCONN2A   I176 @S9S_MB_2U_LIB.S9S_MB_2U(SCH_1):PAGE101
   J20   54  VSS22 SCONN288_ADR50017P087CC-SCONN2A   I176 @S9S_MB_2U_LIB.S9S_MB_2U(SCH_1):PAGE101
   J20   57  VSS23 SCONN288_ADR50017P087CC-SCONN2A   I176 @S9S_MB_2U_LIB.S9S_MB_2U(SCH_1):PAGE101
   J20   59  VSS24 SCONN288_ADR50017P087CC-SCONN2A   I176 @S9S_MB_2U_LIB.S9S_MB_2U(SCH_1):PAGE101
   J20   61  VSS25 SCONN288_ADR50017P087CC-SCONN2A   I176 @S9S_MB_2U_LIB.S9S_MB_2U(SCH_1):PAGE101
   J20   63  VSS26 SCONN288_ADR50017P087CC-SCONN2A   I176 @S9S_MB_2U_LIB.S9S_MB_2U(SCH_1):PAGE101
   J20   65  VSS27 SCONN288_ADR50017P087CC-SCONN2A   I176 @S9S_MB_2U_LIB.S9S_MB_2U(SCH_1):PAGE101
   J20   67  VSS28 SCONN288_ADR50017P087CC-SCONN2A   I176 @S9S_MB_2U_LIB.S9S_MB_2U(SCH_1):PAGE101
   J20   69  VSS29 SCONN288_ADR50017P087CC-SCONN2A   I176 @S9S_MB_2U_LIB.S9S_MB_2U(SCH_1):PAGE101
   J20   71  VSS30 SCONN288_ADR50017P087CC-SCONN2A   I176 @S9S_MB_2U_LIB.S9S_MB_2U(SCH_1):PAGE101
   J20   73  VSS31 SCONN288_ADR50017P087CC-SCONN2A   I176 @S9S_MB_2U_LIB.S9S_MB_2U(SCH_1):PAGE101
   J20   75  VSS32 SCONN288_ADR50017P087CC-SCONN2A   I176 @S9S_MB_2U_LIB.S9S_MB_2U(SCH_1):PAGE101
   J20   77  VSS33 SCONN288_ADR50017P087CC-SCONN2A   I176 @S9S_MB_2U_LIB.S9S_MB_2U(SCH_1):PAGE101
   J20   79  VSS34 SCONN288_ADR50017P087CC-SCONN2A   I176 @S9S_MB_2U_LIB.S9S_MB_2U(SCH_1):PAGE101
   J20   81  VSS35 SCONN288_ADR50017P087CC-SCONN2A   I176 @S9S_MB_2U_LIB.S9S_MB_2U(SCH_1):PAGE101
   J20   83  VSS36 SCONN288_ADR50017P087CC-SCONN2A   I176 @S9S_MB_2U_LIB.S9S_MB_2U(SCH_1):PAGE101
   J20   85  VSS37 SCONN288_ADR50017P087CC-SCONN2A   I176 @S9S_MB_2U_LIB.S9S_MB_2U(SCH_1):PAGE101
   J20   88  VSS38 SCONN288_ADR50017P087CC-SCONN2A   I176 @S9S_MB_2U_LIB.S9S_MB_2U(SCH_1):PAGE101
   J20   90  VSS39 SCONN288_ADR50017P087CC-SCONN2A   I176 @S9S_MB_2U_LIB.S9S_MB_2U(SCH_1):PAGE101
   J20   92  VSS40 SCONN288_ADR50017P087CC-SCONN2A   I176 @S9S_MB_2U_LIB.S9S_MB_2U(SCH_1):PAGE101
   J20   95  VSS41 SCONN288_ADR50017P087CC-SCONN2A   I176 @S9S_MB_2U_LIB.S9S_MB_2U(SCH_1):PAGE101
   J20   97  VSS42 SCONN288_ADR50017P087CC-SCONN2A   I176 @S9S_MB_2U_LIB.S9S_MB_2U(SCH_1):PAGE101
   J20   99  VSS43 SCONN288_ADR50017P087CC-SCONN2A   I176 @S9S_MB_2U_LIB.S9S_MB_2U(SCH_1):PAGE101
   J20  101  VSS44 SCONN288_ADR50017P087CC-SCONN2A   I176 @S9S_MB_2U_LIB.S9S_MB_2U(SCH_1):PAGE101
   J20  103  VSS45 SCONN288_ADR50017P087CC-SCONN2A   I176 @S9S_MB_2U_LIB.S9S_MB_2U(SCH_1):PAGE101
   J20  106  VSS46 SCONN288_ADR50017P087CC-SCONN2A   I176 @S9S_MB_2U_LIB.S9S_MB_2U(SCH_1):PAGE101
   J20  108  VSS47 SCONN288_ADR50017P087CC-SCONN2A   I176 @S9S_MB_2U_LIB.S9S_MB_2U(SCH_1):PAGE101
   J20  110  VSS48 SCONN288_ADR50017P087CC-SCONN2A   I176 @S9S_MB_2U_LIB.S9S_MB_2U(SCH_1):PAGE101
   J20  112  VSS49 SCONN288_ADR50017P087CC-SCONN2A   I176 @S9S_MB_2U_LIB.S9S_MB_2U(SCH_1):PAGE101
   J20  114  VSS50 SCONN288_ADR50017P087CC-SCONN2A   I176 @S9S_MB_2U_LIB.S9S_MB_2U(SCH_1):PAGE101
   J20  117  VSS51 SCONN288_ADR50017P087CC-SCONN2A   I176 @S9S_MB_2U_LIB.S9S_MB_2U(SCH_1):PAGE101
   J20  119  VSS52 SCONN288_ADR50017P087CC-SCONN2A   I176 @S9S_MB_2U_LIB.S9S_MB_2U(SCH_1):PAGE101
   J20  121  VSS53 SCONN288_ADR50017P087CC-SCONN2A   I176 @S9S_MB_2U_LIB.S9S_MB_2U(SCH_1):PAGE101
   J20  123  VSS54 SCONN288_ADR50017P087CC-SCONN2A   I176 @S9S_MB_2U_LIB.S9S_MB_2U(SCH_1):PAGE101
   J20  125  VSS55 SCONN288_ADR50017P087CC-SCONN2A   I176 @S9S_MB_2U_LIB.S9S_MB_2U(SCH_1):PAGE101
   J20  128  VSS56 SCONN288_ADR50017P087CC-SCONN2A   I176 @S9S_MB_2U_LIB.S9S_MB_2U(SCH_1):PAGE101
   J20  130  VSS57 SCONN288_ADR50017P087CC-SCONN2A   I176 @S9S_MB_2U_LIB.S9S_MB_2U(SCH_1):PAGE101
   J20  132  VSS58 SCONN288_ADR50017P087CC-SCONN2A   I176 @S9S_MB_2U_LIB.S9S_MB_2U(SCH_1):PAGE101
   J20  134  VSS59 SCONN288_ADR50017P087CC-SCONN2A   I176 @S9S_MB_2U_LIB.S9S_MB_2U(SCH_1):PAGE101
   J20  136  VSS60 SCONN288_ADR50017P087CC-SCONN2A   I176 @S9S_MB_2U_LIB.S9S_MB_2U(SCH_1):PAGE101
   J20  139  VSS61 SCONN288_ADR50017P087CC-SCONN2A   I176 @S9S_MB_2U_LIB.S9S_MB_2U(SCH_1):PAGE101
   J20  141  VSS62 SCONN288_ADR50017P087CC-SCONN2A   I176 @S9S_MB_2U_LIB.S9S_MB_2U(SCH_1):PAGE101
   J20  143  VSS63 SCONN288_ADR50017P087CC-SCONN2A   I176 @S9S_MB_2U_LIB.S9S_MB_2U(SCH_1):PAGE101
   J20  151  VSS64 SCONN288_ADR50017P087CC-SCONN2A   I176 @S9S_MB_2U_LIB.S9S_MB_2U(SCH_1):PAGE101
   J20  153  VSS65 SCONN288_ADR50017P087CC-SCONN2A   I176 @S9S_MB_2U_LIB.S9S_MB_2U(SCH_1):PAGE101
   J20  155  VSS66 SCONN288_ADR50017P087CC-SCONN2A   I176 @S9S_MB_2U_LIB.S9S_MB_2U(SCH_1):PAGE101
   J20  158  VSS67 SCONN288_ADR50017P087CC-SCONN2A   I176 @S9S_MB_2U_LIB.S9S_MB_2U(SCH_1):PAGE101
   J20  160  VSS68 SCONN288_ADR50017P087CC-SCONN2A   I176 @S9S_MB_2U_LIB.S9S_MB_2U(SCH_1):PAGE101
   J20  162  VSS69 SCONN288_ADR50017P087CC-SCONN2A   I176 @S9S_MB_2U_LIB.S9S_MB_2U(SCH_1):PAGE101
   J20  164  VSS70 SCONN288_ADR50017P087CC-SCONN2A   I176 @S9S_MB_2U_LIB.S9S_MB_2U(SCH_1):PAGE101
   J20  166  VSS71 SCONN288_ADR50017P087CC-SCONN2A   I176 @S9S_MB_2U_LIB.S9S_MB_2U(SCH_1):PAGE101
   J20  169  VSS72 SCONN288_ADR50017P087CC-SCONN2A   I176 @S9S_MB_2U_LIB.S9S_MB_2U(SCH_1):PAGE101
   J20  171  VSS73 SCONN288_ADR50017P087CC-SCONN2A   I176 @S9S_MB_2U_LIB.S9S_MB_2U(SCH_1):PAGE101
   J20  173  VSS74 SCONN288_ADR50017P087CC-SCONN2A   I176 @S9S_MB_2U_LIB.S9S_MB_2U(SCH_1):PAGE101
   J20  175  VSS75 SCONN288_ADR50017P087CC-SCONN2A   I176 @S9S_MB_2U_LIB.S9S_MB_2U(SCH_1):PAGE101
   J20  177  VSS76 SCONN288_ADR50017P087CC-SCONN2A   I176 @S9S_MB_2U_LIB.S9S_MB_2U(SCH_1):PAGE101
   J20  180  VSS77 SCONN288_ADR50017P087CC-SCONN2A   I176 @S9S_MB_2U_LIB.S9S_MB_2U(SCH_1):PAGE101
   J20  182  VSS78 SCONN288_ADR50017P087CC-SCONN2A   I176 @S9S_MB_2U_LIB.S9S_MB_2U(SCH_1):PAGE101
   J20  184  VSS79 SCONN288_ADR50017P087CC-SCONN2A   I176 @S9S_MB_2U_LIB.S9S_MB_2U(SCH_1):PAGE101
   J20  186  VSS80 SCONN288_ADR50017P087CC-SCONN2A   I176 @S9S_MB_2U_LIB.S9S_MB_2U(SCH_1):PAGE101
   J20  188  VSS81 SCONN288_ADR50017P087CC-SCONN2A   I176 @S9S_MB_2U_LIB.S9S_MB_2U(SCH_1):PAGE101
   J20  191  VSS82 SCONN288_ADR50017P087CC-SCONN2A   I176 @S9S_MB_2U_LIB.S9S_MB_2U(SCH_1):PAGE101
   J20  193  VSS83 SCONN288_ADR50017P087CC-SCONN2A   I176 @S9S_MB_2U_LIB.S9S_MB_2U(SCH_1):PAGE101
   J20  195  VSS84 SCONN288_ADR50017P087CC-SCONN2A   I176 @S9S_MB_2U_LIB.S9S_MB_2U(SCH_1):PAGE101
   J20  197  VSS85 SCONN288_ADR50017P087CC-SCONN2A   I176 @S9S_MB_2U_LIB.S9S_MB_2U(SCH_1):PAGE101
   J20  199  VSS86 SCONN288_ADR50017P087CC-SCONN2A   I176 @S9S_MB_2U_LIB.S9S_MB_2U(SCH_1):PAGE101
   J20  202  VSS87 SCONN288_ADR50017P087CC-SCONN2A   I176 @S9S_MB_2U_LIB.S9S_MB_2U(SCH_1):PAGE101
   J20  204  VSS88 SCONN288_ADR50017P087CC-SCONN2A   I176 @S9S_MB_2U_LIB.S9S_MB_2U(SCH_1):PAGE101
   J20  206  VSS89 SCONN288_ADR50017P087CC-SCONN2A   I176 @S9S_MB_2U_LIB.S9S_MB_2U(SCH_1):PAGE101
   J20  208  VSS90 SCONN288_ADR50017P087CC-SCONN2A   I176 @S9S_MB_2U_LIB.S9S_MB_2U(SCH_1):PAGE101
   J20  210  VSS91 SCONN288_ADR50017P087CC-SCONN2A   I176 @S9S_MB_2U_LIB.S9S_MB_2U(SCH_1):PAGE101
   J20  212  VSS92 SCONN288_ADR50017P087CC-SCONN2A   I176 @S9S_MB_2U_LIB.S9S_MB_2U(SCH_1):PAGE101
   J20  214  VSS93 SCONN288_ADR50017P087CC-SCONN2A   I176 @S9S_MB_2U_LIB.S9S_MB_2U(SCH_1):PAGE101
   J20  216  VSS94 SCONN288_ADR50017P087CC-SCONN2A   I176 @S9S_MB_2U_LIB.S9S_MB_2U(SCH_1):PAGE101
   J20  219  VSS95 SCONN288_ADR50017P087CC-SCONN2A   I176 @S9S_MB_2U_LIB.S9S_MB_2U(SCH_1):PAGE101
   J20  222  VSS96 SCONN288_ADR50017P087CC-SCONN2A   I176 @S9S_MB_2U_LIB.S9S_MB_2U(SCH_1):PAGE101
   J20  224  VSS97 SCONN288_ADR50017P087CC-SCONN2A   I176 @S9S_MB_2U_LIB.S9S_MB_2U(SCH_1):PAGE101
   J20  226  VSS98 SCONN288_ADR50017P087CC-SCONN2A   I176 @S9S_MB_2U_LIB.S9S_MB_2U(SCH_1):PAGE101
   J20  228  VSS99 SCONN288_ADR50017P087CC-SCONN2A   I176 @S9S_MB_2U_LIB.S9S_MB_2U(SCH_1):PAGE101
   J20  230 VSS100 SCONN288_ADR50017P087CC-SCONN2A   I176 @S9S_MB_2U_LIB.S9S_MB_2U(SCH_1):PAGE101
   J20  233 VSS101 SCONN288_ADR50017P087CC-SCONN2A   I176 @S9S_MB_2U_LIB.S9S_MB_2U(SCH_1):PAGE101
   J20  235 VSS102 SCONN288_ADR50017P087CC-SCONN2A   I176 @S9S_MB_2U_LIB.S9S_MB_2U(SCH_1):PAGE101
   J20  237 VSS103 SCONN288_ADR50017P087CC-SCONN2A   I176 @S9S_MB_2U_LIB.S9S_MB_2U(SCH_1):PAGE101
   J20  240 VSS104 SCONN288_ADR50017P087CC-SCONN2A   I176 @S9S_MB_2U_LIB.S9S_MB_2U(SCH_1):PAGE101
   J20  242 VSS105 SCONN288_ADR50017P087CC-SCONN2A   I176 @S9S_MB_2U_LIB.S9S_MB_2U(SCH_1):PAGE101
   J20  244 VSS106 SCONN288_ADR50017P087CC-SCONN2A   I176 @S9S_MB_2U_LIB.S9S_MB_2U(SCH_1):PAGE101
   J20  246 VSS107 SCONN288_ADR50017P087CC-SCONN2A   I176 @S9S_MB_2U_LIB.S9S_MB_2U(SCH_1):PAGE101
   J20  248 VSS108 SCONN288_ADR50017P087CC-SCONN2A   I176 @S9S_MB_2U_LIB.S9S_MB_2U(SCH_1):PAGE101
   J20  251 VSS109 SCONN288_ADR50017P087CC-SCONN2A   I176 @S9S_MB_2U_LIB.S9S_MB_2U(SCH_1):PAGE101
   J20  253 VSS110 SCONN288_ADR50017P087CC-SCONN2A   I176 @S9S_MB_2U_LIB.S9S_MB_2U(SCH_1):PAGE101
   J20  255 VSS111 SCONN288_ADR50017P087CC-SCONN2A   I176 @S9S_MB_2U_LIB.S9S_MB_2U(SCH_1):PAGE101
   J20  257 VSS112 SCONN288_ADR50017P087CC-SCONN2A   I176 @S9S_MB_2U_LIB.S9S_MB_2U(SCH_1):PAGE101
   J20  259 VSS113 SCONN288_ADR50017P087CC-SCONN2A   I176 @S9S_MB_2U_LIB.S9S_MB_2U(SCH_1):PAGE101
   J20  262 VSS114 SCONN288_ADR50017P087CC-SCONN2A   I176 @S9S_MB_2U_LIB.S9S_MB_2U(SCH_1):PAGE101
   J20  264 VSS115 SCONN288_ADR50017P087CC-SCONN2A   I176 @S9S_MB_2U_LIB.S9S_MB_2U(SCH_1):PAGE101
   J20  266 VSS116 SCONN288_ADR50017P087CC-SCONN2A   I176 @S9S_MB_2U_LIB.S9S_MB_2U(SCH_1):PAGE101
   J20  268 VSS117 SCONN288_ADR50017P087CC-SCONN2A   I176 @S9S_MB_2U_LIB.S9S_MB_2U(SCH_1):PAGE101
   J20  270 VSS118 SCONN288_ADR50017P087CC-SCONN2A   I176 @S9S_MB_2U_LIB.S9S_MB_2U(SCH_1):PAGE101
   J20  273 VSS119 SCONN288_ADR50017P087CC-SCONN2A   I176 @S9S_MB_2U_LIB.S9S_MB_2U(SCH_1):PAGE101
   J20  275 VSS120 SCONN288_ADR50017P087CC-SCONN2A   I176 @S9S_MB_2U_LIB.S9S_MB_2U(SCH_1):PAGE101
   J20  277 VSS121 SCONN288_ADR50017P087CC-SCONN2A   I176 @S9S_MB_2U_LIB.S9S_MB_2U(SCH_1):PAGE101
   J20  279 VSS122 SCONN288_ADR50017P087CC-SCONN2A   I176 @S9S_MB_2U_LIB.S9S_MB_2U(SCH_1):PAGE101
   J20  281 VSS123 SCONN288_ADR50017P087CC-SCONN2A   I176 @S9S_MB_2U_LIB.S9S_MB_2U(SCH_1):PAGE101
   J20  284 VSS124 SCONN288_ADR50017P087CC-SCONN2A   I176 @S9S_MB_2U_LIB.S9S_MB_2U(SCH_1):PAGE101
   J20  286 VSS125 SCONN288_ADR50017P087CC-SCONN2A   I176 @S9S_MB_2U_LIB.S9S_MB_2U(SCH_1):PAGE101
   J20  288 VSS126 SCONN288_ADR50017P087CC-SCONN2A   I176 @S9S_MB_2U_LIB.S9S_MB_2U(SCH_1):PAGE101
   R46    2      B Q_RES_0402LF-54.9K,1%,1/16W,CHA     I2 @S9S_MB_2U_LIB.S9S_MB_2U(SCH_1):PAGE102
   C62    2      B Q_CAP_C0402-2.2UF,6.3V,20%,X6SA   I124 @S9S_MB_2U_LIB.S9S_MB_2U(SCH_1):PAGE102
   C63    2      B Q_CAP_C0805-10UF,16V,10%,X6S,CA   I127 @S9S_MB_2U_LIB.S9S_MB_2U(SCH_1):PAGE102
   C64    2      B Q_CAP_C0805-10UF,16V,10%,X6S,CA   I167 @S9S_MB_2U_LIB.S9S_MB_2U(SCH_1):PAGE102
   J21   G1     G1 SCONN288_ADR50017P130CC-SCONN2A   I169 @S9S_MB_2U_LIB.S9S_MB_2U(SCH_1):PAGE102
   J21   G2     G2 SCONN288_ADR50017P130CC-SCONN2A   I169 @S9S_MB_2U_LIB.S9S_MB_2U(SCH_1):PAGE102
   J21   G3     G3 SCONN288_ADR50017P130CC-SCONN2A   I169 @S9S_MB_2U_LIB.S9S_MB_2U(SCH_1):PAGE102
   J21    6   VSS0 SCONN288_ADR50017P130CC-SCONN2A   I169 @S9S_MB_2U_LIB.S9S_MB_2U(SCH_1):PAGE102
   J21    8   VSS1 SCONN288_ADR50017P130CC-SCONN2A   I169 @S9S_MB_2U_LIB.S9S_MB_2U(SCH_1):PAGE102
   J21   10   VSS2 SCONN288_ADR50017P130CC-SCONN2A   I169 @S9S_MB_2U_LIB.S9S_MB_2U(SCH_1):PAGE102
   J21   13   VSS3 SCONN288_ADR50017P130CC-SCONN2A   I169 @S9S_MB_2U_LIB.S9S_MB_2U(SCH_1):PAGE102
   J21   15   VSS4 SCONN288_ADR50017P130CC-SCONN2A   I169 @S9S_MB_2U_LIB.S9S_MB_2U(SCH_1):PAGE102
   J21   17   VSS5 SCONN288_ADR50017P130CC-SCONN2A   I169 @S9S_MB_2U_LIB.S9S_MB_2U(SCH_1):PAGE102
   J21   19   VSS6 SCONN288_ADR50017P130CC-SCONN2A   I169 @S9S_MB_2U_LIB.S9S_MB_2U(SCH_1):PAGE102
   J21   21   VSS7 SCONN288_ADR50017P130CC-SCONN2A   I169 @S9S_MB_2U_LIB.S9S_MB_2U(SCH_1):PAGE102
   J21   24   VSS8 SCONN288_ADR50017P130CC-SCONN2A   I169 @S9S_MB_2U_LIB.S9S_MB_2U(SCH_1):PAGE102
   J21   26   VSS9 SCONN288_ADR50017P130CC-SCONN2A   I169 @S9S_MB_2U_LIB.S9S_MB_2U(SCH_1):PAGE102
   J21   28  VSS10 SCONN288_ADR50017P130CC-SCONN2A   I169 @S9S_MB_2U_LIB.S9S_MB_2U(SCH_1):PAGE102
   J21   30  VSS11 SCONN288_ADR50017P130CC-SCONN2A   I169 @S9S_MB_2U_LIB.S9S_MB_2U(SCH_1):PAGE102
   J21   32  VSS12 SCONN288_ADR50017P130CC-SCONN2A   I169 @S9S_MB_2U_LIB.S9S_MB_2U(SCH_1):PAGE102
   J21   35  VSS13 SCONN288_ADR50017P130CC-SCONN2A   I169 @S9S_MB_2U_LIB.S9S_MB_2U(SCH_1):PAGE102
   J21   37  VSS14 SCONN288_ADR50017P130CC-SCONN2A   I169 @S9S_MB_2U_LIB.S9S_MB_2U(SCH_1):PAGE102
   J21   39  VSS15 SCONN288_ADR50017P130CC-SCONN2A   I169 @S9S_MB_2U_LIB.S9S_MB_2U(SCH_1):PAGE102
   J21   41  VSS16 SCONN288_ADR50017P130CC-SCONN2A   I169 @S9S_MB_2U_LIB.S9S_MB_2U(SCH_1):PAGE102
   J21   43  VSS17 SCONN288_ADR50017P130CC-SCONN2A   I169 @S9S_MB_2U_LIB.S9S_MB_2U(SCH_1):PAGE102
   J21   46  VSS18 SCONN288_ADR50017P130CC-SCONN2A   I169 @S9S_MB_2U_LIB.S9S_MB_2U(SCH_1):PAGE102
   J21   48  VSS19 SCONN288_ADR50017P130CC-SCONN2A   I169 @S9S_MB_2U_LIB.S9S_MB_2U(SCH_1):PAGE102
   J21   50  VSS20 SCONN288_ADR50017P130CC-SCONN2A   I169 @S9S_MB_2U_LIB.S9S_MB_2U(SCH_1):PAGE102
   J21   52  VSS21 SCONN288_ADR50017P130CC-SCONN2A   I169 @S9S_MB_2U_LIB.S9S_MB_2U(SCH_1):PAGE102
   J21   54  VSS22 SCONN288_ADR50017P130CC-SCONN2A   I169 @S9S_MB_2U_LIB.S9S_MB_2U(SCH_1):PAGE102
   J21   57  VSS23 SCONN288_ADR50017P130CC-SCONN2A   I169 @S9S_MB_2U_LIB.S9S_MB_2U(SCH_1):PAGE102
   J21   59  VSS24 SCONN288_ADR50017P130CC-SCONN2A   I169 @S9S_MB_2U_LIB.S9S_MB_2U(SCH_1):PAGE102
   J21   61  VSS25 SCONN288_ADR50017P130CC-SCONN2A   I169 @S9S_MB_2U_LIB.S9S_MB_2U(SCH_1):PAGE102
   J21   63  VSS26 SCONN288_ADR50017P130CC-SCONN2A   I169 @S9S_MB_2U_LIB.S9S_MB_2U(SCH_1):PAGE102
   J21   65  VSS27 SCONN288_ADR50017P130CC-SCONN2A   I169 @S9S_MB_2U_LIB.S9S_MB_2U(SCH_1):PAGE102
   J21   67  VSS28 SCONN288_ADR50017P130CC-SCONN2A   I169 @S9S_MB_2U_LIB.S9S_MB_2U(SCH_1):PAGE102
   J21   69  VSS29 SCONN288_ADR50017P130CC-SCONN2A   I169 @S9S_MB_2U_LIB.S9S_MB_2U(SCH_1):PAGE102
   J21   71  VSS30 SCONN288_ADR50017P130CC-SCONN2A   I169 @S9S_MB_2U_LIB.S9S_MB_2U(SCH_1):PAGE102
   J21   73  VSS31 SCONN288_ADR50017P130CC-SCONN2A   I169 @S9S_MB_2U_LIB.S9S_MB_2U(SCH_1):PAGE102
   J21   75  VSS32 SCONN288_ADR50017P130CC-SCONN2A   I169 @S9S_MB_2U_LIB.S9S_MB_2U(SCH_1):PAGE102
   J21   77  VSS33 SCONN288_ADR50017P130CC-SCONN2A   I169 @S9S_MB_2U_LIB.S9S_MB_2U(SCH_1):PAGE102
   J21   79  VSS34 SCONN288_ADR50017P130CC-SCONN2A   I169 @S9S_MB_2U_LIB.S9S_MB_2U(SCH_1):PAGE102
   J21   81  VSS35 SCONN288_ADR50017P130CC-SCONN2A   I169 @S9S_MB_2U_LIB.S9S_MB_2U(SCH_1):PAGE102
   J21   83  VSS36 SCONN288_ADR50017P130CC-SCONN2A   I169 @S9S_MB_2U_LIB.S9S_MB_2U(SCH_1):PAGE102
   J21   85  VSS37 SCONN288_ADR50017P130CC-SCONN2A   I169 @S9S_MB_2U_LIB.S9S_MB_2U(SCH_1):PAGE102
   J21   88  VSS38 SCONN288_ADR50017P130CC-SCONN2A   I169 @S9S_MB_2U_LIB.S9S_MB_2U(SCH_1):PAGE102
   J21   90  VSS39 SCONN288_ADR50017P130CC-SCONN2A   I169 @S9S_MB_2U_LIB.S9S_MB_2U(SCH_1):PAGE102
   J21   92  VSS40 SCONN288_ADR50017P130CC-SCONN2A   I169 @S9S_MB_2U_LIB.S9S_MB_2U(SCH_1):PAGE102
   J21   95  VSS41 SCONN288_ADR50017P130CC-SCONN2A   I169 @S9S_MB_2U_LIB.S9S_MB_2U(SCH_1):PAGE102
   J21   97  VSS42 SCONN288_ADR50017P130CC-SCONN2A   I169 @S9S_MB_2U_LIB.S9S_MB_2U(SCH_1):PAGE102
   J21   99  VSS43 SCONN288_ADR50017P130CC-SCONN2A   I169 @S9S_MB_2U_LIB.S9S_MB_2U(SCH_1):PAGE102
   J21  101  VSS44 SCONN288_ADR50017P130CC-SCONN2A   I169 @S9S_MB_2U_LIB.S9S_MB_2U(SCH_1):PAGE102
   J21  103  VSS45 SCONN288_ADR50017P130CC-SCONN2A   I169 @S9S_MB_2U_LIB.S9S_MB_2U(SCH_1):PAGE102
   J21  106  VSS46 SCONN288_ADR50017P130CC-SCONN2A   I169 @S9S_MB_2U_LIB.S9S_MB_2U(SCH_1):PAGE102
   J21  108  VSS47 SCONN288_ADR50017P130CC-SCONN2A   I169 @S9S_MB_2U_LIB.S9S_MB_2U(SCH_1):PAGE102
   J21  110  VSS48 SCONN288_ADR50017P130CC-SCONN2A   I169 @S9S_MB_2U_LIB.S9S_MB_2U(SCH_1):PAGE102
   J21  112  VSS49 SCONN288_ADR50017P130CC-SCONN2A   I169 @S9S_MB_2U_LIB.S9S_MB_2U(SCH_1):PAGE102
   J21  114  VSS50 SCONN288_ADR50017P130CC-SCONN2A   I169 @S9S_MB_2U_LIB.S9S_MB_2U(SCH_1):PAGE102
   J21  117  VSS51 SCONN288_ADR50017P130CC-SCONN2A   I169 @S9S_MB_2U_LIB.S9S_MB_2U(SCH_1):PAGE102
   J21  119  VSS52 SCONN288_ADR50017P130CC-SCONN2A   I169 @S9S_MB_2U_LIB.S9S_MB_2U(SCH_1):PAGE102
   J21  121  VSS53 SCONN288_ADR50017P130CC-SCONN2A   I169 @S9S_MB_2U_LIB.S9S_MB_2U(SCH_1):PAGE102
   J21  123  VSS54 SCONN288_ADR50017P130CC-SCONN2A   I169 @S9S_MB_2U_LIB.S9S_MB_2U(SCH_1):PAGE102
   J21  125  VSS55 SCONN288_ADR50017P130CC-SCONN2A   I169 @S9S_MB_2U_LIB.S9S_MB_2U(SCH_1):PAGE102
   J21  128  VSS56 SCONN288_ADR50017P130CC-SCONN2A   I169 @S9S_MB_2U_LIB.S9S_MB_2U(SCH_1):PAGE102
   J21  130  VSS57 SCONN288_ADR50017P130CC-SCONN2A   I169 @S9S_MB_2U_LIB.S9S_MB_2U(SCH_1):PAGE102
   J21  132  VSS58 SCONN288_ADR50017P130CC-SCONN2A   I169 @S9S_MB_2U_LIB.S9S_MB_2U(SCH_1):PAGE102
   J21  134  VSS59 SCONN288_ADR50017P130CC-SCONN2A   I169 @S9S_MB_2U_LIB.S9S_MB_2U(SCH_1):PAGE102
   J21  136  VSS60 SCONN288_ADR50017P130CC-SCONN2A   I169 @S9S_MB_2U_LIB.S9S_MB_2U(SCH_1):PAGE102
   J21  139  VSS61 SCONN288_ADR50017P130CC-SCONN2A   I169 @S9S_MB_2U_LIB.S9S_MB_2U(SCH_1):PAGE102
   J21  141  VSS62 SCONN288_ADR50017P130CC-SCONN2A   I169 @S9S_MB_2U_LIB.S9S_MB_2U(SCH_1):PAGE102
   J21  143  VSS63 SCONN288_ADR50017P130CC-SCONN2A   I169 @S9S_MB_2U_LIB.S9S_MB_2U(SCH_1):PAGE102
   J21  151  VSS64 SCONN288_ADR50017P130CC-SCONN2A   I169 @S9S_MB_2U_LIB.S9S_MB_2U(SCH_1):PAGE102
   J21  153  VSS65 SCONN288_ADR50017P130CC-SCONN2A   I169 @S9S_MB_2U_LIB.S9S_MB_2U(SCH_1):PAGE102
   J21  155  VSS66 SCONN288_ADR50017P130CC-SCONN2A   I169 @S9S_MB_2U_LIB.S9S_MB_2U(SCH_1):PAGE102
   J21  158  VSS67 SCONN288_ADR50017P130CC-SCONN2A   I169 @S9S_MB_2U_LIB.S9S_MB_2U(SCH_1):PAGE102
   J21  160  VSS68 SCONN288_ADR50017P130CC-SCONN2A   I169 @S9S_MB_2U_LIB.S9S_MB_2U(SCH_1):PAGE102
   J21  162  VSS69 SCONN288_ADR50017P130CC-SCONN2A   I169 @S9S_MB_2U_LIB.S9S_MB_2U(SCH_1):PAGE102
   J21  164  VSS70 SCONN288_ADR50017P130CC-SCONN2A   I169 @S9S_MB_2U_LIB.S9S_MB_2U(SCH_1):PAGE102
   J21  166  VSS71 SCONN288_ADR50017P130CC-SCONN2A   I169 @S9S_MB_2U_LIB.S9S_MB_2U(SCH_1):PAGE102
   J21  169  VSS72 SCONN288_ADR50017P130CC-SCONN2A   I169 @S9S_MB_2U_LIB.S9S_MB_2U(SCH_1):PAGE102
   J21  171  VSS73 SCONN288_ADR50017P130CC-SCONN2A   I169 @S9S_MB_2U_LIB.S9S_MB_2U(SCH_1):PAGE102
   J21  173  VSS74 SCONN288_ADR50017P130CC-SCONN2A   I169 @S9S_MB_2U_LIB.S9S_MB_2U(SCH_1):PAGE102
   J21  175  VSS75 SCONN288_ADR50017P130CC-SCONN2A   I169 @S9S_MB_2U_LIB.S9S_MB_2U(SCH_1):PAGE102
   J21  177  VSS76 SCONN288_ADR50017P130CC-SCONN2A   I169 @S9S_MB_2U_LIB.S9S_MB_2U(SCH_1):PAGE102
   J21  180  VSS77 SCONN288_ADR50017P130CC-SCONN2A   I169 @S9S_MB_2U_LIB.S9S_MB_2U(SCH_1):PAGE102
   J21  182  VSS78 SCONN288_ADR50017P130CC-SCONN2A   I169 @S9S_MB_2U_LIB.S9S_MB_2U(SCH_1):PAGE102
   J21  184  VSS79 SCONN288_ADR50017P130CC-SCONN2A   I169 @S9S_MB_2U_LIB.S9S_MB_2U(SCH_1):PAGE102
   J21  186  VSS80 SCONN288_ADR50017P130CC-SCONN2A   I169 @S9S_MB_2U_LIB.S9S_MB_2U(SCH_1):PAGE102
   J21  188  VSS81 SCONN288_ADR50017P130CC-SCONN2A   I169 @S9S_MB_2U_LIB.S9S_MB_2U(SCH_1):PAGE102
   J21  191  VSS82 SCONN288_ADR50017P130CC-SCONN2A   I169 @S9S_MB_2U_LIB.S9S_MB_2U(SCH_1):PAGE102
   J21  193  VSS83 SCONN288_ADR50017P130CC-SCONN2A   I169 @S9S_MB_2U_LIB.S9S_MB_2U(SCH_1):PAGE102
   J21  195  VSS84 SCONN288_ADR50017P130CC-SCONN2A   I169 @S9S_MB_2U_LIB.S9S_MB_2U(SCH_1):PAGE102
   J21  197  VSS85 SCONN288_ADR50017P130CC-SCONN2A   I169 @S9S_MB_2U_LIB.S9S_MB_2U(SCH_1):PAGE102
   J21  199  VSS86 SCONN288_ADR50017P130CC-SCONN2A   I169 @S9S_MB_2U_LIB.S9S_MB_2U(SCH_1):PAGE102
   J21  202  VSS87 SCONN288_ADR50017P130CC-SCONN2A   I169 @S9S_MB_2U_LIB.S9S_MB_2U(SCH_1):PAGE102
   J21  204  VSS88 SCONN288_ADR50017P130CC-SCONN2A   I169 @S9S_MB_2U_LIB.S9S_MB_2U(SCH_1):PAGE102
   J21  206  VSS89 SCONN288_ADR50017P130CC-SCONN2A   I169 @S9S_MB_2U_LIB.S9S_MB_2U(SCH_1):PAGE102
   J21  208  VSS90 SCONN288_ADR50017P130CC-SCONN2A   I169 @S9S_MB_2U_LIB.S9S_MB_2U(SCH_1):PAGE102
   J21  210  VSS91 SCONN288_ADR50017P130CC-SCONN2A   I169 @S9S_MB_2U_LIB.S9S_MB_2U(SCH_1):PAGE102
   J21  212  VSS92 SCONN288_ADR50017P130CC-SCONN2A   I169 @S9S_MB_2U_LIB.S9S_MB_2U(SCH_1):PAGE102
   J21  214  VSS93 SCONN288_ADR50017P130CC-SCONN2A   I169 @S9S_MB_2U_LIB.S9S_MB_2U(SCH_1):PAGE102
   J21  216  VSS94 SCONN288_ADR50017P130CC-SCONN2A   I169 @S9S_MB_2U_LIB.S9S_MB_2U(SCH_1):PAGE102
   J21  219  VSS95 SCONN288_ADR50017P130CC-SCONN2A   I169 @S9S_MB_2U_LIB.S9S_MB_2U(SCH_1):PAGE102
   J21  222  VSS96 SCONN288_ADR50017P130CC-SCONN2A   I169 @S9S_MB_2U_LIB.S9S_MB_2U(SCH_1):PAGE102
   J21  224  VSS97 SCONN288_ADR50017P130CC-SCONN2A   I169 @S9S_MB_2U_LIB.S9S_MB_2U(SCH_1):PAGE102
   J21  226  VSS98 SCONN288_ADR50017P130CC-SCONN2A   I169 @S9S_MB_2U_LIB.S9S_MB_2U(SCH_1):PAGE102
   J21  228  VSS99 SCONN288_ADR50017P130CC-SCONN2A   I169 @S9S_MB_2U_LIB.S9S_MB_2U(SCH_1):PAGE102
   J21  230 VSS100 SCONN288_ADR50017P130CC-SCONN2A   I169 @S9S_MB_2U_LIB.S9S_MB_2U(SCH_1):PAGE102
   J21  233 VSS101 SCONN288_ADR50017P130CC-SCONN2A   I169 @S9S_MB_2U_LIB.S9S_MB_2U(SCH_1):PAGE102
   J21  235 VSS102 SCONN288_ADR50017P130CC-SCONN2A   I169 @S9S_MB_2U_LIB.S9S_MB_2U(SCH_1):PAGE102
   J21  237 VSS103 SCONN288_ADR50017P130CC-SCONN2A   I169 @S9S_MB_2U_LIB.S9S_MB_2U(SCH_1):PAGE102
   J21  240 VSS104 SCONN288_ADR50017P130CC-SCONN2A   I169 @S9S_MB_2U_LIB.S9S_MB_2U(SCH_1):PAGE102
   J21  242 VSS105 SCONN288_ADR50017P130CC-SCONN2A   I169 @S9S_MB_2U_LIB.S9S_MB_2U(SCH_1):PAGE102
   J21  244 VSS106 SCONN288_ADR50017P130CC-SCONN2A   I169 @S9S_MB_2U_LIB.S9S_MB_2U(SCH_1):PAGE102
   J21  246 VSS107 SCONN288_ADR50017P130CC-SCONN2A   I169 @S9S_MB_2U_LIB.S9S_MB_2U(SCH_1):PAGE102
   J21  248 VSS108 SCONN288_ADR50017P130CC-SCONN2A   I169 @S9S_MB_2U_LIB.S9S_MB_2U(SCH_1):PAGE102
   J21  251 VSS109 SCONN288_ADR50017P130CC-SCONN2A   I169 @S9S_MB_2U_LIB.S9S_MB_2U(SCH_1):PAGE102
   J21  253 VSS110 SCONN288_ADR50017P130CC-SCONN2A   I169 @S9S_MB_2U_LIB.S9S_MB_2U(SCH_1):PAGE102
   J21  255 VSS111 SCONN288_ADR50017P130CC-SCONN2A   I169 @S9S_MB_2U_LIB.S9S_MB_2U(SCH_1):PAGE102
   J21  257 VSS112 SCONN288_ADR50017P130CC-SCONN2A   I169 @S9S_MB_2U_LIB.S9S_MB_2U(SCH_1):PAGE102
   J21  259 VSS113 SCONN288_ADR50017P130CC-SCONN2A   I169 @S9S_MB_2U_LIB.S9S_MB_2U(SCH_1):PAGE102
   J21  262 VSS114 SCONN288_ADR50017P130CC-SCONN2A   I169 @S9S_MB_2U_LIB.S9S_MB_2U(SCH_1):PAGE102
   J21  264 VSS115 SCONN288_ADR50017P130CC-SCONN2A   I169 @S9S_MB_2U_LIB.S9S_MB_2U(SCH_1):PAGE102
   J21  266 VSS116 SCONN288_ADR50017P130CC-SCONN2A   I169 @S9S_MB_2U_LIB.S9S_MB_2U(SCH_1):PAGE102
   J21  268 VSS117 SCONN288_ADR50017P130CC-SCONN2A   I169 @S9S_MB_2U_LIB.S9S_MB_2U(SCH_1):PAGE102
   J21  270 VSS118 SCONN288_ADR50017P130CC-SCONN2A   I169 @S9S_MB_2U_LIB.S9S_MB_2U(SCH_1):PAGE102
   J21  273 VSS119 SCONN288_ADR50017P130CC-SCONN2A   I169 @S9S_MB_2U_LIB.S9S_MB_2U(SCH_1):PAGE102
   J21  275 VSS120 SCONN288_ADR50017P130CC-SCONN2A   I169 @S9S_MB_2U_LIB.S9S_MB_2U(SCH_1):PAGE102
   J21  277 VSS121 SCONN288_ADR50017P130CC-SCONN2A   I169 @S9S_MB_2U_LIB.S9S_MB_2U(SCH_1):PAGE102
   J21  279 VSS122 SCONN288_ADR50017P130CC-SCONN2A   I169 @S9S_MB_2U_LIB.S9S_MB_2U(SCH_1):PAGE102
   J21  281 VSS123 SCONN288_ADR50017P130CC-SCONN2A   I169 @S9S_MB_2U_LIB.S9S_MB_2U(SCH_1):PAGE102
   J21  284 VSS124 SCONN288_ADR50017P130CC-SCONN2A   I169 @S9S_MB_2U_LIB.S9S_MB_2U(SCH_1):PAGE102
   J21  286 VSS125 SCONN288_ADR50017P130CC-SCONN2A   I169 @S9S_MB_2U_LIB.S9S_MB_2U(SCH_1):PAGE102
   J21  288 VSS126 SCONN288_ADR50017P130CC-SCONN2A   I169 @S9S_MB_2U_LIB.S9S_MB_2U(SCH_1):PAGE102
   R47    2      B Q_RES_0402LF-84.5K,1%,1/16W,CHA     I2 @S9S_MB_2U_LIB.S9S_MB_2U(SCH_1):PAGE103
   C65    2      B Q_CAP_C0402-2.2UF,6.3V,20%,X6SA   I122 @S9S_MB_2U_LIB.S9S_MB_2U(SCH_1):PAGE103
   C66    2      B Q_CAP_C0805-10UF,16V,10%,X6S,CA   I126 @S9S_MB_2U_LIB.S9S_MB_2U(SCH_1):PAGE103
   C67    2      B Q_CAP_C0805-10UF,16V,10%,X6S,CA   I128 @S9S_MB_2U_LIB.S9S_MB_2U(SCH_1):PAGE103
   J22   G1     G1 SCONN288_ADR50017P087CC-SCONN2A   I176 @S9S_MB_2U_LIB.S9S_MB_2U(SCH_1):PAGE103
   J22   G2     G2 SCONN288_ADR50017P087CC-SCONN2A   I176 @S9S_MB_2U_LIB.S9S_MB_2U(SCH_1):PAGE103
   J22   G3     G3 SCONN288_ADR50017P087CC-SCONN2A   I176 @S9S_MB_2U_LIB.S9S_MB_2U(SCH_1):PAGE103
   J22    6   VSS0 SCONN288_ADR50017P087CC-SCONN2A   I176 @S9S_MB_2U_LIB.S9S_MB_2U(SCH_1):PAGE103
   J22    8   VSS1 SCONN288_ADR50017P087CC-SCONN2A   I176 @S9S_MB_2U_LIB.S9S_MB_2U(SCH_1):PAGE103
   J22   10   VSS2 SCONN288_ADR50017P087CC-SCONN2A   I176 @S9S_MB_2U_LIB.S9S_MB_2U(SCH_1):PAGE103
   J22   13   VSS3 SCONN288_ADR50017P087CC-SCONN2A   I176 @S9S_MB_2U_LIB.S9S_MB_2U(SCH_1):PAGE103
   J22   15   VSS4 SCONN288_ADR50017P087CC-SCONN2A   I176 @S9S_MB_2U_LIB.S9S_MB_2U(SCH_1):PAGE103
   J22   17   VSS5 SCONN288_ADR50017P087CC-SCONN2A   I176 @S9S_MB_2U_LIB.S9S_MB_2U(SCH_1):PAGE103
   J22   19   VSS6 SCONN288_ADR50017P087CC-SCONN2A   I176 @S9S_MB_2U_LIB.S9S_MB_2U(SCH_1):PAGE103
   J22   21   VSS7 SCONN288_ADR50017P087CC-SCONN2A   I176 @S9S_MB_2U_LIB.S9S_MB_2U(SCH_1):PAGE103
   J22   24   VSS8 SCONN288_ADR50017P087CC-SCONN2A   I176 @S9S_MB_2U_LIB.S9S_MB_2U(SCH_1):PAGE103
   J22   26   VSS9 SCONN288_ADR50017P087CC-SCONN2A   I176 @S9S_MB_2U_LIB.S9S_MB_2U(SCH_1):PAGE103
   J22   28  VSS10 SCONN288_ADR50017P087CC-SCONN2A   I176 @S9S_MB_2U_LIB.S9S_MB_2U(SCH_1):PAGE103
   J22   30  VSS11 SCONN288_ADR50017P087CC-SCONN2A   I176 @S9S_MB_2U_LIB.S9S_MB_2U(SCH_1):PAGE103
   J22   32  VSS12 SCONN288_ADR50017P087CC-SCONN2A   I176 @S9S_MB_2U_LIB.S9S_MB_2U(SCH_1):PAGE103
   J22   35  VSS13 SCONN288_ADR50017P087CC-SCONN2A   I176 @S9S_MB_2U_LIB.S9S_MB_2U(SCH_1):PAGE103
   J22   37  VSS14 SCONN288_ADR50017P087CC-SCONN2A   I176 @S9S_MB_2U_LIB.S9S_MB_2U(SCH_1):PAGE103
   J22   39  VSS15 SCONN288_ADR50017P087CC-SCONN2A   I176 @S9S_MB_2U_LIB.S9S_MB_2U(SCH_1):PAGE103
   J22   41  VSS16 SCONN288_ADR50017P087CC-SCONN2A   I176 @S9S_MB_2U_LIB.S9S_MB_2U(SCH_1):PAGE103
   J22   43  VSS17 SCONN288_ADR50017P087CC-SCONN2A   I176 @S9S_MB_2U_LIB.S9S_MB_2U(SCH_1):PAGE103
   J22   46  VSS18 SCONN288_ADR50017P087CC-SCONN2A   I176 @S9S_MB_2U_LIB.S9S_MB_2U(SCH_1):PAGE103
   J22   48  VSS19 SCONN288_ADR50017P087CC-SCONN2A   I176 @S9S_MB_2U_LIB.S9S_MB_2U(SCH_1):PAGE103
   J22   50  VSS20 SCONN288_ADR50017P087CC-SCONN2A   I176 @S9S_MB_2U_LIB.S9S_MB_2U(SCH_1):PAGE103
   J22   52  VSS21 SCONN288_ADR50017P087CC-SCONN2A   I176 @S9S_MB_2U_LIB.S9S_MB_2U(SCH_1):PAGE103
   J22   54  VSS22 SCONN288_ADR50017P087CC-SCONN2A   I176 @S9S_MB_2U_LIB.S9S_MB_2U(SCH_1):PAGE103
   J22   57  VSS23 SCONN288_ADR50017P087CC-SCONN2A   I176 @S9S_MB_2U_LIB.S9S_MB_2U(SCH_1):PAGE103
   J22   59  VSS24 SCONN288_ADR50017P087CC-SCONN2A   I176 @S9S_MB_2U_LIB.S9S_MB_2U(SCH_1):PAGE103
   J22   61  VSS25 SCONN288_ADR50017P087CC-SCONN2A   I176 @S9S_MB_2U_LIB.S9S_MB_2U(SCH_1):PAGE103
   J22   63  VSS26 SCONN288_ADR50017P087CC-SCONN2A   I176 @S9S_MB_2U_LIB.S9S_MB_2U(SCH_1):PAGE103
   J22   65  VSS27 SCONN288_ADR50017P087CC-SCONN2A   I176 @S9S_MB_2U_LIB.S9S_MB_2U(SCH_1):PAGE103
   J22   67  VSS28 SCONN288_ADR50017P087CC-SCONN2A   I176 @S9S_MB_2U_LIB.S9S_MB_2U(SCH_1):PAGE103
   J22   69  VSS29 SCONN288_ADR50017P087CC-SCONN2A   I176 @S9S_MB_2U_LIB.S9S_MB_2U(SCH_1):PAGE103
   J22   71  VSS30 SCONN288_ADR50017P087CC-SCONN2A   I176 @S9S_MB_2U_LIB.S9S_MB_2U(SCH_1):PAGE103
   J22   73  VSS31 SCONN288_ADR50017P087CC-SCONN2A   I176 @S9S_MB_2U_LIB.S9S_MB_2U(SCH_1):PAGE103
   J22   75  VSS32 SCONN288_ADR50017P087CC-SCONN2A   I176 @S9S_MB_2U_LIB.S9S_MB_2U(SCH_1):PAGE103
   J22   77  VSS33 SCONN288_ADR50017P087CC-SCONN2A   I176 @S9S_MB_2U_LIB.S9S_MB_2U(SCH_1):PAGE103
   J22   79  VSS34 SCONN288_ADR50017P087CC-SCONN2A   I176 @S9S_MB_2U_LIB.S9S_MB_2U(SCH_1):PAGE103
   J22   81  VSS35 SCONN288_ADR50017P087CC-SCONN2A   I176 @S9S_MB_2U_LIB.S9S_MB_2U(SCH_1):PAGE103
   J22   83  VSS36 SCONN288_ADR50017P087CC-SCONN2A   I176 @S9S_MB_2U_LIB.S9S_MB_2U(SCH_1):PAGE103
   J22   85  VSS37 SCONN288_ADR50017P087CC-SCONN2A   I176 @S9S_MB_2U_LIB.S9S_MB_2U(SCH_1):PAGE103
   J22   88  VSS38 SCONN288_ADR50017P087CC-SCONN2A   I176 @S9S_MB_2U_LIB.S9S_MB_2U(SCH_1):PAGE103
   J22   90  VSS39 SCONN288_ADR50017P087CC-SCONN2A   I176 @S9S_MB_2U_LIB.S9S_MB_2U(SCH_1):PAGE103
   J22   92  VSS40 SCONN288_ADR50017P087CC-SCONN2A   I176 @S9S_MB_2U_LIB.S9S_MB_2U(SCH_1):PAGE103
   J22   95  VSS41 SCONN288_ADR50017P087CC-SCONN2A   I176 @S9S_MB_2U_LIB.S9S_MB_2U(SCH_1):PAGE103
   J22   97  VSS42 SCONN288_ADR50017P087CC-SCONN2A   I176 @S9S_MB_2U_LIB.S9S_MB_2U(SCH_1):PAGE103
   J22   99  VSS43 SCONN288_ADR50017P087CC-SCONN2A   I176 @S9S_MB_2U_LIB.S9S_MB_2U(SCH_1):PAGE103
   J22  101  VSS44 SCONN288_ADR50017P087CC-SCONN2A   I176 @S9S_MB_2U_LIB.S9S_MB_2U(SCH_1):PAGE103
   J22  103  VSS45 SCONN288_ADR50017P087CC-SCONN2A   I176 @S9S_MB_2U_LIB.S9S_MB_2U(SCH_1):PAGE103
   J22  106  VSS46 SCONN288_ADR50017P087CC-SCONN2A   I176 @S9S_MB_2U_LIB.S9S_MB_2U(SCH_1):PAGE103
   J22  108  VSS47 SCONN288_ADR50017P087CC-SCONN2A   I176 @S9S_MB_2U_LIB.S9S_MB_2U(SCH_1):PAGE103
   J22  110  VSS48 SCONN288_ADR50017P087CC-SCONN2A   I176 @S9S_MB_2U_LIB.S9S_MB_2U(SCH_1):PAGE103
   J22  112  VSS49 SCONN288_ADR50017P087CC-SCONN2A   I176 @S9S_MB_2U_LIB.S9S_MB_2U(SCH_1):PAGE103
   J22  114  VSS50 SCONN288_ADR50017P087CC-SCONN2A   I176 @S9S_MB_2U_LIB.S9S_MB_2U(SCH_1):PAGE103
   J22  117  VSS51 SCONN288_ADR50017P087CC-SCONN2A   I176 @S9S_MB_2U_LIB.S9S_MB_2U(SCH_1):PAGE103
   J22  119  VSS52 SCONN288_ADR50017P087CC-SCONN2A   I176 @S9S_MB_2U_LIB.S9S_MB_2U(SCH_1):PAGE103
   J22  121  VSS53 SCONN288_ADR50017P087CC-SCONN2A   I176 @S9S_MB_2U_LIB.S9S_MB_2U(SCH_1):PAGE103
   J22  123  VSS54 SCONN288_ADR50017P087CC-SCONN2A   I176 @S9S_MB_2U_LIB.S9S_MB_2U(SCH_1):PAGE103
   J22  125  VSS55 SCONN288_ADR50017P087CC-SCONN2A   I176 @S9S_MB_2U_LIB.S9S_MB_2U(SCH_1):PAGE103
   J22  128  VSS56 SCONN288_ADR50017P087CC-SCONN2A   I176 @S9S_MB_2U_LIB.S9S_MB_2U(SCH_1):PAGE103
   J22  130  VSS57 SCONN288_ADR50017P087CC-SCONN2A   I176 @S9S_MB_2U_LIB.S9S_MB_2U(SCH_1):PAGE103
   J22  132  VSS58 SCONN288_ADR50017P087CC-SCONN2A   I176 @S9S_MB_2U_LIB.S9S_MB_2U(SCH_1):PAGE103
   J22  134  VSS59 SCONN288_ADR50017P087CC-SCONN2A   I176 @S9S_MB_2U_LIB.S9S_MB_2U(SCH_1):PAGE103
   J22  136  VSS60 SCONN288_ADR50017P087CC-SCONN2A   I176 @S9S_MB_2U_LIB.S9S_MB_2U(SCH_1):PAGE103
   J22  139  VSS61 SCONN288_ADR50017P087CC-SCONN2A   I176 @S9S_MB_2U_LIB.S9S_MB_2U(SCH_1):PAGE103
   J22  141  VSS62 SCONN288_ADR50017P087CC-SCONN2A   I176 @S9S_MB_2U_LIB.S9S_MB_2U(SCH_1):PAGE103
   J22  143  VSS63 SCONN288_ADR50017P087CC-SCONN2A   I176 @S9S_MB_2U_LIB.S9S_MB_2U(SCH_1):PAGE103
   J22  151  VSS64 SCONN288_ADR50017P087CC-SCONN2A   I176 @S9S_MB_2U_LIB.S9S_MB_2U(SCH_1):PAGE103
   J22  153  VSS65 SCONN288_ADR50017P087CC-SCONN2A   I176 @S9S_MB_2U_LIB.S9S_MB_2U(SCH_1):PAGE103
   J22  155  VSS66 SCONN288_ADR50017P087CC-SCONN2A   I176 @S9S_MB_2U_LIB.S9S_MB_2U(SCH_1):PAGE103
   J22  158  VSS67 SCONN288_ADR50017P087CC-SCONN2A   I176 @S9S_MB_2U_LIB.S9S_MB_2U(SCH_1):PAGE103
   J22  160  VSS68 SCONN288_ADR50017P087CC-SCONN2A   I176 @S9S_MB_2U_LIB.S9S_MB_2U(SCH_1):PAGE103
   J22  162  VSS69 SCONN288_ADR50017P087CC-SCONN2A   I176 @S9S_MB_2U_LIB.S9S_MB_2U(SCH_1):PAGE103
   J22  164  VSS70 SCONN288_ADR50017P087CC-SCONN2A   I176 @S9S_MB_2U_LIB.S9S_MB_2U(SCH_1):PAGE103
   J22  166  VSS71 SCONN288_ADR50017P087CC-SCONN2A   I176 @S9S_MB_2U_LIB.S9S_MB_2U(SCH_1):PAGE103
   J22  169  VSS72 SCONN288_ADR50017P087CC-SCONN2A   I176 @S9S_MB_2U_LIB.S9S_MB_2U(SCH_1):PAGE103
   J22  171  VSS73 SCONN288_ADR50017P087CC-SCONN2A   I176 @S9S_MB_2U_LIB.S9S_MB_2U(SCH_1):PAGE103
   J22  173  VSS74 SCONN288_ADR50017P087CC-SCONN2A   I176 @S9S_MB_2U_LIB.S9S_MB_2U(SCH_1):PAGE103
   J22  175  VSS75 SCONN288_ADR50017P087CC-SCONN2A   I176 @S9S_MB_2U_LIB.S9S_MB_2U(SCH_1):PAGE103
   J22  177  VSS76 SCONN288_ADR50017P087CC-SCONN2A   I176 @S9S_MB_2U_LIB.S9S_MB_2U(SCH_1):PAGE103
   J22  180  VSS77 SCONN288_ADR50017P087CC-SCONN2A   I176 @S9S_MB_2U_LIB.S9S_MB_2U(SCH_1):PAGE103
   J22  182  VSS78 SCONN288_ADR50017P087CC-SCONN2A   I176 @S9S_MB_2U_LIB.S9S_MB_2U(SCH_1):PAGE103
   J22  184  VSS79 SCONN288_ADR50017P087CC-SCONN2A   I176 @S9S_MB_2U_LIB.S9S_MB_2U(SCH_1):PAGE103
   J22  186  VSS80 SCONN288_ADR50017P087CC-SCONN2A   I176 @S9S_MB_2U_LIB.S9S_MB_2U(SCH_1):PAGE103
   J22  188  VSS81 SCONN288_ADR50017P087CC-SCONN2A   I176 @S9S_MB_2U_LIB.S9S_MB_2U(SCH_1):PAGE103
   J22  191  VSS82 SCONN288_ADR50017P087CC-SCONN2A   I176 @S9S_MB_2U_LIB.S9S_MB_2U(SCH_1):PAGE103
   J22  193  VSS83 SCONN288_ADR50017P087CC-SCONN2A   I176 @S9S_MB_2U_LIB.S9S_MB_2U(SCH_1):PAGE103
   J22  195  VSS84 SCONN288_ADR50017P087CC-SCONN2A   I176 @S9S_MB_2U_LIB.S9S_MB_2U(SCH_1):PAGE103
   J22  197  VSS85 SCONN288_ADR50017P087CC-SCONN2A   I176 @S9S_MB_2U_LIB.S9S_MB_2U(SCH_1):PAGE103
   J22  199  VSS86 SCONN288_ADR50017P087CC-SCONN2A   I176 @S9S_MB_2U_LIB.S9S_MB_2U(SCH_1):PAGE103
   J22  202  VSS87 SCONN288_ADR50017P087CC-SCONN2A   I176 @S9S_MB_2U_LIB.S9S_MB_2U(SCH_1):PAGE103
   J22  204  VSS88 SCONN288_ADR50017P087CC-SCONN2A   I176 @S9S_MB_2U_LIB.S9S_MB_2U(SCH_1):PAGE103
   J22  206  VSS89 SCONN288_ADR50017P087CC-SCONN2A   I176 @S9S_MB_2U_LIB.S9S_MB_2U(SCH_1):PAGE103
   J22  208  VSS90 SCONN288_ADR50017P087CC-SCONN2A   I176 @S9S_MB_2U_LIB.S9S_MB_2U(SCH_1):PAGE103
   J22  210  VSS91 SCONN288_ADR50017P087CC-SCONN2A   I176 @S9S_MB_2U_LIB.S9S_MB_2U(SCH_1):PAGE103
   J22  212  VSS92 SCONN288_ADR50017P087CC-SCONN2A   I176 @S9S_MB_2U_LIB.S9S_MB_2U(SCH_1):PAGE103
   J22  214  VSS93 SCONN288_ADR50017P087CC-SCONN2A   I176 @S9S_MB_2U_LIB.S9S_MB_2U(SCH_1):PAGE103
   J22  216  VSS94 SCONN288_ADR50017P087CC-SCONN2A   I176 @S9S_MB_2U_LIB.S9S_MB_2U(SCH_1):PAGE103
   J22  219  VSS95 SCONN288_ADR50017P087CC-SCONN2A   I176 @S9S_MB_2U_LIB.S9S_MB_2U(SCH_1):PAGE103
   J22  222  VSS96 SCONN288_ADR50017P087CC-SCONN2A   I176 @S9S_MB_2U_LIB.S9S_MB_2U(SCH_1):PAGE103
   J22  224  VSS97 SCONN288_ADR50017P087CC-SCONN2A   I176 @S9S_MB_2U_LIB.S9S_MB_2U(SCH_1):PAGE103
   J22  226  VSS98 SCONN288_ADR50017P087CC-SCONN2A   I176 @S9S_MB_2U_LIB.S9S_MB_2U(SCH_1):PAGE103
   J22  228  VSS99 SCONN288_ADR50017P087CC-SCONN2A   I176 @S9S_MB_2U_LIB.S9S_MB_2U(SCH_1):PAGE103
   J22  230 VSS100 SCONN288_ADR50017P087CC-SCONN2A   I176 @S9S_MB_2U_LIB.S9S_MB_2U(SCH_1):PAGE103
   J22  233 VSS101 SCONN288_ADR50017P087CC-SCONN2A   I176 @S9S_MB_2U_LIB.S9S_MB_2U(SCH_1):PAGE103
   J22  235 VSS102 SCONN288_ADR50017P087CC-SCONN2A   I176 @S9S_MB_2U_LIB.S9S_MB_2U(SCH_1):PAGE103
   J22  237 VSS103 SCONN288_ADR50017P087CC-SCONN2A   I176 @S9S_MB_2U_LIB.S9S_MB_2U(SCH_1):PAGE103
   J22  240 VSS104 SCONN288_ADR50017P087CC-SCONN2A   I176 @S9S_MB_2U_LIB.S9S_MB_2U(SCH_1):PAGE103
   J22  242 VSS105 SCONN288_ADR50017P087CC-SCONN2A   I176 @S9S_MB_2U_LIB.S9S_MB_2U(SCH_1):PAGE103
   J22  244 VSS106 SCONN288_ADR50017P087CC-SCONN2A   I176 @S9S_MB_2U_LIB.S9S_MB_2U(SCH_1):PAGE103
   J22  246 VSS107 SCONN288_ADR50017P087CC-SCONN2A   I176 @S9S_MB_2U_LIB.S9S_MB_2U(SCH_1):PAGE103
   J22  248 VSS108 SCONN288_ADR50017P087CC-SCONN2A   I176 @S9S_MB_2U_LIB.S9S_MB_2U(SCH_1):PAGE103
   J22  251 VSS109 SCONN288_ADR50017P087CC-SCONN2A   I176 @S9S_MB_2U_LIB.S9S_MB_2U(SCH_1):PAGE103
   J22  253 VSS110 SCONN288_ADR50017P087CC-SCONN2A   I176 @S9S_MB_2U_LIB.S9S_MB_2U(SCH_1):PAGE103
   J22  255 VSS111 SCONN288_ADR50017P087CC-SCONN2A   I176 @S9S_MB_2U_LIB.S9S_MB_2U(SCH_1):PAGE103
   J22  257 VSS112 SCONN288_ADR50017P087CC-SCONN2A   I176 @S9S_MB_2U_LIB.S9S_MB_2U(SCH_1):PAGE103
   J22  259 VSS113 SCONN288_ADR50017P087CC-SCONN2A   I176 @S9S_MB_2U_LIB.S9S_MB_2U(SCH_1):PAGE103
   J22  262 VSS114 SCONN288_ADR50017P087CC-SCONN2A   I176 @S9S_MB_2U_LIB.S9S_MB_2U(SCH_1):PAGE103
   J22  264 VSS115 SCONN288_ADR50017P087CC-SCONN2A   I176 @S9S_MB_2U_LIB.S9S_MB_2U(SCH_1):PAGE103
   J22  266 VSS116 SCONN288_ADR50017P087CC-SCONN2A   I176 @S9S_MB_2U_LIB.S9S_MB_2U(SCH_1):PAGE103
   J22  268 VSS117 SCONN288_ADR50017P087CC-SCONN2A   I176 @S9S_MB_2U_LIB.S9S_MB_2U(SCH_1):PAGE103
   J22  270 VSS118 SCONN288_ADR50017P087CC-SCONN2A   I176 @S9S_MB_2U_LIB.S9S_MB_2U(SCH_1):PAGE103
   J22  273 VSS119 SCONN288_ADR50017P087CC-SCONN2A   I176 @S9S_MB_2U_LIB.S9S_MB_2U(SCH_1):PAGE103
   J22  275 VSS120 SCONN288_ADR50017P087CC-SCONN2A   I176 @S9S_MB_2U_LIB.S9S_MB_2U(SCH_1):PAGE103
   J22  277 VSS121 SCONN288_ADR50017P087CC-SCONN2A   I176 @S9S_MB_2U_LIB.S9S_MB_2U(SCH_1):PAGE103
   J22  279 VSS122 SCONN288_ADR50017P087CC-SCONN2A   I176 @S9S_MB_2U_LIB.S9S_MB_2U(SCH_1):PAGE103
   J22  281 VSS123 SCONN288_ADR50017P087CC-SCONN2A   I176 @S9S_MB_2U_LIB.S9S_MB_2U(SCH_1):PAGE103
   J22  284 VSS124 SCONN288_ADR50017P087CC-SCONN2A   I176 @S9S_MB_2U_LIB.S9S_MB_2U(SCH_1):PAGE103
   J22  286 VSS125 SCONN288_ADR50017P087CC-SCONN2A   I176 @S9S_MB_2U_LIB.S9S_MB_2U(SCH_1):PAGE103
   J22  288 VSS126 SCONN288_ADR50017P087CC-SCONN2A   I176 @S9S_MB_2U_LIB.S9S_MB_2U(SCH_1):PAGE103
   R48    2      B Q_RES_0402LF-127K,1%,1/16W,CHIA     I2 @S9S_MB_2U_LIB.S9S_MB_2U(SCH_1):PAGE104
   C68    2      B Q_CAP_C0402-2.2UF,6.3V,20%,X6SA   I122 @S9S_MB_2U_LIB.S9S_MB_2U(SCH_1):PAGE104
   C69    2      B Q_CAP_C0805-10UF,16V,10%,X6S,CA   I127 @S9S_MB_2U_LIB.S9S_MB_2U(SCH_1):PAGE104
   C70    2      B Q_CAP_C0805-10UF,16V,10%,X6S,CA   I129 @S9S_MB_2U_LIB.S9S_MB_2U(SCH_1):PAGE104
   J23   G1     G1 SCONN288_ADR50017P130CC-SCONN2A   I175 @S9S_MB_2U_LIB.S9S_MB_2U(SCH_1):PAGE104
   J23   G2     G2 SCONN288_ADR50017P130CC-SCONN2A   I175 @S9S_MB_2U_LIB.S9S_MB_2U(SCH_1):PAGE104
   J23   G3     G3 SCONN288_ADR50017P130CC-SCONN2A   I175 @S9S_MB_2U_LIB.S9S_MB_2U(SCH_1):PAGE104
   J23    6   VSS0 SCONN288_ADR50017P130CC-SCONN2A   I175 @S9S_MB_2U_LIB.S9S_MB_2U(SCH_1):PAGE104
   J23    8   VSS1 SCONN288_ADR50017P130CC-SCONN2A   I175 @S9S_MB_2U_LIB.S9S_MB_2U(SCH_1):PAGE104
   J23   10   VSS2 SCONN288_ADR50017P130CC-SCONN2A   I175 @S9S_MB_2U_LIB.S9S_MB_2U(SCH_1):PAGE104
   J23   13   VSS3 SCONN288_ADR50017P130CC-SCONN2A   I175 @S9S_MB_2U_LIB.S9S_MB_2U(SCH_1):PAGE104
   J23   15   VSS4 SCONN288_ADR50017P130CC-SCONN2A   I175 @S9S_MB_2U_LIB.S9S_MB_2U(SCH_1):PAGE104
   J23   17   VSS5 SCONN288_ADR50017P130CC-SCONN2A   I175 @S9S_MB_2U_LIB.S9S_MB_2U(SCH_1):PAGE104
   J23   19   VSS6 SCONN288_ADR50017P130CC-SCONN2A   I175 @S9S_MB_2U_LIB.S9S_MB_2U(SCH_1):PAGE104
   J23   21   VSS7 SCONN288_ADR50017P130CC-SCONN2A   I175 @S9S_MB_2U_LIB.S9S_MB_2U(SCH_1):PAGE104
   J23   24   VSS8 SCONN288_ADR50017P130CC-SCONN2A   I175 @S9S_MB_2U_LIB.S9S_MB_2U(SCH_1):PAGE104
   J23   26   VSS9 SCONN288_ADR50017P130CC-SCONN2A   I175 @S9S_MB_2U_LIB.S9S_MB_2U(SCH_1):PAGE104
   J23   28  VSS10 SCONN288_ADR50017P130CC-SCONN2A   I175 @S9S_MB_2U_LIB.S9S_MB_2U(SCH_1):PAGE104
   J23   30  VSS11 SCONN288_ADR50017P130CC-SCONN2A   I175 @S9S_MB_2U_LIB.S9S_MB_2U(SCH_1):PAGE104
   J23   32  VSS12 SCONN288_ADR50017P130CC-SCONN2A   I175 @S9S_MB_2U_LIB.S9S_MB_2U(SCH_1):PAGE104
   J23   35  VSS13 SCONN288_ADR50017P130CC-SCONN2A   I175 @S9S_MB_2U_LIB.S9S_MB_2U(SCH_1):PAGE104
   J23   37  VSS14 SCONN288_ADR50017P130CC-SCONN2A   I175 @S9S_MB_2U_LIB.S9S_MB_2U(SCH_1):PAGE104
   J23   39  VSS15 SCONN288_ADR50017P130CC-SCONN2A   I175 @S9S_MB_2U_LIB.S9S_MB_2U(SCH_1):PAGE104
   J23   41  VSS16 SCONN288_ADR50017P130CC-SCONN2A   I175 @S9S_MB_2U_LIB.S9S_MB_2U(SCH_1):PAGE104
   J23   43  VSS17 SCONN288_ADR50017P130CC-SCONN2A   I175 @S9S_MB_2U_LIB.S9S_MB_2U(SCH_1):PAGE104
   J23   46  VSS18 SCONN288_ADR50017P130CC-SCONN2A   I175 @S9S_MB_2U_LIB.S9S_MB_2U(SCH_1):PAGE104
   J23   48  VSS19 SCONN288_ADR50017P130CC-SCONN2A   I175 @S9S_MB_2U_LIB.S9S_MB_2U(SCH_1):PAGE104
   J23   50  VSS20 SCONN288_ADR50017P130CC-SCONN2A   I175 @S9S_MB_2U_LIB.S9S_MB_2U(SCH_1):PAGE104
   J23   52  VSS21 SCONN288_ADR50017P130CC-SCONN2A   I175 @S9S_MB_2U_LIB.S9S_MB_2U(SCH_1):PAGE104
   J23   54  VSS22 SCONN288_ADR50017P130CC-SCONN2A   I175 @S9S_MB_2U_LIB.S9S_MB_2U(SCH_1):PAGE104
   J23   57  VSS23 SCONN288_ADR50017P130CC-SCONN2A   I175 @S9S_MB_2U_LIB.S9S_MB_2U(SCH_1):PAGE104
   J23   59  VSS24 SCONN288_ADR50017P130CC-SCONN2A   I175 @S9S_MB_2U_LIB.S9S_MB_2U(SCH_1):PAGE104
   J23   61  VSS25 SCONN288_ADR50017P130CC-SCONN2A   I175 @S9S_MB_2U_LIB.S9S_MB_2U(SCH_1):PAGE104
   J23   63  VSS26 SCONN288_ADR50017P130CC-SCONN2A   I175 @S9S_MB_2U_LIB.S9S_MB_2U(SCH_1):PAGE104
   J23   65  VSS27 SCONN288_ADR50017P130CC-SCONN2A   I175 @S9S_MB_2U_LIB.S9S_MB_2U(SCH_1):PAGE104
   J23   67  VSS28 SCONN288_ADR50017P130CC-SCONN2A   I175 @S9S_MB_2U_LIB.S9S_MB_2U(SCH_1):PAGE104
   J23   69  VSS29 SCONN288_ADR50017P130CC-SCONN2A   I175 @S9S_MB_2U_LIB.S9S_MB_2U(SCH_1):PAGE104
   J23   71  VSS30 SCONN288_ADR50017P130CC-SCONN2A   I175 @S9S_MB_2U_LIB.S9S_MB_2U(SCH_1):PAGE104
   J23   73  VSS31 SCONN288_ADR50017P130CC-SCONN2A   I175 @S9S_MB_2U_LIB.S9S_MB_2U(SCH_1):PAGE104
   J23   75  VSS32 SCONN288_ADR50017P130CC-SCONN2A   I175 @S9S_MB_2U_LIB.S9S_MB_2U(SCH_1):PAGE104
   J23   77  VSS33 SCONN288_ADR50017P130CC-SCONN2A   I175 @S9S_MB_2U_LIB.S9S_MB_2U(SCH_1):PAGE104
   J23   79  VSS34 SCONN288_ADR50017P130CC-SCONN2A   I175 @S9S_MB_2U_LIB.S9S_MB_2U(SCH_1):PAGE104
   J23   81  VSS35 SCONN288_ADR50017P130CC-SCONN2A   I175 @S9S_MB_2U_LIB.S9S_MB_2U(SCH_1):PAGE104
   J23   83  VSS36 SCONN288_ADR50017P130CC-SCONN2A   I175 @S9S_MB_2U_LIB.S9S_MB_2U(SCH_1):PAGE104
   J23   85  VSS37 SCONN288_ADR50017P130CC-SCONN2A   I175 @S9S_MB_2U_LIB.S9S_MB_2U(SCH_1):PAGE104
   J23   88  VSS38 SCONN288_ADR50017P130CC-SCONN2A   I175 @S9S_MB_2U_LIB.S9S_MB_2U(SCH_1):PAGE104
   J23   90  VSS39 SCONN288_ADR50017P130CC-SCONN2A   I175 @S9S_MB_2U_LIB.S9S_MB_2U(SCH_1):PAGE104
   J23   92  VSS40 SCONN288_ADR50017P130CC-SCONN2A   I175 @S9S_MB_2U_LIB.S9S_MB_2U(SCH_1):PAGE104
   J23   95  VSS41 SCONN288_ADR50017P130CC-SCONN2A   I175 @S9S_MB_2U_LIB.S9S_MB_2U(SCH_1):PAGE104
   J23   97  VSS42 SCONN288_ADR50017P130CC-SCONN2A   I175 @S9S_MB_2U_LIB.S9S_MB_2U(SCH_1):PAGE104
   J23   99  VSS43 SCONN288_ADR50017P130CC-SCONN2A   I175 @S9S_MB_2U_LIB.S9S_MB_2U(SCH_1):PAGE104
   J23  101  VSS44 SCONN288_ADR50017P130CC-SCONN2A   I175 @S9S_MB_2U_LIB.S9S_MB_2U(SCH_1):PAGE104
   J23  103  VSS45 SCONN288_ADR50017P130CC-SCONN2A   I175 @S9S_MB_2U_LIB.S9S_MB_2U(SCH_1):PAGE104
   J23  106  VSS46 SCONN288_ADR50017P130CC-SCONN2A   I175 @S9S_MB_2U_LIB.S9S_MB_2U(SCH_1):PAGE104
   J23  108  VSS47 SCONN288_ADR50017P130CC-SCONN2A   I175 @S9S_MB_2U_LIB.S9S_MB_2U(SCH_1):PAGE104
   J23  110  VSS48 SCONN288_ADR50017P130CC-SCONN2A   I175 @S9S_MB_2U_LIB.S9S_MB_2U(SCH_1):PAGE104
   J23  112  VSS49 SCONN288_ADR50017P130CC-SCONN2A   I175 @S9S_MB_2U_LIB.S9S_MB_2U(SCH_1):PAGE104
   J23  114  VSS50 SCONN288_ADR50017P130CC-SCONN2A   I175 @S9S_MB_2U_LIB.S9S_MB_2U(SCH_1):PAGE104
   J23  117  VSS51 SCONN288_ADR50017P130CC-SCONN2A   I175 @S9S_MB_2U_LIB.S9S_MB_2U(SCH_1):PAGE104
   J23  119  VSS52 SCONN288_ADR50017P130CC-SCONN2A   I175 @S9S_MB_2U_LIB.S9S_MB_2U(SCH_1):PAGE104
   J23  121  VSS53 SCONN288_ADR50017P130CC-SCONN2A   I175 @S9S_MB_2U_LIB.S9S_MB_2U(SCH_1):PAGE104
   J23  123  VSS54 SCONN288_ADR50017P130CC-SCONN2A   I175 @S9S_MB_2U_LIB.S9S_MB_2U(SCH_1):PAGE104
   J23  125  VSS55 SCONN288_ADR50017P130CC-SCONN2A   I175 @S9S_MB_2U_LIB.S9S_MB_2U(SCH_1):PAGE104
   J23  128  VSS56 SCONN288_ADR50017P130CC-SCONN2A   I175 @S9S_MB_2U_LIB.S9S_MB_2U(SCH_1):PAGE104
   J23  130  VSS57 SCONN288_ADR50017P130CC-SCONN2A   I175 @S9S_MB_2U_LIB.S9S_MB_2U(SCH_1):PAGE104
   J23  132  VSS58 SCONN288_ADR50017P130CC-SCONN2A   I175 @S9S_MB_2U_LIB.S9S_MB_2U(SCH_1):PAGE104
   J23  134  VSS59 SCONN288_ADR50017P130CC-SCONN2A   I175 @S9S_MB_2U_LIB.S9S_MB_2U(SCH_1):PAGE104
   J23  136  VSS60 SCONN288_ADR50017P130CC-SCONN2A   I175 @S9S_MB_2U_LIB.S9S_MB_2U(SCH_1):PAGE104
   J23  139  VSS61 SCONN288_ADR50017P130CC-SCONN2A   I175 @S9S_MB_2U_LIB.S9S_MB_2U(SCH_1):PAGE104
   J23  141  VSS62 SCONN288_ADR50017P130CC-SCONN2A   I175 @S9S_MB_2U_LIB.S9S_MB_2U(SCH_1):PAGE104
   J23  143  VSS63 SCONN288_ADR50017P130CC-SCONN2A   I175 @S9S_MB_2U_LIB.S9S_MB_2U(SCH_1):PAGE104
   J23  151  VSS64 SCONN288_ADR50017P130CC-SCONN2A   I175 @S9S_MB_2U_LIB.S9S_MB_2U(SCH_1):PAGE104
   J23  153  VSS65 SCONN288_ADR50017P130CC-SCONN2A   I175 @S9S_MB_2U_LIB.S9S_MB_2U(SCH_1):PAGE104
   J23  155  VSS66 SCONN288_ADR50017P130CC-SCONN2A   I175 @S9S_MB_2U_LIB.S9S_MB_2U(SCH_1):PAGE104
   J23  158  VSS67 SCONN288_ADR50017P130CC-SCONN2A   I175 @S9S_MB_2U_LIB.S9S_MB_2U(SCH_1):PAGE104
   J23  160  VSS68 SCONN288_ADR50017P130CC-SCONN2A   I175 @S9S_MB_2U_LIB.S9S_MB_2U(SCH_1):PAGE104
   J23  162  VSS69 SCONN288_ADR50017P130CC-SCONN2A   I175 @S9S_MB_2U_LIB.S9S_MB_2U(SCH_1):PAGE104
   J23  164  VSS70 SCONN288_ADR50017P130CC-SCONN2A   I175 @S9S_MB_2U_LIB.S9S_MB_2U(SCH_1):PAGE104
   J23  166  VSS71 SCONN288_ADR50017P130CC-SCONN2A   I175 @S9S_MB_2U_LIB.S9S_MB_2U(SCH_1):PAGE104
   J23  169  VSS72 SCONN288_ADR50017P130CC-SCONN2A   I175 @S9S_MB_2U_LIB.S9S_MB_2U(SCH_1):PAGE104
   J23  171  VSS73 SCONN288_ADR50017P130CC-SCONN2A   I175 @S9S_MB_2U_LIB.S9S_MB_2U(SCH_1):PAGE104
   J23  173  VSS74 SCONN288_ADR50017P130CC-SCONN2A   I175 @S9S_MB_2U_LIB.S9S_MB_2U(SCH_1):PAGE104
   J23  175  VSS75 SCONN288_ADR50017P130CC-SCONN2A   I175 @S9S_MB_2U_LIB.S9S_MB_2U(SCH_1):PAGE104
   J23  177  VSS76 SCONN288_ADR50017P130CC-SCONN2A   I175 @S9S_MB_2U_LIB.S9S_MB_2U(SCH_1):PAGE104
   J23  180  VSS77 SCONN288_ADR50017P130CC-SCONN2A   I175 @S9S_MB_2U_LIB.S9S_MB_2U(SCH_1):PAGE104
   J23  182  VSS78 SCONN288_ADR50017P130CC-SCONN2A   I175 @S9S_MB_2U_LIB.S9S_MB_2U(SCH_1):PAGE104
   J23  184  VSS79 SCONN288_ADR50017P130CC-SCONN2A   I175 @S9S_MB_2U_LIB.S9S_MB_2U(SCH_1):PAGE104
   J23  186  VSS80 SCONN288_ADR50017P130CC-SCONN2A   I175 @S9S_MB_2U_LIB.S9S_MB_2U(SCH_1):PAGE104
   J23  188  VSS81 SCONN288_ADR50017P130CC-SCONN2A   I175 @S9S_MB_2U_LIB.S9S_MB_2U(SCH_1):PAGE104
   J23  191  VSS82 SCONN288_ADR50017P130CC-SCONN2A   I175 @S9S_MB_2U_LIB.S9S_MB_2U(SCH_1):PAGE104
   J23  193  VSS83 SCONN288_ADR50017P130CC-SCONN2A   I175 @S9S_MB_2U_LIB.S9S_MB_2U(SCH_1):PAGE104
   J23  195  VSS84 SCONN288_ADR50017P130CC-SCONN2A   I175 @S9S_MB_2U_LIB.S9S_MB_2U(SCH_1):PAGE104
   J23  197  VSS85 SCONN288_ADR50017P130CC-SCONN2A   I175 @S9S_MB_2U_LIB.S9S_MB_2U(SCH_1):PAGE104
   J23  199  VSS86 SCONN288_ADR50017P130CC-SCONN2A   I175 @S9S_MB_2U_LIB.S9S_MB_2U(SCH_1):PAGE104
   J23  202  VSS87 SCONN288_ADR50017P130CC-SCONN2A   I175 @S9S_MB_2U_LIB.S9S_MB_2U(SCH_1):PAGE104
   J23  204  VSS88 SCONN288_ADR50017P130CC-SCONN2A   I175 @S9S_MB_2U_LIB.S9S_MB_2U(SCH_1):PAGE104
   J23  206  VSS89 SCONN288_ADR50017P130CC-SCONN2A   I175 @S9S_MB_2U_LIB.S9S_MB_2U(SCH_1):PAGE104
   J23  208  VSS90 SCONN288_ADR50017P130CC-SCONN2A   I175 @S9S_MB_2U_LIB.S9S_MB_2U(SCH_1):PAGE104
   J23  210  VSS91 SCONN288_ADR50017P130CC-SCONN2A   I175 @S9S_MB_2U_LIB.S9S_MB_2U(SCH_1):PAGE104
   J23  212  VSS92 SCONN288_ADR50017P130CC-SCONN2A   I175 @S9S_MB_2U_LIB.S9S_MB_2U(SCH_1):PAGE104
   J23  214  VSS93 SCONN288_ADR50017P130CC-SCONN2A   I175 @S9S_MB_2U_LIB.S9S_MB_2U(SCH_1):PAGE104
   J23  216  VSS94 SCONN288_ADR50017P130CC-SCONN2A   I175 @S9S_MB_2U_LIB.S9S_MB_2U(SCH_1):PAGE104
   J23  219  VSS95 SCONN288_ADR50017P130CC-SCONN2A   I175 @S9S_MB_2U_LIB.S9S_MB_2U(SCH_1):PAGE104
   J23  222  VSS96 SCONN288_ADR50017P130CC-SCONN2A   I175 @S9S_MB_2U_LIB.S9S_MB_2U(SCH_1):PAGE104
   J23  224  VSS97 SCONN288_ADR50017P130CC-SCONN2A   I175 @S9S_MB_2U_LIB.S9S_MB_2U(SCH_1):PAGE104
   J23  226  VSS98 SCONN288_ADR50017P130CC-SCONN2A   I175 @S9S_MB_2U_LIB.S9S_MB_2U(SCH_1):PAGE104
   J23  228  VSS99 SCONN288_ADR50017P130CC-SCONN2A   I175 @S9S_MB_2U_LIB.S9S_MB_2U(SCH_1):PAGE104
   J23  230 VSS100 SCONN288_ADR50017P130CC-SCONN2A   I175 @S9S_MB_2U_LIB.S9S_MB_2U(SCH_1):PAGE104
   J23  233 VSS101 SCONN288_ADR50017P130CC-SCONN2A   I175 @S9S_MB_2U_LIB.S9S_MB_2U(SCH_1):PAGE104
   J23  235 VSS102 SCONN288_ADR50017P130CC-SCONN2A   I175 @S9S_MB_2U_LIB.S9S_MB_2U(SCH_1):PAGE104
   J23  237 VSS103 SCONN288_ADR50017P130CC-SCONN2A   I175 @S9S_MB_2U_LIB.S9S_MB_2U(SCH_1):PAGE104
   J23  240 VSS104 SCONN288_ADR50017P130CC-SCONN2A   I175 @S9S_MB_2U_LIB.S9S_MB_2U(SCH_1):PAGE104
   J23  242 VSS105 SCONN288_ADR50017P130CC-SCONN2A   I175 @S9S_MB_2U_LIB.S9S_MB_2U(SCH_1):PAGE104
   J23  244 VSS106 SCONN288_ADR50017P130CC-SCONN2A   I175 @S9S_MB_2U_LIB.S9S_MB_2U(SCH_1):PAGE104
   J23  246 VSS107 SCONN288_ADR50017P130CC-SCONN2A   I175 @S9S_MB_2U_LIB.S9S_MB_2U(SCH_1):PAGE104
   J23  248 VSS108 SCONN288_ADR50017P130CC-SCONN2A   I175 @S9S_MB_2U_LIB.S9S_MB_2U(SCH_1):PAGE104
   J23  251 VSS109 SCONN288_ADR50017P130CC-SCONN2A   I175 @S9S_MB_2U_LIB.S9S_MB_2U(SCH_1):PAGE104
   J23  253 VSS110 SCONN288_ADR50017P130CC-SCONN2A   I175 @S9S_MB_2U_LIB.S9S_MB_2U(SCH_1):PAGE104
   J23  255 VSS111 SCONN288_ADR50017P130CC-SCONN2A   I175 @S9S_MB_2U_LIB.S9S_MB_2U(SCH_1):PAGE104
   J23  257 VSS112 SCONN288_ADR50017P130CC-SCONN2A   I175 @S9S_MB_2U_LIB.S9S_MB_2U(SCH_1):PAGE104
   J23  259 VSS113 SCONN288_ADR50017P130CC-SCONN2A   I175 @S9S_MB_2U_LIB.S9S_MB_2U(SCH_1):PAGE104
   J23  262 VSS114 SCONN288_ADR50017P130CC-SCONN2A   I175 @S9S_MB_2U_LIB.S9S_MB_2U(SCH_1):PAGE104
   J23  264 VSS115 SCONN288_ADR50017P130CC-SCONN2A   I175 @S9S_MB_2U_LIB.S9S_MB_2U(SCH_1):PAGE104
   J23  266 VSS116 SCONN288_ADR50017P130CC-SCONN2A   I175 @S9S_MB_2U_LIB.S9S_MB_2U(SCH_1):PAGE104
   J23  268 VSS117 SCONN288_ADR50017P130CC-SCONN2A   I175 @S9S_MB_2U_LIB.S9S_MB_2U(SCH_1):PAGE104
   J23  270 VSS118 SCONN288_ADR50017P130CC-SCONN2A   I175 @S9S_MB_2U_LIB.S9S_MB_2U(SCH_1):PAGE104
   J23  273 VSS119 SCONN288_ADR50017P130CC-SCONN2A   I175 @S9S_MB_2U_LIB.S9S_MB_2U(SCH_1):PAGE104
   J23  275 VSS120 SCONN288_ADR50017P130CC-SCONN2A   I175 @S9S_MB_2U_LIB.S9S_MB_2U(SCH_1):PAGE104
   J23  277 VSS121 SCONN288_ADR50017P130CC-SCONN2A   I175 @S9S_MB_2U_LIB.S9S_MB_2U(SCH_1):PAGE104
   J23  279 VSS122 SCONN288_ADR50017P130CC-SCONN2A   I175 @S9S_MB_2U_LIB.S9S_MB_2U(SCH_1):PAGE104
   J23  281 VSS123 SCONN288_ADR50017P130CC-SCONN2A   I175 @S9S_MB_2U_LIB.S9S_MB_2U(SCH_1):PAGE104
   J23  284 VSS124 SCONN288_ADR50017P130CC-SCONN2A   I175 @S9S_MB_2U_LIB.S9S_MB_2U(SCH_1):PAGE104
   J23  286 VSS125 SCONN288_ADR50017P130CC-SCONN2A   I175 @S9S_MB_2U_LIB.S9S_MB_2U(SCH_1):PAGE104
   J23  288 VSS126 SCONN288_ADR50017P130CC-SCONN2A   I175 @S9S_MB_2U_LIB.S9S_MB_2U(SCH_1):PAGE104
   R80    2      B Q_RES_0402LF-196K,1%,1/16W,CHIA     I2 @S9S_MB_2U_LIB.S9S_MB_2U(SCH_1):PAGE105
   C96    2      B Q_CAP_C0402-2.2UF,6.3V,20%,X6SA   I123 @S9S_MB_2U_LIB.S9S_MB_2U(SCH_1):PAGE105
   C97    2      B Q_CAP_C0805-10UF,16V,10%,X6S,CA   I124 @S9S_MB_2U_LIB.S9S_MB_2U(SCH_1):PAGE105
   C98    2      B Q_CAP_C0805-10UF,16V,10%,X6S,CA   I146 @S9S_MB_2U_LIB.S9S_MB_2U(SCH_1):PAGE105
   J24   G1     G1 SCONN288_ADR50017P087CC-SCONN2A   I180 @S9S_MB_2U_LIB.S9S_MB_2U(SCH_1):PAGE105
   J24   G2     G2 SCONN288_ADR50017P087CC-SCONN2A   I180 @S9S_MB_2U_LIB.S9S_MB_2U(SCH_1):PAGE105
   J24   G3     G3 SCONN288_ADR50017P087CC-SCONN2A   I180 @S9S_MB_2U_LIB.S9S_MB_2U(SCH_1):PAGE105
   J24    6   VSS0 SCONN288_ADR50017P087CC-SCONN2A   I180 @S9S_MB_2U_LIB.S9S_MB_2U(SCH_1):PAGE105
   J24    8   VSS1 SCONN288_ADR50017P087CC-SCONN2A   I180 @S9S_MB_2U_LIB.S9S_MB_2U(SCH_1):PAGE105
   J24   10   VSS2 SCONN288_ADR50017P087CC-SCONN2A   I180 @S9S_MB_2U_LIB.S9S_MB_2U(SCH_1):PAGE105
   J24   13   VSS3 SCONN288_ADR50017P087CC-SCONN2A   I180 @S9S_MB_2U_LIB.S9S_MB_2U(SCH_1):PAGE105
   J24   15   VSS4 SCONN288_ADR50017P087CC-SCONN2A   I180 @S9S_MB_2U_LIB.S9S_MB_2U(SCH_1):PAGE105
   J24   17   VSS5 SCONN288_ADR50017P087CC-SCONN2A   I180 @S9S_MB_2U_LIB.S9S_MB_2U(SCH_1):PAGE105
   J24   19   VSS6 SCONN288_ADR50017P087CC-SCONN2A   I180 @S9S_MB_2U_LIB.S9S_MB_2U(SCH_1):PAGE105
   J24   21   VSS7 SCONN288_ADR50017P087CC-SCONN2A   I180 @S9S_MB_2U_LIB.S9S_MB_2U(SCH_1):PAGE105
   J24   24   VSS8 SCONN288_ADR50017P087CC-SCONN2A   I180 @S9S_MB_2U_LIB.S9S_MB_2U(SCH_1):PAGE105
   J24   26   VSS9 SCONN288_ADR50017P087CC-SCONN2A   I180 @S9S_MB_2U_LIB.S9S_MB_2U(SCH_1):PAGE105
   J24   28  VSS10 SCONN288_ADR50017P087CC-SCONN2A   I180 @S9S_MB_2U_LIB.S9S_MB_2U(SCH_1):PAGE105
   J24   30  VSS11 SCONN288_ADR50017P087CC-SCONN2A   I180 @S9S_MB_2U_LIB.S9S_MB_2U(SCH_1):PAGE105
   J24   32  VSS12 SCONN288_ADR50017P087CC-SCONN2A   I180 @S9S_MB_2U_LIB.S9S_MB_2U(SCH_1):PAGE105
   J24   35  VSS13 SCONN288_ADR50017P087CC-SCONN2A   I180 @S9S_MB_2U_LIB.S9S_MB_2U(SCH_1):PAGE105
   J24   37  VSS14 SCONN288_ADR50017P087CC-SCONN2A   I180 @S9S_MB_2U_LIB.S9S_MB_2U(SCH_1):PAGE105
   J24   39  VSS15 SCONN288_ADR50017P087CC-SCONN2A   I180 @S9S_MB_2U_LIB.S9S_MB_2U(SCH_1):PAGE105
   J24   41  VSS16 SCONN288_ADR50017P087CC-SCONN2A   I180 @S9S_MB_2U_LIB.S9S_MB_2U(SCH_1):PAGE105
   J24   43  VSS17 SCONN288_ADR50017P087CC-SCONN2A   I180 @S9S_MB_2U_LIB.S9S_MB_2U(SCH_1):PAGE105
   J24   46  VSS18 SCONN288_ADR50017P087CC-SCONN2A   I180 @S9S_MB_2U_LIB.S9S_MB_2U(SCH_1):PAGE105
   J24   48  VSS19 SCONN288_ADR50017P087CC-SCONN2A   I180 @S9S_MB_2U_LIB.S9S_MB_2U(SCH_1):PAGE105
   J24   50  VSS20 SCONN288_ADR50017P087CC-SCONN2A   I180 @S9S_MB_2U_LIB.S9S_MB_2U(SCH_1):PAGE105
   J24   52  VSS21 SCONN288_ADR50017P087CC-SCONN2A   I180 @S9S_MB_2U_LIB.S9S_MB_2U(SCH_1):PAGE105
   J24   54  VSS22 SCONN288_ADR50017P087CC-SCONN2A   I180 @S9S_MB_2U_LIB.S9S_MB_2U(SCH_1):PAGE105
   J24   57  VSS23 SCONN288_ADR50017P087CC-SCONN2A   I180 @S9S_MB_2U_LIB.S9S_MB_2U(SCH_1):PAGE105
   J24   59  VSS24 SCONN288_ADR50017P087CC-SCONN2A   I180 @S9S_MB_2U_LIB.S9S_MB_2U(SCH_1):PAGE105
   J24   61  VSS25 SCONN288_ADR50017P087CC-SCONN2A   I180 @S9S_MB_2U_LIB.S9S_MB_2U(SCH_1):PAGE105
   J24   63  VSS26 SCONN288_ADR50017P087CC-SCONN2A   I180 @S9S_MB_2U_LIB.S9S_MB_2U(SCH_1):PAGE105
   J24   65  VSS27 SCONN288_ADR50017P087CC-SCONN2A   I180 @S9S_MB_2U_LIB.S9S_MB_2U(SCH_1):PAGE105
   J24   67  VSS28 SCONN288_ADR50017P087CC-SCONN2A   I180 @S9S_MB_2U_LIB.S9S_MB_2U(SCH_1):PAGE105
   J24   69  VSS29 SCONN288_ADR50017P087CC-SCONN2A   I180 @S9S_MB_2U_LIB.S9S_MB_2U(SCH_1):PAGE105
   J24   71  VSS30 SCONN288_ADR50017P087CC-SCONN2A   I180 @S9S_MB_2U_LIB.S9S_MB_2U(SCH_1):PAGE105
   J24   73  VSS31 SCONN288_ADR50017P087CC-SCONN2A   I180 @S9S_MB_2U_LIB.S9S_MB_2U(SCH_1):PAGE105
   J24   75  VSS32 SCONN288_ADR50017P087CC-SCONN2A   I180 @S9S_MB_2U_LIB.S9S_MB_2U(SCH_1):PAGE105
   J24   77  VSS33 SCONN288_ADR50017P087CC-SCONN2A   I180 @S9S_MB_2U_LIB.S9S_MB_2U(SCH_1):PAGE105
   J24   79  VSS34 SCONN288_ADR50017P087CC-SCONN2A   I180 @S9S_MB_2U_LIB.S9S_MB_2U(SCH_1):PAGE105
   J24   81  VSS35 SCONN288_ADR50017P087CC-SCONN2A   I180 @S9S_MB_2U_LIB.S9S_MB_2U(SCH_1):PAGE105
   J24   83  VSS36 SCONN288_ADR50017P087CC-SCONN2A   I180 @S9S_MB_2U_LIB.S9S_MB_2U(SCH_1):PAGE105
   J24   85  VSS37 SCONN288_ADR50017P087CC-SCONN2A   I180 @S9S_MB_2U_LIB.S9S_MB_2U(SCH_1):PAGE105
   J24   88  VSS38 SCONN288_ADR50017P087CC-SCONN2A   I180 @S9S_MB_2U_LIB.S9S_MB_2U(SCH_1):PAGE105
   J24   90  VSS39 SCONN288_ADR50017P087CC-SCONN2A   I180 @S9S_MB_2U_LIB.S9S_MB_2U(SCH_1):PAGE105
   J24   92  VSS40 SCONN288_ADR50017P087CC-SCONN2A   I180 @S9S_MB_2U_LIB.S9S_MB_2U(SCH_1):PAGE105
   J24   95  VSS41 SCONN288_ADR50017P087CC-SCONN2A   I180 @S9S_MB_2U_LIB.S9S_MB_2U(SCH_1):PAGE105
   J24   97  VSS42 SCONN288_ADR50017P087CC-SCONN2A   I180 @S9S_MB_2U_LIB.S9S_MB_2U(SCH_1):PAGE105
   J24   99  VSS43 SCONN288_ADR50017P087CC-SCONN2A   I180 @S9S_MB_2U_LIB.S9S_MB_2U(SCH_1):PAGE105
   J24  101  VSS44 SCONN288_ADR50017P087CC-SCONN2A   I180 @S9S_MB_2U_LIB.S9S_MB_2U(SCH_1):PAGE105
   J24  103  VSS45 SCONN288_ADR50017P087CC-SCONN2A   I180 @S9S_MB_2U_LIB.S9S_MB_2U(SCH_1):PAGE105
   J24  106  VSS46 SCONN288_ADR50017P087CC-SCONN2A   I180 @S9S_MB_2U_LIB.S9S_MB_2U(SCH_1):PAGE105
   J24  108  VSS47 SCONN288_ADR50017P087CC-SCONN2A   I180 @S9S_MB_2U_LIB.S9S_MB_2U(SCH_1):PAGE105
   J24  110  VSS48 SCONN288_ADR50017P087CC-SCONN2A   I180 @S9S_MB_2U_LIB.S9S_MB_2U(SCH_1):PAGE105
   J24  112  VSS49 SCONN288_ADR50017P087CC-SCONN2A   I180 @S9S_MB_2U_LIB.S9S_MB_2U(SCH_1):PAGE105
   J24  114  VSS50 SCONN288_ADR50017P087CC-SCONN2A   I180 @S9S_MB_2U_LIB.S9S_MB_2U(SCH_1):PAGE105
   J24  117  VSS51 SCONN288_ADR50017P087CC-SCONN2A   I180 @S9S_MB_2U_LIB.S9S_MB_2U(SCH_1):PAGE105
   J24  119  VSS52 SCONN288_ADR50017P087CC-SCONN2A   I180 @S9S_MB_2U_LIB.S9S_MB_2U(SCH_1):PAGE105
   J24  121  VSS53 SCONN288_ADR50017P087CC-SCONN2A   I180 @S9S_MB_2U_LIB.S9S_MB_2U(SCH_1):PAGE105
   J24  123  VSS54 SCONN288_ADR50017P087CC-SCONN2A   I180 @S9S_MB_2U_LIB.S9S_MB_2U(SCH_1):PAGE105
   J24  125  VSS55 SCONN288_ADR50017P087CC-SCONN2A   I180 @S9S_MB_2U_LIB.S9S_MB_2U(SCH_1):PAGE105
   J24  128  VSS56 SCONN288_ADR50017P087CC-SCONN2A   I180 @S9S_MB_2U_LIB.S9S_MB_2U(SCH_1):PAGE105
   J24  130  VSS57 SCONN288_ADR50017P087CC-SCONN2A   I180 @S9S_MB_2U_LIB.S9S_MB_2U(SCH_1):PAGE105
   J24  132  VSS58 SCONN288_ADR50017P087CC-SCONN2A   I180 @S9S_MB_2U_LIB.S9S_MB_2U(SCH_1):PAGE105
   J24  134  VSS59 SCONN288_ADR50017P087CC-SCONN2A   I180 @S9S_MB_2U_LIB.S9S_MB_2U(SCH_1):PAGE105
   J24  136  VSS60 SCONN288_ADR50017P087CC-SCONN2A   I180 @S9S_MB_2U_LIB.S9S_MB_2U(SCH_1):PAGE105
   J24  139  VSS61 SCONN288_ADR50017P087CC-SCONN2A   I180 @S9S_MB_2U_LIB.S9S_MB_2U(SCH_1):PAGE105
   J24  141  VSS62 SCONN288_ADR50017P087CC-SCONN2A   I180 @S9S_MB_2U_LIB.S9S_MB_2U(SCH_1):PAGE105
   J24  143  VSS63 SCONN288_ADR50017P087CC-SCONN2A   I180 @S9S_MB_2U_LIB.S9S_MB_2U(SCH_1):PAGE105
   J24  151  VSS64 SCONN288_ADR50017P087CC-SCONN2A   I180 @S9S_MB_2U_LIB.S9S_MB_2U(SCH_1):PAGE105
   J24  153  VSS65 SCONN288_ADR50017P087CC-SCONN2A   I180 @S9S_MB_2U_LIB.S9S_MB_2U(SCH_1):PAGE105
   J24  155  VSS66 SCONN288_ADR50017P087CC-SCONN2A   I180 @S9S_MB_2U_LIB.S9S_MB_2U(SCH_1):PAGE105
   J24  158  VSS67 SCONN288_ADR50017P087CC-SCONN2A   I180 @S9S_MB_2U_LIB.S9S_MB_2U(SCH_1):PAGE105
   J24  160  VSS68 SCONN288_ADR50017P087CC-SCONN2A   I180 @S9S_MB_2U_LIB.S9S_MB_2U(SCH_1):PAGE105
   J24  162  VSS69 SCONN288_ADR50017P087CC-SCONN2A   I180 @S9S_MB_2U_LIB.S9S_MB_2U(SCH_1):PAGE105
   J24  164  VSS70 SCONN288_ADR50017P087CC-SCONN2A   I180 @S9S_MB_2U_LIB.S9S_MB_2U(SCH_1):PAGE105
   J24  166  VSS71 SCONN288_ADR50017P087CC-SCONN2A   I180 @S9S_MB_2U_LIB.S9S_MB_2U(SCH_1):PAGE105
   J24  169  VSS72 SCONN288_ADR50017P087CC-SCONN2A   I180 @S9S_MB_2U_LIB.S9S_MB_2U(SCH_1):PAGE105
   J24  171  VSS73 SCONN288_ADR50017P087CC-SCONN2A   I180 @S9S_MB_2U_LIB.S9S_MB_2U(SCH_1):PAGE105
   J24  173  VSS74 SCONN288_ADR50017P087CC-SCONN2A   I180 @S9S_MB_2U_LIB.S9S_MB_2U(SCH_1):PAGE105
   J24  175  VSS75 SCONN288_ADR50017P087CC-SCONN2A   I180 @S9S_MB_2U_LIB.S9S_MB_2U(SCH_1):PAGE105
   J24  177  VSS76 SCONN288_ADR50017P087CC-SCONN2A   I180 @S9S_MB_2U_LIB.S9S_MB_2U(SCH_1):PAGE105
   J24  180  VSS77 SCONN288_ADR50017P087CC-SCONN2A   I180 @S9S_MB_2U_LIB.S9S_MB_2U(SCH_1):PAGE105
   J24  182  VSS78 SCONN288_ADR50017P087CC-SCONN2A   I180 @S9S_MB_2U_LIB.S9S_MB_2U(SCH_1):PAGE105
   J24  184  VSS79 SCONN288_ADR50017P087CC-SCONN2A   I180 @S9S_MB_2U_LIB.S9S_MB_2U(SCH_1):PAGE105
   J24  186  VSS80 SCONN288_ADR50017P087CC-SCONN2A   I180 @S9S_MB_2U_LIB.S9S_MB_2U(SCH_1):PAGE105
   J24  188  VSS81 SCONN288_ADR50017P087CC-SCONN2A   I180 @S9S_MB_2U_LIB.S9S_MB_2U(SCH_1):PAGE105
   J24  191  VSS82 SCONN288_ADR50017P087CC-SCONN2A   I180 @S9S_MB_2U_LIB.S9S_MB_2U(SCH_1):PAGE105
   J24  193  VSS83 SCONN288_ADR50017P087CC-SCONN2A   I180 @S9S_MB_2U_LIB.S9S_MB_2U(SCH_1):PAGE105
   J24  195  VSS84 SCONN288_ADR50017P087CC-SCONN2A   I180 @S9S_MB_2U_LIB.S9S_MB_2U(SCH_1):PAGE105
   J24  197  VSS85 SCONN288_ADR50017P087CC-SCONN2A   I180 @S9S_MB_2U_LIB.S9S_MB_2U(SCH_1):PAGE105
   J24  199  VSS86 SCONN288_ADR50017P087CC-SCONN2A   I180 @S9S_MB_2U_LIB.S9S_MB_2U(SCH_1):PAGE105
   J24  202  VSS87 SCONN288_ADR50017P087CC-SCONN2A   I180 @S9S_MB_2U_LIB.S9S_MB_2U(SCH_1):PAGE105
   J24  204  VSS88 SCONN288_ADR50017P087CC-SCONN2A   I180 @S9S_MB_2U_LIB.S9S_MB_2U(SCH_1):PAGE105
   J24  206  VSS89 SCONN288_ADR50017P087CC-SCONN2A   I180 @S9S_MB_2U_LIB.S9S_MB_2U(SCH_1):PAGE105
   J24  208  VSS90 SCONN288_ADR50017P087CC-SCONN2A   I180 @S9S_MB_2U_LIB.S9S_MB_2U(SCH_1):PAGE105
   J24  210  VSS91 SCONN288_ADR50017P087CC-SCONN2A   I180 @S9S_MB_2U_LIB.S9S_MB_2U(SCH_1):PAGE105
   J24  212  VSS92 SCONN288_ADR50017P087CC-SCONN2A   I180 @S9S_MB_2U_LIB.S9S_MB_2U(SCH_1):PAGE105
   J24  214  VSS93 SCONN288_ADR50017P087CC-SCONN2A   I180 @S9S_MB_2U_LIB.S9S_MB_2U(SCH_1):PAGE105
   J24  216  VSS94 SCONN288_ADR50017P087CC-SCONN2A   I180 @S9S_MB_2U_LIB.S9S_MB_2U(SCH_1):PAGE105
   J24  219  VSS95 SCONN288_ADR50017P087CC-SCONN2A   I180 @S9S_MB_2U_LIB.S9S_MB_2U(SCH_1):PAGE105
   J24  222  VSS96 SCONN288_ADR50017P087CC-SCONN2A   I180 @S9S_MB_2U_LIB.S9S_MB_2U(SCH_1):PAGE105
   J24  224  VSS97 SCONN288_ADR50017P087CC-SCONN2A   I180 @S9S_MB_2U_LIB.S9S_MB_2U(SCH_1):PAGE105
   J24  226  VSS98 SCONN288_ADR50017P087CC-SCONN2A   I180 @S9S_MB_2U_LIB.S9S_MB_2U(SCH_1):PAGE105
   J24  228  VSS99 SCONN288_ADR50017P087CC-SCONN2A   I180 @S9S_MB_2U_LIB.S9S_MB_2U(SCH_1):PAGE105
   J24  230 VSS100 SCONN288_ADR50017P087CC-SCONN2A   I180 @S9S_MB_2U_LIB.S9S_MB_2U(SCH_1):PAGE105
   J24  233 VSS101 SCONN288_ADR50017P087CC-SCONN2A   I180 @S9S_MB_2U_LIB.S9S_MB_2U(SCH_1):PAGE105
   J24  235 VSS102 SCONN288_ADR50017P087CC-SCONN2A   I180 @S9S_MB_2U_LIB.S9S_MB_2U(SCH_1):PAGE105
   J24  237 VSS103 SCONN288_ADR50017P087CC-SCONN2A   I180 @S9S_MB_2U_LIB.S9S_MB_2U(SCH_1):PAGE105
   J24  240 VSS104 SCONN288_ADR50017P087CC-SCONN2A   I180 @S9S_MB_2U_LIB.S9S_MB_2U(SCH_1):PAGE105
   J24  242 VSS105 SCONN288_ADR50017P087CC-SCONN2A   I180 @S9S_MB_2U_LIB.S9S_MB_2U(SCH_1):PAGE105
   J24  244 VSS106 SCONN288_ADR50017P087CC-SCONN2A   I180 @S9S_MB_2U_LIB.S9S_MB_2U(SCH_1):PAGE105
   J24  246 VSS107 SCONN288_ADR50017P087CC-SCONN2A   I180 @S9S_MB_2U_LIB.S9S_MB_2U(SCH_1):PAGE105
   J24  248 VSS108 SCONN288_ADR50017P087CC-SCONN2A   I180 @S9S_MB_2U_LIB.S9S_MB_2U(SCH_1):PAGE105
   J24  251 VSS109 SCONN288_ADR50017P087CC-SCONN2A   I180 @S9S_MB_2U_LIB.S9S_MB_2U(SCH_1):PAGE105
   J24  253 VSS110 SCONN288_ADR50017P087CC-SCONN2A   I180 @S9S_MB_2U_LIB.S9S_MB_2U(SCH_1):PAGE105
   J24  255 VSS111 SCONN288_ADR50017P087CC-SCONN2A   I180 @S9S_MB_2U_LIB.S9S_MB_2U(SCH_1):PAGE105
   J24  257 VSS112 SCONN288_ADR50017P087CC-SCONN2A   I180 @S9S_MB_2U_LIB.S9S_MB_2U(SCH_1):PAGE105
   J24  259 VSS113 SCONN288_ADR50017P087CC-SCONN2A   I180 @S9S_MB_2U_LIB.S9S_MB_2U(SCH_1):PAGE105
   J24  262 VSS114 SCONN288_ADR50017P087CC-SCONN2A   I180 @S9S_MB_2U_LIB.S9S_MB_2U(SCH_1):PAGE105
   J24  264 VSS115 SCONN288_ADR50017P087CC-SCONN2A   I180 @S9S_MB_2U_LIB.S9S_MB_2U(SCH_1):PAGE105
   J24  266 VSS116 SCONN288_ADR50017P087CC-SCONN2A   I180 @S9S_MB_2U_LIB.S9S_MB_2U(SCH_1):PAGE105
   J24  268 VSS117 SCONN288_ADR50017P087CC-SCONN2A   I180 @S9S_MB_2U_LIB.S9S_MB_2U(SCH_1):PAGE105
   J24  270 VSS118 SCONN288_ADR50017P087CC-SCONN2A   I180 @S9S_MB_2U_LIB.S9S_MB_2U(SCH_1):PAGE105
   J24  273 VSS119 SCONN288_ADR50017P087CC-SCONN2A   I180 @S9S_MB_2U_LIB.S9S_MB_2U(SCH_1):PAGE105
   J24  275 VSS120 SCONN288_ADR50017P087CC-SCONN2A   I180 @S9S_MB_2U_LIB.S9S_MB_2U(SCH_1):PAGE105
   J24  277 VSS121 SCONN288_ADR50017P087CC-SCONN2A   I180 @S9S_MB_2U_LIB.S9S_MB_2U(SCH_1):PAGE105
   J24  279 VSS122 SCONN288_ADR50017P087CC-SCONN2A   I180 @S9S_MB_2U_LIB.S9S_MB_2U(SCH_1):PAGE105
   J24  281 VSS123 SCONN288_ADR50017P087CC-SCONN2A   I180 @S9S_MB_2U_LIB.S9S_MB_2U(SCH_1):PAGE105
   J24  284 VSS124 SCONN288_ADR50017P087CC-SCONN2A   I180 @S9S_MB_2U_LIB.S9S_MB_2U(SCH_1):PAGE105
   J24  286 VSS125 SCONN288_ADR50017P087CC-SCONN2A   I180 @S9S_MB_2U_LIB.S9S_MB_2U(SCH_1):PAGE105
   J24  288 VSS126 SCONN288_ADR50017P087CC-SCONN2A   I180 @S9S_MB_2U_LIB.S9S_MB_2U(SCH_1):PAGE105
   R79    2      B Q_RES_0402LF-10K,1%,1/16W,CHIPA     I2 @S9S_MB_2U_LIB.S9S_MB_2U(SCH_1):PAGE106
   C93    2      B Q_CAP_C0402-2.2UF,6.3V,20%,X6SA   I122 @S9S_MB_2U_LIB.S9S_MB_2U(SCH_1):PAGE106
   C94    2      B Q_CAP_C0805-10UF,16V,10%,X6S,CA   I127 @S9S_MB_2U_LIB.S9S_MB_2U(SCH_1):PAGE106
   C95    2      B Q_CAP_C0805-10UF,16V,10%,X6S,CA   I130 @S9S_MB_2U_LIB.S9S_MB_2U(SCH_1):PAGE106
   J25   G1     G1 SCONN288_ADR50017P130CC-SCONN2A   I178 @S9S_MB_2U_LIB.S9S_MB_2U(SCH_1):PAGE106
   J25   G2     G2 SCONN288_ADR50017P130CC-SCONN2A   I178 @S9S_MB_2U_LIB.S9S_MB_2U(SCH_1):PAGE106
   J25   G3     G3 SCONN288_ADR50017P130CC-SCONN2A   I178 @S9S_MB_2U_LIB.S9S_MB_2U(SCH_1):PAGE106
   J25    6   VSS0 SCONN288_ADR50017P130CC-SCONN2A   I178 @S9S_MB_2U_LIB.S9S_MB_2U(SCH_1):PAGE106
   J25    8   VSS1 SCONN288_ADR50017P130CC-SCONN2A   I178 @S9S_MB_2U_LIB.S9S_MB_2U(SCH_1):PAGE106
   J25   10   VSS2 SCONN288_ADR50017P130CC-SCONN2A   I178 @S9S_MB_2U_LIB.S9S_MB_2U(SCH_1):PAGE106
   J25   13   VSS3 SCONN288_ADR50017P130CC-SCONN2A   I178 @S9S_MB_2U_LIB.S9S_MB_2U(SCH_1):PAGE106
   J25   15   VSS4 SCONN288_ADR50017P130CC-SCONN2A   I178 @S9S_MB_2U_LIB.S9S_MB_2U(SCH_1):PAGE106
   J25   17   VSS5 SCONN288_ADR50017P130CC-SCONN2A   I178 @S9S_MB_2U_LIB.S9S_MB_2U(SCH_1):PAGE106
   J25   19   VSS6 SCONN288_ADR50017P130CC-SCONN2A   I178 @S9S_MB_2U_LIB.S9S_MB_2U(SCH_1):PAGE106
   J25   21   VSS7 SCONN288_ADR50017P130CC-SCONN2A   I178 @S9S_MB_2U_LIB.S9S_MB_2U(SCH_1):PAGE106
   J25   24   VSS8 SCONN288_ADR50017P130CC-SCONN2A   I178 @S9S_MB_2U_LIB.S9S_MB_2U(SCH_1):PAGE106
   J25   26   VSS9 SCONN288_ADR50017P130CC-SCONN2A   I178 @S9S_MB_2U_LIB.S9S_MB_2U(SCH_1):PAGE106
   J25   28  VSS10 SCONN288_ADR50017P130CC-SCONN2A   I178 @S9S_MB_2U_LIB.S9S_MB_2U(SCH_1):PAGE106
   J25   30  VSS11 SCONN288_ADR50017P130CC-SCONN2A   I178 @S9S_MB_2U_LIB.S9S_MB_2U(SCH_1):PAGE106
   J25   32  VSS12 SCONN288_ADR50017P130CC-SCONN2A   I178 @S9S_MB_2U_LIB.S9S_MB_2U(SCH_1):PAGE106
   J25   35  VSS13 SCONN288_ADR50017P130CC-SCONN2A   I178 @S9S_MB_2U_LIB.S9S_MB_2U(SCH_1):PAGE106
   J25   37  VSS14 SCONN288_ADR50017P130CC-SCONN2A   I178 @S9S_MB_2U_LIB.S9S_MB_2U(SCH_1):PAGE106
   J25   39  VSS15 SCONN288_ADR50017P130CC-SCONN2A   I178 @S9S_MB_2U_LIB.S9S_MB_2U(SCH_1):PAGE106
   J25   41  VSS16 SCONN288_ADR50017P130CC-SCONN2A   I178 @S9S_MB_2U_LIB.S9S_MB_2U(SCH_1):PAGE106
   J25   43  VSS17 SCONN288_ADR50017P130CC-SCONN2A   I178 @S9S_MB_2U_LIB.S9S_MB_2U(SCH_1):PAGE106
   J25   46  VSS18 SCONN288_ADR50017P130CC-SCONN2A   I178 @S9S_MB_2U_LIB.S9S_MB_2U(SCH_1):PAGE106
   J25   48  VSS19 SCONN288_ADR50017P130CC-SCONN2A   I178 @S9S_MB_2U_LIB.S9S_MB_2U(SCH_1):PAGE106
   J25   50  VSS20 SCONN288_ADR50017P130CC-SCONN2A   I178 @S9S_MB_2U_LIB.S9S_MB_2U(SCH_1):PAGE106
   J25   52  VSS21 SCONN288_ADR50017P130CC-SCONN2A   I178 @S9S_MB_2U_LIB.S9S_MB_2U(SCH_1):PAGE106
   J25   54  VSS22 SCONN288_ADR50017P130CC-SCONN2A   I178 @S9S_MB_2U_LIB.S9S_MB_2U(SCH_1):PAGE106
   J25   57  VSS23 SCONN288_ADR50017P130CC-SCONN2A   I178 @S9S_MB_2U_LIB.S9S_MB_2U(SCH_1):PAGE106
   J25   59  VSS24 SCONN288_ADR50017P130CC-SCONN2A   I178 @S9S_MB_2U_LIB.S9S_MB_2U(SCH_1):PAGE106
   J25   61  VSS25 SCONN288_ADR50017P130CC-SCONN2A   I178 @S9S_MB_2U_LIB.S9S_MB_2U(SCH_1):PAGE106
   J25   63  VSS26 SCONN288_ADR50017P130CC-SCONN2A   I178 @S9S_MB_2U_LIB.S9S_MB_2U(SCH_1):PAGE106
   J25   65  VSS27 SCONN288_ADR50017P130CC-SCONN2A   I178 @S9S_MB_2U_LIB.S9S_MB_2U(SCH_1):PAGE106
   J25   67  VSS28 SCONN288_ADR50017P130CC-SCONN2A   I178 @S9S_MB_2U_LIB.S9S_MB_2U(SCH_1):PAGE106
   J25   69  VSS29 SCONN288_ADR50017P130CC-SCONN2A   I178 @S9S_MB_2U_LIB.S9S_MB_2U(SCH_1):PAGE106
   J25   71  VSS30 SCONN288_ADR50017P130CC-SCONN2A   I178 @S9S_MB_2U_LIB.S9S_MB_2U(SCH_1):PAGE106
   J25   73  VSS31 SCONN288_ADR50017P130CC-SCONN2A   I178 @S9S_MB_2U_LIB.S9S_MB_2U(SCH_1):PAGE106
   J25   75  VSS32 SCONN288_ADR50017P130CC-SCONN2A   I178 @S9S_MB_2U_LIB.S9S_MB_2U(SCH_1):PAGE106
   J25   77  VSS33 SCONN288_ADR50017P130CC-SCONN2A   I178 @S9S_MB_2U_LIB.S9S_MB_2U(SCH_1):PAGE106
   J25   79  VSS34 SCONN288_ADR50017P130CC-SCONN2A   I178 @S9S_MB_2U_LIB.S9S_MB_2U(SCH_1):PAGE106
   J25   81  VSS35 SCONN288_ADR50017P130CC-SCONN2A   I178 @S9S_MB_2U_LIB.S9S_MB_2U(SCH_1):PAGE106
   J25   83  VSS36 SCONN288_ADR50017P130CC-SCONN2A   I178 @S9S_MB_2U_LIB.S9S_MB_2U(SCH_1):PAGE106
   J25   85  VSS37 SCONN288_ADR50017P130CC-SCONN2A   I178 @S9S_MB_2U_LIB.S9S_MB_2U(SCH_1):PAGE106
   J25   88  VSS38 SCONN288_ADR50017P130CC-SCONN2A   I178 @S9S_MB_2U_LIB.S9S_MB_2U(SCH_1):PAGE106
   J25   90  VSS39 SCONN288_ADR50017P130CC-SCONN2A   I178 @S9S_MB_2U_LIB.S9S_MB_2U(SCH_1):PAGE106
   J25   92  VSS40 SCONN288_ADR50017P130CC-SCONN2A   I178 @S9S_MB_2U_LIB.S9S_MB_2U(SCH_1):PAGE106
   J25   95  VSS41 SCONN288_ADR50017P130CC-SCONN2A   I178 @S9S_MB_2U_LIB.S9S_MB_2U(SCH_1):PAGE106
   J25   97  VSS42 SCONN288_ADR50017P130CC-SCONN2A   I178 @S9S_MB_2U_LIB.S9S_MB_2U(SCH_1):PAGE106
   J25   99  VSS43 SCONN288_ADR50017P130CC-SCONN2A   I178 @S9S_MB_2U_LIB.S9S_MB_2U(SCH_1):PAGE106
   J25  101  VSS44 SCONN288_ADR50017P130CC-SCONN2A   I178 @S9S_MB_2U_LIB.S9S_MB_2U(SCH_1):PAGE106
   J25  103  VSS45 SCONN288_ADR50017P130CC-SCONN2A   I178 @S9S_MB_2U_LIB.S9S_MB_2U(SCH_1):PAGE106
   J25  106  VSS46 SCONN288_ADR50017P130CC-SCONN2A   I178 @S9S_MB_2U_LIB.S9S_MB_2U(SCH_1):PAGE106
   J25  108  VSS47 SCONN288_ADR50017P130CC-SCONN2A   I178 @S9S_MB_2U_LIB.S9S_MB_2U(SCH_1):PAGE106
   J25  110  VSS48 SCONN288_ADR50017P130CC-SCONN2A   I178 @S9S_MB_2U_LIB.S9S_MB_2U(SCH_1):PAGE106
   J25  112  VSS49 SCONN288_ADR50017P130CC-SCONN2A   I178 @S9S_MB_2U_LIB.S9S_MB_2U(SCH_1):PAGE106
   J25  114  VSS50 SCONN288_ADR50017P130CC-SCONN2A   I178 @S9S_MB_2U_LIB.S9S_MB_2U(SCH_1):PAGE106
   J25  117  VSS51 SCONN288_ADR50017P130CC-SCONN2A   I178 @S9S_MB_2U_LIB.S9S_MB_2U(SCH_1):PAGE106
   J25  119  VSS52 SCONN288_ADR50017P130CC-SCONN2A   I178 @S9S_MB_2U_LIB.S9S_MB_2U(SCH_1):PAGE106
   J25  121  VSS53 SCONN288_ADR50017P130CC-SCONN2A   I178 @S9S_MB_2U_LIB.S9S_MB_2U(SCH_1):PAGE106
   J25  123  VSS54 SCONN288_ADR50017P130CC-SCONN2A   I178 @S9S_MB_2U_LIB.S9S_MB_2U(SCH_1):PAGE106
   J25  125  VSS55 SCONN288_ADR50017P130CC-SCONN2A   I178 @S9S_MB_2U_LIB.S9S_MB_2U(SCH_1):PAGE106
   J25  128  VSS56 SCONN288_ADR50017P130CC-SCONN2A   I178 @S9S_MB_2U_LIB.S9S_MB_2U(SCH_1):PAGE106
   J25  130  VSS57 SCONN288_ADR50017P130CC-SCONN2A   I178 @S9S_MB_2U_LIB.S9S_MB_2U(SCH_1):PAGE106
   J25  132  VSS58 SCONN288_ADR50017P130CC-SCONN2A   I178 @S9S_MB_2U_LIB.S9S_MB_2U(SCH_1):PAGE106
   J25  134  VSS59 SCONN288_ADR50017P130CC-SCONN2A   I178 @S9S_MB_2U_LIB.S9S_MB_2U(SCH_1):PAGE106
   J25  136  VSS60 SCONN288_ADR50017P130CC-SCONN2A   I178 @S9S_MB_2U_LIB.S9S_MB_2U(SCH_1):PAGE106
   J25  139  VSS61 SCONN288_ADR50017P130CC-SCONN2A   I178 @S9S_MB_2U_LIB.S9S_MB_2U(SCH_1):PAGE106
   J25  141  VSS62 SCONN288_ADR50017P130CC-SCONN2A   I178 @S9S_MB_2U_LIB.S9S_MB_2U(SCH_1):PAGE106
   J25  143  VSS63 SCONN288_ADR50017P130CC-SCONN2A   I178 @S9S_MB_2U_LIB.S9S_MB_2U(SCH_1):PAGE106
   J25  151  VSS64 SCONN288_ADR50017P130CC-SCONN2A   I178 @S9S_MB_2U_LIB.S9S_MB_2U(SCH_1):PAGE106
   J25  153  VSS65 SCONN288_ADR50017P130CC-SCONN2A   I178 @S9S_MB_2U_LIB.S9S_MB_2U(SCH_1):PAGE106
   J25  155  VSS66 SCONN288_ADR50017P130CC-SCONN2A   I178 @S9S_MB_2U_LIB.S9S_MB_2U(SCH_1):PAGE106
   J25  158  VSS67 SCONN288_ADR50017P130CC-SCONN2A   I178 @S9S_MB_2U_LIB.S9S_MB_2U(SCH_1):PAGE106
   J25  160  VSS68 SCONN288_ADR50017P130CC-SCONN2A   I178 @S9S_MB_2U_LIB.S9S_MB_2U(SCH_1):PAGE106
   J25  162  VSS69 SCONN288_ADR50017P130CC-SCONN2A   I178 @S9S_MB_2U_LIB.S9S_MB_2U(SCH_1):PAGE106
   J25  164  VSS70 SCONN288_ADR50017P130CC-SCONN2A   I178 @S9S_MB_2U_LIB.S9S_MB_2U(SCH_1):PAGE106
   J25  166  VSS71 SCONN288_ADR50017P130CC-SCONN2A   I178 @S9S_MB_2U_LIB.S9S_MB_2U(SCH_1):PAGE106
   J25  169  VSS72 SCONN288_ADR50017P130CC-SCONN2A   I178 @S9S_MB_2U_LIB.S9S_MB_2U(SCH_1):PAGE106
   J25  171  VSS73 SCONN288_ADR50017P130CC-SCONN2A   I178 @S9S_MB_2U_LIB.S9S_MB_2U(SCH_1):PAGE106
   J25  173  VSS74 SCONN288_ADR50017P130CC-SCONN2A   I178 @S9S_MB_2U_LIB.S9S_MB_2U(SCH_1):PAGE106
   J25  175  VSS75 SCONN288_ADR50017P130CC-SCONN2A   I178 @S9S_MB_2U_LIB.S9S_MB_2U(SCH_1):PAGE106
   J25  177  VSS76 SCONN288_ADR50017P130CC-SCONN2A   I178 @S9S_MB_2U_LIB.S9S_MB_2U(SCH_1):PAGE106
   J25  180  VSS77 SCONN288_ADR50017P130CC-SCONN2A   I178 @S9S_MB_2U_LIB.S9S_MB_2U(SCH_1):PAGE106
   J25  182  VSS78 SCONN288_ADR50017P130CC-SCONN2A   I178 @S9S_MB_2U_LIB.S9S_MB_2U(SCH_1):PAGE106
   J25  184  VSS79 SCONN288_ADR50017P130CC-SCONN2A   I178 @S9S_MB_2U_LIB.S9S_MB_2U(SCH_1):PAGE106
   J25  186  VSS80 SCONN288_ADR50017P130CC-SCONN2A   I178 @S9S_MB_2U_LIB.S9S_MB_2U(SCH_1):PAGE106
   J25  188  VSS81 SCONN288_ADR50017P130CC-SCONN2A   I178 @S9S_MB_2U_LIB.S9S_MB_2U(SCH_1):PAGE106
   J25  191  VSS82 SCONN288_ADR50017P130CC-SCONN2A   I178 @S9S_MB_2U_LIB.S9S_MB_2U(SCH_1):PAGE106
   J25  193  VSS83 SCONN288_ADR50017P130CC-SCONN2A   I178 @S9S_MB_2U_LIB.S9S_MB_2U(SCH_1):PAGE106
   J25  195  VSS84 SCONN288_ADR50017P130CC-SCONN2A   I178 @S9S_MB_2U_LIB.S9S_MB_2U(SCH_1):PAGE106
   J25  197  VSS85 SCONN288_ADR50017P130CC-SCONN2A   I178 @S9S_MB_2U_LIB.S9S_MB_2U(SCH_1):PAGE106
   J25  199  VSS86 SCONN288_ADR50017P130CC-SCONN2A   I178 @S9S_MB_2U_LIB.S9S_MB_2U(SCH_1):PAGE106
   J25  202  VSS87 SCONN288_ADR50017P130CC-SCONN2A   I178 @S9S_MB_2U_LIB.S9S_MB_2U(SCH_1):PAGE106
   J25  204  VSS88 SCONN288_ADR50017P130CC-SCONN2A   I178 @S9S_MB_2U_LIB.S9S_MB_2U(SCH_1):PAGE106
   J25  206  VSS89 SCONN288_ADR50017P130CC-SCONN2A   I178 @S9S_MB_2U_LIB.S9S_MB_2U(SCH_1):PAGE106
   J25  208  VSS90 SCONN288_ADR50017P130CC-SCONN2A   I178 @S9S_MB_2U_LIB.S9S_MB_2U(SCH_1):PAGE106
   J25  210  VSS91 SCONN288_ADR50017P130CC-SCONN2A   I178 @S9S_MB_2U_LIB.S9S_MB_2U(SCH_1):PAGE106
   J25  212  VSS92 SCONN288_ADR50017P130CC-SCONN2A   I178 @S9S_MB_2U_LIB.S9S_MB_2U(SCH_1):PAGE106
   J25  214  VSS93 SCONN288_ADR50017P130CC-SCONN2A   I178 @S9S_MB_2U_LIB.S9S_MB_2U(SCH_1):PAGE106
   J25  216  VSS94 SCONN288_ADR50017P130CC-SCONN2A   I178 @S9S_MB_2U_LIB.S9S_MB_2U(SCH_1):PAGE106
   J25  219  VSS95 SCONN288_ADR50017P130CC-SCONN2A   I178 @S9S_MB_2U_LIB.S9S_MB_2U(SCH_1):PAGE106
   J25  222  VSS96 SCONN288_ADR50017P130CC-SCONN2A   I178 @S9S_MB_2U_LIB.S9S_MB_2U(SCH_1):PAGE106
   J25  224  VSS97 SCONN288_ADR50017P130CC-SCONN2A   I178 @S9S_MB_2U_LIB.S9S_MB_2U(SCH_1):PAGE106
   J25  226  VSS98 SCONN288_ADR50017P130CC-SCONN2A   I178 @S9S_MB_2U_LIB.S9S_MB_2U(SCH_1):PAGE106
   J25  228  VSS99 SCONN288_ADR50017P130CC-SCONN2A   I178 @S9S_MB_2U_LIB.S9S_MB_2U(SCH_1):PAGE106
   J25  230 VSS100 SCONN288_ADR50017P130CC-SCONN2A   I178 @S9S_MB_2U_LIB.S9S_MB_2U(SCH_1):PAGE106
   J25  233 VSS101 SCONN288_ADR50017P130CC-SCONN2A   I178 @S9S_MB_2U_LIB.S9S_MB_2U(SCH_1):PAGE106
   J25  235 VSS102 SCONN288_ADR50017P130CC-SCONN2A   I178 @S9S_MB_2U_LIB.S9S_MB_2U(SCH_1):PAGE106
   J25  237 VSS103 SCONN288_ADR50017P130CC-SCONN2A   I178 @S9S_MB_2U_LIB.S9S_MB_2U(SCH_1):PAGE106
   J25  240 VSS104 SCONN288_ADR50017P130CC-SCONN2A   I178 @S9S_MB_2U_LIB.S9S_MB_2U(SCH_1):PAGE106
   J25  242 VSS105 SCONN288_ADR50017P130CC-SCONN2A   I178 @S9S_MB_2U_LIB.S9S_MB_2U(SCH_1):PAGE106
   J25  244 VSS106 SCONN288_ADR50017P130CC-SCONN2A   I178 @S9S_MB_2U_LIB.S9S_MB_2U(SCH_1):PAGE106
   J25  246 VSS107 SCONN288_ADR50017P130CC-SCONN2A   I178 @S9S_MB_2U_LIB.S9S_MB_2U(SCH_1):PAGE106
   J25  248 VSS108 SCONN288_ADR50017P130CC-SCONN2A   I178 @S9S_MB_2U_LIB.S9S_MB_2U(SCH_1):PAGE106
   J25  251 VSS109 SCONN288_ADR50017P130CC-SCONN2A   I178 @S9S_MB_2U_LIB.S9S_MB_2U(SCH_1):PAGE106
   J25  253 VSS110 SCONN288_ADR50017P130CC-SCONN2A   I178 @S9S_MB_2U_LIB.S9S_MB_2U(SCH_1):PAGE106
   J25  255 VSS111 SCONN288_ADR50017P130CC-SCONN2A   I178 @S9S_MB_2U_LIB.S9S_MB_2U(SCH_1):PAGE106
   J25  257 VSS112 SCONN288_ADR50017P130CC-SCONN2A   I178 @S9S_MB_2U_LIB.S9S_MB_2U(SCH_1):PAGE106
   J25  259 VSS113 SCONN288_ADR50017P130CC-SCONN2A   I178 @S9S_MB_2U_LIB.S9S_MB_2U(SCH_1):PAGE106
   J25  262 VSS114 SCONN288_ADR50017P130CC-SCONN2A   I178 @S9S_MB_2U_LIB.S9S_MB_2U(SCH_1):PAGE106
   J25  264 VSS115 SCONN288_ADR50017P130CC-SCONN2A   I178 @S9S_MB_2U_LIB.S9S_MB_2U(SCH_1):PAGE106
   J25  266 VSS116 SCONN288_ADR50017P130CC-SCONN2A   I178 @S9S_MB_2U_LIB.S9S_MB_2U(SCH_1):PAGE106
   J25  268 VSS117 SCONN288_ADR50017P130CC-SCONN2A   I178 @S9S_MB_2U_LIB.S9S_MB_2U(SCH_1):PAGE106
   J25  270 VSS118 SCONN288_ADR50017P130CC-SCONN2A   I178 @S9S_MB_2U_LIB.S9S_MB_2U(SCH_1):PAGE106
   J25  273 VSS119 SCONN288_ADR50017P130CC-SCONN2A   I178 @S9S_MB_2U_LIB.S9S_MB_2U(SCH_1):PAGE106
   J25  275 VSS120 SCONN288_ADR50017P130CC-SCONN2A   I178 @S9S_MB_2U_LIB.S9S_MB_2U(SCH_1):PAGE106
   J25  277 VSS121 SCONN288_ADR50017P130CC-SCONN2A   I178 @S9S_MB_2U_LIB.S9S_MB_2U(SCH_1):PAGE106
   J25  279 VSS122 SCONN288_ADR50017P130CC-SCONN2A   I178 @S9S_MB_2U_LIB.S9S_MB_2U(SCH_1):PAGE106
   J25  281 VSS123 SCONN288_ADR50017P130CC-SCONN2A   I178 @S9S_MB_2U_LIB.S9S_MB_2U(SCH_1):PAGE106
   J25  284 VSS124 SCONN288_ADR50017P130CC-SCONN2A   I178 @S9S_MB_2U_LIB.S9S_MB_2U(SCH_1):PAGE106
   J25  286 VSS125 SCONN288_ADR50017P130CC-SCONN2A   I178 @S9S_MB_2U_LIB.S9S_MB_2U(SCH_1):PAGE106
   J25  288 VSS126 SCONN288_ADR50017P130CC-SCONN2A   I178 @S9S_MB_2U_LIB.S9S_MB_2U(SCH_1):PAGE106
   R78    2      B Q_RES_0402LF-15.4K,1%,1/16W,CHA     I2 @S9S_MB_2U_LIB.S9S_MB_2U(SCH_1):PAGE107
   C90    2      B Q_CAP_C0402-2.2UF,6.3V,20%,X6SA   I122 @S9S_MB_2U_LIB.S9S_MB_2U(SCH_1):PAGE107
   C91    2      B Q_CAP_C0805-10UF,16V,10%,X6S,CA   I126 @S9S_MB_2U_LIB.S9S_MB_2U(SCH_1):PAGE107
   C92    2      B Q_CAP_C0805-10UF,16V,10%,X6S,CA   I128 @S9S_MB_2U_LIB.S9S_MB_2U(SCH_1):PAGE107
   J26   G1     G1 SCONN288_ADR50017P087CC-SCONN2A   I179 @S9S_MB_2U_LIB.S9S_MB_2U(SCH_1):PAGE107
   J26   G2     G2 SCONN288_ADR50017P087CC-SCONN2A   I179 @S9S_MB_2U_LIB.S9S_MB_2U(SCH_1):PAGE107
   J26   G3     G3 SCONN288_ADR50017P087CC-SCONN2A   I179 @S9S_MB_2U_LIB.S9S_MB_2U(SCH_1):PAGE107
   J26    6   VSS0 SCONN288_ADR50017P087CC-SCONN2A   I179 @S9S_MB_2U_LIB.S9S_MB_2U(SCH_1):PAGE107
   J26    8   VSS1 SCONN288_ADR50017P087CC-SCONN2A   I179 @S9S_MB_2U_LIB.S9S_MB_2U(SCH_1):PAGE107
   J26   10   VSS2 SCONN288_ADR50017P087CC-SCONN2A   I179 @S9S_MB_2U_LIB.S9S_MB_2U(SCH_1):PAGE107
   J26   13   VSS3 SCONN288_ADR50017P087CC-SCONN2A   I179 @S9S_MB_2U_LIB.S9S_MB_2U(SCH_1):PAGE107
   J26   15   VSS4 SCONN288_ADR50017P087CC-SCONN2A   I179 @S9S_MB_2U_LIB.S9S_MB_2U(SCH_1):PAGE107
   J26   17   VSS5 SCONN288_ADR50017P087CC-SCONN2A   I179 @S9S_MB_2U_LIB.S9S_MB_2U(SCH_1):PAGE107
   J26   19   VSS6 SCONN288_ADR50017P087CC-SCONN2A   I179 @S9S_MB_2U_LIB.S9S_MB_2U(SCH_1):PAGE107
   J26   21   VSS7 SCONN288_ADR50017P087CC-SCONN2A   I179 @S9S_MB_2U_LIB.S9S_MB_2U(SCH_1):PAGE107
   J26   24   VSS8 SCONN288_ADR50017P087CC-SCONN2A   I179 @S9S_MB_2U_LIB.S9S_MB_2U(SCH_1):PAGE107
   J26   26   VSS9 SCONN288_ADR50017P087CC-SCONN2A   I179 @S9S_MB_2U_LIB.S9S_MB_2U(SCH_1):PAGE107
   J26   28  VSS10 SCONN288_ADR50017P087CC-SCONN2A   I179 @S9S_MB_2U_LIB.S9S_MB_2U(SCH_1):PAGE107
   J26   30  VSS11 SCONN288_ADR50017P087CC-SCONN2A   I179 @S9S_MB_2U_LIB.S9S_MB_2U(SCH_1):PAGE107
   J26   32  VSS12 SCONN288_ADR50017P087CC-SCONN2A   I179 @S9S_MB_2U_LIB.S9S_MB_2U(SCH_1):PAGE107
   J26   35  VSS13 SCONN288_ADR50017P087CC-SCONN2A   I179 @S9S_MB_2U_LIB.S9S_MB_2U(SCH_1):PAGE107
   J26   37  VSS14 SCONN288_ADR50017P087CC-SCONN2A   I179 @S9S_MB_2U_LIB.S9S_MB_2U(SCH_1):PAGE107
   J26   39  VSS15 SCONN288_ADR50017P087CC-SCONN2A   I179 @S9S_MB_2U_LIB.S9S_MB_2U(SCH_1):PAGE107
   J26   41  VSS16 SCONN288_ADR50017P087CC-SCONN2A   I179 @S9S_MB_2U_LIB.S9S_MB_2U(SCH_1):PAGE107
   J26   43  VSS17 SCONN288_ADR50017P087CC-SCONN2A   I179 @S9S_MB_2U_LIB.S9S_MB_2U(SCH_1):PAGE107
   J26   46  VSS18 SCONN288_ADR50017P087CC-SCONN2A   I179 @S9S_MB_2U_LIB.S9S_MB_2U(SCH_1):PAGE107
   J26   48  VSS19 SCONN288_ADR50017P087CC-SCONN2A   I179 @S9S_MB_2U_LIB.S9S_MB_2U(SCH_1):PAGE107
   J26   50  VSS20 SCONN288_ADR50017P087CC-SCONN2A   I179 @S9S_MB_2U_LIB.S9S_MB_2U(SCH_1):PAGE107
   J26   52  VSS21 SCONN288_ADR50017P087CC-SCONN2A   I179 @S9S_MB_2U_LIB.S9S_MB_2U(SCH_1):PAGE107
   J26   54  VSS22 SCONN288_ADR50017P087CC-SCONN2A   I179 @S9S_MB_2U_LIB.S9S_MB_2U(SCH_1):PAGE107
   J26   57  VSS23 SCONN288_ADR50017P087CC-SCONN2A   I179 @S9S_MB_2U_LIB.S9S_MB_2U(SCH_1):PAGE107
   J26   59  VSS24 SCONN288_ADR50017P087CC-SCONN2A   I179 @S9S_MB_2U_LIB.S9S_MB_2U(SCH_1):PAGE107
   J26   61  VSS25 SCONN288_ADR50017P087CC-SCONN2A   I179 @S9S_MB_2U_LIB.S9S_MB_2U(SCH_1):PAGE107
   J26   63  VSS26 SCONN288_ADR50017P087CC-SCONN2A   I179 @S9S_MB_2U_LIB.S9S_MB_2U(SCH_1):PAGE107
   J26   65  VSS27 SCONN288_ADR50017P087CC-SCONN2A   I179 @S9S_MB_2U_LIB.S9S_MB_2U(SCH_1):PAGE107
   J26   67  VSS28 SCONN288_ADR50017P087CC-SCONN2A   I179 @S9S_MB_2U_LIB.S9S_MB_2U(SCH_1):PAGE107
   J26   69  VSS29 SCONN288_ADR50017P087CC-SCONN2A   I179 @S9S_MB_2U_LIB.S9S_MB_2U(SCH_1):PAGE107
   J26   71  VSS30 SCONN288_ADR50017P087CC-SCONN2A   I179 @S9S_MB_2U_LIB.S9S_MB_2U(SCH_1):PAGE107
   J26   73  VSS31 SCONN288_ADR50017P087CC-SCONN2A   I179 @S9S_MB_2U_LIB.S9S_MB_2U(SCH_1):PAGE107
   J26   75  VSS32 SCONN288_ADR50017P087CC-SCONN2A   I179 @S9S_MB_2U_LIB.S9S_MB_2U(SCH_1):PAGE107
   J26   77  VSS33 SCONN288_ADR50017P087CC-SCONN2A   I179 @S9S_MB_2U_LIB.S9S_MB_2U(SCH_1):PAGE107
   J26   79  VSS34 SCONN288_ADR50017P087CC-SCONN2A   I179 @S9S_MB_2U_LIB.S9S_MB_2U(SCH_1):PAGE107
   J26   81  VSS35 SCONN288_ADR50017P087CC-SCONN2A   I179 @S9S_MB_2U_LIB.S9S_MB_2U(SCH_1):PAGE107
   J26   83  VSS36 SCONN288_ADR50017P087CC-SCONN2A   I179 @S9S_MB_2U_LIB.S9S_MB_2U(SCH_1):PAGE107
   J26   85  VSS37 SCONN288_ADR50017P087CC-SCONN2A   I179 @S9S_MB_2U_LIB.S9S_MB_2U(SCH_1):PAGE107
   J26   88  VSS38 SCONN288_ADR50017P087CC-SCONN2A   I179 @S9S_MB_2U_LIB.S9S_MB_2U(SCH_1):PAGE107
   J26   90  VSS39 SCONN288_ADR50017P087CC-SCONN2A   I179 @S9S_MB_2U_LIB.S9S_MB_2U(SCH_1):PAGE107
   J26   92  VSS40 SCONN288_ADR50017P087CC-SCONN2A   I179 @S9S_MB_2U_LIB.S9S_MB_2U(SCH_1):PAGE107
   J26   95  VSS41 SCONN288_ADR50017P087CC-SCONN2A   I179 @S9S_MB_2U_LIB.S9S_MB_2U(SCH_1):PAGE107
   J26   97  VSS42 SCONN288_ADR50017P087CC-SCONN2A   I179 @S9S_MB_2U_LIB.S9S_MB_2U(SCH_1):PAGE107
   J26   99  VSS43 SCONN288_ADR50017P087CC-SCONN2A   I179 @S9S_MB_2U_LIB.S9S_MB_2U(SCH_1):PAGE107
   J26  101  VSS44 SCONN288_ADR50017P087CC-SCONN2A   I179 @S9S_MB_2U_LIB.S9S_MB_2U(SCH_1):PAGE107
   J26  103  VSS45 SCONN288_ADR50017P087CC-SCONN2A   I179 @S9S_MB_2U_LIB.S9S_MB_2U(SCH_1):PAGE107
   J26  106  VSS46 SCONN288_ADR50017P087CC-SCONN2A   I179 @S9S_MB_2U_LIB.S9S_MB_2U(SCH_1):PAGE107
   J26  108  VSS47 SCONN288_ADR50017P087CC-SCONN2A   I179 @S9S_MB_2U_LIB.S9S_MB_2U(SCH_1):PAGE107
   J26  110  VSS48 SCONN288_ADR50017P087CC-SCONN2A   I179 @S9S_MB_2U_LIB.S9S_MB_2U(SCH_1):PAGE107
   J26  112  VSS49 SCONN288_ADR50017P087CC-SCONN2A   I179 @S9S_MB_2U_LIB.S9S_MB_2U(SCH_1):PAGE107
   J26  114  VSS50 SCONN288_ADR50017P087CC-SCONN2A   I179 @S9S_MB_2U_LIB.S9S_MB_2U(SCH_1):PAGE107
   J26  117  VSS51 SCONN288_ADR50017P087CC-SCONN2A   I179 @S9S_MB_2U_LIB.S9S_MB_2U(SCH_1):PAGE107
   J26  119  VSS52 SCONN288_ADR50017P087CC-SCONN2A   I179 @S9S_MB_2U_LIB.S9S_MB_2U(SCH_1):PAGE107
   J26  121  VSS53 SCONN288_ADR50017P087CC-SCONN2A   I179 @S9S_MB_2U_LIB.S9S_MB_2U(SCH_1):PAGE107
   J26  123  VSS54 SCONN288_ADR50017P087CC-SCONN2A   I179 @S9S_MB_2U_LIB.S9S_MB_2U(SCH_1):PAGE107
   J26  125  VSS55 SCONN288_ADR50017P087CC-SCONN2A   I179 @S9S_MB_2U_LIB.S9S_MB_2U(SCH_1):PAGE107
   J26  128  VSS56 SCONN288_ADR50017P087CC-SCONN2A   I179 @S9S_MB_2U_LIB.S9S_MB_2U(SCH_1):PAGE107
   J26  130  VSS57 SCONN288_ADR50017P087CC-SCONN2A   I179 @S9S_MB_2U_LIB.S9S_MB_2U(SCH_1):PAGE107
   J26  132  VSS58 SCONN288_ADR50017P087CC-SCONN2A   I179 @S9S_MB_2U_LIB.S9S_MB_2U(SCH_1):PAGE107
   J26  134  VSS59 SCONN288_ADR50017P087CC-SCONN2A   I179 @S9S_MB_2U_LIB.S9S_MB_2U(SCH_1):PAGE107
   J26  136  VSS60 SCONN288_ADR50017P087CC-SCONN2A   I179 @S9S_MB_2U_LIB.S9S_MB_2U(SCH_1):PAGE107
   J26  139  VSS61 SCONN288_ADR50017P087CC-SCONN2A   I179 @S9S_MB_2U_LIB.S9S_MB_2U(SCH_1):PAGE107
   J26  141  VSS62 SCONN288_ADR50017P087CC-SCONN2A   I179 @S9S_MB_2U_LIB.S9S_MB_2U(SCH_1):PAGE107
   J26  143  VSS63 SCONN288_ADR50017P087CC-SCONN2A   I179 @S9S_MB_2U_LIB.S9S_MB_2U(SCH_1):PAGE107
   J26  151  VSS64 SCONN288_ADR50017P087CC-SCONN2A   I179 @S9S_MB_2U_LIB.S9S_MB_2U(SCH_1):PAGE107
   J26  153  VSS65 SCONN288_ADR50017P087CC-SCONN2A   I179 @S9S_MB_2U_LIB.S9S_MB_2U(SCH_1):PAGE107
   J26  155  VSS66 SCONN288_ADR50017P087CC-SCONN2A   I179 @S9S_MB_2U_LIB.S9S_MB_2U(SCH_1):PAGE107
   J26  158  VSS67 SCONN288_ADR50017P087CC-SCONN2A   I179 @S9S_MB_2U_LIB.S9S_MB_2U(SCH_1):PAGE107
   J26  160  VSS68 SCONN288_ADR50017P087CC-SCONN2A   I179 @S9S_MB_2U_LIB.S9S_MB_2U(SCH_1):PAGE107
   J26  162  VSS69 SCONN288_ADR50017P087CC-SCONN2A   I179 @S9S_MB_2U_LIB.S9S_MB_2U(SCH_1):PAGE107
   J26  164  VSS70 SCONN288_ADR50017P087CC-SCONN2A   I179 @S9S_MB_2U_LIB.S9S_MB_2U(SCH_1):PAGE107
   J26  166  VSS71 SCONN288_ADR50017P087CC-SCONN2A   I179 @S9S_MB_2U_LIB.S9S_MB_2U(SCH_1):PAGE107
   J26  169  VSS72 SCONN288_ADR50017P087CC-SCONN2A   I179 @S9S_MB_2U_LIB.S9S_MB_2U(SCH_1):PAGE107
   J26  171  VSS73 SCONN288_ADR50017P087CC-SCONN2A   I179 @S9S_MB_2U_LIB.S9S_MB_2U(SCH_1):PAGE107
   J26  173  VSS74 SCONN288_ADR50017P087CC-SCONN2A   I179 @S9S_MB_2U_LIB.S9S_MB_2U(SCH_1):PAGE107
   J26  175  VSS75 SCONN288_ADR50017P087CC-SCONN2A   I179 @S9S_MB_2U_LIB.S9S_MB_2U(SCH_1):PAGE107
   J26  177  VSS76 SCONN288_ADR50017P087CC-SCONN2A   I179 @S9S_MB_2U_LIB.S9S_MB_2U(SCH_1):PAGE107
   J26  180  VSS77 SCONN288_ADR50017P087CC-SCONN2A   I179 @S9S_MB_2U_LIB.S9S_MB_2U(SCH_1):PAGE107
   J26  182  VSS78 SCONN288_ADR50017P087CC-SCONN2A   I179 @S9S_MB_2U_LIB.S9S_MB_2U(SCH_1):PAGE107
   J26  184  VSS79 SCONN288_ADR50017P087CC-SCONN2A   I179 @S9S_MB_2U_LIB.S9S_MB_2U(SCH_1):PAGE107
   J26  186  VSS80 SCONN288_ADR50017P087CC-SCONN2A   I179 @S9S_MB_2U_LIB.S9S_MB_2U(SCH_1):PAGE107
   J26  188  VSS81 SCONN288_ADR50017P087CC-SCONN2A   I179 @S9S_MB_2U_LIB.S9S_MB_2U(SCH_1):PAGE107
   J26  191  VSS82 SCONN288_ADR50017P087CC-SCONN2A   I179 @S9S_MB_2U_LIB.S9S_MB_2U(SCH_1):PAGE107
   J26  193  VSS83 SCONN288_ADR50017P087CC-SCONN2A   I179 @S9S_MB_2U_LIB.S9S_MB_2U(SCH_1):PAGE107
   J26  195  VSS84 SCONN288_ADR50017P087CC-SCONN2A   I179 @S9S_MB_2U_LIB.S9S_MB_2U(SCH_1):PAGE107
   J26  197  VSS85 SCONN288_ADR50017P087CC-SCONN2A   I179 @S9S_MB_2U_LIB.S9S_MB_2U(SCH_1):PAGE107
   J26  199  VSS86 SCONN288_ADR50017P087CC-SCONN2A   I179 @S9S_MB_2U_LIB.S9S_MB_2U(SCH_1):PAGE107
   J26  202  VSS87 SCONN288_ADR50017P087CC-SCONN2A   I179 @S9S_MB_2U_LIB.S9S_MB_2U(SCH_1):PAGE107
   J26  204  VSS88 SCONN288_ADR50017P087CC-SCONN2A   I179 @S9S_MB_2U_LIB.S9S_MB_2U(SCH_1):PAGE107
   J26  206  VSS89 SCONN288_ADR50017P087CC-SCONN2A   I179 @S9S_MB_2U_LIB.S9S_MB_2U(SCH_1):PAGE107
   J26  208  VSS90 SCONN288_ADR50017P087CC-SCONN2A   I179 @S9S_MB_2U_LIB.S9S_MB_2U(SCH_1):PAGE107
   J26  210  VSS91 SCONN288_ADR50017P087CC-SCONN2A   I179 @S9S_MB_2U_LIB.S9S_MB_2U(SCH_1):PAGE107
   J26  212  VSS92 SCONN288_ADR50017P087CC-SCONN2A   I179 @S9S_MB_2U_LIB.S9S_MB_2U(SCH_1):PAGE107
   J26  214  VSS93 SCONN288_ADR50017P087CC-SCONN2A   I179 @S9S_MB_2U_LIB.S9S_MB_2U(SCH_1):PAGE107
   J26  216  VSS94 SCONN288_ADR50017P087CC-SCONN2A   I179 @S9S_MB_2U_LIB.S9S_MB_2U(SCH_1):PAGE107
   J26  219  VSS95 SCONN288_ADR50017P087CC-SCONN2A   I179 @S9S_MB_2U_LIB.S9S_MB_2U(SCH_1):PAGE107
   J26  222  VSS96 SCONN288_ADR50017P087CC-SCONN2A   I179 @S9S_MB_2U_LIB.S9S_MB_2U(SCH_1):PAGE107
   J26  224  VSS97 SCONN288_ADR50017P087CC-SCONN2A   I179 @S9S_MB_2U_LIB.S9S_MB_2U(SCH_1):PAGE107
   J26  226  VSS98 SCONN288_ADR50017P087CC-SCONN2A   I179 @S9S_MB_2U_LIB.S9S_MB_2U(SCH_1):PAGE107
   J26  228  VSS99 SCONN288_ADR50017P087CC-SCONN2A   I179 @S9S_MB_2U_LIB.S9S_MB_2U(SCH_1):PAGE107
   J26  230 VSS100 SCONN288_ADR50017P087CC-SCONN2A   I179 @S9S_MB_2U_LIB.S9S_MB_2U(SCH_1):PAGE107
   J26  233 VSS101 SCONN288_ADR50017P087CC-SCONN2A   I179 @S9S_MB_2U_LIB.S9S_MB_2U(SCH_1):PAGE107
   J26  235 VSS102 SCONN288_ADR50017P087CC-SCONN2A   I179 @S9S_MB_2U_LIB.S9S_MB_2U(SCH_1):PAGE107
   J26  237 VSS103 SCONN288_ADR50017P087CC-SCONN2A   I179 @S9S_MB_2U_LIB.S9S_MB_2U(SCH_1):PAGE107
   J26  240 VSS104 SCONN288_ADR50017P087CC-SCONN2A   I179 @S9S_MB_2U_LIB.S9S_MB_2U(SCH_1):PAGE107
   J26  242 VSS105 SCONN288_ADR50017P087CC-SCONN2A   I179 @S9S_MB_2U_LIB.S9S_MB_2U(SCH_1):PAGE107
   J26  244 VSS106 SCONN288_ADR50017P087CC-SCONN2A   I179 @S9S_MB_2U_LIB.S9S_MB_2U(SCH_1):PAGE107
   J26  246 VSS107 SCONN288_ADR50017P087CC-SCONN2A   I179 @S9S_MB_2U_LIB.S9S_MB_2U(SCH_1):PAGE107
   J26  248 VSS108 SCONN288_ADR50017P087CC-SCONN2A   I179 @S9S_MB_2U_LIB.S9S_MB_2U(SCH_1):PAGE107
   J26  251 VSS109 SCONN288_ADR50017P087CC-SCONN2A   I179 @S9S_MB_2U_LIB.S9S_MB_2U(SCH_1):PAGE107
   J26  253 VSS110 SCONN288_ADR50017P087CC-SCONN2A   I179 @S9S_MB_2U_LIB.S9S_MB_2U(SCH_1):PAGE107
   J26  255 VSS111 SCONN288_ADR50017P087CC-SCONN2A   I179 @S9S_MB_2U_LIB.S9S_MB_2U(SCH_1):PAGE107
   J26  257 VSS112 SCONN288_ADR50017P087CC-SCONN2A   I179 @S9S_MB_2U_LIB.S9S_MB_2U(SCH_1):PAGE107
   J26  259 VSS113 SCONN288_ADR50017P087CC-SCONN2A   I179 @S9S_MB_2U_LIB.S9S_MB_2U(SCH_1):PAGE107
   J26  262 VSS114 SCONN288_ADR50017P087CC-SCONN2A   I179 @S9S_MB_2U_LIB.S9S_MB_2U(SCH_1):PAGE107
   J26  264 VSS115 SCONN288_ADR50017P087CC-SCONN2A   I179 @S9S_MB_2U_LIB.S9S_MB_2U(SCH_1):PAGE107
   J26  266 VSS116 SCONN288_ADR50017P087CC-SCONN2A   I179 @S9S_MB_2U_LIB.S9S_MB_2U(SCH_1):PAGE107
   J26  268 VSS117 SCONN288_ADR50017P087CC-SCONN2A   I179 @S9S_MB_2U_LIB.S9S_MB_2U(SCH_1):PAGE107
   J26  270 VSS118 SCONN288_ADR50017P087CC-SCONN2A   I179 @S9S_MB_2U_LIB.S9S_MB_2U(SCH_1):PAGE107
   J26  273 VSS119 SCONN288_ADR50017P087CC-SCONN2A   I179 @S9S_MB_2U_LIB.S9S_MB_2U(SCH_1):PAGE107
   J26  275 VSS120 SCONN288_ADR50017P087CC-SCONN2A   I179 @S9S_MB_2U_LIB.S9S_MB_2U(SCH_1):PAGE107
   J26  277 VSS121 SCONN288_ADR50017P087CC-SCONN2A   I179 @S9S_MB_2U_LIB.S9S_MB_2U(SCH_1):PAGE107
   J26  279 VSS122 SCONN288_ADR50017P087CC-SCONN2A   I179 @S9S_MB_2U_LIB.S9S_MB_2U(SCH_1):PAGE107
   J26  281 VSS123 SCONN288_ADR50017P087CC-SCONN2A   I179 @S9S_MB_2U_LIB.S9S_MB_2U(SCH_1):PAGE107
   J26  284 VSS124 SCONN288_ADR50017P087CC-SCONN2A   I179 @S9S_MB_2U_LIB.S9S_MB_2U(SCH_1):PAGE107
   J26  286 VSS125 SCONN288_ADR50017P087CC-SCONN2A   I179 @S9S_MB_2U_LIB.S9S_MB_2U(SCH_1):PAGE107
   J26  288 VSS126 SCONN288_ADR50017P087CC-SCONN2A   I179 @S9S_MB_2U_LIB.S9S_MB_2U(SCH_1):PAGE107
   R77    2      B Q_RES_0402LF-23.2K,1%,1/16W,CHA    I10 @S9S_MB_2U_LIB.S9S_MB_2U(SCH_1):PAGE108
   C87    2      B Q_CAP_C0402-2.2UF,6.3V,20%,X6SA   I121 @S9S_MB_2U_LIB.S9S_MB_2U(SCH_1):PAGE108
   C88    2      B Q_CAP_C0805-10UF,16V,10%,X6S,CA   I123 @S9S_MB_2U_LIB.S9S_MB_2U(SCH_1):PAGE108
   C89    2      B Q_CAP_C0805-10UF,16V,10%,X6S,CA   I160 @S9S_MB_2U_LIB.S9S_MB_2U(SCH_1):PAGE108
   J27   G1     G1 SCONN288_ADR50017P130CC-SCONN2A   I178 @S9S_MB_2U_LIB.S9S_MB_2U(SCH_1):PAGE108
   J27   G2     G2 SCONN288_ADR50017P130CC-SCONN2A   I178 @S9S_MB_2U_LIB.S9S_MB_2U(SCH_1):PAGE108
   J27   G3     G3 SCONN288_ADR50017P130CC-SCONN2A   I178 @S9S_MB_2U_LIB.S9S_MB_2U(SCH_1):PAGE108
   J27    6   VSS0 SCONN288_ADR50017P130CC-SCONN2A   I178 @S9S_MB_2U_LIB.S9S_MB_2U(SCH_1):PAGE108
   J27    8   VSS1 SCONN288_ADR50017P130CC-SCONN2A   I178 @S9S_MB_2U_LIB.S9S_MB_2U(SCH_1):PAGE108
   J27   10   VSS2 SCONN288_ADR50017P130CC-SCONN2A   I178 @S9S_MB_2U_LIB.S9S_MB_2U(SCH_1):PAGE108
   J27   13   VSS3 SCONN288_ADR50017P130CC-SCONN2A   I178 @S9S_MB_2U_LIB.S9S_MB_2U(SCH_1):PAGE108
   J27   15   VSS4 SCONN288_ADR50017P130CC-SCONN2A   I178 @S9S_MB_2U_LIB.S9S_MB_2U(SCH_1):PAGE108
   J27   17   VSS5 SCONN288_ADR50017P130CC-SCONN2A   I178 @S9S_MB_2U_LIB.S9S_MB_2U(SCH_1):PAGE108
   J27   19   VSS6 SCONN288_ADR50017P130CC-SCONN2A   I178 @S9S_MB_2U_LIB.S9S_MB_2U(SCH_1):PAGE108
   J27   21   VSS7 SCONN288_ADR50017P130CC-SCONN2A   I178 @S9S_MB_2U_LIB.S9S_MB_2U(SCH_1):PAGE108
   J27   24   VSS8 SCONN288_ADR50017P130CC-SCONN2A   I178 @S9S_MB_2U_LIB.S9S_MB_2U(SCH_1):PAGE108
   J27   26   VSS9 SCONN288_ADR50017P130CC-SCONN2A   I178 @S9S_MB_2U_LIB.S9S_MB_2U(SCH_1):PAGE108
   J27   28  VSS10 SCONN288_ADR50017P130CC-SCONN2A   I178 @S9S_MB_2U_LIB.S9S_MB_2U(SCH_1):PAGE108
   J27   30  VSS11 SCONN288_ADR50017P130CC-SCONN2A   I178 @S9S_MB_2U_LIB.S9S_MB_2U(SCH_1):PAGE108
   J27   32  VSS12 SCONN288_ADR50017P130CC-SCONN2A   I178 @S9S_MB_2U_LIB.S9S_MB_2U(SCH_1):PAGE108
   J27   35  VSS13 SCONN288_ADR50017P130CC-SCONN2A   I178 @S9S_MB_2U_LIB.S9S_MB_2U(SCH_1):PAGE108
   J27   37  VSS14 SCONN288_ADR50017P130CC-SCONN2A   I178 @S9S_MB_2U_LIB.S9S_MB_2U(SCH_1):PAGE108
   J27   39  VSS15 SCONN288_ADR50017P130CC-SCONN2A   I178 @S9S_MB_2U_LIB.S9S_MB_2U(SCH_1):PAGE108
   J27   41  VSS16 SCONN288_ADR50017P130CC-SCONN2A   I178 @S9S_MB_2U_LIB.S9S_MB_2U(SCH_1):PAGE108
   J27   43  VSS17 SCONN288_ADR50017P130CC-SCONN2A   I178 @S9S_MB_2U_LIB.S9S_MB_2U(SCH_1):PAGE108
   J27   46  VSS18 SCONN288_ADR50017P130CC-SCONN2A   I178 @S9S_MB_2U_LIB.S9S_MB_2U(SCH_1):PAGE108
   J27   48  VSS19 SCONN288_ADR50017P130CC-SCONN2A   I178 @S9S_MB_2U_LIB.S9S_MB_2U(SCH_1):PAGE108
   J27   50  VSS20 SCONN288_ADR50017P130CC-SCONN2A   I178 @S9S_MB_2U_LIB.S9S_MB_2U(SCH_1):PAGE108
   J27   52  VSS21 SCONN288_ADR50017P130CC-SCONN2A   I178 @S9S_MB_2U_LIB.S9S_MB_2U(SCH_1):PAGE108
   J27   54  VSS22 SCONN288_ADR50017P130CC-SCONN2A   I178 @S9S_MB_2U_LIB.S9S_MB_2U(SCH_1):PAGE108
   J27   57  VSS23 SCONN288_ADR50017P130CC-SCONN2A   I178 @S9S_MB_2U_LIB.S9S_MB_2U(SCH_1):PAGE108
   J27   59  VSS24 SCONN288_ADR50017P130CC-SCONN2A   I178 @S9S_MB_2U_LIB.S9S_MB_2U(SCH_1):PAGE108
   J27   61  VSS25 SCONN288_ADR50017P130CC-SCONN2A   I178 @S9S_MB_2U_LIB.S9S_MB_2U(SCH_1):PAGE108
   J27   63  VSS26 SCONN288_ADR50017P130CC-SCONN2A   I178 @S9S_MB_2U_LIB.S9S_MB_2U(SCH_1):PAGE108
   J27   65  VSS27 SCONN288_ADR50017P130CC-SCONN2A   I178 @S9S_MB_2U_LIB.S9S_MB_2U(SCH_1):PAGE108
   J27   67  VSS28 SCONN288_ADR50017P130CC-SCONN2A   I178 @S9S_MB_2U_LIB.S9S_MB_2U(SCH_1):PAGE108
   J27   69  VSS29 SCONN288_ADR50017P130CC-SCONN2A   I178 @S9S_MB_2U_LIB.S9S_MB_2U(SCH_1):PAGE108
   J27   71  VSS30 SCONN288_ADR50017P130CC-SCONN2A   I178 @S9S_MB_2U_LIB.S9S_MB_2U(SCH_1):PAGE108
   J27   73  VSS31 SCONN288_ADR50017P130CC-SCONN2A   I178 @S9S_MB_2U_LIB.S9S_MB_2U(SCH_1):PAGE108
   J27   75  VSS32 SCONN288_ADR50017P130CC-SCONN2A   I178 @S9S_MB_2U_LIB.S9S_MB_2U(SCH_1):PAGE108
   J27   77  VSS33 SCONN288_ADR50017P130CC-SCONN2A   I178 @S9S_MB_2U_LIB.S9S_MB_2U(SCH_1):PAGE108
   J27   79  VSS34 SCONN288_ADR50017P130CC-SCONN2A   I178 @S9S_MB_2U_LIB.S9S_MB_2U(SCH_1):PAGE108
   J27   81  VSS35 SCONN288_ADR50017P130CC-SCONN2A   I178 @S9S_MB_2U_LIB.S9S_MB_2U(SCH_1):PAGE108
   J27   83  VSS36 SCONN288_ADR50017P130CC-SCONN2A   I178 @S9S_MB_2U_LIB.S9S_MB_2U(SCH_1):PAGE108
   J27   85  VSS37 SCONN288_ADR50017P130CC-SCONN2A   I178 @S9S_MB_2U_LIB.S9S_MB_2U(SCH_1):PAGE108
   J27   88  VSS38 SCONN288_ADR50017P130CC-SCONN2A   I178 @S9S_MB_2U_LIB.S9S_MB_2U(SCH_1):PAGE108
   J27   90  VSS39 SCONN288_ADR50017P130CC-SCONN2A   I178 @S9S_MB_2U_LIB.S9S_MB_2U(SCH_1):PAGE108
   J27   92  VSS40 SCONN288_ADR50017P130CC-SCONN2A   I178 @S9S_MB_2U_LIB.S9S_MB_2U(SCH_1):PAGE108
   J27   95  VSS41 SCONN288_ADR50017P130CC-SCONN2A   I178 @S9S_MB_2U_LIB.S9S_MB_2U(SCH_1):PAGE108
   J27   97  VSS42 SCONN288_ADR50017P130CC-SCONN2A   I178 @S9S_MB_2U_LIB.S9S_MB_2U(SCH_1):PAGE108
   J27   99  VSS43 SCONN288_ADR50017P130CC-SCONN2A   I178 @S9S_MB_2U_LIB.S9S_MB_2U(SCH_1):PAGE108
   J27  101  VSS44 SCONN288_ADR50017P130CC-SCONN2A   I178 @S9S_MB_2U_LIB.S9S_MB_2U(SCH_1):PAGE108
   J27  103  VSS45 SCONN288_ADR50017P130CC-SCONN2A   I178 @S9S_MB_2U_LIB.S9S_MB_2U(SCH_1):PAGE108
   J27  106  VSS46 SCONN288_ADR50017P130CC-SCONN2A   I178 @S9S_MB_2U_LIB.S9S_MB_2U(SCH_1):PAGE108
   J27  108  VSS47 SCONN288_ADR50017P130CC-SCONN2A   I178 @S9S_MB_2U_LIB.S9S_MB_2U(SCH_1):PAGE108
   J27  110  VSS48 SCONN288_ADR50017P130CC-SCONN2A   I178 @S9S_MB_2U_LIB.S9S_MB_2U(SCH_1):PAGE108
   J27  112  VSS49 SCONN288_ADR50017P130CC-SCONN2A   I178 @S9S_MB_2U_LIB.S9S_MB_2U(SCH_1):PAGE108
   J27  114  VSS50 SCONN288_ADR50017P130CC-SCONN2A   I178 @S9S_MB_2U_LIB.S9S_MB_2U(SCH_1):PAGE108
   J27  117  VSS51 SCONN288_ADR50017P130CC-SCONN2A   I178 @S9S_MB_2U_LIB.S9S_MB_2U(SCH_1):PAGE108
   J27  119  VSS52 SCONN288_ADR50017P130CC-SCONN2A   I178 @S9S_MB_2U_LIB.S9S_MB_2U(SCH_1):PAGE108
   J27  121  VSS53 SCONN288_ADR50017P130CC-SCONN2A   I178 @S9S_MB_2U_LIB.S9S_MB_2U(SCH_1):PAGE108
   J27  123  VSS54 SCONN288_ADR50017P130CC-SCONN2A   I178 @S9S_MB_2U_LIB.S9S_MB_2U(SCH_1):PAGE108
   J27  125  VSS55 SCONN288_ADR50017P130CC-SCONN2A   I178 @S9S_MB_2U_LIB.S9S_MB_2U(SCH_1):PAGE108
   J27  128  VSS56 SCONN288_ADR50017P130CC-SCONN2A   I178 @S9S_MB_2U_LIB.S9S_MB_2U(SCH_1):PAGE108
   J27  130  VSS57 SCONN288_ADR50017P130CC-SCONN2A   I178 @S9S_MB_2U_LIB.S9S_MB_2U(SCH_1):PAGE108
   J27  132  VSS58 SCONN288_ADR50017P130CC-SCONN2A   I178 @S9S_MB_2U_LIB.S9S_MB_2U(SCH_1):PAGE108
   J27  134  VSS59 SCONN288_ADR50017P130CC-SCONN2A   I178 @S9S_MB_2U_LIB.S9S_MB_2U(SCH_1):PAGE108
   J27  136  VSS60 SCONN288_ADR50017P130CC-SCONN2A   I178 @S9S_MB_2U_LIB.S9S_MB_2U(SCH_1):PAGE108
   J27  139  VSS61 SCONN288_ADR50017P130CC-SCONN2A   I178 @S9S_MB_2U_LIB.S9S_MB_2U(SCH_1):PAGE108
   J27  141  VSS62 SCONN288_ADR50017P130CC-SCONN2A   I178 @S9S_MB_2U_LIB.S9S_MB_2U(SCH_1):PAGE108
   J27  143  VSS63 SCONN288_ADR50017P130CC-SCONN2A   I178 @S9S_MB_2U_LIB.S9S_MB_2U(SCH_1):PAGE108
   J27  151  VSS64 SCONN288_ADR50017P130CC-SCONN2A   I178 @S9S_MB_2U_LIB.S9S_MB_2U(SCH_1):PAGE108
   J27  153  VSS65 SCONN288_ADR50017P130CC-SCONN2A   I178 @S9S_MB_2U_LIB.S9S_MB_2U(SCH_1):PAGE108
   J27  155  VSS66 SCONN288_ADR50017P130CC-SCONN2A   I178 @S9S_MB_2U_LIB.S9S_MB_2U(SCH_1):PAGE108
   J27  158  VSS67 SCONN288_ADR50017P130CC-SCONN2A   I178 @S9S_MB_2U_LIB.S9S_MB_2U(SCH_1):PAGE108
   J27  160  VSS68 SCONN288_ADR50017P130CC-SCONN2A   I178 @S9S_MB_2U_LIB.S9S_MB_2U(SCH_1):PAGE108
   J27  162  VSS69 SCONN288_ADR50017P130CC-SCONN2A   I178 @S9S_MB_2U_LIB.S9S_MB_2U(SCH_1):PAGE108
   J27  164  VSS70 SCONN288_ADR50017P130CC-SCONN2A   I178 @S9S_MB_2U_LIB.S9S_MB_2U(SCH_1):PAGE108
   J27  166  VSS71 SCONN288_ADR50017P130CC-SCONN2A   I178 @S9S_MB_2U_LIB.S9S_MB_2U(SCH_1):PAGE108
   J27  169  VSS72 SCONN288_ADR50017P130CC-SCONN2A   I178 @S9S_MB_2U_LIB.S9S_MB_2U(SCH_1):PAGE108
   J27  171  VSS73 SCONN288_ADR50017P130CC-SCONN2A   I178 @S9S_MB_2U_LIB.S9S_MB_2U(SCH_1):PAGE108
   J27  173  VSS74 SCONN288_ADR50017P130CC-SCONN2A   I178 @S9S_MB_2U_LIB.S9S_MB_2U(SCH_1):PAGE108
   J27  175  VSS75 SCONN288_ADR50017P130CC-SCONN2A   I178 @S9S_MB_2U_LIB.S9S_MB_2U(SCH_1):PAGE108
   J27  177  VSS76 SCONN288_ADR50017P130CC-SCONN2A   I178 @S9S_MB_2U_LIB.S9S_MB_2U(SCH_1):PAGE108
   J27  180  VSS77 SCONN288_ADR50017P130CC-SCONN2A   I178 @S9S_MB_2U_LIB.S9S_MB_2U(SCH_1):PAGE108
   J27  182  VSS78 SCONN288_ADR50017P130CC-SCONN2A   I178 @S9S_MB_2U_LIB.S9S_MB_2U(SCH_1):PAGE108
   J27  184  VSS79 SCONN288_ADR50017P130CC-SCONN2A   I178 @S9S_MB_2U_LIB.S9S_MB_2U(SCH_1):PAGE108
   J27  186  VSS80 SCONN288_ADR50017P130CC-SCONN2A   I178 @S9S_MB_2U_LIB.S9S_MB_2U(SCH_1):PAGE108
   J27  188  VSS81 SCONN288_ADR50017P130CC-SCONN2A   I178 @S9S_MB_2U_LIB.S9S_MB_2U(SCH_1):PAGE108
   J27  191  VSS82 SCONN288_ADR50017P130CC-SCONN2A   I178 @S9S_MB_2U_LIB.S9S_MB_2U(SCH_1):PAGE108
   J27  193  VSS83 SCONN288_ADR50017P130CC-SCONN2A   I178 @S9S_MB_2U_LIB.S9S_MB_2U(SCH_1):PAGE108
   J27  195  VSS84 SCONN288_ADR50017P130CC-SCONN2A   I178 @S9S_MB_2U_LIB.S9S_MB_2U(SCH_1):PAGE108
   J27  197  VSS85 SCONN288_ADR50017P130CC-SCONN2A   I178 @S9S_MB_2U_LIB.S9S_MB_2U(SCH_1):PAGE108
   J27  199  VSS86 SCONN288_ADR50017P130CC-SCONN2A   I178 @S9S_MB_2U_LIB.S9S_MB_2U(SCH_1):PAGE108
   J27  202  VSS87 SCONN288_ADR50017P130CC-SCONN2A   I178 @S9S_MB_2U_LIB.S9S_MB_2U(SCH_1):PAGE108
   J27  204  VSS88 SCONN288_ADR50017P130CC-SCONN2A   I178 @S9S_MB_2U_LIB.S9S_MB_2U(SCH_1):PAGE108
   J27  206  VSS89 SCONN288_ADR50017P130CC-SCONN2A   I178 @S9S_MB_2U_LIB.S9S_MB_2U(SCH_1):PAGE108
   J27  208  VSS90 SCONN288_ADR50017P130CC-SCONN2A   I178 @S9S_MB_2U_LIB.S9S_MB_2U(SCH_1):PAGE108
   J27  210  VSS91 SCONN288_ADR50017P130CC-SCONN2A   I178 @S9S_MB_2U_LIB.S9S_MB_2U(SCH_1):PAGE108
   J27  212  VSS92 SCONN288_ADR50017P130CC-SCONN2A   I178 @S9S_MB_2U_LIB.S9S_MB_2U(SCH_1):PAGE108
   J27  214  VSS93 SCONN288_ADR50017P130CC-SCONN2A   I178 @S9S_MB_2U_LIB.S9S_MB_2U(SCH_1):PAGE108
   J27  216  VSS94 SCONN288_ADR50017P130CC-SCONN2A   I178 @S9S_MB_2U_LIB.S9S_MB_2U(SCH_1):PAGE108
   J27  219  VSS95 SCONN288_ADR50017P130CC-SCONN2A   I178 @S9S_MB_2U_LIB.S9S_MB_2U(SCH_1):PAGE108
   J27  222  VSS96 SCONN288_ADR50017P130CC-SCONN2A   I178 @S9S_MB_2U_LIB.S9S_MB_2U(SCH_1):PAGE108
   J27  224  VSS97 SCONN288_ADR50017P130CC-SCONN2A   I178 @S9S_MB_2U_LIB.S9S_MB_2U(SCH_1):PAGE108
   J27  226  VSS98 SCONN288_ADR50017P130CC-SCONN2A   I178 @S9S_MB_2U_LIB.S9S_MB_2U(SCH_1):PAGE108
   J27  228  VSS99 SCONN288_ADR50017P130CC-SCONN2A   I178 @S9S_MB_2U_LIB.S9S_MB_2U(SCH_1):PAGE108
   J27  230 VSS100 SCONN288_ADR50017P130CC-SCONN2A   I178 @S9S_MB_2U_LIB.S9S_MB_2U(SCH_1):PAGE108
   J27  233 VSS101 SCONN288_ADR50017P130CC-SCONN2A   I178 @S9S_MB_2U_LIB.S9S_MB_2U(SCH_1):PAGE108
   J27  235 VSS102 SCONN288_ADR50017P130CC-SCONN2A   I178 @S9S_MB_2U_LIB.S9S_MB_2U(SCH_1):PAGE108
   J27  237 VSS103 SCONN288_ADR50017P130CC-SCONN2A   I178 @S9S_MB_2U_LIB.S9S_MB_2U(SCH_1):PAGE108
   J27  240 VSS104 SCONN288_ADR50017P130CC-SCONN2A   I178 @S9S_MB_2U_LIB.S9S_MB_2U(SCH_1):PAGE108
   J27  242 VSS105 SCONN288_ADR50017P130CC-SCONN2A   I178 @S9S_MB_2U_LIB.S9S_MB_2U(SCH_1):PAGE108
   J27  244 VSS106 SCONN288_ADR50017P130CC-SCONN2A   I178 @S9S_MB_2U_LIB.S9S_MB_2U(SCH_1):PAGE108
   J27  246 VSS107 SCONN288_ADR50017P130CC-SCONN2A   I178 @S9S_MB_2U_LIB.S9S_MB_2U(SCH_1):PAGE108
   J27  248 VSS108 SCONN288_ADR50017P130CC-SCONN2A   I178 @S9S_MB_2U_LIB.S9S_MB_2U(SCH_1):PAGE108
   J27  251 VSS109 SCONN288_ADR50017P130CC-SCONN2A   I178 @S9S_MB_2U_LIB.S9S_MB_2U(SCH_1):PAGE108
   J27  253 VSS110 SCONN288_ADR50017P130CC-SCONN2A   I178 @S9S_MB_2U_LIB.S9S_MB_2U(SCH_1):PAGE108
   J27  255 VSS111 SCONN288_ADR50017P130CC-SCONN2A   I178 @S9S_MB_2U_LIB.S9S_MB_2U(SCH_1):PAGE108
   J27  257 VSS112 SCONN288_ADR50017P130CC-SCONN2A   I178 @S9S_MB_2U_LIB.S9S_MB_2U(SCH_1):PAGE108
   J27  259 VSS113 SCONN288_ADR50017P130CC-SCONN2A   I178 @S9S_MB_2U_LIB.S9S_MB_2U(SCH_1):PAGE108
   J27  262 VSS114 SCONN288_ADR50017P130CC-SCONN2A   I178 @S9S_MB_2U_LIB.S9S_MB_2U(SCH_1):PAGE108
   J27  264 VSS115 SCONN288_ADR50017P130CC-SCONN2A   I178 @S9S_MB_2U_LIB.S9S_MB_2U(SCH_1):PAGE108
   J27  266 VSS116 SCONN288_ADR50017P130CC-SCONN2A   I178 @S9S_MB_2U_LIB.S9S_MB_2U(SCH_1):PAGE108
   J27  268 VSS117 SCONN288_ADR50017P130CC-SCONN2A   I178 @S9S_MB_2U_LIB.S9S_MB_2U(SCH_1):PAGE108
   J27  270 VSS118 SCONN288_ADR50017P130CC-SCONN2A   I178 @S9S_MB_2U_LIB.S9S_MB_2U(SCH_1):PAGE108
   J27  273 VSS119 SCONN288_ADR50017P130CC-SCONN2A   I178 @S9S_MB_2U_LIB.S9S_MB_2U(SCH_1):PAGE108
   J27  275 VSS120 SCONN288_ADR50017P130CC-SCONN2A   I178 @S9S_MB_2U_LIB.S9S_MB_2U(SCH_1):PAGE108
   J27  277 VSS121 SCONN288_ADR50017P130CC-SCONN2A   I178 @S9S_MB_2U_LIB.S9S_MB_2U(SCH_1):PAGE108
   J27  279 VSS122 SCONN288_ADR50017P130CC-SCONN2A   I178 @S9S_MB_2U_LIB.S9S_MB_2U(SCH_1):PAGE108
   J27  281 VSS123 SCONN288_ADR50017P130CC-SCONN2A   I178 @S9S_MB_2U_LIB.S9S_MB_2U(SCH_1):PAGE108
   J27  284 VSS124 SCONN288_ADR50017P130CC-SCONN2A   I178 @S9S_MB_2U_LIB.S9S_MB_2U(SCH_1):PAGE108
   J27  286 VSS125 SCONN288_ADR50017P130CC-SCONN2A   I178 @S9S_MB_2U_LIB.S9S_MB_2U(SCH_1):PAGE108
   J27  288 VSS126 SCONN288_ADR50017P130CC-SCONN2A   I178 @S9S_MB_2U_LIB.S9S_MB_2U(SCH_1):PAGE108
   R76    2      B Q_RES_0402LF-35.7K,1%,1/16W,CHA    I46 @S9S_MB_2U_LIB.S9S_MB_2U(SCH_1):PAGE109
   C84    2      B Q_CAP_C0402-2.2UF,6.3V,20%,X6SA   I121 @S9S_MB_2U_LIB.S9S_MB_2U(SCH_1):PAGE109
   C85    2      B Q_CAP_C0805-10UF,16V,10%,X6S,CA   I125 @S9S_MB_2U_LIB.S9S_MB_2U(SCH_1):PAGE109
   C86    2      B Q_CAP_C0805-10UF,16V,10%,X6S,CA   I128 @S9S_MB_2U_LIB.S9S_MB_2U(SCH_1):PAGE109
   J28   G1     G1 SCONN288_ADR50017P087CC-SCONN2A   I176 @S9S_MB_2U_LIB.S9S_MB_2U(SCH_1):PAGE109
   J28   G2     G2 SCONN288_ADR50017P087CC-SCONN2A   I176 @S9S_MB_2U_LIB.S9S_MB_2U(SCH_1):PAGE109
   J28   G3     G3 SCONN288_ADR50017P087CC-SCONN2A   I176 @S9S_MB_2U_LIB.S9S_MB_2U(SCH_1):PAGE109
   J28    6   VSS0 SCONN288_ADR50017P087CC-SCONN2A   I176 @S9S_MB_2U_LIB.S9S_MB_2U(SCH_1):PAGE109
   J28    8   VSS1 SCONN288_ADR50017P087CC-SCONN2A   I176 @S9S_MB_2U_LIB.S9S_MB_2U(SCH_1):PAGE109
   J28   10   VSS2 SCONN288_ADR50017P087CC-SCONN2A   I176 @S9S_MB_2U_LIB.S9S_MB_2U(SCH_1):PAGE109
   J28   13   VSS3 SCONN288_ADR50017P087CC-SCONN2A   I176 @S9S_MB_2U_LIB.S9S_MB_2U(SCH_1):PAGE109
   J28   15   VSS4 SCONN288_ADR50017P087CC-SCONN2A   I176 @S9S_MB_2U_LIB.S9S_MB_2U(SCH_1):PAGE109
   J28   17   VSS5 SCONN288_ADR50017P087CC-SCONN2A   I176 @S9S_MB_2U_LIB.S9S_MB_2U(SCH_1):PAGE109
   J28   19   VSS6 SCONN288_ADR50017P087CC-SCONN2A   I176 @S9S_MB_2U_LIB.S9S_MB_2U(SCH_1):PAGE109
   J28   21   VSS7 SCONN288_ADR50017P087CC-SCONN2A   I176 @S9S_MB_2U_LIB.S9S_MB_2U(SCH_1):PAGE109
   J28   24   VSS8 SCONN288_ADR50017P087CC-SCONN2A   I176 @S9S_MB_2U_LIB.S9S_MB_2U(SCH_1):PAGE109
   J28   26   VSS9 SCONN288_ADR50017P087CC-SCONN2A   I176 @S9S_MB_2U_LIB.S9S_MB_2U(SCH_1):PAGE109
   J28   28  VSS10 SCONN288_ADR50017P087CC-SCONN2A   I176 @S9S_MB_2U_LIB.S9S_MB_2U(SCH_1):PAGE109
   J28   30  VSS11 SCONN288_ADR50017P087CC-SCONN2A   I176 @S9S_MB_2U_LIB.S9S_MB_2U(SCH_1):PAGE109
   J28   32  VSS12 SCONN288_ADR50017P087CC-SCONN2A   I176 @S9S_MB_2U_LIB.S9S_MB_2U(SCH_1):PAGE109
   J28   35  VSS13 SCONN288_ADR50017P087CC-SCONN2A   I176 @S9S_MB_2U_LIB.S9S_MB_2U(SCH_1):PAGE109
   J28   37  VSS14 SCONN288_ADR50017P087CC-SCONN2A   I176 @S9S_MB_2U_LIB.S9S_MB_2U(SCH_1):PAGE109
   J28   39  VSS15 SCONN288_ADR50017P087CC-SCONN2A   I176 @S9S_MB_2U_LIB.S9S_MB_2U(SCH_1):PAGE109
   J28   41  VSS16 SCONN288_ADR50017P087CC-SCONN2A   I176 @S9S_MB_2U_LIB.S9S_MB_2U(SCH_1):PAGE109
   J28   43  VSS17 SCONN288_ADR50017P087CC-SCONN2A   I176 @S9S_MB_2U_LIB.S9S_MB_2U(SCH_1):PAGE109
   J28   46  VSS18 SCONN288_ADR50017P087CC-SCONN2A   I176 @S9S_MB_2U_LIB.S9S_MB_2U(SCH_1):PAGE109
   J28   48  VSS19 SCONN288_ADR50017P087CC-SCONN2A   I176 @S9S_MB_2U_LIB.S9S_MB_2U(SCH_1):PAGE109
   J28   50  VSS20 SCONN288_ADR50017P087CC-SCONN2A   I176 @S9S_MB_2U_LIB.S9S_MB_2U(SCH_1):PAGE109
   J28   52  VSS21 SCONN288_ADR50017P087CC-SCONN2A   I176 @S9S_MB_2U_LIB.S9S_MB_2U(SCH_1):PAGE109
   J28   54  VSS22 SCONN288_ADR50017P087CC-SCONN2A   I176 @S9S_MB_2U_LIB.S9S_MB_2U(SCH_1):PAGE109
   J28   57  VSS23 SCONN288_ADR50017P087CC-SCONN2A   I176 @S9S_MB_2U_LIB.S9S_MB_2U(SCH_1):PAGE109
   J28   59  VSS24 SCONN288_ADR50017P087CC-SCONN2A   I176 @S9S_MB_2U_LIB.S9S_MB_2U(SCH_1):PAGE109
   J28   61  VSS25 SCONN288_ADR50017P087CC-SCONN2A   I176 @S9S_MB_2U_LIB.S9S_MB_2U(SCH_1):PAGE109
   J28   63  VSS26 SCONN288_ADR50017P087CC-SCONN2A   I176 @S9S_MB_2U_LIB.S9S_MB_2U(SCH_1):PAGE109
   J28   65  VSS27 SCONN288_ADR50017P087CC-SCONN2A   I176 @S9S_MB_2U_LIB.S9S_MB_2U(SCH_1):PAGE109
   J28   67  VSS28 SCONN288_ADR50017P087CC-SCONN2A   I176 @S9S_MB_2U_LIB.S9S_MB_2U(SCH_1):PAGE109
   J28   69  VSS29 SCONN288_ADR50017P087CC-SCONN2A   I176 @S9S_MB_2U_LIB.S9S_MB_2U(SCH_1):PAGE109
   J28   71  VSS30 SCONN288_ADR50017P087CC-SCONN2A   I176 @S9S_MB_2U_LIB.S9S_MB_2U(SCH_1):PAGE109
   J28   73  VSS31 SCONN288_ADR50017P087CC-SCONN2A   I176 @S9S_MB_2U_LIB.S9S_MB_2U(SCH_1):PAGE109
   J28   75  VSS32 SCONN288_ADR50017P087CC-SCONN2A   I176 @S9S_MB_2U_LIB.S9S_MB_2U(SCH_1):PAGE109
   J28   77  VSS33 SCONN288_ADR50017P087CC-SCONN2A   I176 @S9S_MB_2U_LIB.S9S_MB_2U(SCH_1):PAGE109
   J28   79  VSS34 SCONN288_ADR50017P087CC-SCONN2A   I176 @S9S_MB_2U_LIB.S9S_MB_2U(SCH_1):PAGE109
   J28   81  VSS35 SCONN288_ADR50017P087CC-SCONN2A   I176 @S9S_MB_2U_LIB.S9S_MB_2U(SCH_1):PAGE109
   J28   83  VSS36 SCONN288_ADR50017P087CC-SCONN2A   I176 @S9S_MB_2U_LIB.S9S_MB_2U(SCH_1):PAGE109
   J28   85  VSS37 SCONN288_ADR50017P087CC-SCONN2A   I176 @S9S_MB_2U_LIB.S9S_MB_2U(SCH_1):PAGE109
   J28   88  VSS38 SCONN288_ADR50017P087CC-SCONN2A   I176 @S9S_MB_2U_LIB.S9S_MB_2U(SCH_1):PAGE109
   J28   90  VSS39 SCONN288_ADR50017P087CC-SCONN2A   I176 @S9S_MB_2U_LIB.S9S_MB_2U(SCH_1):PAGE109
   J28   92  VSS40 SCONN288_ADR50017P087CC-SCONN2A   I176 @S9S_MB_2U_LIB.S9S_MB_2U(SCH_1):PAGE109
   J28   95  VSS41 SCONN288_ADR50017P087CC-SCONN2A   I176 @S9S_MB_2U_LIB.S9S_MB_2U(SCH_1):PAGE109
   J28   97  VSS42 SCONN288_ADR50017P087CC-SCONN2A   I176 @S9S_MB_2U_LIB.S9S_MB_2U(SCH_1):PAGE109
   J28   99  VSS43 SCONN288_ADR50017P087CC-SCONN2A   I176 @S9S_MB_2U_LIB.S9S_MB_2U(SCH_1):PAGE109
   J28  101  VSS44 SCONN288_ADR50017P087CC-SCONN2A   I176 @S9S_MB_2U_LIB.S9S_MB_2U(SCH_1):PAGE109
   J28  103  VSS45 SCONN288_ADR50017P087CC-SCONN2A   I176 @S9S_MB_2U_LIB.S9S_MB_2U(SCH_1):PAGE109
   J28  106  VSS46 SCONN288_ADR50017P087CC-SCONN2A   I176 @S9S_MB_2U_LIB.S9S_MB_2U(SCH_1):PAGE109
   J28  108  VSS47 SCONN288_ADR50017P087CC-SCONN2A   I176 @S9S_MB_2U_LIB.S9S_MB_2U(SCH_1):PAGE109
   J28  110  VSS48 SCONN288_ADR50017P087CC-SCONN2A   I176 @S9S_MB_2U_LIB.S9S_MB_2U(SCH_1):PAGE109
   J28  112  VSS49 SCONN288_ADR50017P087CC-SCONN2A   I176 @S9S_MB_2U_LIB.S9S_MB_2U(SCH_1):PAGE109
   J28  114  VSS50 SCONN288_ADR50017P087CC-SCONN2A   I176 @S9S_MB_2U_LIB.S9S_MB_2U(SCH_1):PAGE109
   J28  117  VSS51 SCONN288_ADR50017P087CC-SCONN2A   I176 @S9S_MB_2U_LIB.S9S_MB_2U(SCH_1):PAGE109
   J28  119  VSS52 SCONN288_ADR50017P087CC-SCONN2A   I176 @S9S_MB_2U_LIB.S9S_MB_2U(SCH_1):PAGE109
   J28  121  VSS53 SCONN288_ADR50017P087CC-SCONN2A   I176 @S9S_MB_2U_LIB.S9S_MB_2U(SCH_1):PAGE109
   J28  123  VSS54 SCONN288_ADR50017P087CC-SCONN2A   I176 @S9S_MB_2U_LIB.S9S_MB_2U(SCH_1):PAGE109
   J28  125  VSS55 SCONN288_ADR50017P087CC-SCONN2A   I176 @S9S_MB_2U_LIB.S9S_MB_2U(SCH_1):PAGE109
   J28  128  VSS56 SCONN288_ADR50017P087CC-SCONN2A   I176 @S9S_MB_2U_LIB.S9S_MB_2U(SCH_1):PAGE109
   J28  130  VSS57 SCONN288_ADR50017P087CC-SCONN2A   I176 @S9S_MB_2U_LIB.S9S_MB_2U(SCH_1):PAGE109
   J28  132  VSS58 SCONN288_ADR50017P087CC-SCONN2A   I176 @S9S_MB_2U_LIB.S9S_MB_2U(SCH_1):PAGE109
   J28  134  VSS59 SCONN288_ADR50017P087CC-SCONN2A   I176 @S9S_MB_2U_LIB.S9S_MB_2U(SCH_1):PAGE109
   J28  136  VSS60 SCONN288_ADR50017P087CC-SCONN2A   I176 @S9S_MB_2U_LIB.S9S_MB_2U(SCH_1):PAGE109
   J28  139  VSS61 SCONN288_ADR50017P087CC-SCONN2A   I176 @S9S_MB_2U_LIB.S9S_MB_2U(SCH_1):PAGE109
   J28  141  VSS62 SCONN288_ADR50017P087CC-SCONN2A   I176 @S9S_MB_2U_LIB.S9S_MB_2U(SCH_1):PAGE109
   J28  143  VSS63 SCONN288_ADR50017P087CC-SCONN2A   I176 @S9S_MB_2U_LIB.S9S_MB_2U(SCH_1):PAGE109
   J28  151  VSS64 SCONN288_ADR50017P087CC-SCONN2A   I176 @S9S_MB_2U_LIB.S9S_MB_2U(SCH_1):PAGE109
   J28  153  VSS65 SCONN288_ADR50017P087CC-SCONN2A   I176 @S9S_MB_2U_LIB.S9S_MB_2U(SCH_1):PAGE109
   J28  155  VSS66 SCONN288_ADR50017P087CC-SCONN2A   I176 @S9S_MB_2U_LIB.S9S_MB_2U(SCH_1):PAGE109
   J28  158  VSS67 SCONN288_ADR50017P087CC-SCONN2A   I176 @S9S_MB_2U_LIB.S9S_MB_2U(SCH_1):PAGE109
   J28  160  VSS68 SCONN288_ADR50017P087CC-SCONN2A   I176 @S9S_MB_2U_LIB.S9S_MB_2U(SCH_1):PAGE109
   J28  162  VSS69 SCONN288_ADR50017P087CC-SCONN2A   I176 @S9S_MB_2U_LIB.S9S_MB_2U(SCH_1):PAGE109
   J28  164  VSS70 SCONN288_ADR50017P087CC-SCONN2A   I176 @S9S_MB_2U_LIB.S9S_MB_2U(SCH_1):PAGE109
   J28  166  VSS71 SCONN288_ADR50017P087CC-SCONN2A   I176 @S9S_MB_2U_LIB.S9S_MB_2U(SCH_1):PAGE109
   J28  169  VSS72 SCONN288_ADR50017P087CC-SCONN2A   I176 @S9S_MB_2U_LIB.S9S_MB_2U(SCH_1):PAGE109
   J28  171  VSS73 SCONN288_ADR50017P087CC-SCONN2A   I176 @S9S_MB_2U_LIB.S9S_MB_2U(SCH_1):PAGE109
   J28  173  VSS74 SCONN288_ADR50017P087CC-SCONN2A   I176 @S9S_MB_2U_LIB.S9S_MB_2U(SCH_1):PAGE109
   J28  175  VSS75 SCONN288_ADR50017P087CC-SCONN2A   I176 @S9S_MB_2U_LIB.S9S_MB_2U(SCH_1):PAGE109
   J28  177  VSS76 SCONN288_ADR50017P087CC-SCONN2A   I176 @S9S_MB_2U_LIB.S9S_MB_2U(SCH_1):PAGE109
   J28  180  VSS77 SCONN288_ADR50017P087CC-SCONN2A   I176 @S9S_MB_2U_LIB.S9S_MB_2U(SCH_1):PAGE109
   J28  182  VSS78 SCONN288_ADR50017P087CC-SCONN2A   I176 @S9S_MB_2U_LIB.S9S_MB_2U(SCH_1):PAGE109
   J28  184  VSS79 SCONN288_ADR50017P087CC-SCONN2A   I176 @S9S_MB_2U_LIB.S9S_MB_2U(SCH_1):PAGE109
   J28  186  VSS80 SCONN288_ADR50017P087CC-SCONN2A   I176 @S9S_MB_2U_LIB.S9S_MB_2U(SCH_1):PAGE109
   J28  188  VSS81 SCONN288_ADR50017P087CC-SCONN2A   I176 @S9S_MB_2U_LIB.S9S_MB_2U(SCH_1):PAGE109
   J28  191  VSS82 SCONN288_ADR50017P087CC-SCONN2A   I176 @S9S_MB_2U_LIB.S9S_MB_2U(SCH_1):PAGE109
   J28  193  VSS83 SCONN288_ADR50017P087CC-SCONN2A   I176 @S9S_MB_2U_LIB.S9S_MB_2U(SCH_1):PAGE109
   J28  195  VSS84 SCONN288_ADR50017P087CC-SCONN2A   I176 @S9S_MB_2U_LIB.S9S_MB_2U(SCH_1):PAGE109
   J28  197  VSS85 SCONN288_ADR50017P087CC-SCONN2A   I176 @S9S_MB_2U_LIB.S9S_MB_2U(SCH_1):PAGE109
   J28  199  VSS86 SCONN288_ADR50017P087CC-SCONN2A   I176 @S9S_MB_2U_LIB.S9S_MB_2U(SCH_1):PAGE109
   J28  202  VSS87 SCONN288_ADR50017P087CC-SCONN2A   I176 @S9S_MB_2U_LIB.S9S_MB_2U(SCH_1):PAGE109
   J28  204  VSS88 SCONN288_ADR50017P087CC-SCONN2A   I176 @S9S_MB_2U_LIB.S9S_MB_2U(SCH_1):PAGE109
   J28  206  VSS89 SCONN288_ADR50017P087CC-SCONN2A   I176 @S9S_MB_2U_LIB.S9S_MB_2U(SCH_1):PAGE109
   J28  208  VSS90 SCONN288_ADR50017P087CC-SCONN2A   I176 @S9S_MB_2U_LIB.S9S_MB_2U(SCH_1):PAGE109
   J28  210  VSS91 SCONN288_ADR50017P087CC-SCONN2A   I176 @S9S_MB_2U_LIB.S9S_MB_2U(SCH_1):PAGE109
   J28  212  VSS92 SCONN288_ADR50017P087CC-SCONN2A   I176 @S9S_MB_2U_LIB.S9S_MB_2U(SCH_1):PAGE109
   J28  214  VSS93 SCONN288_ADR50017P087CC-SCONN2A   I176 @S9S_MB_2U_LIB.S9S_MB_2U(SCH_1):PAGE109
   J28  216  VSS94 SCONN288_ADR50017P087CC-SCONN2A   I176 @S9S_MB_2U_LIB.S9S_MB_2U(SCH_1):PAGE109
   J28  219  VSS95 SCONN288_ADR50017P087CC-SCONN2A   I176 @S9S_MB_2U_LIB.S9S_MB_2U(SCH_1):PAGE109
   J28  222  VSS96 SCONN288_ADR50017P087CC-SCONN2A   I176 @S9S_MB_2U_LIB.S9S_MB_2U(SCH_1):PAGE109
   J28  224  VSS97 SCONN288_ADR50017P087CC-SCONN2A   I176 @S9S_MB_2U_LIB.S9S_MB_2U(SCH_1):PAGE109
   J28  226  VSS98 SCONN288_ADR50017P087CC-SCONN2A   I176 @S9S_MB_2U_LIB.S9S_MB_2U(SCH_1):PAGE109
   J28  228  VSS99 SCONN288_ADR50017P087CC-SCONN2A   I176 @S9S_MB_2U_LIB.S9S_MB_2U(SCH_1):PAGE109
   J28  230 VSS100 SCONN288_ADR50017P087CC-SCONN2A   I176 @S9S_MB_2U_LIB.S9S_MB_2U(SCH_1):PAGE109
   J28  233 VSS101 SCONN288_ADR50017P087CC-SCONN2A   I176 @S9S_MB_2U_LIB.S9S_MB_2U(SCH_1):PAGE109
   J28  235 VSS102 SCONN288_ADR50017P087CC-SCONN2A   I176 @S9S_MB_2U_LIB.S9S_MB_2U(SCH_1):PAGE109
   J28  237 VSS103 SCONN288_ADR50017P087CC-SCONN2A   I176 @S9S_MB_2U_LIB.S9S_MB_2U(SCH_1):PAGE109
   J28  240 VSS104 SCONN288_ADR50017P087CC-SCONN2A   I176 @S9S_MB_2U_LIB.S9S_MB_2U(SCH_1):PAGE109
   J28  242 VSS105 SCONN288_ADR50017P087CC-SCONN2A   I176 @S9S_MB_2U_LIB.S9S_MB_2U(SCH_1):PAGE109
   J28  244 VSS106 SCONN288_ADR50017P087CC-SCONN2A   I176 @S9S_MB_2U_LIB.S9S_MB_2U(SCH_1):PAGE109
   J28  246 VSS107 SCONN288_ADR50017P087CC-SCONN2A   I176 @S9S_MB_2U_LIB.S9S_MB_2U(SCH_1):PAGE109
   J28  248 VSS108 SCONN288_ADR50017P087CC-SCONN2A   I176 @S9S_MB_2U_LIB.S9S_MB_2U(SCH_1):PAGE109
   J28  251 VSS109 SCONN288_ADR50017P087CC-SCONN2A   I176 @S9S_MB_2U_LIB.S9S_MB_2U(SCH_1):PAGE109
   J28  253 VSS110 SCONN288_ADR50017P087CC-SCONN2A   I176 @S9S_MB_2U_LIB.S9S_MB_2U(SCH_1):PAGE109
   J28  255 VSS111 SCONN288_ADR50017P087CC-SCONN2A   I176 @S9S_MB_2U_LIB.S9S_MB_2U(SCH_1):PAGE109
   J28  257 VSS112 SCONN288_ADR50017P087CC-SCONN2A   I176 @S9S_MB_2U_LIB.S9S_MB_2U(SCH_1):PAGE109
   J28  259 VSS113 SCONN288_ADR50017P087CC-SCONN2A   I176 @S9S_MB_2U_LIB.S9S_MB_2U(SCH_1):PAGE109
   J28  262 VSS114 SCONN288_ADR50017P087CC-SCONN2A   I176 @S9S_MB_2U_LIB.S9S_MB_2U(SCH_1):PAGE109
   J28  264 VSS115 SCONN288_ADR50017P087CC-SCONN2A   I176 @S9S_MB_2U_LIB.S9S_MB_2U(SCH_1):PAGE109
   J28  266 VSS116 SCONN288_ADR50017P087CC-SCONN2A   I176 @S9S_MB_2U_LIB.S9S_MB_2U(SCH_1):PAGE109
   J28  268 VSS117 SCONN288_ADR50017P087CC-SCONN2A   I176 @S9S_MB_2U_LIB.S9S_MB_2U(SCH_1):PAGE109
   J28  270 VSS118 SCONN288_ADR50017P087CC-SCONN2A   I176 @S9S_MB_2U_LIB.S9S_MB_2U(SCH_1):PAGE109
   J28  273 VSS119 SCONN288_ADR50017P087CC-SCONN2A   I176 @S9S_MB_2U_LIB.S9S_MB_2U(SCH_1):PAGE109
   J28  275 VSS120 SCONN288_ADR50017P087CC-SCONN2A   I176 @S9S_MB_2U_LIB.S9S_MB_2U(SCH_1):PAGE109
   J28  277 VSS121 SCONN288_ADR50017P087CC-SCONN2A   I176 @S9S_MB_2U_LIB.S9S_MB_2U(SCH_1):PAGE109
   J28  279 VSS122 SCONN288_ADR50017P087CC-SCONN2A   I176 @S9S_MB_2U_LIB.S9S_MB_2U(SCH_1):PAGE109
   J28  281 VSS123 SCONN288_ADR50017P087CC-SCONN2A   I176 @S9S_MB_2U_LIB.S9S_MB_2U(SCH_1):PAGE109
   J28  284 VSS124 SCONN288_ADR50017P087CC-SCONN2A   I176 @S9S_MB_2U_LIB.S9S_MB_2U(SCH_1):PAGE109
   J28  286 VSS125 SCONN288_ADR50017P087CC-SCONN2A   I176 @S9S_MB_2U_LIB.S9S_MB_2U(SCH_1):PAGE109
   J28  288 VSS126 SCONN288_ADR50017P087CC-SCONN2A   I176 @S9S_MB_2U_LIB.S9S_MB_2U(SCH_1):PAGE109
   R75    2      B Q_RES_0402LF-54.9K,1%,1/16W,CHA    I47 @S9S_MB_2U_LIB.S9S_MB_2U(SCH_1):PAGE110
   C81    2      B Q_CAP_C0402-2.2UF,6.3V,20%,X6SA   I120 @S9S_MB_2U_LIB.S9S_MB_2U(SCH_1):PAGE110
   C82    2      B Q_CAP_C0805-10UF,16V,10%,X6S,CA   I124 @S9S_MB_2U_LIB.S9S_MB_2U(SCH_1):PAGE110
   C83    2      B Q_CAP_C0805-10UF,16V,10%,X6S,CA   I126 @S9S_MB_2U_LIB.S9S_MB_2U(SCH_1):PAGE110
   J29   G1     G1 SCONN288_ADR50017P130CC-SCONN2A   I178 @S9S_MB_2U_LIB.S9S_MB_2U(SCH_1):PAGE110
   J29   G2     G2 SCONN288_ADR50017P130CC-SCONN2A   I178 @S9S_MB_2U_LIB.S9S_MB_2U(SCH_1):PAGE110
   J29   G3     G3 SCONN288_ADR50017P130CC-SCONN2A   I178 @S9S_MB_2U_LIB.S9S_MB_2U(SCH_1):PAGE110
   J29    6   VSS0 SCONN288_ADR50017P130CC-SCONN2A   I178 @S9S_MB_2U_LIB.S9S_MB_2U(SCH_1):PAGE110
   J29    8   VSS1 SCONN288_ADR50017P130CC-SCONN2A   I178 @S9S_MB_2U_LIB.S9S_MB_2U(SCH_1):PAGE110
   J29   10   VSS2 SCONN288_ADR50017P130CC-SCONN2A   I178 @S9S_MB_2U_LIB.S9S_MB_2U(SCH_1):PAGE110
   J29   13   VSS3 SCONN288_ADR50017P130CC-SCONN2A   I178 @S9S_MB_2U_LIB.S9S_MB_2U(SCH_1):PAGE110
   J29   15   VSS4 SCONN288_ADR50017P130CC-SCONN2A   I178 @S9S_MB_2U_LIB.S9S_MB_2U(SCH_1):PAGE110
   J29   17   VSS5 SCONN288_ADR50017P130CC-SCONN2A   I178 @S9S_MB_2U_LIB.S9S_MB_2U(SCH_1):PAGE110
   J29   19   VSS6 SCONN288_ADR50017P130CC-SCONN2A   I178 @S9S_MB_2U_LIB.S9S_MB_2U(SCH_1):PAGE110
   J29   21   VSS7 SCONN288_ADR50017P130CC-SCONN2A   I178 @S9S_MB_2U_LIB.S9S_MB_2U(SCH_1):PAGE110
   J29   24   VSS8 SCONN288_ADR50017P130CC-SCONN2A   I178 @S9S_MB_2U_LIB.S9S_MB_2U(SCH_1):PAGE110
   J29   26   VSS9 SCONN288_ADR50017P130CC-SCONN2A   I178 @S9S_MB_2U_LIB.S9S_MB_2U(SCH_1):PAGE110
   J29   28  VSS10 SCONN288_ADR50017P130CC-SCONN2A   I178 @S9S_MB_2U_LIB.S9S_MB_2U(SCH_1):PAGE110
   J29   30  VSS11 SCONN288_ADR50017P130CC-SCONN2A   I178 @S9S_MB_2U_LIB.S9S_MB_2U(SCH_1):PAGE110
   J29   32  VSS12 SCONN288_ADR50017P130CC-SCONN2A   I178 @S9S_MB_2U_LIB.S9S_MB_2U(SCH_1):PAGE110
   J29   35  VSS13 SCONN288_ADR50017P130CC-SCONN2A   I178 @S9S_MB_2U_LIB.S9S_MB_2U(SCH_1):PAGE110
   J29   37  VSS14 SCONN288_ADR50017P130CC-SCONN2A   I178 @S9S_MB_2U_LIB.S9S_MB_2U(SCH_1):PAGE110
   J29   39  VSS15 SCONN288_ADR50017P130CC-SCONN2A   I178 @S9S_MB_2U_LIB.S9S_MB_2U(SCH_1):PAGE110
   J29   41  VSS16 SCONN288_ADR50017P130CC-SCONN2A   I178 @S9S_MB_2U_LIB.S9S_MB_2U(SCH_1):PAGE110
   J29   43  VSS17 SCONN288_ADR50017P130CC-SCONN2A   I178 @S9S_MB_2U_LIB.S9S_MB_2U(SCH_1):PAGE110
   J29   46  VSS18 SCONN288_ADR50017P130CC-SCONN2A   I178 @S9S_MB_2U_LIB.S9S_MB_2U(SCH_1):PAGE110
   J29   48  VSS19 SCONN288_ADR50017P130CC-SCONN2A   I178 @S9S_MB_2U_LIB.S9S_MB_2U(SCH_1):PAGE110
   J29   50  VSS20 SCONN288_ADR50017P130CC-SCONN2A   I178 @S9S_MB_2U_LIB.S9S_MB_2U(SCH_1):PAGE110
   J29   52  VSS21 SCONN288_ADR50017P130CC-SCONN2A   I178 @S9S_MB_2U_LIB.S9S_MB_2U(SCH_1):PAGE110
   J29   54  VSS22 SCONN288_ADR50017P130CC-SCONN2A   I178 @S9S_MB_2U_LIB.S9S_MB_2U(SCH_1):PAGE110
   J29   57  VSS23 SCONN288_ADR50017P130CC-SCONN2A   I178 @S9S_MB_2U_LIB.S9S_MB_2U(SCH_1):PAGE110
   J29   59  VSS24 SCONN288_ADR50017P130CC-SCONN2A   I178 @S9S_MB_2U_LIB.S9S_MB_2U(SCH_1):PAGE110
   J29   61  VSS25 SCONN288_ADR50017P130CC-SCONN2A   I178 @S9S_MB_2U_LIB.S9S_MB_2U(SCH_1):PAGE110
   J29   63  VSS26 SCONN288_ADR50017P130CC-SCONN2A   I178 @S9S_MB_2U_LIB.S9S_MB_2U(SCH_1):PAGE110
   J29   65  VSS27 SCONN288_ADR50017P130CC-SCONN2A   I178 @S9S_MB_2U_LIB.S9S_MB_2U(SCH_1):PAGE110
   J29   67  VSS28 SCONN288_ADR50017P130CC-SCONN2A   I178 @S9S_MB_2U_LIB.S9S_MB_2U(SCH_1):PAGE110
   J29   69  VSS29 SCONN288_ADR50017P130CC-SCONN2A   I178 @S9S_MB_2U_LIB.S9S_MB_2U(SCH_1):PAGE110
   J29   71  VSS30 SCONN288_ADR50017P130CC-SCONN2A   I178 @S9S_MB_2U_LIB.S9S_MB_2U(SCH_1):PAGE110
   J29   73  VSS31 SCONN288_ADR50017P130CC-SCONN2A   I178 @S9S_MB_2U_LIB.S9S_MB_2U(SCH_1):PAGE110
   J29   75  VSS32 SCONN288_ADR50017P130CC-SCONN2A   I178 @S9S_MB_2U_LIB.S9S_MB_2U(SCH_1):PAGE110
   J29   77  VSS33 SCONN288_ADR50017P130CC-SCONN2A   I178 @S9S_MB_2U_LIB.S9S_MB_2U(SCH_1):PAGE110
   J29   79  VSS34 SCONN288_ADR50017P130CC-SCONN2A   I178 @S9S_MB_2U_LIB.S9S_MB_2U(SCH_1):PAGE110
   J29   81  VSS35 SCONN288_ADR50017P130CC-SCONN2A   I178 @S9S_MB_2U_LIB.S9S_MB_2U(SCH_1):PAGE110
   J29   83  VSS36 SCONN288_ADR50017P130CC-SCONN2A   I178 @S9S_MB_2U_LIB.S9S_MB_2U(SCH_1):PAGE110
   J29   85  VSS37 SCONN288_ADR50017P130CC-SCONN2A   I178 @S9S_MB_2U_LIB.S9S_MB_2U(SCH_1):PAGE110
   J29   88  VSS38 SCONN288_ADR50017P130CC-SCONN2A   I178 @S9S_MB_2U_LIB.S9S_MB_2U(SCH_1):PAGE110
   J29   90  VSS39 SCONN288_ADR50017P130CC-SCONN2A   I178 @S9S_MB_2U_LIB.S9S_MB_2U(SCH_1):PAGE110
   J29   92  VSS40 SCONN288_ADR50017P130CC-SCONN2A   I178 @S9S_MB_2U_LIB.S9S_MB_2U(SCH_1):PAGE110
   J29   95  VSS41 SCONN288_ADR50017P130CC-SCONN2A   I178 @S9S_MB_2U_LIB.S9S_MB_2U(SCH_1):PAGE110
   J29   97  VSS42 SCONN288_ADR50017P130CC-SCONN2A   I178 @S9S_MB_2U_LIB.S9S_MB_2U(SCH_1):PAGE110
   J29   99  VSS43 SCONN288_ADR50017P130CC-SCONN2A   I178 @S9S_MB_2U_LIB.S9S_MB_2U(SCH_1):PAGE110
   J29  101  VSS44 SCONN288_ADR50017P130CC-SCONN2A   I178 @S9S_MB_2U_LIB.S9S_MB_2U(SCH_1):PAGE110
   J29  103  VSS45 SCONN288_ADR50017P130CC-SCONN2A   I178 @S9S_MB_2U_LIB.S9S_MB_2U(SCH_1):PAGE110
   J29  106  VSS46 SCONN288_ADR50017P130CC-SCONN2A   I178 @S9S_MB_2U_LIB.S9S_MB_2U(SCH_1):PAGE110
   J29  108  VSS47 SCONN288_ADR50017P130CC-SCONN2A   I178 @S9S_MB_2U_LIB.S9S_MB_2U(SCH_1):PAGE110
   J29  110  VSS48 SCONN288_ADR50017P130CC-SCONN2A   I178 @S9S_MB_2U_LIB.S9S_MB_2U(SCH_1):PAGE110
   J29  112  VSS49 SCONN288_ADR50017P130CC-SCONN2A   I178 @S9S_MB_2U_LIB.S9S_MB_2U(SCH_1):PAGE110
   J29  114  VSS50 SCONN288_ADR50017P130CC-SCONN2A   I178 @S9S_MB_2U_LIB.S9S_MB_2U(SCH_1):PAGE110
   J29  117  VSS51 SCONN288_ADR50017P130CC-SCONN2A   I178 @S9S_MB_2U_LIB.S9S_MB_2U(SCH_1):PAGE110
   J29  119  VSS52 SCONN288_ADR50017P130CC-SCONN2A   I178 @S9S_MB_2U_LIB.S9S_MB_2U(SCH_1):PAGE110
   J29  121  VSS53 SCONN288_ADR50017P130CC-SCONN2A   I178 @S9S_MB_2U_LIB.S9S_MB_2U(SCH_1):PAGE110
   J29  123  VSS54 SCONN288_ADR50017P130CC-SCONN2A   I178 @S9S_MB_2U_LIB.S9S_MB_2U(SCH_1):PAGE110
   J29  125  VSS55 SCONN288_ADR50017P130CC-SCONN2A   I178 @S9S_MB_2U_LIB.S9S_MB_2U(SCH_1):PAGE110
   J29  128  VSS56 SCONN288_ADR50017P130CC-SCONN2A   I178 @S9S_MB_2U_LIB.S9S_MB_2U(SCH_1):PAGE110
   J29  130  VSS57 SCONN288_ADR50017P130CC-SCONN2A   I178 @S9S_MB_2U_LIB.S9S_MB_2U(SCH_1):PAGE110
   J29  132  VSS58 SCONN288_ADR50017P130CC-SCONN2A   I178 @S9S_MB_2U_LIB.S9S_MB_2U(SCH_1):PAGE110
   J29  134  VSS59 SCONN288_ADR50017P130CC-SCONN2A   I178 @S9S_MB_2U_LIB.S9S_MB_2U(SCH_1):PAGE110
   J29  136  VSS60 SCONN288_ADR50017P130CC-SCONN2A   I178 @S9S_MB_2U_LIB.S9S_MB_2U(SCH_1):PAGE110
   J29  139  VSS61 SCONN288_ADR50017P130CC-SCONN2A   I178 @S9S_MB_2U_LIB.S9S_MB_2U(SCH_1):PAGE110
   J29  141  VSS62 SCONN288_ADR50017P130CC-SCONN2A   I178 @S9S_MB_2U_LIB.S9S_MB_2U(SCH_1):PAGE110
   J29  143  VSS63 SCONN288_ADR50017P130CC-SCONN2A   I178 @S9S_MB_2U_LIB.S9S_MB_2U(SCH_1):PAGE110
   J29  151  VSS64 SCONN288_ADR50017P130CC-SCONN2A   I178 @S9S_MB_2U_LIB.S9S_MB_2U(SCH_1):PAGE110
   J29  153  VSS65 SCONN288_ADR50017P130CC-SCONN2A   I178 @S9S_MB_2U_LIB.S9S_MB_2U(SCH_1):PAGE110
   J29  155  VSS66 SCONN288_ADR50017P130CC-SCONN2A   I178 @S9S_MB_2U_LIB.S9S_MB_2U(SCH_1):PAGE110
   J29  158  VSS67 SCONN288_ADR50017P130CC-SCONN2A   I178 @S9S_MB_2U_LIB.S9S_MB_2U(SCH_1):PAGE110
   J29  160  VSS68 SCONN288_ADR50017P130CC-SCONN2A   I178 @S9S_MB_2U_LIB.S9S_MB_2U(SCH_1):PAGE110
   J29  162  VSS69 SCONN288_ADR50017P130CC-SCONN2A   I178 @S9S_MB_2U_LIB.S9S_MB_2U(SCH_1):PAGE110
   J29  164  VSS70 SCONN288_ADR50017P130CC-SCONN2A   I178 @S9S_MB_2U_LIB.S9S_MB_2U(SCH_1):PAGE110
   J29  166  VSS71 SCONN288_ADR50017P130CC-SCONN2A   I178 @S9S_MB_2U_LIB.S9S_MB_2U(SCH_1):PAGE110
   J29  169  VSS72 SCONN288_ADR50017P130CC-SCONN2A   I178 @S9S_MB_2U_LIB.S9S_MB_2U(SCH_1):PAGE110
   J29  171  VSS73 SCONN288_ADR50017P130CC-SCONN2A   I178 @S9S_MB_2U_LIB.S9S_MB_2U(SCH_1):PAGE110
   J29  173  VSS74 SCONN288_ADR50017P130CC-SCONN2A   I178 @S9S_MB_2U_LIB.S9S_MB_2U(SCH_1):PAGE110
   J29  175  VSS75 SCONN288_ADR50017P130CC-SCONN2A   I178 @S9S_MB_2U_LIB.S9S_MB_2U(SCH_1):PAGE110
   J29  177  VSS76 SCONN288_ADR50017P130CC-SCONN2A   I178 @S9S_MB_2U_LIB.S9S_MB_2U(SCH_1):PAGE110
   J29  180  VSS77 SCONN288_ADR50017P130CC-SCONN2A   I178 @S9S_MB_2U_LIB.S9S_MB_2U(SCH_1):PAGE110
   J29  182  VSS78 SCONN288_ADR50017P130CC-SCONN2A   I178 @S9S_MB_2U_LIB.S9S_MB_2U(SCH_1):PAGE110
   J29  184  VSS79 SCONN288_ADR50017P130CC-SCONN2A   I178 @S9S_MB_2U_LIB.S9S_MB_2U(SCH_1):PAGE110
   J29  186  VSS80 SCONN288_ADR50017P130CC-SCONN2A   I178 @S9S_MB_2U_LIB.S9S_MB_2U(SCH_1):PAGE110
   J29  188  VSS81 SCONN288_ADR50017P130CC-SCONN2A   I178 @S9S_MB_2U_LIB.S9S_MB_2U(SCH_1):PAGE110
   J29  191  VSS82 SCONN288_ADR50017P130CC-SCONN2A   I178 @S9S_MB_2U_LIB.S9S_MB_2U(SCH_1):PAGE110
   J29  193  VSS83 SCONN288_ADR50017P130CC-SCONN2A   I178 @S9S_MB_2U_LIB.S9S_MB_2U(SCH_1):PAGE110
   J29  195  VSS84 SCONN288_ADR50017P130CC-SCONN2A   I178 @S9S_MB_2U_LIB.S9S_MB_2U(SCH_1):PAGE110
   J29  197  VSS85 SCONN288_ADR50017P130CC-SCONN2A   I178 @S9S_MB_2U_LIB.S9S_MB_2U(SCH_1):PAGE110
   J29  199  VSS86 SCONN288_ADR50017P130CC-SCONN2A   I178 @S9S_MB_2U_LIB.S9S_MB_2U(SCH_1):PAGE110
   J29  202  VSS87 SCONN288_ADR50017P130CC-SCONN2A   I178 @S9S_MB_2U_LIB.S9S_MB_2U(SCH_1):PAGE110
   J29  204  VSS88 SCONN288_ADR50017P130CC-SCONN2A   I178 @S9S_MB_2U_LIB.S9S_MB_2U(SCH_1):PAGE110
   J29  206  VSS89 SCONN288_ADR50017P130CC-SCONN2A   I178 @S9S_MB_2U_LIB.S9S_MB_2U(SCH_1):PAGE110
   J29  208  VSS90 SCONN288_ADR50017P130CC-SCONN2A   I178 @S9S_MB_2U_LIB.S9S_MB_2U(SCH_1):PAGE110
   J29  210  VSS91 SCONN288_ADR50017P130CC-SCONN2A   I178 @S9S_MB_2U_LIB.S9S_MB_2U(SCH_1):PAGE110
   J29  212  VSS92 SCONN288_ADR50017P130CC-SCONN2A   I178 @S9S_MB_2U_LIB.S9S_MB_2U(SCH_1):PAGE110
   J29  214  VSS93 SCONN288_ADR50017P130CC-SCONN2A   I178 @S9S_MB_2U_LIB.S9S_MB_2U(SCH_1):PAGE110
   J29  216  VSS94 SCONN288_ADR50017P130CC-SCONN2A   I178 @S9S_MB_2U_LIB.S9S_MB_2U(SCH_1):PAGE110
   J29  219  VSS95 SCONN288_ADR50017P130CC-SCONN2A   I178 @S9S_MB_2U_LIB.S9S_MB_2U(SCH_1):PAGE110
   J29  222  VSS96 SCONN288_ADR50017P130CC-SCONN2A   I178 @S9S_MB_2U_LIB.S9S_MB_2U(SCH_1):PAGE110
   J29  224  VSS97 SCONN288_ADR50017P130CC-SCONN2A   I178 @S9S_MB_2U_LIB.S9S_MB_2U(SCH_1):PAGE110
   J29  226  VSS98 SCONN288_ADR50017P130CC-SCONN2A   I178 @S9S_MB_2U_LIB.S9S_MB_2U(SCH_1):PAGE110
   J29  228  VSS99 SCONN288_ADR50017P130CC-SCONN2A   I178 @S9S_MB_2U_LIB.S9S_MB_2U(SCH_1):PAGE110
   J29  230 VSS100 SCONN288_ADR50017P130CC-SCONN2A   I178 @S9S_MB_2U_LIB.S9S_MB_2U(SCH_1):PAGE110
   J29  233 VSS101 SCONN288_ADR50017P130CC-SCONN2A   I178 @S9S_MB_2U_LIB.S9S_MB_2U(SCH_1):PAGE110
   J29  235 VSS102 SCONN288_ADR50017P130CC-SCONN2A   I178 @S9S_MB_2U_LIB.S9S_MB_2U(SCH_1):PAGE110
   J29  237 VSS103 SCONN288_ADR50017P130CC-SCONN2A   I178 @S9S_MB_2U_LIB.S9S_MB_2U(SCH_1):PAGE110
   J29  240 VSS104 SCONN288_ADR50017P130CC-SCONN2A   I178 @S9S_MB_2U_LIB.S9S_MB_2U(SCH_1):PAGE110
   J29  242 VSS105 SCONN288_ADR50017P130CC-SCONN2A   I178 @S9S_MB_2U_LIB.S9S_MB_2U(SCH_1):PAGE110
   J29  244 VSS106 SCONN288_ADR50017P130CC-SCONN2A   I178 @S9S_MB_2U_LIB.S9S_MB_2U(SCH_1):PAGE110
   J29  246 VSS107 SCONN288_ADR50017P130CC-SCONN2A   I178 @S9S_MB_2U_LIB.S9S_MB_2U(SCH_1):PAGE110
   J29  248 VSS108 SCONN288_ADR50017P130CC-SCONN2A   I178 @S9S_MB_2U_LIB.S9S_MB_2U(SCH_1):PAGE110
   J29  251 VSS109 SCONN288_ADR50017P130CC-SCONN2A   I178 @S9S_MB_2U_LIB.S9S_MB_2U(SCH_1):PAGE110
   J29  253 VSS110 SCONN288_ADR50017P130CC-SCONN2A   I178 @S9S_MB_2U_LIB.S9S_MB_2U(SCH_1):PAGE110
   J29  255 VSS111 SCONN288_ADR50017P130CC-SCONN2A   I178 @S9S_MB_2U_LIB.S9S_MB_2U(SCH_1):PAGE110
   J29  257 VSS112 SCONN288_ADR50017P130CC-SCONN2A   I178 @S9S_MB_2U_LIB.S9S_MB_2U(SCH_1):PAGE110
   J29  259 VSS113 SCONN288_ADR50017P130CC-SCONN2A   I178 @S9S_MB_2U_LIB.S9S_MB_2U(SCH_1):PAGE110
   J29  262 VSS114 SCONN288_ADR50017P130CC-SCONN2A   I178 @S9S_MB_2U_LIB.S9S_MB_2U(SCH_1):PAGE110
   J29  264 VSS115 SCONN288_ADR50017P130CC-SCONN2A   I178 @S9S_MB_2U_LIB.S9S_MB_2U(SCH_1):PAGE110
   J29  266 VSS116 SCONN288_ADR50017P130CC-SCONN2A   I178 @S9S_MB_2U_LIB.S9S_MB_2U(SCH_1):PAGE110
   J29  268 VSS117 SCONN288_ADR50017P130CC-SCONN2A   I178 @S9S_MB_2U_LIB.S9S_MB_2U(SCH_1):PAGE110
   J29  270 VSS118 SCONN288_ADR50017P130CC-SCONN2A   I178 @S9S_MB_2U_LIB.S9S_MB_2U(SCH_1):PAGE110
   J29  273 VSS119 SCONN288_ADR50017P130CC-SCONN2A   I178 @S9S_MB_2U_LIB.S9S_MB_2U(SCH_1):PAGE110
   J29  275 VSS120 SCONN288_ADR50017P130CC-SCONN2A   I178 @S9S_MB_2U_LIB.S9S_MB_2U(SCH_1):PAGE110
   J29  277 VSS121 SCONN288_ADR50017P130CC-SCONN2A   I178 @S9S_MB_2U_LIB.S9S_MB_2U(SCH_1):PAGE110
   J29  279 VSS122 SCONN288_ADR50017P130CC-SCONN2A   I178 @S9S_MB_2U_LIB.S9S_MB_2U(SCH_1):PAGE110
   J29  281 VSS123 SCONN288_ADR50017P130CC-SCONN2A   I178 @S9S_MB_2U_LIB.S9S_MB_2U(SCH_1):PAGE110
   J29  284 VSS124 SCONN288_ADR50017P130CC-SCONN2A   I178 @S9S_MB_2U_LIB.S9S_MB_2U(SCH_1):PAGE110
   J29  286 VSS125 SCONN288_ADR50017P130CC-SCONN2A   I178 @S9S_MB_2U_LIB.S9S_MB_2U(SCH_1):PAGE110
   J29  288 VSS126 SCONN288_ADR50017P130CC-SCONN2A   I178 @S9S_MB_2U_LIB.S9S_MB_2U(SCH_1):PAGE110
   R74    2      B Q_RES_0402LF-84.5K,1%,1/16W,CHA     I5 @S9S_MB_2U_LIB.S9S_MB_2U(SCH_1):PAGE111
   C78    2      B Q_CAP_C0402-2.2UF,6.3V,20%,X6SA    I54 @S9S_MB_2U_LIB.S9S_MB_2U(SCH_1):PAGE111
   C79    2      B Q_CAP_C0805-10UF,16V,10%,X6S,CA    I56 @S9S_MB_2U_LIB.S9S_MB_2U(SCH_1):PAGE111
   C80    2      B Q_CAP_C0805-10UF,16V,10%,X6S,CA    I59 @S9S_MB_2U_LIB.S9S_MB_2U(SCH_1):PAGE111
   J30   G1     G1 SCONN288_ADR50017P087CC-SCONN2A   I178 @S9S_MB_2U_LIB.S9S_MB_2U(SCH_1):PAGE111
   J30   G2     G2 SCONN288_ADR50017P087CC-SCONN2A   I178 @S9S_MB_2U_LIB.S9S_MB_2U(SCH_1):PAGE111
   J30   G3     G3 SCONN288_ADR50017P087CC-SCONN2A   I178 @S9S_MB_2U_LIB.S9S_MB_2U(SCH_1):PAGE111
   J30    6   VSS0 SCONN288_ADR50017P087CC-SCONN2A   I178 @S9S_MB_2U_LIB.S9S_MB_2U(SCH_1):PAGE111
   J30    8   VSS1 SCONN288_ADR50017P087CC-SCONN2A   I178 @S9S_MB_2U_LIB.S9S_MB_2U(SCH_1):PAGE111
   J30   10   VSS2 SCONN288_ADR50017P087CC-SCONN2A   I178 @S9S_MB_2U_LIB.S9S_MB_2U(SCH_1):PAGE111
   J30   13   VSS3 SCONN288_ADR50017P087CC-SCONN2A   I178 @S9S_MB_2U_LIB.S9S_MB_2U(SCH_1):PAGE111
   J30   15   VSS4 SCONN288_ADR50017P087CC-SCONN2A   I178 @S9S_MB_2U_LIB.S9S_MB_2U(SCH_1):PAGE111
   J30   17   VSS5 SCONN288_ADR50017P087CC-SCONN2A   I178 @S9S_MB_2U_LIB.S9S_MB_2U(SCH_1):PAGE111
   J30   19   VSS6 SCONN288_ADR50017P087CC-SCONN2A   I178 @S9S_MB_2U_LIB.S9S_MB_2U(SCH_1):PAGE111
   J30   21   VSS7 SCONN288_ADR50017P087CC-SCONN2A   I178 @S9S_MB_2U_LIB.S9S_MB_2U(SCH_1):PAGE111
   J30   24   VSS8 SCONN288_ADR50017P087CC-SCONN2A   I178 @S9S_MB_2U_LIB.S9S_MB_2U(SCH_1):PAGE111
   J30   26   VSS9 SCONN288_ADR50017P087CC-SCONN2A   I178 @S9S_MB_2U_LIB.S9S_MB_2U(SCH_1):PAGE111
   J30   28  VSS10 SCONN288_ADR50017P087CC-SCONN2A   I178 @S9S_MB_2U_LIB.S9S_MB_2U(SCH_1):PAGE111
   J30   30  VSS11 SCONN288_ADR50017P087CC-SCONN2A   I178 @S9S_MB_2U_LIB.S9S_MB_2U(SCH_1):PAGE111
   J30   32  VSS12 SCONN288_ADR50017P087CC-SCONN2A   I178 @S9S_MB_2U_LIB.S9S_MB_2U(SCH_1):PAGE111
   J30   35  VSS13 SCONN288_ADR50017P087CC-SCONN2A   I178 @S9S_MB_2U_LIB.S9S_MB_2U(SCH_1):PAGE111
   J30   37  VSS14 SCONN288_ADR50017P087CC-SCONN2A   I178 @S9S_MB_2U_LIB.S9S_MB_2U(SCH_1):PAGE111
   J30   39  VSS15 SCONN288_ADR50017P087CC-SCONN2A   I178 @S9S_MB_2U_LIB.S9S_MB_2U(SCH_1):PAGE111
   J30   41  VSS16 SCONN288_ADR50017P087CC-SCONN2A   I178 @S9S_MB_2U_LIB.S9S_MB_2U(SCH_1):PAGE111
   J30   43  VSS17 SCONN288_ADR50017P087CC-SCONN2A   I178 @S9S_MB_2U_LIB.S9S_MB_2U(SCH_1):PAGE111
   J30   46  VSS18 SCONN288_ADR50017P087CC-SCONN2A   I178 @S9S_MB_2U_LIB.S9S_MB_2U(SCH_1):PAGE111
   J30   48  VSS19 SCONN288_ADR50017P087CC-SCONN2A   I178 @S9S_MB_2U_LIB.S9S_MB_2U(SCH_1):PAGE111
   J30   50  VSS20 SCONN288_ADR50017P087CC-SCONN2A   I178 @S9S_MB_2U_LIB.S9S_MB_2U(SCH_1):PAGE111
   J30   52  VSS21 SCONN288_ADR50017P087CC-SCONN2A   I178 @S9S_MB_2U_LIB.S9S_MB_2U(SCH_1):PAGE111
   J30   54  VSS22 SCONN288_ADR50017P087CC-SCONN2A   I178 @S9S_MB_2U_LIB.S9S_MB_2U(SCH_1):PAGE111
   J30   57  VSS23 SCONN288_ADR50017P087CC-SCONN2A   I178 @S9S_MB_2U_LIB.S9S_MB_2U(SCH_1):PAGE111
   J30   59  VSS24 SCONN288_ADR50017P087CC-SCONN2A   I178 @S9S_MB_2U_LIB.S9S_MB_2U(SCH_1):PAGE111
   J30   61  VSS25 SCONN288_ADR50017P087CC-SCONN2A   I178 @S9S_MB_2U_LIB.S9S_MB_2U(SCH_1):PAGE111
   J30   63  VSS26 SCONN288_ADR50017P087CC-SCONN2A   I178 @S9S_MB_2U_LIB.S9S_MB_2U(SCH_1):PAGE111
   J30   65  VSS27 SCONN288_ADR50017P087CC-SCONN2A   I178 @S9S_MB_2U_LIB.S9S_MB_2U(SCH_1):PAGE111
   J30   67  VSS28 SCONN288_ADR50017P087CC-SCONN2A   I178 @S9S_MB_2U_LIB.S9S_MB_2U(SCH_1):PAGE111
   J30   69  VSS29 SCONN288_ADR50017P087CC-SCONN2A   I178 @S9S_MB_2U_LIB.S9S_MB_2U(SCH_1):PAGE111
   J30   71  VSS30 SCONN288_ADR50017P087CC-SCONN2A   I178 @S9S_MB_2U_LIB.S9S_MB_2U(SCH_1):PAGE111
   J30   73  VSS31 SCONN288_ADR50017P087CC-SCONN2A   I178 @S9S_MB_2U_LIB.S9S_MB_2U(SCH_1):PAGE111
   J30   75  VSS32 SCONN288_ADR50017P087CC-SCONN2A   I178 @S9S_MB_2U_LIB.S9S_MB_2U(SCH_1):PAGE111
   J30   77  VSS33 SCONN288_ADR50017P087CC-SCONN2A   I178 @S9S_MB_2U_LIB.S9S_MB_2U(SCH_1):PAGE111
   J30   79  VSS34 SCONN288_ADR50017P087CC-SCONN2A   I178 @S9S_MB_2U_LIB.S9S_MB_2U(SCH_1):PAGE111
   J30   81  VSS35 SCONN288_ADR50017P087CC-SCONN2A   I178 @S9S_MB_2U_LIB.S9S_MB_2U(SCH_1):PAGE111
   J30   83  VSS36 SCONN288_ADR50017P087CC-SCONN2A   I178 @S9S_MB_2U_LIB.S9S_MB_2U(SCH_1):PAGE111
   J30   85  VSS37 SCONN288_ADR50017P087CC-SCONN2A   I178 @S9S_MB_2U_LIB.S9S_MB_2U(SCH_1):PAGE111
   J30   88  VSS38 SCONN288_ADR50017P087CC-SCONN2A   I178 @S9S_MB_2U_LIB.S9S_MB_2U(SCH_1):PAGE111
   J30   90  VSS39 SCONN288_ADR50017P087CC-SCONN2A   I178 @S9S_MB_2U_LIB.S9S_MB_2U(SCH_1):PAGE111
   J30   92  VSS40 SCONN288_ADR50017P087CC-SCONN2A   I178 @S9S_MB_2U_LIB.S9S_MB_2U(SCH_1):PAGE111
   J30   95  VSS41 SCONN288_ADR50017P087CC-SCONN2A   I178 @S9S_MB_2U_LIB.S9S_MB_2U(SCH_1):PAGE111
   J30   97  VSS42 SCONN288_ADR50017P087CC-SCONN2A   I178 @S9S_MB_2U_LIB.S9S_MB_2U(SCH_1):PAGE111
   J30   99  VSS43 SCONN288_ADR50017P087CC-SCONN2A   I178 @S9S_MB_2U_LIB.S9S_MB_2U(SCH_1):PAGE111
   J30  101  VSS44 SCONN288_ADR50017P087CC-SCONN2A   I178 @S9S_MB_2U_LIB.S9S_MB_2U(SCH_1):PAGE111
   J30  103  VSS45 SCONN288_ADR50017P087CC-SCONN2A   I178 @S9S_MB_2U_LIB.S9S_MB_2U(SCH_1):PAGE111
   J30  106  VSS46 SCONN288_ADR50017P087CC-SCONN2A   I178 @S9S_MB_2U_LIB.S9S_MB_2U(SCH_1):PAGE111
   J30  108  VSS47 SCONN288_ADR50017P087CC-SCONN2A   I178 @S9S_MB_2U_LIB.S9S_MB_2U(SCH_1):PAGE111
   J30  110  VSS48 SCONN288_ADR50017P087CC-SCONN2A   I178 @S9S_MB_2U_LIB.S9S_MB_2U(SCH_1):PAGE111
   J30  112  VSS49 SCONN288_ADR50017P087CC-SCONN2A   I178 @S9S_MB_2U_LIB.S9S_MB_2U(SCH_1):PAGE111
   J30  114  VSS50 SCONN288_ADR50017P087CC-SCONN2A   I178 @S9S_MB_2U_LIB.S9S_MB_2U(SCH_1):PAGE111
   J30  117  VSS51 SCONN288_ADR50017P087CC-SCONN2A   I178 @S9S_MB_2U_LIB.S9S_MB_2U(SCH_1):PAGE111
   J30  119  VSS52 SCONN288_ADR50017P087CC-SCONN2A   I178 @S9S_MB_2U_LIB.S9S_MB_2U(SCH_1):PAGE111
   J30  121  VSS53 SCONN288_ADR50017P087CC-SCONN2A   I178 @S9S_MB_2U_LIB.S9S_MB_2U(SCH_1):PAGE111
   J30  123  VSS54 SCONN288_ADR50017P087CC-SCONN2A   I178 @S9S_MB_2U_LIB.S9S_MB_2U(SCH_1):PAGE111
   J30  125  VSS55 SCONN288_ADR50017P087CC-SCONN2A   I178 @S9S_MB_2U_LIB.S9S_MB_2U(SCH_1):PAGE111
   J30  128  VSS56 SCONN288_ADR50017P087CC-SCONN2A   I178 @S9S_MB_2U_LIB.S9S_MB_2U(SCH_1):PAGE111
   J30  130  VSS57 SCONN288_ADR50017P087CC-SCONN2A   I178 @S9S_MB_2U_LIB.S9S_MB_2U(SCH_1):PAGE111
   J30  132  VSS58 SCONN288_ADR50017P087CC-SCONN2A   I178 @S9S_MB_2U_LIB.S9S_MB_2U(SCH_1):PAGE111
   J30  134  VSS59 SCONN288_ADR50017P087CC-SCONN2A   I178 @S9S_MB_2U_LIB.S9S_MB_2U(SCH_1):PAGE111
   J30  136  VSS60 SCONN288_ADR50017P087CC-SCONN2A   I178 @S9S_MB_2U_LIB.S9S_MB_2U(SCH_1):PAGE111
   J30  139  VSS61 SCONN288_ADR50017P087CC-SCONN2A   I178 @S9S_MB_2U_LIB.S9S_MB_2U(SCH_1):PAGE111
   J30  141  VSS62 SCONN288_ADR50017P087CC-SCONN2A   I178 @S9S_MB_2U_LIB.S9S_MB_2U(SCH_1):PAGE111
   J30  143  VSS63 SCONN288_ADR50017P087CC-SCONN2A   I178 @S9S_MB_2U_LIB.S9S_MB_2U(SCH_1):PAGE111
   J30  151  VSS64 SCONN288_ADR50017P087CC-SCONN2A   I178 @S9S_MB_2U_LIB.S9S_MB_2U(SCH_1):PAGE111
   J30  153  VSS65 SCONN288_ADR50017P087CC-SCONN2A   I178 @S9S_MB_2U_LIB.S9S_MB_2U(SCH_1):PAGE111
   J30  155  VSS66 SCONN288_ADR50017P087CC-SCONN2A   I178 @S9S_MB_2U_LIB.S9S_MB_2U(SCH_1):PAGE111
   J30  158  VSS67 SCONN288_ADR50017P087CC-SCONN2A   I178 @S9S_MB_2U_LIB.S9S_MB_2U(SCH_1):PAGE111
   J30  160  VSS68 SCONN288_ADR50017P087CC-SCONN2A   I178 @S9S_MB_2U_LIB.S9S_MB_2U(SCH_1):PAGE111
   J30  162  VSS69 SCONN288_ADR50017P087CC-SCONN2A   I178 @S9S_MB_2U_LIB.S9S_MB_2U(SCH_1):PAGE111
   J30  164  VSS70 SCONN288_ADR50017P087CC-SCONN2A   I178 @S9S_MB_2U_LIB.S9S_MB_2U(SCH_1):PAGE111
   J30  166  VSS71 SCONN288_ADR50017P087CC-SCONN2A   I178 @S9S_MB_2U_LIB.S9S_MB_2U(SCH_1):PAGE111
   J30  169  VSS72 SCONN288_ADR50017P087CC-SCONN2A   I178 @S9S_MB_2U_LIB.S9S_MB_2U(SCH_1):PAGE111
   J30  171  VSS73 SCONN288_ADR50017P087CC-SCONN2A   I178 @S9S_MB_2U_LIB.S9S_MB_2U(SCH_1):PAGE111
   J30  173  VSS74 SCONN288_ADR50017P087CC-SCONN2A   I178 @S9S_MB_2U_LIB.S9S_MB_2U(SCH_1):PAGE111
   J30  175  VSS75 SCONN288_ADR50017P087CC-SCONN2A   I178 @S9S_MB_2U_LIB.S9S_MB_2U(SCH_1):PAGE111
   J30  177  VSS76 SCONN288_ADR50017P087CC-SCONN2A   I178 @S9S_MB_2U_LIB.S9S_MB_2U(SCH_1):PAGE111
   J30  180  VSS77 SCONN288_ADR50017P087CC-SCONN2A   I178 @S9S_MB_2U_LIB.S9S_MB_2U(SCH_1):PAGE111
   J30  182  VSS78 SCONN288_ADR50017P087CC-SCONN2A   I178 @S9S_MB_2U_LIB.S9S_MB_2U(SCH_1):PAGE111
   J30  184  VSS79 SCONN288_ADR50017P087CC-SCONN2A   I178 @S9S_MB_2U_LIB.S9S_MB_2U(SCH_1):PAGE111
   J30  186  VSS80 SCONN288_ADR50017P087CC-SCONN2A   I178 @S9S_MB_2U_LIB.S9S_MB_2U(SCH_1):PAGE111
   J30  188  VSS81 SCONN288_ADR50017P087CC-SCONN2A   I178 @S9S_MB_2U_LIB.S9S_MB_2U(SCH_1):PAGE111
   J30  191  VSS82 SCONN288_ADR50017P087CC-SCONN2A   I178 @S9S_MB_2U_LIB.S9S_MB_2U(SCH_1):PAGE111
   J30  193  VSS83 SCONN288_ADR50017P087CC-SCONN2A   I178 @S9S_MB_2U_LIB.S9S_MB_2U(SCH_1):PAGE111
   J30  195  VSS84 SCONN288_ADR50017P087CC-SCONN2A   I178 @S9S_MB_2U_LIB.S9S_MB_2U(SCH_1):PAGE111
   J30  197  VSS85 SCONN288_ADR50017P087CC-SCONN2A   I178 @S9S_MB_2U_LIB.S9S_MB_2U(SCH_1):PAGE111
   J30  199  VSS86 SCONN288_ADR50017P087CC-SCONN2A   I178 @S9S_MB_2U_LIB.S9S_MB_2U(SCH_1):PAGE111
   J30  202  VSS87 SCONN288_ADR50017P087CC-SCONN2A   I178 @S9S_MB_2U_LIB.S9S_MB_2U(SCH_1):PAGE111
   J30  204  VSS88 SCONN288_ADR50017P087CC-SCONN2A   I178 @S9S_MB_2U_LIB.S9S_MB_2U(SCH_1):PAGE111
   J30  206  VSS89 SCONN288_ADR50017P087CC-SCONN2A   I178 @S9S_MB_2U_LIB.S9S_MB_2U(SCH_1):PAGE111
   J30  208  VSS90 SCONN288_ADR50017P087CC-SCONN2A   I178 @S9S_MB_2U_LIB.S9S_MB_2U(SCH_1):PAGE111
   J30  210  VSS91 SCONN288_ADR50017P087CC-SCONN2A   I178 @S9S_MB_2U_LIB.S9S_MB_2U(SCH_1):PAGE111
   J30  212  VSS92 SCONN288_ADR50017P087CC-SCONN2A   I178 @S9S_MB_2U_LIB.S9S_MB_2U(SCH_1):PAGE111
   J30  214  VSS93 SCONN288_ADR50017P087CC-SCONN2A   I178 @S9S_MB_2U_LIB.S9S_MB_2U(SCH_1):PAGE111
   J30  216  VSS94 SCONN288_ADR50017P087CC-SCONN2A   I178 @S9S_MB_2U_LIB.S9S_MB_2U(SCH_1):PAGE111
   J30  219  VSS95 SCONN288_ADR50017P087CC-SCONN2A   I178 @S9S_MB_2U_LIB.S9S_MB_2U(SCH_1):PAGE111
   J30  222  VSS96 SCONN288_ADR50017P087CC-SCONN2A   I178 @S9S_MB_2U_LIB.S9S_MB_2U(SCH_1):PAGE111
   J30  224  VSS97 SCONN288_ADR50017P087CC-SCONN2A   I178 @S9S_MB_2U_LIB.S9S_MB_2U(SCH_1):PAGE111
   J30  226  VSS98 SCONN288_ADR50017P087CC-SCONN2A   I178 @S9S_MB_2U_LIB.S9S_MB_2U(SCH_1):PAGE111
   J30  228  VSS99 SCONN288_ADR50017P087CC-SCONN2A   I178 @S9S_MB_2U_LIB.S9S_MB_2U(SCH_1):PAGE111
   J30  230 VSS100 SCONN288_ADR50017P087CC-SCONN2A   I178 @S9S_MB_2U_LIB.S9S_MB_2U(SCH_1):PAGE111
   J30  233 VSS101 SCONN288_ADR50017P087CC-SCONN2A   I178 @S9S_MB_2U_LIB.S9S_MB_2U(SCH_1):PAGE111
   J30  235 VSS102 SCONN288_ADR50017P087CC-SCONN2A   I178 @S9S_MB_2U_LIB.S9S_MB_2U(SCH_1):PAGE111
   J30  237 VSS103 SCONN288_ADR50017P087CC-SCONN2A   I178 @S9S_MB_2U_LIB.S9S_MB_2U(SCH_1):PAGE111
   J30  240 VSS104 SCONN288_ADR50017P087CC-SCONN2A   I178 @S9S_MB_2U_LIB.S9S_MB_2U(SCH_1):PAGE111
   J30  242 VSS105 SCONN288_ADR50017P087CC-SCONN2A   I178 @S9S_MB_2U_LIB.S9S_MB_2U(SCH_1):PAGE111
   J30  244 VSS106 SCONN288_ADR50017P087CC-SCONN2A   I178 @S9S_MB_2U_LIB.S9S_MB_2U(SCH_1):PAGE111
   J30  246 VSS107 SCONN288_ADR50017P087CC-SCONN2A   I178 @S9S_MB_2U_LIB.S9S_MB_2U(SCH_1):PAGE111
   J30  248 VSS108 SCONN288_ADR50017P087CC-SCONN2A   I178 @S9S_MB_2U_LIB.S9S_MB_2U(SCH_1):PAGE111
   J30  251 VSS109 SCONN288_ADR50017P087CC-SCONN2A   I178 @S9S_MB_2U_LIB.S9S_MB_2U(SCH_1):PAGE111
   J30  253 VSS110 SCONN288_ADR50017P087CC-SCONN2A   I178 @S9S_MB_2U_LIB.S9S_MB_2U(SCH_1):PAGE111
   J30  255 VSS111 SCONN288_ADR50017P087CC-SCONN2A   I178 @S9S_MB_2U_LIB.S9S_MB_2U(SCH_1):PAGE111
   J30  257 VSS112 SCONN288_ADR50017P087CC-SCONN2A   I178 @S9S_MB_2U_LIB.S9S_MB_2U(SCH_1):PAGE111
   J30  259 VSS113 SCONN288_ADR50017P087CC-SCONN2A   I178 @S9S_MB_2U_LIB.S9S_MB_2U(SCH_1):PAGE111
   J30  262 VSS114 SCONN288_ADR50017P087CC-SCONN2A   I178 @S9S_MB_2U_LIB.S9S_MB_2U(SCH_1):PAGE111
   J30  264 VSS115 SCONN288_ADR50017P087CC-SCONN2A   I178 @S9S_MB_2U_LIB.S9S_MB_2U(SCH_1):PAGE111
   J30  266 VSS116 SCONN288_ADR50017P087CC-SCONN2A   I178 @S9S_MB_2U_LIB.S9S_MB_2U(SCH_1):PAGE111
   J30  268 VSS117 SCONN288_ADR50017P087CC-SCONN2A   I178 @S9S_MB_2U_LIB.S9S_MB_2U(SCH_1):PAGE111
   J30  270 VSS118 SCONN288_ADR50017P087CC-SCONN2A   I178 @S9S_MB_2U_LIB.S9S_MB_2U(SCH_1):PAGE111
   J30  273 VSS119 SCONN288_ADR50017P087CC-SCONN2A   I178 @S9S_MB_2U_LIB.S9S_MB_2U(SCH_1):PAGE111
   J30  275 VSS120 SCONN288_ADR50017P087CC-SCONN2A   I178 @S9S_MB_2U_LIB.S9S_MB_2U(SCH_1):PAGE111
   J30  277 VSS121 SCONN288_ADR50017P087CC-SCONN2A   I178 @S9S_MB_2U_LIB.S9S_MB_2U(SCH_1):PAGE111
   J30  279 VSS122 SCONN288_ADR50017P087CC-SCONN2A   I178 @S9S_MB_2U_LIB.S9S_MB_2U(SCH_1):PAGE111
   J30  281 VSS123 SCONN288_ADR50017P087CC-SCONN2A   I178 @S9S_MB_2U_LIB.S9S_MB_2U(SCH_1):PAGE111
   J30  284 VSS124 SCONN288_ADR50017P087CC-SCONN2A   I178 @S9S_MB_2U_LIB.S9S_MB_2U(SCH_1):PAGE111
   J30  286 VSS125 SCONN288_ADR50017P087CC-SCONN2A   I178 @S9S_MB_2U_LIB.S9S_MB_2U(SCH_1):PAGE111
   J30  288 VSS126 SCONN288_ADR50017P087CC-SCONN2A   I178 @S9S_MB_2U_LIB.S9S_MB_2U(SCH_1):PAGE111
   R73    2      B Q_RES_0402LF-127K,1%,1/16W,CHIA     I3 @S9S_MB_2U_LIB.S9S_MB_2U(SCH_1):PAGE112
   C75    2      B Q_CAP_C0402-2.2UF,6.3V,20%,X6SA   I124 @S9S_MB_2U_LIB.S9S_MB_2U(SCH_1):PAGE112
   C76    2      B Q_CAP_C0805-10UF,16V,10%,X6S,CA   I125 @S9S_MB_2U_LIB.S9S_MB_2U(SCH_1):PAGE112
   C77    2      B Q_CAP_C0805-10UF,16V,10%,X6S,CA   I126 @S9S_MB_2U_LIB.S9S_MB_2U(SCH_1):PAGE112
   J31   G1     G1 SCONN288_ADR50017P130CC-SCONN2A   I178 @S9S_MB_2U_LIB.S9S_MB_2U(SCH_1):PAGE112
   J31   G2     G2 SCONN288_ADR50017P130CC-SCONN2A   I178 @S9S_MB_2U_LIB.S9S_MB_2U(SCH_1):PAGE112
   J31   G3     G3 SCONN288_ADR50017P130CC-SCONN2A   I178 @S9S_MB_2U_LIB.S9S_MB_2U(SCH_1):PAGE112
   J31    6   VSS0 SCONN288_ADR50017P130CC-SCONN2A   I178 @S9S_MB_2U_LIB.S9S_MB_2U(SCH_1):PAGE112
   J31    8   VSS1 SCONN288_ADR50017P130CC-SCONN2A   I178 @S9S_MB_2U_LIB.S9S_MB_2U(SCH_1):PAGE112
   J31   10   VSS2 SCONN288_ADR50017P130CC-SCONN2A   I178 @S9S_MB_2U_LIB.S9S_MB_2U(SCH_1):PAGE112
   J31   13   VSS3 SCONN288_ADR50017P130CC-SCONN2A   I178 @S9S_MB_2U_LIB.S9S_MB_2U(SCH_1):PAGE112
   J31   15   VSS4 SCONN288_ADR50017P130CC-SCONN2A   I178 @S9S_MB_2U_LIB.S9S_MB_2U(SCH_1):PAGE112
   J31   17   VSS5 SCONN288_ADR50017P130CC-SCONN2A   I178 @S9S_MB_2U_LIB.S9S_MB_2U(SCH_1):PAGE112
   J31   19   VSS6 SCONN288_ADR50017P130CC-SCONN2A   I178 @S9S_MB_2U_LIB.S9S_MB_2U(SCH_1):PAGE112
   J31   21   VSS7 SCONN288_ADR50017P130CC-SCONN2A   I178 @S9S_MB_2U_LIB.S9S_MB_2U(SCH_1):PAGE112
   J31   24   VSS8 SCONN288_ADR50017P130CC-SCONN2A   I178 @S9S_MB_2U_LIB.S9S_MB_2U(SCH_1):PAGE112
   J31   26   VSS9 SCONN288_ADR50017P130CC-SCONN2A   I178 @S9S_MB_2U_LIB.S9S_MB_2U(SCH_1):PAGE112
   J31   28  VSS10 SCONN288_ADR50017P130CC-SCONN2A   I178 @S9S_MB_2U_LIB.S9S_MB_2U(SCH_1):PAGE112
   J31   30  VSS11 SCONN288_ADR50017P130CC-SCONN2A   I178 @S9S_MB_2U_LIB.S9S_MB_2U(SCH_1):PAGE112
   J31   32  VSS12 SCONN288_ADR50017P130CC-SCONN2A   I178 @S9S_MB_2U_LIB.S9S_MB_2U(SCH_1):PAGE112
   J31   35  VSS13 SCONN288_ADR50017P130CC-SCONN2A   I178 @S9S_MB_2U_LIB.S9S_MB_2U(SCH_1):PAGE112
   J31   37  VSS14 SCONN288_ADR50017P130CC-SCONN2A   I178 @S9S_MB_2U_LIB.S9S_MB_2U(SCH_1):PAGE112
   J31   39  VSS15 SCONN288_ADR50017P130CC-SCONN2A   I178 @S9S_MB_2U_LIB.S9S_MB_2U(SCH_1):PAGE112
   J31   41  VSS16 SCONN288_ADR50017P130CC-SCONN2A   I178 @S9S_MB_2U_LIB.S9S_MB_2U(SCH_1):PAGE112
   J31   43  VSS17 SCONN288_ADR50017P130CC-SCONN2A   I178 @S9S_MB_2U_LIB.S9S_MB_2U(SCH_1):PAGE112
   J31   46  VSS18 SCONN288_ADR50017P130CC-SCONN2A   I178 @S9S_MB_2U_LIB.S9S_MB_2U(SCH_1):PAGE112
   J31   48  VSS19 SCONN288_ADR50017P130CC-SCONN2A   I178 @S9S_MB_2U_LIB.S9S_MB_2U(SCH_1):PAGE112
   J31   50  VSS20 SCONN288_ADR50017P130CC-SCONN2A   I178 @S9S_MB_2U_LIB.S9S_MB_2U(SCH_1):PAGE112
   J31   52  VSS21 SCONN288_ADR50017P130CC-SCONN2A   I178 @S9S_MB_2U_LIB.S9S_MB_2U(SCH_1):PAGE112
   J31   54  VSS22 SCONN288_ADR50017P130CC-SCONN2A   I178 @S9S_MB_2U_LIB.S9S_MB_2U(SCH_1):PAGE112
   J31   57  VSS23 SCONN288_ADR50017P130CC-SCONN2A   I178 @S9S_MB_2U_LIB.S9S_MB_2U(SCH_1):PAGE112
   J31   59  VSS24 SCONN288_ADR50017P130CC-SCONN2A   I178 @S9S_MB_2U_LIB.S9S_MB_2U(SCH_1):PAGE112
   J31   61  VSS25 SCONN288_ADR50017P130CC-SCONN2A   I178 @S9S_MB_2U_LIB.S9S_MB_2U(SCH_1):PAGE112
   J31   63  VSS26 SCONN288_ADR50017P130CC-SCONN2A   I178 @S9S_MB_2U_LIB.S9S_MB_2U(SCH_1):PAGE112
   J31   65  VSS27 SCONN288_ADR50017P130CC-SCONN2A   I178 @S9S_MB_2U_LIB.S9S_MB_2U(SCH_1):PAGE112
   J31   67  VSS28 SCONN288_ADR50017P130CC-SCONN2A   I178 @S9S_MB_2U_LIB.S9S_MB_2U(SCH_1):PAGE112
   J31   69  VSS29 SCONN288_ADR50017P130CC-SCONN2A   I178 @S9S_MB_2U_LIB.S9S_MB_2U(SCH_1):PAGE112
   J31   71  VSS30 SCONN288_ADR50017P130CC-SCONN2A   I178 @S9S_MB_2U_LIB.S9S_MB_2U(SCH_1):PAGE112
   J31   73  VSS31 SCONN288_ADR50017P130CC-SCONN2A   I178 @S9S_MB_2U_LIB.S9S_MB_2U(SCH_1):PAGE112
   J31   75  VSS32 SCONN288_ADR50017P130CC-SCONN2A   I178 @S9S_MB_2U_LIB.S9S_MB_2U(SCH_1):PAGE112
   J31   77  VSS33 SCONN288_ADR50017P130CC-SCONN2A   I178 @S9S_MB_2U_LIB.S9S_MB_2U(SCH_1):PAGE112
   J31   79  VSS34 SCONN288_ADR50017P130CC-SCONN2A   I178 @S9S_MB_2U_LIB.S9S_MB_2U(SCH_1):PAGE112
   J31   81  VSS35 SCONN288_ADR50017P130CC-SCONN2A   I178 @S9S_MB_2U_LIB.S9S_MB_2U(SCH_1):PAGE112
   J31   83  VSS36 SCONN288_ADR50017P130CC-SCONN2A   I178 @S9S_MB_2U_LIB.S9S_MB_2U(SCH_1):PAGE112
   J31   85  VSS37 SCONN288_ADR50017P130CC-SCONN2A   I178 @S9S_MB_2U_LIB.S9S_MB_2U(SCH_1):PAGE112
   J31   88  VSS38 SCONN288_ADR50017P130CC-SCONN2A   I178 @S9S_MB_2U_LIB.S9S_MB_2U(SCH_1):PAGE112
   J31   90  VSS39 SCONN288_ADR50017P130CC-SCONN2A   I178 @S9S_MB_2U_LIB.S9S_MB_2U(SCH_1):PAGE112
   J31   92  VSS40 SCONN288_ADR50017P130CC-SCONN2A   I178 @S9S_MB_2U_LIB.S9S_MB_2U(SCH_1):PAGE112
   J31   95  VSS41 SCONN288_ADR50017P130CC-SCONN2A   I178 @S9S_MB_2U_LIB.S9S_MB_2U(SCH_1):PAGE112
   J31   97  VSS42 SCONN288_ADR50017P130CC-SCONN2A   I178 @S9S_MB_2U_LIB.S9S_MB_2U(SCH_1):PAGE112
   J31   99  VSS43 SCONN288_ADR50017P130CC-SCONN2A   I178 @S9S_MB_2U_LIB.S9S_MB_2U(SCH_1):PAGE112
   J31  101  VSS44 SCONN288_ADR50017P130CC-SCONN2A   I178 @S9S_MB_2U_LIB.S9S_MB_2U(SCH_1):PAGE112
   J31  103  VSS45 SCONN288_ADR50017P130CC-SCONN2A   I178 @S9S_MB_2U_LIB.S9S_MB_2U(SCH_1):PAGE112
   J31  106  VSS46 SCONN288_ADR50017P130CC-SCONN2A   I178 @S9S_MB_2U_LIB.S9S_MB_2U(SCH_1):PAGE112
   J31  108  VSS47 SCONN288_ADR50017P130CC-SCONN2A   I178 @S9S_MB_2U_LIB.S9S_MB_2U(SCH_1):PAGE112
   J31  110  VSS48 SCONN288_ADR50017P130CC-SCONN2A   I178 @S9S_MB_2U_LIB.S9S_MB_2U(SCH_1):PAGE112
   J31  112  VSS49 SCONN288_ADR50017P130CC-SCONN2A   I178 @S9S_MB_2U_LIB.S9S_MB_2U(SCH_1):PAGE112
   J31  114  VSS50 SCONN288_ADR50017P130CC-SCONN2A   I178 @S9S_MB_2U_LIB.S9S_MB_2U(SCH_1):PAGE112
   J31  117  VSS51 SCONN288_ADR50017P130CC-SCONN2A   I178 @S9S_MB_2U_LIB.S9S_MB_2U(SCH_1):PAGE112
   J31  119  VSS52 SCONN288_ADR50017P130CC-SCONN2A   I178 @S9S_MB_2U_LIB.S9S_MB_2U(SCH_1):PAGE112
   J31  121  VSS53 SCONN288_ADR50017P130CC-SCONN2A   I178 @S9S_MB_2U_LIB.S9S_MB_2U(SCH_1):PAGE112
   J31  123  VSS54 SCONN288_ADR50017P130CC-SCONN2A   I178 @S9S_MB_2U_LIB.S9S_MB_2U(SCH_1):PAGE112
   J31  125  VSS55 SCONN288_ADR50017P130CC-SCONN2A   I178 @S9S_MB_2U_LIB.S9S_MB_2U(SCH_1):PAGE112
   J31  128  VSS56 SCONN288_ADR50017P130CC-SCONN2A   I178 @S9S_MB_2U_LIB.S9S_MB_2U(SCH_1):PAGE112
   J31  130  VSS57 SCONN288_ADR50017P130CC-SCONN2A   I178 @S9S_MB_2U_LIB.S9S_MB_2U(SCH_1):PAGE112
   J31  132  VSS58 SCONN288_ADR50017P130CC-SCONN2A   I178 @S9S_MB_2U_LIB.S9S_MB_2U(SCH_1):PAGE112
   J31  134  VSS59 SCONN288_ADR50017P130CC-SCONN2A   I178 @S9S_MB_2U_LIB.S9S_MB_2U(SCH_1):PAGE112
   J31  136  VSS60 SCONN288_ADR50017P130CC-SCONN2A   I178 @S9S_MB_2U_LIB.S9S_MB_2U(SCH_1):PAGE112
   J31  139  VSS61 SCONN288_ADR50017P130CC-SCONN2A   I178 @S9S_MB_2U_LIB.S9S_MB_2U(SCH_1):PAGE112
   J31  141  VSS62 SCONN288_ADR50017P130CC-SCONN2A   I178 @S9S_MB_2U_LIB.S9S_MB_2U(SCH_1):PAGE112
   J31  143  VSS63 SCONN288_ADR50017P130CC-SCONN2A   I178 @S9S_MB_2U_LIB.S9S_MB_2U(SCH_1):PAGE112
   J31  151  VSS64 SCONN288_ADR50017P130CC-SCONN2A   I178 @S9S_MB_2U_LIB.S9S_MB_2U(SCH_1):PAGE112
   J31  153  VSS65 SCONN288_ADR50017P130CC-SCONN2A   I178 @S9S_MB_2U_LIB.S9S_MB_2U(SCH_1):PAGE112
   J31  155  VSS66 SCONN288_ADR50017P130CC-SCONN2A   I178 @S9S_MB_2U_LIB.S9S_MB_2U(SCH_1):PAGE112
   J31  158  VSS67 SCONN288_ADR50017P130CC-SCONN2A   I178 @S9S_MB_2U_LIB.S9S_MB_2U(SCH_1):PAGE112
   J31  160  VSS68 SCONN288_ADR50017P130CC-SCONN2A   I178 @S9S_MB_2U_LIB.S9S_MB_2U(SCH_1):PAGE112
   J31  162  VSS69 SCONN288_ADR50017P130CC-SCONN2A   I178 @S9S_MB_2U_LIB.S9S_MB_2U(SCH_1):PAGE112
   J31  164  VSS70 SCONN288_ADR50017P130CC-SCONN2A   I178 @S9S_MB_2U_LIB.S9S_MB_2U(SCH_1):PAGE112
   J31  166  VSS71 SCONN288_ADR50017P130CC-SCONN2A   I178 @S9S_MB_2U_LIB.S9S_MB_2U(SCH_1):PAGE112
   J31  169  VSS72 SCONN288_ADR50017P130CC-SCONN2A   I178 @S9S_MB_2U_LIB.S9S_MB_2U(SCH_1):PAGE112
   J31  171  VSS73 SCONN288_ADR50017P130CC-SCONN2A   I178 @S9S_MB_2U_LIB.S9S_MB_2U(SCH_1):PAGE112
   J31  173  VSS74 SCONN288_ADR50017P130CC-SCONN2A   I178 @S9S_MB_2U_LIB.S9S_MB_2U(SCH_1):PAGE112
   J31  175  VSS75 SCONN288_ADR50017P130CC-SCONN2A   I178 @S9S_MB_2U_LIB.S9S_MB_2U(SCH_1):PAGE112
   J31  177  VSS76 SCONN288_ADR50017P130CC-SCONN2A   I178 @S9S_MB_2U_LIB.S9S_MB_2U(SCH_1):PAGE112
   J31  180  VSS77 SCONN288_ADR50017P130CC-SCONN2A   I178 @S9S_MB_2U_LIB.S9S_MB_2U(SCH_1):PAGE112
   J31  182  VSS78 SCONN288_ADR50017P130CC-SCONN2A   I178 @S9S_MB_2U_LIB.S9S_MB_2U(SCH_1):PAGE112
   J31  184  VSS79 SCONN288_ADR50017P130CC-SCONN2A   I178 @S9S_MB_2U_LIB.S9S_MB_2U(SCH_1):PAGE112
   J31  186  VSS80 SCONN288_ADR50017P130CC-SCONN2A   I178 @S9S_MB_2U_LIB.S9S_MB_2U(SCH_1):PAGE112
   J31  188  VSS81 SCONN288_ADR50017P130CC-SCONN2A   I178 @S9S_MB_2U_LIB.S9S_MB_2U(SCH_1):PAGE112
   J31  191  VSS82 SCONN288_ADR50017P130CC-SCONN2A   I178 @S9S_MB_2U_LIB.S9S_MB_2U(SCH_1):PAGE112
   J31  193  VSS83 SCONN288_ADR50017P130CC-SCONN2A   I178 @S9S_MB_2U_LIB.S9S_MB_2U(SCH_1):PAGE112
   J31  195  VSS84 SCONN288_ADR50017P130CC-SCONN2A   I178 @S9S_MB_2U_LIB.S9S_MB_2U(SCH_1):PAGE112
   J31  197  VSS85 SCONN288_ADR50017P130CC-SCONN2A   I178 @S9S_MB_2U_LIB.S9S_MB_2U(SCH_1):PAGE112
   J31  199  VSS86 SCONN288_ADR50017P130CC-SCONN2A   I178 @S9S_MB_2U_LIB.S9S_MB_2U(SCH_1):PAGE112
   J31  202  VSS87 SCONN288_ADR50017P130CC-SCONN2A   I178 @S9S_MB_2U_LIB.S9S_MB_2U(SCH_1):PAGE112
   J31  204  VSS88 SCONN288_ADR50017P130CC-SCONN2A   I178 @S9S_MB_2U_LIB.S9S_MB_2U(SCH_1):PAGE112
   J31  206  VSS89 SCONN288_ADR50017P130CC-SCONN2A   I178 @S9S_MB_2U_LIB.S9S_MB_2U(SCH_1):PAGE112
   J31  208  VSS90 SCONN288_ADR50017P130CC-SCONN2A   I178 @S9S_MB_2U_LIB.S9S_MB_2U(SCH_1):PAGE112
   J31  210  VSS91 SCONN288_ADR50017P130CC-SCONN2A   I178 @S9S_MB_2U_LIB.S9S_MB_2U(SCH_1):PAGE112
   J31  212  VSS92 SCONN288_ADR50017P130CC-SCONN2A   I178 @S9S_MB_2U_LIB.S9S_MB_2U(SCH_1):PAGE112
   J31  214  VSS93 SCONN288_ADR50017P130CC-SCONN2A   I178 @S9S_MB_2U_LIB.S9S_MB_2U(SCH_1):PAGE112
   J31  216  VSS94 SCONN288_ADR50017P130CC-SCONN2A   I178 @S9S_MB_2U_LIB.S9S_MB_2U(SCH_1):PAGE112
   J31  219  VSS95 SCONN288_ADR50017P130CC-SCONN2A   I178 @S9S_MB_2U_LIB.S9S_MB_2U(SCH_1):PAGE112
   J31  222  VSS96 SCONN288_ADR50017P130CC-SCONN2A   I178 @S9S_MB_2U_LIB.S9S_MB_2U(SCH_1):PAGE112
   J31  224  VSS97 SCONN288_ADR50017P130CC-SCONN2A   I178 @S9S_MB_2U_LIB.S9S_MB_2U(SCH_1):PAGE112
   J31  226  VSS98 SCONN288_ADR50017P130CC-SCONN2A   I178 @S9S_MB_2U_LIB.S9S_MB_2U(SCH_1):PAGE112
   J31  228  VSS99 SCONN288_ADR50017P130CC-SCONN2A   I178 @S9S_MB_2U_LIB.S9S_MB_2U(SCH_1):PAGE112
   J31  230 VSS100 SCONN288_ADR50017P130CC-SCONN2A   I178 @S9S_MB_2U_LIB.S9S_MB_2U(SCH_1):PAGE112
   J31  233 VSS101 SCONN288_ADR50017P130CC-SCONN2A   I178 @S9S_MB_2U_LIB.S9S_MB_2U(SCH_1):PAGE112
   J31  235 VSS102 SCONN288_ADR50017P130CC-SCONN2A   I178 @S9S_MB_2U_LIB.S9S_MB_2U(SCH_1):PAGE112
   J31  237 VSS103 SCONN288_ADR50017P130CC-SCONN2A   I178 @S9S_MB_2U_LIB.S9S_MB_2U(SCH_1):PAGE112
   J31  240 VSS104 SCONN288_ADR50017P130CC-SCONN2A   I178 @S9S_MB_2U_LIB.S9S_MB_2U(SCH_1):PAGE112
   J31  242 VSS105 SCONN288_ADR50017P130CC-SCONN2A   I178 @S9S_MB_2U_LIB.S9S_MB_2U(SCH_1):PAGE112
   J31  244 VSS106 SCONN288_ADR50017P130CC-SCONN2A   I178 @S9S_MB_2U_LIB.S9S_MB_2U(SCH_1):PAGE112
   J31  246 VSS107 SCONN288_ADR50017P130CC-SCONN2A   I178 @S9S_MB_2U_LIB.S9S_MB_2U(SCH_1):PAGE112
   J31  248 VSS108 SCONN288_ADR50017P130CC-SCONN2A   I178 @S9S_MB_2U_LIB.S9S_MB_2U(SCH_1):PAGE112
   J31  251 VSS109 SCONN288_ADR50017P130CC-SCONN2A   I178 @S9S_MB_2U_LIB.S9S_MB_2U(SCH_1):PAGE112
   J31  253 VSS110 SCONN288_ADR50017P130CC-SCONN2A   I178 @S9S_MB_2U_LIB.S9S_MB_2U(SCH_1):PAGE112
   J31  255 VSS111 SCONN288_ADR50017P130CC-SCONN2A   I178 @S9S_MB_2U_LIB.S9S_MB_2U(SCH_1):PAGE112
   J31  257 VSS112 SCONN288_ADR50017P130CC-SCONN2A   I178 @S9S_MB_2U_LIB.S9S_MB_2U(SCH_1):PAGE112
   J31  259 VSS113 SCONN288_ADR50017P130CC-SCONN2A   I178 @S9S_MB_2U_LIB.S9S_MB_2U(SCH_1):PAGE112
   J31  262 VSS114 SCONN288_ADR50017P130CC-SCONN2A   I178 @S9S_MB_2U_LIB.S9S_MB_2U(SCH_1):PAGE112
   J31  264 VSS115 SCONN288_ADR50017P130CC-SCONN2A   I178 @S9S_MB_2U_LIB.S9S_MB_2U(SCH_1):PAGE112
   J31  266 VSS116 SCONN288_ADR50017P130CC-SCONN2A   I178 @S9S_MB_2U_LIB.S9S_MB_2U(SCH_1):PAGE112
   J31  268 VSS117 SCONN288_ADR50017P130CC-SCONN2A   I178 @S9S_MB_2U_LIB.S9S_MB_2U(SCH_1):PAGE112
   J31  270 VSS118 SCONN288_ADR50017P130CC-SCONN2A   I178 @S9S_MB_2U_LIB.S9S_MB_2U(SCH_1):PAGE112
   J31  273 VSS119 SCONN288_ADR50017P130CC-SCONN2A   I178 @S9S_MB_2U_LIB.S9S_MB_2U(SCH_1):PAGE112
   J31  275 VSS120 SCONN288_ADR50017P130CC-SCONN2A   I178 @S9S_MB_2U_LIB.S9S_MB_2U(SCH_1):PAGE112
   J31  277 VSS121 SCONN288_ADR50017P130CC-SCONN2A   I178 @S9S_MB_2U_LIB.S9S_MB_2U(SCH_1):PAGE112
   J31  279 VSS122 SCONN288_ADR50017P130CC-SCONN2A   I178 @S9S_MB_2U_LIB.S9S_MB_2U(SCH_1):PAGE112
   J31  281 VSS123 SCONN288_ADR50017P130CC-SCONN2A   I178 @S9S_MB_2U_LIB.S9S_MB_2U(SCH_1):PAGE112
   J31  284 VSS124 SCONN288_ADR50017P130CC-SCONN2A   I178 @S9S_MB_2U_LIB.S9S_MB_2U(SCH_1):PAGE112
   J31  286 VSS125 SCONN288_ADR50017P130CC-SCONN2A   I178 @S9S_MB_2U_LIB.S9S_MB_2U(SCH_1):PAGE112
   J31  288 VSS126 SCONN288_ADR50017P130CC-SCONN2A   I178 @S9S_MB_2U_LIB.S9S_MB_2U(SCH_1):PAGE112
   R72    2      B Q_RES_0402LF-196K,1%,1/16W,CHIA     I2 @S9S_MB_2U_LIB.S9S_MB_2U(SCH_1):PAGE113
   C72    2      B Q_CAP_C0402-2.2UF,6.3V,20%,X6SA   I116 @S9S_MB_2U_LIB.S9S_MB_2U(SCH_1):PAGE113
   C73    2      B Q_CAP_C0805-10UF,16V,10%,X6S,CA   I120 @S9S_MB_2U_LIB.S9S_MB_2U(SCH_1):PAGE113
   C74    2      B Q_CAP_C0805-10UF,16V,10%,X6S,CA   I122 @S9S_MB_2U_LIB.S9S_MB_2U(SCH_1):PAGE113
   J32   G1     G1 SCONN288_ADR50017P087CC-SCONN2A   I177 @S9S_MB_2U_LIB.S9S_MB_2U(SCH_1):PAGE113
   J32   G2     G2 SCONN288_ADR50017P087CC-SCONN2A   I177 @S9S_MB_2U_LIB.S9S_MB_2U(SCH_1):PAGE113
   J32   G3     G3 SCONN288_ADR50017P087CC-SCONN2A   I177 @S9S_MB_2U_LIB.S9S_MB_2U(SCH_1):PAGE113
   J32    6   VSS0 SCONN288_ADR50017P087CC-SCONN2A   I177 @S9S_MB_2U_LIB.S9S_MB_2U(SCH_1):PAGE113
   J32    8   VSS1 SCONN288_ADR50017P087CC-SCONN2A   I177 @S9S_MB_2U_LIB.S9S_MB_2U(SCH_1):PAGE113
   J32   10   VSS2 SCONN288_ADR50017P087CC-SCONN2A   I177 @S9S_MB_2U_LIB.S9S_MB_2U(SCH_1):PAGE113
   J32   13   VSS3 SCONN288_ADR50017P087CC-SCONN2A   I177 @S9S_MB_2U_LIB.S9S_MB_2U(SCH_1):PAGE113
   J32   15   VSS4 SCONN288_ADR50017P087CC-SCONN2A   I177 @S9S_MB_2U_LIB.S9S_MB_2U(SCH_1):PAGE113
   J32   17   VSS5 SCONN288_ADR50017P087CC-SCONN2A   I177 @S9S_MB_2U_LIB.S9S_MB_2U(SCH_1):PAGE113
   J32   19   VSS6 SCONN288_ADR50017P087CC-SCONN2A   I177 @S9S_MB_2U_LIB.S9S_MB_2U(SCH_1):PAGE113
   J32   21   VSS7 SCONN288_ADR50017P087CC-SCONN2A   I177 @S9S_MB_2U_LIB.S9S_MB_2U(SCH_1):PAGE113
   J32   24   VSS8 SCONN288_ADR50017P087CC-SCONN2A   I177 @S9S_MB_2U_LIB.S9S_MB_2U(SCH_1):PAGE113
   J32   26   VSS9 SCONN288_ADR50017P087CC-SCONN2A   I177 @S9S_MB_2U_LIB.S9S_MB_2U(SCH_1):PAGE113
   J32   28  VSS10 SCONN288_ADR50017P087CC-SCONN2A   I177 @S9S_MB_2U_LIB.S9S_MB_2U(SCH_1):PAGE113
   J32   30  VSS11 SCONN288_ADR50017P087CC-SCONN2A   I177 @S9S_MB_2U_LIB.S9S_MB_2U(SCH_1):PAGE113
   J32   32  VSS12 SCONN288_ADR50017P087CC-SCONN2A   I177 @S9S_MB_2U_LIB.S9S_MB_2U(SCH_1):PAGE113
   J32   35  VSS13 SCONN288_ADR50017P087CC-SCONN2A   I177 @S9S_MB_2U_LIB.S9S_MB_2U(SCH_1):PAGE113
   J32   37  VSS14 SCONN288_ADR50017P087CC-SCONN2A   I177 @S9S_MB_2U_LIB.S9S_MB_2U(SCH_1):PAGE113
   J32   39  VSS15 SCONN288_ADR50017P087CC-SCONN2A   I177 @S9S_MB_2U_LIB.S9S_MB_2U(SCH_1):PAGE113
   J32   41  VSS16 SCONN288_ADR50017P087CC-SCONN2A   I177 @S9S_MB_2U_LIB.S9S_MB_2U(SCH_1):PAGE113
   J32   43  VSS17 SCONN288_ADR50017P087CC-SCONN2A   I177 @S9S_MB_2U_LIB.S9S_MB_2U(SCH_1):PAGE113
   J32   46  VSS18 SCONN288_ADR50017P087CC-SCONN2A   I177 @S9S_MB_2U_LIB.S9S_MB_2U(SCH_1):PAGE113
   J32   48  VSS19 SCONN288_ADR50017P087CC-SCONN2A   I177 @S9S_MB_2U_LIB.S9S_MB_2U(SCH_1):PAGE113
   J32   50  VSS20 SCONN288_ADR50017P087CC-SCONN2A   I177 @S9S_MB_2U_LIB.S9S_MB_2U(SCH_1):PAGE113
   J32   52  VSS21 SCONN288_ADR50017P087CC-SCONN2A   I177 @S9S_MB_2U_LIB.S9S_MB_2U(SCH_1):PAGE113
   J32   54  VSS22 SCONN288_ADR50017P087CC-SCONN2A   I177 @S9S_MB_2U_LIB.S9S_MB_2U(SCH_1):PAGE113
   J32   57  VSS23 SCONN288_ADR50017P087CC-SCONN2A   I177 @S9S_MB_2U_LIB.S9S_MB_2U(SCH_1):PAGE113
   J32   59  VSS24 SCONN288_ADR50017P087CC-SCONN2A   I177 @S9S_MB_2U_LIB.S9S_MB_2U(SCH_1):PAGE113
   J32   61  VSS25 SCONN288_ADR50017P087CC-SCONN2A   I177 @S9S_MB_2U_LIB.S9S_MB_2U(SCH_1):PAGE113
   J32   63  VSS26 SCONN288_ADR50017P087CC-SCONN2A   I177 @S9S_MB_2U_LIB.S9S_MB_2U(SCH_1):PAGE113
   J32   65  VSS27 SCONN288_ADR50017P087CC-SCONN2A   I177 @S9S_MB_2U_LIB.S9S_MB_2U(SCH_1):PAGE113
   J32   67  VSS28 SCONN288_ADR50017P087CC-SCONN2A   I177 @S9S_MB_2U_LIB.S9S_MB_2U(SCH_1):PAGE113
   J32   69  VSS29 SCONN288_ADR50017P087CC-SCONN2A   I177 @S9S_MB_2U_LIB.S9S_MB_2U(SCH_1):PAGE113
   J32   71  VSS30 SCONN288_ADR50017P087CC-SCONN2A   I177 @S9S_MB_2U_LIB.S9S_MB_2U(SCH_1):PAGE113
   J32   73  VSS31 SCONN288_ADR50017P087CC-SCONN2A   I177 @S9S_MB_2U_LIB.S9S_MB_2U(SCH_1):PAGE113
   J32   75  VSS32 SCONN288_ADR50017P087CC-SCONN2A   I177 @S9S_MB_2U_LIB.S9S_MB_2U(SCH_1):PAGE113
   J32   77  VSS33 SCONN288_ADR50017P087CC-SCONN2A   I177 @S9S_MB_2U_LIB.S9S_MB_2U(SCH_1):PAGE113
   J32   79  VSS34 SCONN288_ADR50017P087CC-SCONN2A   I177 @S9S_MB_2U_LIB.S9S_MB_2U(SCH_1):PAGE113
   J32   81  VSS35 SCONN288_ADR50017P087CC-SCONN2A   I177 @S9S_MB_2U_LIB.S9S_MB_2U(SCH_1):PAGE113
   J32   83  VSS36 SCONN288_ADR50017P087CC-SCONN2A   I177 @S9S_MB_2U_LIB.S9S_MB_2U(SCH_1):PAGE113
   J32   85  VSS37 SCONN288_ADR50017P087CC-SCONN2A   I177 @S9S_MB_2U_LIB.S9S_MB_2U(SCH_1):PAGE113
   J32   88  VSS38 SCONN288_ADR50017P087CC-SCONN2A   I177 @S9S_MB_2U_LIB.S9S_MB_2U(SCH_1):PAGE113
   J32   90  VSS39 SCONN288_ADR50017P087CC-SCONN2A   I177 @S9S_MB_2U_LIB.S9S_MB_2U(SCH_1):PAGE113
   J32   92  VSS40 SCONN288_ADR50017P087CC-SCONN2A   I177 @S9S_MB_2U_LIB.S9S_MB_2U(SCH_1):PAGE113
   J32   95  VSS41 SCONN288_ADR50017P087CC-SCONN2A   I177 @S9S_MB_2U_LIB.S9S_MB_2U(SCH_1):PAGE113
   J32   97  VSS42 SCONN288_ADR50017P087CC-SCONN2A   I177 @S9S_MB_2U_LIB.S9S_MB_2U(SCH_1):PAGE113
   J32   99  VSS43 SCONN288_ADR50017P087CC-SCONN2A   I177 @S9S_MB_2U_LIB.S9S_MB_2U(SCH_1):PAGE113
   J32  101  VSS44 SCONN288_ADR50017P087CC-SCONN2A   I177 @S9S_MB_2U_LIB.S9S_MB_2U(SCH_1):PAGE113
   J32  103  VSS45 SCONN288_ADR50017P087CC-SCONN2A   I177 @S9S_MB_2U_LIB.S9S_MB_2U(SCH_1):PAGE113
   J32  106  VSS46 SCONN288_ADR50017P087CC-SCONN2A   I177 @S9S_MB_2U_LIB.S9S_MB_2U(SCH_1):PAGE113
   J32  108  VSS47 SCONN288_ADR50017P087CC-SCONN2A   I177 @S9S_MB_2U_LIB.S9S_MB_2U(SCH_1):PAGE113
   J32  110  VSS48 SCONN288_ADR50017P087CC-SCONN2A   I177 @S9S_MB_2U_LIB.S9S_MB_2U(SCH_1):PAGE113
   J32  112  VSS49 SCONN288_ADR50017P087CC-SCONN2A   I177 @S9S_MB_2U_LIB.S9S_MB_2U(SCH_1):PAGE113
   J32  114  VSS50 SCONN288_ADR50017P087CC-SCONN2A   I177 @S9S_MB_2U_LIB.S9S_MB_2U(SCH_1):PAGE113
   J32  117  VSS51 SCONN288_ADR50017P087CC-SCONN2A   I177 @S9S_MB_2U_LIB.S9S_MB_2U(SCH_1):PAGE113
   J32  119  VSS52 SCONN288_ADR50017P087CC-SCONN2A   I177 @S9S_MB_2U_LIB.S9S_MB_2U(SCH_1):PAGE113
   J32  121  VSS53 SCONN288_ADR50017P087CC-SCONN2A   I177 @S9S_MB_2U_LIB.S9S_MB_2U(SCH_1):PAGE113
   J32  123  VSS54 SCONN288_ADR50017P087CC-SCONN2A   I177 @S9S_MB_2U_LIB.S9S_MB_2U(SCH_1):PAGE113
   J32  125  VSS55 SCONN288_ADR50017P087CC-SCONN2A   I177 @S9S_MB_2U_LIB.S9S_MB_2U(SCH_1):PAGE113
   J32  128  VSS56 SCONN288_ADR50017P087CC-SCONN2A   I177 @S9S_MB_2U_LIB.S9S_MB_2U(SCH_1):PAGE113
   J32  130  VSS57 SCONN288_ADR50017P087CC-SCONN2A   I177 @S9S_MB_2U_LIB.S9S_MB_2U(SCH_1):PAGE113
   J32  132  VSS58 SCONN288_ADR50017P087CC-SCONN2A   I177 @S9S_MB_2U_LIB.S9S_MB_2U(SCH_1):PAGE113
   J32  134  VSS59 SCONN288_ADR50017P087CC-SCONN2A   I177 @S9S_MB_2U_LIB.S9S_MB_2U(SCH_1):PAGE113
   J32  136  VSS60 SCONN288_ADR50017P087CC-SCONN2A   I177 @S9S_MB_2U_LIB.S9S_MB_2U(SCH_1):PAGE113
   J32  139  VSS61 SCONN288_ADR50017P087CC-SCONN2A   I177 @S9S_MB_2U_LIB.S9S_MB_2U(SCH_1):PAGE113
   J32  141  VSS62 SCONN288_ADR50017P087CC-SCONN2A   I177 @S9S_MB_2U_LIB.S9S_MB_2U(SCH_1):PAGE113
   J32  143  VSS63 SCONN288_ADR50017P087CC-SCONN2A   I177 @S9S_MB_2U_LIB.S9S_MB_2U(SCH_1):PAGE113
   J32  151  VSS64 SCONN288_ADR50017P087CC-SCONN2A   I177 @S9S_MB_2U_LIB.S9S_MB_2U(SCH_1):PAGE113
   J32  153  VSS65 SCONN288_ADR50017P087CC-SCONN2A   I177 @S9S_MB_2U_LIB.S9S_MB_2U(SCH_1):PAGE113
   J32  155  VSS66 SCONN288_ADR50017P087CC-SCONN2A   I177 @S9S_MB_2U_LIB.S9S_MB_2U(SCH_1):PAGE113
   J32  158  VSS67 SCONN288_ADR50017P087CC-SCONN2A   I177 @S9S_MB_2U_LIB.S9S_MB_2U(SCH_1):PAGE113
   J32  160  VSS68 SCONN288_ADR50017P087CC-SCONN2A   I177 @S9S_MB_2U_LIB.S9S_MB_2U(SCH_1):PAGE113
   J32  162  VSS69 SCONN288_ADR50017P087CC-SCONN2A   I177 @S9S_MB_2U_LIB.S9S_MB_2U(SCH_1):PAGE113
   J32  164  VSS70 SCONN288_ADR50017P087CC-SCONN2A   I177 @S9S_MB_2U_LIB.S9S_MB_2U(SCH_1):PAGE113
   J32  166  VSS71 SCONN288_ADR50017P087CC-SCONN2A   I177 @S9S_MB_2U_LIB.S9S_MB_2U(SCH_1):PAGE113
   J32  169  VSS72 SCONN288_ADR50017P087CC-SCONN2A   I177 @S9S_MB_2U_LIB.S9S_MB_2U(SCH_1):PAGE113
   J32  171  VSS73 SCONN288_ADR50017P087CC-SCONN2A   I177 @S9S_MB_2U_LIB.S9S_MB_2U(SCH_1):PAGE113
   J32  173  VSS74 SCONN288_ADR50017P087CC-SCONN2A   I177 @S9S_MB_2U_LIB.S9S_MB_2U(SCH_1):PAGE113
   J32  175  VSS75 SCONN288_ADR50017P087CC-SCONN2A   I177 @S9S_MB_2U_LIB.S9S_MB_2U(SCH_1):PAGE113
   J32  177  VSS76 SCONN288_ADR50017P087CC-SCONN2A   I177 @S9S_MB_2U_LIB.S9S_MB_2U(SCH_1):PAGE113
   J32  180  VSS77 SCONN288_ADR50017P087CC-SCONN2A   I177 @S9S_MB_2U_LIB.S9S_MB_2U(SCH_1):PAGE113
   J32  182  VSS78 SCONN288_ADR50017P087CC-SCONN2A   I177 @S9S_MB_2U_LIB.S9S_MB_2U(SCH_1):PAGE113
   J32  184  VSS79 SCONN288_ADR50017P087CC-SCONN2A   I177 @S9S_MB_2U_LIB.S9S_MB_2U(SCH_1):PAGE113
   J32  186  VSS80 SCONN288_ADR50017P087CC-SCONN2A   I177 @S9S_MB_2U_LIB.S9S_MB_2U(SCH_1):PAGE113
   J32  188  VSS81 SCONN288_ADR50017P087CC-SCONN2A   I177 @S9S_MB_2U_LIB.S9S_MB_2U(SCH_1):PAGE113
   J32  191  VSS82 SCONN288_ADR50017P087CC-SCONN2A   I177 @S9S_MB_2U_LIB.S9S_MB_2U(SCH_1):PAGE113
   J32  193  VSS83 SCONN288_ADR50017P087CC-SCONN2A   I177 @S9S_MB_2U_LIB.S9S_MB_2U(SCH_1):PAGE113
   J32  195  VSS84 SCONN288_ADR50017P087CC-SCONN2A   I177 @S9S_MB_2U_LIB.S9S_MB_2U(SCH_1):PAGE113
   J32  197  VSS85 SCONN288_ADR50017P087CC-SCONN2A   I177 @S9S_MB_2U_LIB.S9S_MB_2U(SCH_1):PAGE113
   J32  199  VSS86 SCONN288_ADR50017P087CC-SCONN2A   I177 @S9S_MB_2U_LIB.S9S_MB_2U(SCH_1):PAGE113
   J32  202  VSS87 SCONN288_ADR50017P087CC-SCONN2A   I177 @S9S_MB_2U_LIB.S9S_MB_2U(SCH_1):PAGE113
   J32  204  VSS88 SCONN288_ADR50017P087CC-SCONN2A   I177 @S9S_MB_2U_LIB.S9S_MB_2U(SCH_1):PAGE113
   J32  206  VSS89 SCONN288_ADR50017P087CC-SCONN2A   I177 @S9S_MB_2U_LIB.S9S_MB_2U(SCH_1):PAGE113
   J32  208  VSS90 SCONN288_ADR50017P087CC-SCONN2A   I177 @S9S_MB_2U_LIB.S9S_MB_2U(SCH_1):PAGE113
   J32  210  VSS91 SCONN288_ADR50017P087CC-SCONN2A   I177 @S9S_MB_2U_LIB.S9S_MB_2U(SCH_1):PAGE113
   J32  212  VSS92 SCONN288_ADR50017P087CC-SCONN2A   I177 @S9S_MB_2U_LIB.S9S_MB_2U(SCH_1):PAGE113
   J32  214  VSS93 SCONN288_ADR50017P087CC-SCONN2A   I177 @S9S_MB_2U_LIB.S9S_MB_2U(SCH_1):PAGE113
   J32  216  VSS94 SCONN288_ADR50017P087CC-SCONN2A   I177 @S9S_MB_2U_LIB.S9S_MB_2U(SCH_1):PAGE113
   J32  219  VSS95 SCONN288_ADR50017P087CC-SCONN2A   I177 @S9S_MB_2U_LIB.S9S_MB_2U(SCH_1):PAGE113
   J32  222  VSS96 SCONN288_ADR50017P087CC-SCONN2A   I177 @S9S_MB_2U_LIB.S9S_MB_2U(SCH_1):PAGE113
   J32  224  VSS97 SCONN288_ADR50017P087CC-SCONN2A   I177 @S9S_MB_2U_LIB.S9S_MB_2U(SCH_1):PAGE113
   J32  226  VSS98 SCONN288_ADR50017P087CC-SCONN2A   I177 @S9S_MB_2U_LIB.S9S_MB_2U(SCH_1):PAGE113
   J32  228  VSS99 SCONN288_ADR50017P087CC-SCONN2A   I177 @S9S_MB_2U_LIB.S9S_MB_2U(SCH_1):PAGE113
   J32  230 VSS100 SCONN288_ADR50017P087CC-SCONN2A   I177 @S9S_MB_2U_LIB.S9S_MB_2U(SCH_1):PAGE113
   J32  233 VSS101 SCONN288_ADR50017P087CC-SCONN2A   I177 @S9S_MB_2U_LIB.S9S_MB_2U(SCH_1):PAGE113
   J32  235 VSS102 SCONN288_ADR50017P087CC-SCONN2A   I177 @S9S_MB_2U_LIB.S9S_MB_2U(SCH_1):PAGE113
   J32  237 VSS103 SCONN288_ADR50017P087CC-SCONN2A   I177 @S9S_MB_2U_LIB.S9S_MB_2U(SCH_1):PAGE113
   J32  240 VSS104 SCONN288_ADR50017P087CC-SCONN2A   I177 @S9S_MB_2U_LIB.S9S_MB_2U(SCH_1):PAGE113
   J32  242 VSS105 SCONN288_ADR50017P087CC-SCONN2A   I177 @S9S_MB_2U_LIB.S9S_MB_2U(SCH_1):PAGE113
   J32  244 VSS106 SCONN288_ADR50017P087CC-SCONN2A   I177 @S9S_MB_2U_LIB.S9S_MB_2U(SCH_1):PAGE113
   J32  246 VSS107 SCONN288_ADR50017P087CC-SCONN2A   I177 @S9S_MB_2U_LIB.S9S_MB_2U(SCH_1):PAGE113
   J32  248 VSS108 SCONN288_ADR50017P087CC-SCONN2A   I177 @S9S_MB_2U_LIB.S9S_MB_2U(SCH_1):PAGE113
   J32  251 VSS109 SCONN288_ADR50017P087CC-SCONN2A   I177 @S9S_MB_2U_LIB.S9S_MB_2U(SCH_1):PAGE113
   J32  253 VSS110 SCONN288_ADR50017P087CC-SCONN2A   I177 @S9S_MB_2U_LIB.S9S_MB_2U(SCH_1):PAGE113
   J32  255 VSS111 SCONN288_ADR50017P087CC-SCONN2A   I177 @S9S_MB_2U_LIB.S9S_MB_2U(SCH_1):PAGE113
   J32  257 VSS112 SCONN288_ADR50017P087CC-SCONN2A   I177 @S9S_MB_2U_LIB.S9S_MB_2U(SCH_1):PAGE113
   J32  259 VSS113 SCONN288_ADR50017P087CC-SCONN2A   I177 @S9S_MB_2U_LIB.S9S_MB_2U(SCH_1):PAGE113
   J32  262 VSS114 SCONN288_ADR50017P087CC-SCONN2A   I177 @S9S_MB_2U_LIB.S9S_MB_2U(SCH_1):PAGE113
   J32  264 VSS115 SCONN288_ADR50017P087CC-SCONN2A   I177 @S9S_MB_2U_LIB.S9S_MB_2U(SCH_1):PAGE113
   J32  266 VSS116 SCONN288_ADR50017P087CC-SCONN2A   I177 @S9S_MB_2U_LIB.S9S_MB_2U(SCH_1):PAGE113
   J32  268 VSS117 SCONN288_ADR50017P087CC-SCONN2A   I177 @S9S_MB_2U_LIB.S9S_MB_2U(SCH_1):PAGE113
   J32  270 VSS118 SCONN288_ADR50017P087CC-SCONN2A   I177 @S9S_MB_2U_LIB.S9S_MB_2U(SCH_1):PAGE113
   J32  273 VSS119 SCONN288_ADR50017P087CC-SCONN2A   I177 @S9S_MB_2U_LIB.S9S_MB_2U(SCH_1):PAGE113
   J32  275 VSS120 SCONN288_ADR50017P087CC-SCONN2A   I177 @S9S_MB_2U_LIB.S9S_MB_2U(SCH_1):PAGE113
   J32  277 VSS121 SCONN288_ADR50017P087CC-SCONN2A   I177 @S9S_MB_2U_LIB.S9S_MB_2U(SCH_1):PAGE113
   J32  279 VSS122 SCONN288_ADR50017P087CC-SCONN2A   I177 @S9S_MB_2U_LIB.S9S_MB_2U(SCH_1):PAGE113
   J32  281 VSS123 SCONN288_ADR50017P087CC-SCONN2A   I177 @S9S_MB_2U_LIB.S9S_MB_2U(SCH_1):PAGE113
   J32  284 VSS124 SCONN288_ADR50017P087CC-SCONN2A   I177 @S9S_MB_2U_LIB.S9S_MB_2U(SCH_1):PAGE113
   J32  286 VSS125 SCONN288_ADR50017P087CC-SCONN2A   I177 @S9S_MB_2U_LIB.S9S_MB_2U(SCH_1):PAGE113
   J32  288 VSS126 SCONN288_ADR50017P087CC-SCONN2A   I177 @S9S_MB_2U_LIB.S9S_MB_2U(SCH_1):PAGE113
 R1241    2      B Q_RES_0402LF-249,1%,1/16W,CHIPA    I17 @S9S_MB_2U_LIB.S9S_MB_2U(SCH_1):PAGE117
 R1243    2      B Q_RES_0402LF-249,1%,1/16W,CHIPA    I19 @S9S_MB_2U_LIB.S9S_MB_2U(SCH_1):PAGE117
  R294    1      A Q_RES_0402LF-240,1%,1/16W,EMPTA    I71 @S9S_MB_2U_LIB.S9S_MB_2U(SCH_1):PAGE119
  R295    1      A Q_RES_0402LF-240,1%,1/16W,EMPTA    I72 @S9S_MB_2U_LIB.S9S_MB_2U(SCH_1):PAGE119
  R291    1      A Q_RES_0402LF-240,1%,1/16W,EMPTA   I116 @S9S_MB_2U_LIB.S9S_MB_2U(SCH_1):PAGE119
  R290    1      A Q_RES_0402LF-240,1%,1/16W,CHIPA   I135 @S9S_MB_2U_LIB.S9S_MB_2U(SCH_1):PAGE119
 R1237    1      A Q_RES_0402LF-240,1%,1/16W,EMPTA   I160 @S9S_MB_2U_LIB.S9S_MB_2U(SCH_1):PAGE119
 R1238    1      A Q_RES_0402LF-240,1%,1/16W,EMPTA   I161 @S9S_MB_2U_LIB.S9S_MB_2U(SCH_1):PAGE119
 R1239    1      A Q_RES_0402LF-240,1%,1/16W,EMPTA   I163 @S9S_MB_2U_LIB.S9S_MB_2U(SCH_1):PAGE119
 R3024    1      A Q_RES_0402LF-240,1%,1/16W,EMPTA   I172 @S9S_MB_2U_LIB.S9S_MB_2U(SCH_1):PAGE119
 R1235    1      A Q_RES_0402LF-240,1%,1/16W,EMPTA   I176 @S9S_MB_2U_LIB.S9S_MB_2U(SCH_1):PAGE119
 R1236    1      A Q_RES_0402LF-240,1%,1/16W,EMPTA   I177 @S9S_MB_2U_LIB.S9S_MB_2U(SCH_1):PAGE119
 R1391    1      A Q_RES_0402LF-240,1%,1/16W,EMPTA    I61 @S9S_MB_2U_LIB.S9S_MB_2U(SCH_1):PAGE120
 R1392    1      A Q_RES_0402LF-240,1%,1/16W,EMPTA    I62 @S9S_MB_2U_LIB.S9S_MB_2U(SCH_1):PAGE120
 R1393    1      A Q_RES_0402LF-240,1%,1/16W,EMPTA    I66 @S9S_MB_2U_LIB.S9S_MB_2U(SCH_1):PAGE120
 R1394    1      A Q_RES_0402LF-240,1%,1/16W,EMPTA    I67 @S9S_MB_2U_LIB.S9S_MB_2U(SCH_1):PAGE120
  R334    2      B Q_RES_0402LF-10K,1%,1/16W,CHIPA     I1 @S9S_MB_2U_LIB.S9S_MB_2U(SCH_1):PAGE127
  R515    2      B Q_RES_0402LF-10K,1%,1/16W,CHIPA     I7 @S9S_MB_2U_LIB.S9S_MB_2U(SCH_1):PAGE127
  R630    2      B Q_RES_0402LF-10K,1%,1/16W,EMPTA    I15 @S9S_MB_2U_LIB.S9S_MB_2U(SCH_1):PAGE127
  R628    2      B Q_RES_0402LF-10K,1%,1/16W,CHIPA    I17 @S9S_MB_2U_LIB.S9S_MB_2U(SCH_1):PAGE127
  R332    2      B Q_RES_0402LF-10K,1%,1/16W,CHIPA    I21 @S9S_MB_2U_LIB.S9S_MB_2U(SCH_1):PAGE127
  R626    2      B Q_RES_0402LF-10K,1%,1/16W,CHIPA    I26 @S9S_MB_2U_LIB.S9S_MB_2U(SCH_1):PAGE127
  R997    2      B Q_RES_0402LF-10K,1%,1/16W,EMPTA    I31 @S9S_MB_2U_LIB.S9S_MB_2U(SCH_1):PAGE127
 R1005    2      B Q_RES_0402LF-10K,1%,1/16W,EMPTA    I36 @S9S_MB_2U_LIB.S9S_MB_2U(SCH_1):PAGE127
  R938    2      B Q_RES_0402LF-10K,1%,1/16W,CHIPA    I77 @S9S_MB_2U_LIB.S9S_MB_2U(SCH_1):PAGE128
  R936    2      B Q_RES_0402LF-10K,1%,1/16W,CHIPA    I78 @S9S_MB_2U_LIB.S9S_MB_2U(SCH_1):PAGE128
  R934    2      B Q_RES_0402LF-10K,1%,1/16W,CHIPA    I79 @S9S_MB_2U_LIB.S9S_MB_2U(SCH_1):PAGE128
  R932    2      B Q_RES_0402LF-10K,1%,1/16W,CHIPA    I80 @S9S_MB_2U_LIB.S9S_MB_2U(SCH_1):PAGE128
  R933    2      B Q_RES_0402LF-10K,1%,1/16W,CHIPA    I82 @S9S_MB_2U_LIB.S9S_MB_2U(SCH_1):PAGE128
  R939    2      B Q_RES_0402LF-10K,1%,1/16W,CHIPA    I83 @S9S_MB_2U_LIB.S9S_MB_2U(SCH_1):PAGE128
  R937    2      B Q_RES_0402LF-10K,1%,1/16W,CHIPA    I85 @S9S_MB_2U_LIB.S9S_MB_2U(SCH_1):PAGE128
  R935    2      B Q_RES_0402LF-10K,1%,1/16W,CHIPA    I86 @S9S_MB_2U_LIB.S9S_MB_2U(SCH_1):PAGE128
  C622    2      B Q_CAP_C0402-1UF,25V,10%,EMPTY,A    I91 @S9S_MB_2U_LIB.S9S_MB_2U(SCH_1):PAGE129
  C623    2      B Q_CAP_C0402-1UF,25V,10%,EMPTY,A    I94 @S9S_MB_2U_LIB.S9S_MB_2U(SCH_1):PAGE129
  C624    2      B Q_CAP_C0402-1UF,25V,10%,EMPTY,A    I99 @S9S_MB_2U_LIB.S9S_MB_2U(SCH_1):PAGE129
  C621    2      B Q_CAP_C0402-1UF,25V,10%,EMPTY,A   I102 @S9S_MB_2U_LIB.S9S_MB_2U(SCH_1):PAGE129
  R706    2      B Q_RES_0402LF-10K,1%,1/16W,EMPTA   I103 @S9S_MB_2U_LIB.S9S_MB_2U(SCH_1):PAGE129
  R707    2      B Q_RES_0402LF-10K,1%,1/16W,EMPTA   I106 @S9S_MB_2U_LIB.S9S_MB_2U(SCH_1):PAGE129
  R708    2      B Q_RES_0402LF-10K,1%,1/16W,EMPTA   I109 @S9S_MB_2U_LIB.S9S_MB_2U(SCH_1):PAGE129
  R705    2      B Q_RES_0402LF-10K,1%,1/16W,EMPTA   I112 @S9S_MB_2U_LIB.S9S_MB_2U(SCH_1):PAGE129
  C616    2      B Q_CAP_C0402-1UF,25V,10%,EMPTY,A    I59 @S9S_MB_2U_LIB.S9S_MB_2U(SCH_1):PAGE130
  C615    2      B Q_CAP_C0402-1UF,25V,10%,EMPTY,A    I62 @S9S_MB_2U_LIB.S9S_MB_2U(SCH_1):PAGE130
  R701    2      B Q_RES_0402LF-10K,1%,1/16W,EMPTA    I63 @S9S_MB_2U_LIB.S9S_MB_2U(SCH_1):PAGE130
  C614    2      B Q_CAP_C0402-1UF,25V,10%,EMPTY,A    I65 @S9S_MB_2U_LIB.S9S_MB_2U(SCH_1):PAGE130
  C613    2      B Q_CAP_C0402-1UF,25V,10%,EMPTY,A    I68 @S9S_MB_2U_LIB.S9S_MB_2U(SCH_1):PAGE130
  R704    2      B Q_RES_0402LF-10K,1%,1/16W,EMPTA    I75 @S9S_MB_2U_LIB.S9S_MB_2U(SCH_1):PAGE130
  R702    2      B Q_RES_0402LF-10K,1%,1/16W,EMPTA    I76 @S9S_MB_2U_LIB.S9S_MB_2U(SCH_1):PAGE130
  R703    2      B Q_RES_0402LF-10K,1%,1/16W,EMPTA    I79 @S9S_MB_2U_LIB.S9S_MB_2U(SCH_1):PAGE130
   J42   14     14 SCONN60_ASP21410801-SCONN60_ASA    I44 @S9S_MB_2U_LIB.S9S_MB_2U(SCH_1):PAGE133
   J42   16     16 SCONN60_ASP21410801-SCONN60_ASA    I44 @S9S_MB_2U_LIB.S9S_MB_2U(SCH_1):PAGE133
   J42   57     57 SCONN60_ASP21410801-SCONN60_ASA    I44 @S9S_MB_2U_LIB.S9S_MB_2U(SCH_1):PAGE133
   J42   58     58 SCONN60_ASP21410801-SCONN60_ASA    I44 @S9S_MB_2U_LIB.S9S_MB_2U(SCH_1):PAGE133
   J42   60     60 SCONN60_ASP21410801-SCONN60_ASA    I44 @S9S_MB_2U_LIB.S9S_MB_2U(SCH_1):PAGE133
   J42   G1     G1 SCONN60_ASP21410801-SCONN60_ASA    I44 @S9S_MB_2U_LIB.S9S_MB_2U(SCH_1):PAGE133
   J42   G2     G2 SCONN60_ASP21410801-SCONN60_ASA    I44 @S9S_MB_2U_LIB.S9S_MB_2U(SCH_1):PAGE133
   J42   G3     G3 SCONN60_ASP21410801-SCONN60_ASA    I44 @S9S_MB_2U_LIB.S9S_MB_2U(SCH_1):PAGE133
   J42   G4     G4 SCONN60_ASP21410801-SCONN60_ASA    I44 @S9S_MB_2U_LIB.S9S_MB_2U(SCH_1):PAGE133
  C552    2      B Q_CAP_0402-0.1UF,25V,10%,X7R,CA    I96 @S9S_MB_2U_LIB.S9S_MB_2U(SCH_1):PAGE133
  C550    2      B Q_CAP_C0402-1UF,25V,10%,X6S,CHA    I99 @S9S_MB_2U_LIB.S9S_MB_2U(SCH_1):PAGE133
  C547    2      B Q_CAP_C0402-1UF,25V,10%,X6S,CHA   I100 @S9S_MB_2U_LIB.S9S_MB_2U(SCH_1):PAGE133
  R769    2      B Q_RES_0402LF-10K,1%,1/16W,CHIPA   I102 @S9S_MB_2U_LIB.S9S_MB_2U(SCH_1):PAGE133
  C551    2      B Q_CAP_C0402-1UF,25V,10%,X6S,CHA   I105 @S9S_MB_2U_LIB.S9S_MB_2U(SCH_1):PAGE133
  C549    2      B Q_CAP_0402-0.1UF,25V,10%,X7R,CA   I129 @S9S_MB_2U_LIB.S9S_MB_2U(SCH_1):PAGE133
  C548    2      B Q_CAP_0402-0.1UF,25V,10%,X7R,CA   I130 @S9S_MB_2U_LIB.S9S_MB_2U(SCH_1):PAGE133
  R774    2      B Q_RES_0402LF-75,1%,1/16W,CHIP,A   I132 @S9S_MB_2U_LIB.S9S_MB_2U(SCH_1):PAGE133
   U17    7    GND 74CBTLV3126PW-74CBTLV3126PW,SMA    I80 @S9S_MB_2U_LIB.S9S_MB_2U(SCH_1):PAGE134
  R746    2      B Q_RES_0402LF-0,5%,1/16W,CHIP,CA    I90 @S9S_MB_2U_LIB.S9S_MB_2U(SCH_1):PAGE134
  C545    2      B Q_CAP_C0402-1UF,25V,10%,X6S,CHA    I93 @S9S_MB_2U_LIB.S9S_MB_2U(SCH_1):PAGE134
   U18    7    GND 74CBTLV3126PW-74CBTLV3126PW,SMA   I129 @S9S_MB_2U_LIB.S9S_MB_2U(SCH_1):PAGE134
  C546    2      B Q_CAP_C0402-1UF,25V,10%,X6S,CHA   I135 @S9S_MB_2U_LIB.S9S_MB_2U(SCH_1):PAGE134
   U21    2    GND NC7SB3157_SMLF-NC7SB3157P6X,NCA    I58 @S9S_MB_2U_LIB.S9S_MB_2U(SCH_1):PAGE135
  C541    2      B Q_CAP_C0402-1UF,25V,10%,X6S,CHA    I61 @S9S_MB_2U_LIB.S9S_MB_2U(SCH_1):PAGE135
  C539    2      B Q_CAP_0402-0.1UF,25V,10%,X7R,CA    I70 @S9S_MB_2U_LIB.S9S_MB_2U(SCH_1):PAGE135
   U22    2    GND NC7SB3157_SMLF-NC7SB3157P6X,NCA    I71 @S9S_MB_2U_LIB.S9S_MB_2U(SCH_1):PAGE135
  C542    2      B Q_CAP_C0402-1UF,25V,10%,X6S,CHA    I80 @S9S_MB_2U_LIB.S9S_MB_2U(SCH_1):PAGE135
  C540    2      B Q_CAP_0402-0.1UF,25V,10%,X7R,CA    I81 @S9S_MB_2U_LIB.S9S_MB_2U(SCH_1):PAGE135
  C544    2      B Q_CAP_0402-0.1UF,25V,10%,X7R,CA    I94 @S9S_MB_2U_LIB.S9S_MB_2U(SCH_1):PAGE135
   U23    3    GND 74LVC1G02GW_SMLF-74LVC1G02GW,IA    I96 @S9S_MB_2U_LIB.S9S_MB_2U(SCH_1):PAGE135
  C543    2      B Q_CAP_0402-0.1UF,25V,10%,X7R,CA   I100 @S9S_MB_2U_LIB.S9S_MB_2U(SCH_1):PAGE135
   U86    7    GND 74CBTLV3126PW-74CBTLV3126PW,SMA    I84 @S9S_MB_2U_LIB.S9S_MB_2U(SCH_1):PAGE137
 C1292    2      B Q_CAP_0402-0.1UF,25V,10%,X7R,CA    I90 @S9S_MB_2U_LIB.S9S_MB_2U(SCH_1):PAGE137
 C1293    2      B Q_CAP_C0402-1UF,25V,10%,X6S,CHA    I95 @S9S_MB_2U_LIB.S9S_MB_2U(SCH_1):PAGE137
 R1375    2      B Q_RES_0402LF-10K,1%,1/16W,CHIPA    I97 @S9S_MB_2U_LIB.S9S_MB_2U(SCH_1):PAGE137
 R3025    2      B Q_RES_0402LF-1K,1%,1/16W,EMPTYA   I102 @S9S_MB_2U_LIB.S9S_MB_2U(SCH_1):PAGE137
 R1374    2      B Q_RES_0402LF-1K,1%,1/16W,CHIP,A   I103 @S9S_MB_2U_LIB.S9S_MB_2U(SCH_1):PAGE137
 R3027    2      B Q_RES_0402LF-1K,1%,1/16W,CHIP,A   I105 @S9S_MB_2U_LIB.S9S_MB_2U(SCH_1):PAGE137
 R3026    2      B Q_RES_0402LF-1K,1%,1/16W,CHIP,A   I106 @S9S_MB_2U_LIB.S9S_MB_2U(SCH_1):PAGE137
   U85    2    GND NC7SB3157_SMLF-NC7SB3157P6X,NCA   I109 @S9S_MB_2U_LIB.S9S_MB_2U(SCH_1):PAGE137
 C1289    2      B Q_CAP_C0402-1UF,25V,10%,X6S,CHA   I110 @S9S_MB_2U_LIB.S9S_MB_2U(SCH_1):PAGE137
 C1288    2      B Q_CAP_0402-0.1UF,25V,10%,X7R,CA   I112 @S9S_MB_2U_LIB.S9S_MB_2U(SCH_1):PAGE137
 R1365    2      B Q_RES_0402LF-1K,1%,1/16W,CHIP,A   I116 @S9S_MB_2U_LIB.S9S_MB_2U(SCH_1):PAGE137
 R1353    2      B Q_RES_0402LF-100K,1%,1/16W,CHIA    I56 @S9S_MB_2U_LIB.S9S_MB_2U(SCH_1):PAGE151
   U75    3    GND 74LVC1G17GW-74LVC1G17GW,SMLF,IA     I1 @S9S_MB_2U_LIB.S9S_MB_2U(SCH_1):PAGE152
 C1173    2      B Q_CAP_0402-0.1UF,25V,10%,X7R,CA     I4 @S9S_MB_2U_LIB.S9S_MB_2U(SCH_1):PAGE152
 C1175    2      B Q_CAP_0402-0.1UF,25V,10%,X7R,CA    I24 @S9S_MB_2U_LIB.S9S_MB_2U(SCH_1):PAGE152
  C188    2      B Q_CAP_0402-0.1UF,25V,10%,X7R,CA    I44 @S9S_MB_2U_LIB.S9S_MB_2U(SCH_1):PAGE152
   U90    4    GND PI6CV304LE-PI6CV304LE,SMLF,IC,A    I46 @S9S_MB_2U_LIB.S9S_MB_2U(SCH_1):PAGE152
 C1275    2      B Q_CAP_0402-0.1UF,25V,10%,X7R,CA    I49 @S9S_MB_2U_LIB.S9S_MB_2U(SCH_1):PAGE152
 C1274    2      B Q_CAP_0402-0.1UF,25V,10%,X7R,CA    I59 @S9S_MB_2U_LIB.S9S_MB_2U(SCH_1):PAGE152
  U104    3    GND 74LVC1G07GV-74LVC1G07GV,SMLF,IA    I63 @S9S_MB_2U_LIB.S9S_MB_2U(SCH_1):PAGE152
  U157    3    GND 74LVC1G07GV-74LVC1G07GV,SMLF,IA    I65 @S9S_MB_2U_LIB.S9S_MB_2U(SCH_1):PAGE152
 C1663    2      B Q_CAP_0402-0.1UF,25V,10%,X7R,CA    I68 @S9S_MB_2U_LIB.S9S_MB_2U(SCH_1):PAGE152
 R1128    2      B Q_RES_0402LF-1K,1%,1/16W,CHIP,A   I137 @S9S_MB_2U_LIB.S9S_MB_2U(SCH_1):PAGE154
 R1126    2      B Q_RES_0402LF-1K,1%,1/16W,CHIP,A   I140 @S9S_MB_2U_LIB.S9S_MB_2U(SCH_1):PAGE154
 R1124    2      B Q_RES_0402LF-1K,1%,1/16W,CHIP,A   I143 @S9S_MB_2U_LIB.S9S_MB_2U(SCH_1):PAGE154
  C581    2      B Q_CAP_0402-0.1UF,25V,10%,X7R,CA   I148 @S9S_MB_2U_LIB.S9S_MB_2U(SCH_1):PAGE154
  C578    2      B Q_CAP_0402-0.1UF,25V,10%,X7R,CA   I169 @S9S_MB_2U_LIB.S9S_MB_2U(SCH_1):PAGE154
   U49    S SOURCE MOSFET_N_SMLF-BSS138K,BSS138K,A   I177 @S9S_MB_2U_LIB.S9S_MB_2U(SCH_1):PAGE154
 C1507    2      B Q_CAP_0402-18PF,50V,5%,C0G,CH0A    I10 @S9S_MB_2U_LIB.S9S_MB_2U(SCH_1):PAGE171
 C1508    2      B Q_CAP_0402-18PF,50V,5%,C0G,CH0A    I17 @S9S_MB_2U_LIB.S9S_MB_2U(SCH_1):PAGE171
  R477    2      B Q_RES_0402LF-60.4,1%,1/16W,CHIA    I69 @S9S_MB_2U_LIB.S9S_MB_2U(SCH_1):PAGE171
    Y7    2     G1 Q_XTAL_4P_13BI_24GND-25MHZ,SMLA    I75 @S9S_MB_2U_LIB.S9S_MB_2U(SCH_1):PAGE171
    Y7    4     G2 Q_XTAL_4P_13BI_24GND-25MHZ,SMLA    I75 @S9S_MB_2U_LIB.S9S_MB_2U(SCH_1):PAGE171
  C104    2      B Q_CAP_0402-27PF  ,50V ,5% ,EMPA    I76 @S9S_MB_2U_LIB.S9S_MB_2U(SCH_1):PAGE171
  C103    2      B Q_CAP_0402-27PF  ,50V ,5% ,EMPA    I77 @S9S_MB_2U_LIB.S9S_MB_2U(SCH_1):PAGE171
  C609    2      B Q_CAP_0402-0.1UF,25V,10%,X7R,CA    I89 @S9S_MB_2U_LIB.S9S_MB_2U(SCH_1):PAGE171
  R496    2      B Q_RES_0402LF-113,1%,1/16W,CHIPA    I10 @S9S_MB_2U_LIB.S9S_MB_2U(SCH_1):PAGE172
 R1025    2      B Q_RES_0402LF-75,1%,1/16W,EMPTYA    I38 @S9S_MB_2U_LIB.S9S_MB_2U(SCH_1):PAGE174
 R1024    2      B Q_RES_0402LF-100,1%,1/16W,CHIPA    I41 @S9S_MB_2U_LIB.S9S_MB_2U(SCH_1):PAGE174
 R1197    1      A Q_RES_0402LF-1K,1%,1/16W,EMPTYA    I50 @S9S_MB_2U_LIB.S9S_MB_2U(SCH_1):PAGE174
 R1676    2      B Q_RES_0402LF-1K,1%,1/16W,EMPTYA    I94 @S9S_MB_2U_LIB.S9S_MB_2U(SCH_1):PAGE174
 R1487    2      B Q_RES_0402LF-100,1%,1/16W,CHIPA   I125 @S9S_MB_2U_LIB.S9S_MB_2U(SCH_1):PAGE175
 R1269    2      B Q_RES_0402LF-4.75K,1%,1/16W,CHA   I225 @S9S_MB_2U_LIB.S9S_MB_2U(SCH_1):PAGE175
   JP4    2      2 CONN3_210HP1030BR1-CONN3_210-HA   I256 @S9S_MB_2U_LIB.S9S_MB_2U(SCH_1):PAGE175
   JP9    2      2 CONN3_210HP1030BR1-CONN3_210-HA   I263 @S9S_MB_2U_LIB.S9S_MB_2U(SCH_1):PAGE175
 R2509    2      B Q_RES_0402LF-1K,1%,1/16W,EMPTYA   I174 @S9S_MB_2U_LIB.S9S_MB_2U(SCH_1):PAGE176
 R2511    2      B Q_RES_0402LF-1K,1%,1/16W,EMPTYA   I176 @S9S_MB_2U_LIB.S9S_MB_2U(SCH_1):PAGE176
   BT1    2      2 CONN2_AAABAT029Y19-CONN2_AAA-BA    I63 @S9S_MB_2U_LIB.S9S_MB_2U(SCH_1):PAGE177
  C611    2      B Q_CAP_C0402-1UF,25V,10%,X6S,CHA    I65 @S9S_MB_2U_LIB.S9S_MB_2U(SCH_1):PAGE177
  C610    2      B Q_CAP_C0402-1UF,25V,10%,X6S,CHA    I68 @S9S_MB_2U_LIB.S9S_MB_2U(SCH_1):PAGE177
    U4 BG40 VSS_BG40 EMMITSBURG_REV0P9-GFNOCPU04302A    I11 @S9S_MB_2U_LIB.S9S_MB_2U(SCH_1):PAGE178
  R497    2      B Q_RES_0402LF-200,1%,1/16W,CHIPA     I2 @S9S_MB_2U_LIB.S9S_MB_2U(SCH_1):PAGE179
    U4  AY3 VSS_AY3 EMMITSBURG_REV0P9-GFNOCPU04302A     I7 @S9S_MB_2U_LIB.S9S_MB_2U(SCH_1):PAGE180
    U4  AY5 VSS_AY5 EMMITSBURG_REV0P9-GFNOCPU04302A     I7 @S9S_MB_2U_LIB.S9S_MB_2U(SCH_1):PAGE180
    U4  AY8 VSS_AY8 EMMITSBURG_REV0P9-GFNOCPU04302A     I7 @S9S_MB_2U_LIB.S9S_MB_2U(SCH_1):PAGE180
    U4 AY28 VSS_AY28 EMMITSBURG_REV0P9-GFNOCPU04302A     I7 @S9S_MB_2U_LIB.S9S_MB_2U(SCH_1):PAGE180
    U4 AY31 VSS_AY31 EMMITSBURG_REV0P9-GFNOCPU04302A     I7 @S9S_MB_2U_LIB.S9S_MB_2U(SCH_1):PAGE180
    U4 AY34 VSS_AY34 EMMITSBURG_REV0P9-GFNOCPU04302A     I7 @S9S_MB_2U_LIB.S9S_MB_2U(SCH_1):PAGE180
    U4 AY37 VSS_AY37 EMMITSBURG_REV0P9-GFNOCPU04302A     I7 @S9S_MB_2U_LIB.S9S_MB_2U(SCH_1):PAGE180
    U4 AY39 VSS_AY39 EMMITSBURG_REV0P9-GFNOCPU04302A     I7 @S9S_MB_2U_LIB.S9S_MB_2U(SCH_1):PAGE180
    U4   B9 VSS_B9 EMMITSBURG_REV0P9-GFNOCPU04302A     I7 @S9S_MB_2U_LIB.S9S_MB_2U(SCH_1):PAGE180
    U4  B13 VSS_B13 EMMITSBURG_REV0P9-GFNOCPU04302A     I7 @S9S_MB_2U_LIB.S9S_MB_2U(SCH_1):PAGE180
    U4  B29 VSS_B29 EMMITSBURG_REV0P9-GFNOCPU04302A     I7 @S9S_MB_2U_LIB.S9S_MB_2U(SCH_1):PAGE180
    U4  B39 VSS_B39 EMMITSBURG_REV0P9-GFNOCPU04302A     I7 @S9S_MB_2U_LIB.S9S_MB_2U(SCH_1):PAGE180
    U4  BB5 VSS_BB5 EMMITSBURG_REV0P9-GFNOCPU04302A     I7 @S9S_MB_2U_LIB.S9S_MB_2U(SCH_1):PAGE180
    U4 BB39 VSS_BB39 EMMITSBURG_REV0P9-GFNOCPU04302A     I7 @S9S_MB_2U_LIB.S9S_MB_2U(SCH_1):PAGE180
    U4  BC6 VSS_BC6 EMMITSBURG_REV0P9-GFNOCPU04302A     I7 @S9S_MB_2U_LIB.S9S_MB_2U(SCH_1):PAGE180
    U4  BC8 VSS_BC8 EMMITSBURG_REV0P9-GFNOCPU04302A     I7 @S9S_MB_2U_LIB.S9S_MB_2U(SCH_1):PAGE180
    U4 BC10 VSS_BC10 EMMITSBURG_REV0P9-GFNOCPU04302A     I7 @S9S_MB_2U_LIB.S9S_MB_2U(SCH_1):PAGE180
    U4 BC12 VSS_BC12 EMMITSBURG_REV0P9-GFNOCPU04302A     I7 @S9S_MB_2U_LIB.S9S_MB_2U(SCH_1):PAGE180
    U4 BC14 VSS_BC14 EMMITSBURG_REV0P9-GFNOCPU04302A     I7 @S9S_MB_2U_LIB.S9S_MB_2U(SCH_1):PAGE180
    U4 BC16 VSS_BC16 EMMITSBURG_REV0P9-GFNOCPU04302A     I7 @S9S_MB_2U_LIB.S9S_MB_2U(SCH_1):PAGE180
    U4 BC18 VSS_BC18 EMMITSBURG_REV0P9-GFNOCPU04302A     I7 @S9S_MB_2U_LIB.S9S_MB_2U(SCH_1):PAGE180
    U4 BC20 VSS_BC20 EMMITSBURG_REV0P9-GFNOCPU04302A     I7 @S9S_MB_2U_LIB.S9S_MB_2U(SCH_1):PAGE180
    U4 BC22 VSS_BC22 EMMITSBURG_REV0P9-GFNOCPU04302A     I7 @S9S_MB_2U_LIB.S9S_MB_2U(SCH_1):PAGE180
    U4 BC24 VSS_BC24 EMMITSBURG_REV0P9-GFNOCPU04302A     I7 @S9S_MB_2U_LIB.S9S_MB_2U(SCH_1):PAGE180
    U4 BC26 VSS_BC26 EMMITSBURG_REV0P9-GFNOCPU04302A     I7 @S9S_MB_2U_LIB.S9S_MB_2U(SCH_1):PAGE180
    U4 BC28 VSS_BC28 EMMITSBURG_REV0P9-GFNOCPU04302A     I7 @S9S_MB_2U_LIB.S9S_MB_2U(SCH_1):PAGE180
    U4 BC30 VSS_BC30 EMMITSBURG_REV0P9-GFNOCPU04302A     I7 @S9S_MB_2U_LIB.S9S_MB_2U(SCH_1):PAGE180
    U4 BC32 VSS_BC32 EMMITSBURG_REV0P9-GFNOCPU04302A     I7 @S9S_MB_2U_LIB.S9S_MB_2U(SCH_1):PAGE180
    U4 BC34 VSS_BC34 EMMITSBURG_REV0P9-GFNOCPU04302A     I7 @S9S_MB_2U_LIB.S9S_MB_2U(SCH_1):PAGE180
    U4 BC36 VSS_BC36 EMMITSBURG_REV0P9-GFNOCPU04302A     I7 @S9S_MB_2U_LIB.S9S_MB_2U(SCH_1):PAGE180
    U4 BC38 VSS_BC38 EMMITSBURG_REV0P9-GFNOCPU04302A     I7 @S9S_MB_2U_LIB.S9S_MB_2U(SCH_1):PAGE180
    U4  BD5 VSS_BD5 EMMITSBURG_REV0P9-GFNOCPU04302A     I7 @S9S_MB_2U_LIB.S9S_MB_2U(SCH_1):PAGE180
    U4 BD21 VSS_BD21 EMMITSBURG_REV0P9-GFNOCPU04302A     I7 @S9S_MB_2U_LIB.S9S_MB_2U(SCH_1):PAGE180
    U4 BD39 VSS_BD39 EMMITSBURG_REV0P9-GFNOCPU04302A     I7 @S9S_MB_2U_LIB.S9S_MB_2U(SCH_1):PAGE180
    U4 BE10 VSS_BE10 EMMITSBURG_REV0P9-GFNOCPU04302A     I7 @S9S_MB_2U_LIB.S9S_MB_2U(SCH_1):PAGE180
    U4 BE34 VSS_BE34 EMMITSBURG_REV0P9-GFNOCPU04302A     I7 @S9S_MB_2U_LIB.S9S_MB_2U(SCH_1):PAGE180
    U4 BF21 VSS_BF21 EMMITSBURG_REV0P9-GFNOCPU04302A     I7 @S9S_MB_2U_LIB.S9S_MB_2U(SCH_1):PAGE180
    U4 BG10 VSS_BG10 EMMITSBURG_REV0P9-GFNOCPU04302A     I7 @S9S_MB_2U_LIB.S9S_MB_2U(SCH_1):PAGE180
    U4 BG34 VSS_BG34 EMMITSBURG_REV0P9-GFNOCPU04302A     I7 @S9S_MB_2U_LIB.S9S_MB_2U(SCH_1):PAGE180
    U4   C4 VSS_C4 EMMITSBURG_REV0P9-GFNOCPU04302A     I7 @S9S_MB_2U_LIB.S9S_MB_2U(SCH_1):PAGE180
    U4  C20 VSS_C20 EMMITSBURG_REV0P9-GFNOCPU04302A     I7 @S9S_MB_2U_LIB.S9S_MB_2U(SCH_1):PAGE180
    U4  C22 VSS_C22 EMMITSBURG_REV0P9-GFNOCPU04302A     I7 @S9S_MB_2U_LIB.S9S_MB_2U(SCH_1):PAGE180
    U4  C24 VSS_C24 EMMITSBURG_REV0P9-GFNOCPU04302A     I7 @S9S_MB_2U_LIB.S9S_MB_2U(SCH_1):PAGE180
    U4  C26 VSS_C26 EMMITSBURG_REV0P9-GFNOCPU04302A     I7 @S9S_MB_2U_LIB.S9S_MB_2U(SCH_1):PAGE180
    U4  C38 VSS_C38 EMMITSBURG_REV0P9-GFNOCPU04302A     I7 @S9S_MB_2U_LIB.S9S_MB_2U(SCH_1):PAGE180
    U4   D5 VSS_D5 EMMITSBURG_REV0P9-GFNOCPU04302A     I7 @S9S_MB_2U_LIB.S9S_MB_2U(SCH_1):PAGE180
    U4   D9 VSS_D9 EMMITSBURG_REV0P9-GFNOCPU04302A     I7 @S9S_MB_2U_LIB.S9S_MB_2U(SCH_1):PAGE180
    U4  D13 VSS_D13 EMMITSBURG_REV0P9-GFNOCPU04302A     I7 @S9S_MB_2U_LIB.S9S_MB_2U(SCH_1):PAGE180
    U4  D29 VSS_D29 EMMITSBURG_REV0P9-GFNOCPU04302A     I7 @S9S_MB_2U_LIB.S9S_MB_2U(SCH_1):PAGE180
    U4   E6 VSS_E6 EMMITSBURG_REV0P9-GFNOCPU04302A     I7 @S9S_MB_2U_LIB.S9S_MB_2U(SCH_1):PAGE180
    U4   E8 VSS_E8 EMMITSBURG_REV0P9-GFNOCPU04302A     I7 @S9S_MB_2U_LIB.S9S_MB_2U(SCH_1):PAGE180
    U4  E10 VSS_E10 EMMITSBURG_REV0P9-GFNOCPU04302A     I7 @S9S_MB_2U_LIB.S9S_MB_2U(SCH_1):PAGE180
    U4  E12 VSS_E12 EMMITSBURG_REV0P9-GFNOCPU04302A     I7 @S9S_MB_2U_LIB.S9S_MB_2U(SCH_1):PAGE180
    U4  E14 VSS_E14 EMMITSBURG_REV0P9-GFNOCPU04302A     I7 @S9S_MB_2U_LIB.S9S_MB_2U(SCH_1):PAGE180
    U4  E16 VSS_E16 EMMITSBURG_REV0P9-GFNOCPU04302A     I7 @S9S_MB_2U_LIB.S9S_MB_2U(SCH_1):PAGE180
    U4  E18 VSS_E18 EMMITSBURG_REV0P9-GFNOCPU04302A     I7 @S9S_MB_2U_LIB.S9S_MB_2U(SCH_1):PAGE180
    U4  E20 VSS_E20 EMMITSBURG_REV0P9-GFNOCPU04302A     I7 @S9S_MB_2U_LIB.S9S_MB_2U(SCH_1):PAGE180
    U4  E22 VSS_E22 EMMITSBURG_REV0P9-GFNOCPU04302A     I7 @S9S_MB_2U_LIB.S9S_MB_2U(SCH_1):PAGE180
    U4  E24 VSS_E24 EMMITSBURG_REV0P9-GFNOCPU04302A     I7 @S9S_MB_2U_LIB.S9S_MB_2U(SCH_1):PAGE180
    U4  E26 VSS_E26 EMMITSBURG_REV0P9-GFNOCPU04302A     I7 @S9S_MB_2U_LIB.S9S_MB_2U(SCH_1):PAGE180
    U4  E28 VSS_E28 EMMITSBURG_REV0P9-GFNOCPU04302A     I7 @S9S_MB_2U_LIB.S9S_MB_2U(SCH_1):PAGE180
    U4  E30 VSS_E30 EMMITSBURG_REV0P9-GFNOCPU04302A     I7 @S9S_MB_2U_LIB.S9S_MB_2U(SCH_1):PAGE180
    U4  E32 VSS_E32 EMMITSBURG_REV0P9-GFNOCPU04302A     I7 @S9S_MB_2U_LIB.S9S_MB_2U(SCH_1):PAGE180
    U4  E34 VSS_E34 EMMITSBURG_REV0P9-GFNOCPU04302A     I7 @S9S_MB_2U_LIB.S9S_MB_2U(SCH_1):PAGE180
    U4  E36 VSS_E36 EMMITSBURG_REV0P9-GFNOCPU04302A     I7 @S9S_MB_2U_LIB.S9S_MB_2U(SCH_1):PAGE180
    U4  E38 VSS_E38 EMMITSBURG_REV0P9-GFNOCPU04302A     I7 @S9S_MB_2U_LIB.S9S_MB_2U(SCH_1):PAGE180
    U4  E40 VSS_E40 EMMITSBURG_REV0P9-GFNOCPU04302A     I7 @S9S_MB_2U_LIB.S9S_MB_2U(SCH_1):PAGE180
    U4  F15 VSS_F15 EMMITSBURG_REV0P9-GFNOCPU04302A     I7 @S9S_MB_2U_LIB.S9S_MB_2U(SCH_1):PAGE180
    U4  F24 VSS_F24 EMMITSBURG_REV0P9-GFNOCPU04302A     I7 @S9S_MB_2U_LIB.S9S_MB_2U(SCH_1):PAGE180
    U4  F31 VSS_F31 EMMITSBURG_REV0P9-GFNOCPU04302A     I7 @S9S_MB_2U_LIB.S9S_MB_2U(SCH_1):PAGE180
    U4  F34 VSS_F34 EMMITSBURG_REV0P9-GFNOCPU04302A     I7 @S9S_MB_2U_LIB.S9S_MB_2U(SCH_1):PAGE180
    U4  F39 VSS_F39 EMMITSBURG_REV0P9-GFNOCPU04302A     I7 @S9S_MB_2U_LIB.S9S_MB_2U(SCH_1):PAGE180
    U4  F41 VSS_F41 EMMITSBURG_REV0P9-GFNOCPU04302A     I7 @S9S_MB_2U_LIB.S9S_MB_2U(SCH_1):PAGE180
    U4  G13 VSS_G13 EMMITSBURG_REV0P9-GFNOCPU04302A     I7 @S9S_MB_2U_LIB.S9S_MB_2U(SCH_1):PAGE180
    U4  G20 VSS_G20 EMMITSBURG_REV0P9-GFNOCPU04302A     I7 @S9S_MB_2U_LIB.S9S_MB_2U(SCH_1):PAGE180
    U4  G26 VSS_G26 EMMITSBURG_REV0P9-GFNOCPU04302A     I7 @S9S_MB_2U_LIB.S9S_MB_2U(SCH_1):PAGE180
    U4   H5 VSS_H5 EMMITSBURG_REV0P9-GFNOCPU04302A     I7 @S9S_MB_2U_LIB.S9S_MB_2U(SCH_1):PAGE180
    U4   H8 VSS_H8 EMMITSBURG_REV0P9-GFNOCPU04302A     I7 @S9S_MB_2U_LIB.S9S_MB_2U(SCH_1):PAGE180
    U4  H39 VSS_H39 EMMITSBURG_REV0P9-GFNOCPU04302A     I7 @S9S_MB_2U_LIB.S9S_MB_2U(SCH_1):PAGE180
    U4  J13 VSS_J13 EMMITSBURG_REV0P9-GFNOCPU04302A     I7 @S9S_MB_2U_LIB.S9S_MB_2U(SCH_1):PAGE180
    U4  J20 VSS_J20 EMMITSBURG_REV0P9-GFNOCPU04302A     I7 @S9S_MB_2U_LIB.S9S_MB_2U(SCH_1):PAGE180
    U4  J26 VSS_J26 EMMITSBURG_REV0P9-GFNOCPU04302A     I7 @S9S_MB_2U_LIB.S9S_MB_2U(SCH_1):PAGE180
    U4   K5 VSS_K5 EMMITSBURG_REV0P9-GFNOCPU04302A     I7 @S9S_MB_2U_LIB.S9S_MB_2U(SCH_1):PAGE180
    U4  K11 VSS_K11 EMMITSBURG_REV0P9-GFNOCPU04302A     I7 @S9S_MB_2U_LIB.S9S_MB_2U(SCH_1):PAGE180
    U4  K15 VSS_K15 EMMITSBURG_REV0P9-GFNOCPU04302A     I7 @S9S_MB_2U_LIB.S9S_MB_2U(SCH_1):PAGE180
    U4  K24 VSS_K24 EMMITSBURG_REV0P9-GFNOCPU04302A     I7 @S9S_MB_2U_LIB.S9S_MB_2U(SCH_1):PAGE180
    U4  K34 VSS_K34 EMMITSBURG_REV0P9-GFNOCPU04302A     I7 @S9S_MB_2U_LIB.S9S_MB_2U(SCH_1):PAGE180
    U4  K39 VSS_K39 EMMITSBURG_REV0P9-GFNOCPU04302A     I7 @S9S_MB_2U_LIB.S9S_MB_2U(SCH_1):PAGE180
    U4  L10 VSS_L10 EMMITSBURG_REV0P9-GFNOCPU04302A     I7 @S9S_MB_2U_LIB.S9S_MB_2U(SCH_1):PAGE180
    U4  L16 VSS_L16 EMMITSBURG_REV0P9-GFNOCPU04302A     I7 @S9S_MB_2U_LIB.S9S_MB_2U(SCH_1):PAGE180
    U4  L20 VSS_L20 EMMITSBURG_REV0P9-GFNOCPU04302A     I7 @S9S_MB_2U_LIB.S9S_MB_2U(SCH_1):PAGE180
    U4  L23 VSS_L23 EMMITSBURG_REV0P9-GFNOCPU04302A     I7 @S9S_MB_2U_LIB.S9S_MB_2U(SCH_1):PAGE180
    U4  L26 VSS_L26 EMMITSBURG_REV0P9-GFNOCPU04302A     I7 @S9S_MB_2U_LIB.S9S_MB_2U(SCH_1):PAGE180
    U4  L29 VSS_L29 EMMITSBURG_REV0P9-GFNOCPU04302A     I7 @S9S_MB_2U_LIB.S9S_MB_2U(SCH_1):PAGE180
    U4  L36 VSS_L36 EMMITSBURG_REV0P9-GFNOCPU04302A     I7 @S9S_MB_2U_LIB.S9S_MB_2U(SCH_1):PAGE180
    U4   M1 VSS_M1 EMMITSBURG_REV0P9-GFNOCPU04302A     I7 @S9S_MB_2U_LIB.S9S_MB_2U(SCH_1):PAGE180
    U4   M3 VSS_M3 EMMITSBURG_REV0P9-GFNOCPU04302A     I7 @S9S_MB_2U_LIB.S9S_MB_2U(SCH_1):PAGE180
    U4   M5 VSS_M5 EMMITSBURG_REV0P9-GFNOCPU04302A     I7 @S9S_MB_2U_LIB.S9S_MB_2U(SCH_1):PAGE180
    U4  M11 VSS_M11 EMMITSBURG_REV0P9-GFNOCPU04302A     I7 @S9S_MB_2U_LIB.S9S_MB_2U(SCH_1):PAGE180
    U4  M15 VSS_M15 EMMITSBURG_REV0P9-GFNOCPU04302A     I7 @S9S_MB_2U_LIB.S9S_MB_2U(SCH_1):PAGE180
    U4  M18 VSS_M18 EMMITSBURG_REV0P9-GFNOCPU04302A     I7 @S9S_MB_2U_LIB.S9S_MB_2U(SCH_1):PAGE180
    U4  M21 VSS_M21 EMMITSBURG_REV0P9-GFNOCPU04302A     I7 @S9S_MB_2U_LIB.S9S_MB_2U(SCH_1):PAGE180
    U4  M28 VSS_M28 EMMITSBURG_REV0P9-GFNOCPU04302A     I7 @S9S_MB_2U_LIB.S9S_MB_2U(SCH_1):PAGE180
    U4  M31 VSS_M31 EMMITSBURG_REV0P9-GFNOCPU04302A     I7 @S9S_MB_2U_LIB.S9S_MB_2U(SCH_1):PAGE180
    U4  M34 VSS_M34 EMMITSBURG_REV0P9-GFNOCPU04302A     I7 @S9S_MB_2U_LIB.S9S_MB_2U(SCH_1):PAGE180
    U4  M37 VSS_M37 EMMITSBURG_REV0P9-GFNOCPU04302A     I7 @S9S_MB_2U_LIB.S9S_MB_2U(SCH_1):PAGE180
    U4  M39 VSS_M39 EMMITSBURG_REV0P9-GFNOCPU04302A     I7 @S9S_MB_2U_LIB.S9S_MB_2U(SCH_1):PAGE180
    U4  N16 VSS_N16 EMMITSBURG_REV0P9-GFNOCPU04302A     I7 @S9S_MB_2U_LIB.S9S_MB_2U(SCH_1):PAGE180
    U4  N32 VSS_N32 EMMITSBURG_REV0P9-GFNOCPU04302A     I7 @S9S_MB_2U_LIB.S9S_MB_2U(SCH_1):PAGE180
    U4   P5 VSS_P5 EMMITSBURG_REV0P9-GFNOCPU04302A     I7 @S9S_MB_2U_LIB.S9S_MB_2U(SCH_1):PAGE180
    U4   P8 VSS_P8 EMMITSBURG_REV0P9-GFNOCPU04302A     I7 @S9S_MB_2U_LIB.S9S_MB_2U(SCH_1):PAGE180
    U4  P11 VSS_P11 EMMITSBURG_REV0P9-GFNOCPU04302A     I7 @S9S_MB_2U_LIB.S9S_MB_2U(SCH_1):PAGE180
    U4  P24 VSS_P24 EMMITSBURG_REV0P9-GFNOCPU04302A     I7 @S9S_MB_2U_LIB.S9S_MB_2U(SCH_1):PAGE180
    U4  P28 VSS_P28 EMMITSBURG_REV0P9-GFNOCPU04302A     I7 @S9S_MB_2U_LIB.S9S_MB_2U(SCH_1):PAGE180
    U4  P31 VSS_P31 EMMITSBURG_REV0P9-GFNOCPU04302A     I7 @S9S_MB_2U_LIB.S9S_MB_2U(SCH_1):PAGE180
    U4  P37 VSS_P37 EMMITSBURG_REV0P9-GFNOCPU04302A     I7 @S9S_MB_2U_LIB.S9S_MB_2U(SCH_1):PAGE180
    U4  P39 VSS_P39 EMMITSBURG_REV0P9-GFNOCPU04302A     I7 @S9S_MB_2U_LIB.S9S_MB_2U(SCH_1):PAGE180
    U4  P41 VSS_P41 EMMITSBURG_REV0P9-GFNOCPU04302A     I7 @S9S_MB_2U_LIB.S9S_MB_2U(SCH_1):PAGE180
    U4  P43 VSS_P43 EMMITSBURG_REV0P9-GFNOCPU04302A     I7 @S9S_MB_2U_LIB.S9S_MB_2U(SCH_1):PAGE180
    U4  R13 VSS_R13 EMMITSBURG_REV0P9-GFNOCPU04302A     I7 @S9S_MB_2U_LIB.S9S_MB_2U(SCH_1):PAGE180
    U4  R16 VSS_R16 EMMITSBURG_REV0P9-GFNOCPU04302A     I7 @S9S_MB_2U_LIB.S9S_MB_2U(SCH_1):PAGE180
    U4  R20 VSS_R20 EMMITSBURG_REV0P9-GFNOCPU04302A     I7 @S9S_MB_2U_LIB.S9S_MB_2U(SCH_1):PAGE180
    U4  R36 VSS_R36 EMMITSBURG_REV0P9-GFNOCPU04302A     I7 @S9S_MB_2U_LIB.S9S_MB_2U(SCH_1):PAGE180
    U4  T31 VSS_T31 EMMITSBURG_REV0P9-GFNOCPU04302A     I7 @S9S_MB_2U_LIB.S9S_MB_2U(SCH_1):PAGE180
    U4   U5 VSS_U5 EMMITSBURG_REV0P9-GFNOCPU04302A     I7 @S9S_MB_2U_LIB.S9S_MB_2U(SCH_1):PAGE180
    U4  U10 VSS_U10 EMMITSBURG_REV0P9-GFNOCPU04302A     I7 @S9S_MB_2U_LIB.S9S_MB_2U(SCH_1):PAGE180
    U4  U13 VSS_U13 EMMITSBURG_REV0P9-GFNOCPU04302A     I7 @S9S_MB_2U_LIB.S9S_MB_2U(SCH_1):PAGE180
    U4  U25 VSS_U25 EMMITSBURG_REV0P9-GFNOCPU04302A     I7 @S9S_MB_2U_LIB.S9S_MB_2U(SCH_1):PAGE180
    U4  U39 VSS_U39 EMMITSBURG_REV0P9-GFNOCPU04302A     I7 @S9S_MB_2U_LIB.S9S_MB_2U(SCH_1):PAGE180
    U4   V2 VSS_V2 EMMITSBURG_REV0P9-GFNOCPU04302A     I7 @S9S_MB_2U_LIB.S9S_MB_2U(SCH_1):PAGE180
    U4  V31 VSS_V31 EMMITSBURG_REV0P9-GFNOCPU04302A     I7 @S9S_MB_2U_LIB.S9S_MB_2U(SCH_1):PAGE180
    U4   W3 VSS_W3 EMMITSBURG_REV0P9-GFNOCPU04302A     I7 @S9S_MB_2U_LIB.S9S_MB_2U(SCH_1):PAGE180
    U4   W5 VSS_W5 EMMITSBURG_REV0P9-GFNOCPU04302A     I7 @S9S_MB_2U_LIB.S9S_MB_2U(SCH_1):PAGE180
    U4  W25 VSS_W25 EMMITSBURG_REV0P9-GFNOCPU04302A     I7 @S9S_MB_2U_LIB.S9S_MB_2U(SCH_1):PAGE180
    U4  W39 VSS_W39 EMMITSBURG_REV0P9-GFNOCPU04302A     I7 @S9S_MB_2U_LIB.S9S_MB_2U(SCH_1):PAGE180
    U4   Y8 VSS_Y8 EMMITSBURG_REV0P9-GFNOCPU04302A     I7 @S9S_MB_2U_LIB.S9S_MB_2U(SCH_1):PAGE180
    U4  Y11 VSS_Y11 EMMITSBURG_REV0P9-GFNOCPU04302A     I7 @S9S_MB_2U_LIB.S9S_MB_2U(SCH_1):PAGE180
    U4  Y15 VSS_Y15 EMMITSBURG_REV0P9-GFNOCPU04302A     I7 @S9S_MB_2U_LIB.S9S_MB_2U(SCH_1):PAGE180
    U4  Y31 VSS_Y31 EMMITSBURG_REV0P9-GFNOCPU04302A     I7 @S9S_MB_2U_LIB.S9S_MB_2U(SCH_1):PAGE180
    U4  Y34 VSS_Y34 EMMITSBURG_REV0P9-GFNOCPU04302A     I7 @S9S_MB_2U_LIB.S9S_MB_2U(SCH_1):PAGE180
    U4   A6 VSS_A6 EMMITSBURG_REV0P9-GFNOCPU04302A     I9 @S9S_MB_2U_LIB.S9S_MB_2U(SCH_1):PAGE180
    U4  A20 VSS_A20 EMMITSBURG_REV0P9-GFNOCPU04302A     I9 @S9S_MB_2U_LIB.S9S_MB_2U(SCH_1):PAGE180
    U4  A22 VSS_A22 EMMITSBURG_REV0P9-GFNOCPU04302A     I9 @S9S_MB_2U_LIB.S9S_MB_2U(SCH_1):PAGE180
    U4  A24 VSS_A24 EMMITSBURG_REV0P9-GFNOCPU04302A     I9 @S9S_MB_2U_LIB.S9S_MB_2U(SCH_1):PAGE180
    U4  A26 VSS_A26 EMMITSBURG_REV0P9-GFNOCPU04302A     I9 @S9S_MB_2U_LIB.S9S_MB_2U(SCH_1):PAGE180
    U4  A38 VSS_A38 EMMITSBURG_REV0P9-GFNOCPU04302A     I9 @S9S_MB_2U_LIB.S9S_MB_2U(SCH_1):PAGE180
    U4  A40 VSS_A40 EMMITSBURG_REV0P9-GFNOCPU04302A     I9 @S9S_MB_2U_LIB.S9S_MB_2U(SCH_1):PAGE180
    U4  AA5 VSS_AA5 EMMITSBURG_REV0P9-GFNOCPU04302A     I9 @S9S_MB_2U_LIB.S9S_MB_2U(SCH_1):PAGE180
    U4 AA17 VSS_AA17 EMMITSBURG_REV0P9-GFNOCPU04302A     I9 @S9S_MB_2U_LIB.S9S_MB_2U(SCH_1):PAGE180
    U4 AA19 VSS_AA19 EMMITSBURG_REV0P9-GFNOCPU04302A     I9 @S9S_MB_2U_LIB.S9S_MB_2U(SCH_1):PAGE180
    U4 AA20 VSS_AA20 EMMITSBURG_REV0P9-GFNOCPU04302A     I9 @S9S_MB_2U_LIB.S9S_MB_2U(SCH_1):PAGE180
    U4 AA22 VSS_AA22 EMMITSBURG_REV0P9-GFNOCPU04302A     I9 @S9S_MB_2U_LIB.S9S_MB_2U(SCH_1):PAGE180
    U4 AA24 VSS_AA24 EMMITSBURG_REV0P9-GFNOCPU04302A     I9 @S9S_MB_2U_LIB.S9S_MB_2U(SCH_1):PAGE180
    U4 AA25 VSS_AA25 EMMITSBURG_REV0P9-GFNOCPU04302A     I9 @S9S_MB_2U_LIB.S9S_MB_2U(SCH_1):PAGE180
    U4 AA27 VSS_AA27 EMMITSBURG_REV0P9-GFNOCPU04302A     I9 @S9S_MB_2U_LIB.S9S_MB_2U(SCH_1):PAGE180
    U4 AA32 VSS_AA32 EMMITSBURG_REV0P9-GFNOCPU04302A     I9 @S9S_MB_2U_LIB.S9S_MB_2U(SCH_1):PAGE180
    U4 AA36 VSS_AA36 EMMITSBURG_REV0P9-GFNOCPU04302A     I9 @S9S_MB_2U_LIB.S9S_MB_2U(SCH_1):PAGE180
    U4 AA39 VSS_AA39 EMMITSBURG_REV0P9-GFNOCPU04302A     I9 @S9S_MB_2U_LIB.S9S_MB_2U(SCH_1):PAGE180
    U4 AB15 VSS_AB15 EMMITSBURG_REV0P9-GFNOCPU04302A     I9 @S9S_MB_2U_LIB.S9S_MB_2U(SCH_1):PAGE180
    U4 AB17 VSS_AB17 EMMITSBURG_REV0P9-GFNOCPU04302A     I9 @S9S_MB_2U_LIB.S9S_MB_2U(SCH_1):PAGE180
    U4 AB25 VSS_AB25 EMMITSBURG_REV0P9-GFNOCPU04302A     I9 @S9S_MB_2U_LIB.S9S_MB_2U(SCH_1):PAGE180
    U4 AB37 VSS_AB37 EMMITSBURG_REV0P9-GFNOCPU04302A     I9 @S9S_MB_2U_LIB.S9S_MB_2U(SCH_1):PAGE180
    U4  AC5 VSS_AC5 EMMITSBURG_REV0P9-GFNOCPU04302A     I9 @S9S_MB_2U_LIB.S9S_MB_2U(SCH_1):PAGE180
    U4 AC29 VSS_AC29 EMMITSBURG_REV0P9-GFNOCPU04302A     I9 @S9S_MB_2U_LIB.S9S_MB_2U(SCH_1):PAGE180
    U4 AC32 VSS_AC32 EMMITSBURG_REV0P9-GFNOCPU04302A     I9 @S9S_MB_2U_LIB.S9S_MB_2U(SCH_1):PAGE180
    U4 AC36 VSS_AC36 EMMITSBURG_REV0P9-GFNOCPU04302A     I9 @S9S_MB_2U_LIB.S9S_MB_2U(SCH_1):PAGE180
    U4 AC39 VSS_AC39 EMMITSBURG_REV0P9-GFNOCPU04302A     I9 @S9S_MB_2U_LIB.S9S_MB_2U(SCH_1):PAGE180
    U4  AD8 VSS_AD8 EMMITSBURG_REV0P9-GFNOCPU04302A     I9 @S9S_MB_2U_LIB.S9S_MB_2U(SCH_1):PAGE180
    U4 AD11 VSS_AD11 EMMITSBURG_REV0P9-GFNOCPU04302A     I9 @S9S_MB_2U_LIB.S9S_MB_2U(SCH_1):PAGE180
    U4 AD19 VSS_AD19 EMMITSBURG_REV0P9-GFNOCPU04302A     I9 @S9S_MB_2U_LIB.S9S_MB_2U(SCH_1):PAGE180
    U4 AD20 VSS_AD20 EMMITSBURG_REV0P9-GFNOCPU04302A     I9 @S9S_MB_2U_LIB.S9S_MB_2U(SCH_1):PAGE180
    U4 AD22 VSS_AD22 EMMITSBURG_REV0P9-GFNOCPU04302A     I9 @S9S_MB_2U_LIB.S9S_MB_2U(SCH_1):PAGE180
    U4 AD24 VSS_AD24 EMMITSBURG_REV0P9-GFNOCPU04302A     I9 @S9S_MB_2U_LIB.S9S_MB_2U(SCH_1):PAGE180
    U4 AD31 VSS_AD31 EMMITSBURG_REV0P9-GFNOCPU04302A     I9 @S9S_MB_2U_LIB.S9S_MB_2U(SCH_1):PAGE180
    U4 AD34 VSS_AD34 EMMITSBURG_REV0P9-GFNOCPU04302A     I9 @S9S_MB_2U_LIB.S9S_MB_2U(SCH_1):PAGE180
    U4  AE5 VSS_AE5 EMMITSBURG_REV0P9-GFNOCPU04302A     I9 @S9S_MB_2U_LIB.S9S_MB_2U(SCH_1):PAGE180
    U4 AE13 VSS_AE13 EMMITSBURG_REV0P9-GFNOCPU04302A     I9 @S9S_MB_2U_LIB.S9S_MB_2U(SCH_1):PAGE180
    U4 AE39 VSS_AE39 EMMITSBURG_REV0P9-GFNOCPU04302A     I9 @S9S_MB_2U_LIB.S9S_MB_2U(SCH_1):PAGE180
    U4 AF19 VSS_AF19 EMMITSBURG_REV0P9-GFNOCPU04302A     I9 @S9S_MB_2U_LIB.S9S_MB_2U(SCH_1):PAGE180
    U4 AF24 VSS_AF24 EMMITSBURG_REV0P9-GFNOCPU04302A     I9 @S9S_MB_2U_LIB.S9S_MB_2U(SCH_1):PAGE180
    U4 AF31 VSS_AF31 EMMITSBURG_REV0P9-GFNOCPU04302A     I9 @S9S_MB_2U_LIB.S9S_MB_2U(SCH_1):PAGE180
    U4 AF40 VSS_AF40 EMMITSBURG_REV0P9-GFNOCPU04302A     I9 @S9S_MB_2U_LIB.S9S_MB_2U(SCH_1):PAGE180
    U4 AF42 VSS_AF42 EMMITSBURG_REV0P9-GFNOCPU04302A     I9 @S9S_MB_2U_LIB.S9S_MB_2U(SCH_1):PAGE180
    U4  AG5 VSS_AG5 EMMITSBURG_REV0P9-GFNOCPU04302A     I9 @S9S_MB_2U_LIB.S9S_MB_2U(SCH_1):PAGE180
    U4 AG13 VSS_AG13 EMMITSBURG_REV0P9-GFNOCPU04302A     I9 @S9S_MB_2U_LIB.S9S_MB_2U(SCH_1):PAGE180
    U4 AG19 VSS_AG19 EMMITSBURG_REV0P9-GFNOCPU04302A     I9 @S9S_MB_2U_LIB.S9S_MB_2U(SCH_1):PAGE180
    U4 AG24 VSS_AG24 EMMITSBURG_REV0P9-GFNOCPU04302A     I9 @S9S_MB_2U_LIB.S9S_MB_2U(SCH_1):PAGE180
    U4 AG39 VSS_AG39 EMMITSBURG_REV0P9-GFNOCPU04302A     I9 @S9S_MB_2U_LIB.S9S_MB_2U(SCH_1):PAGE180
    U4  AH8 VSS_AH8 EMMITSBURG_REV0P9-GFNOCPU04302A     I9 @S9S_MB_2U_LIB.S9S_MB_2U(SCH_1):PAGE180
    U4 AH31 VSS_AH31 EMMITSBURG_REV0P9-GFNOCPU04302A     I9 @S9S_MB_2U_LIB.S9S_MB_2U(SCH_1):PAGE180
    U4  AJ5 VSS_AJ5 EMMITSBURG_REV0P9-GFNOCPU04302A     I9 @S9S_MB_2U_LIB.S9S_MB_2U(SCH_1):PAGE180
    U4 AJ19 VSS_AJ19 EMMITSBURG_REV0P9-GFNOCPU04302A     I9 @S9S_MB_2U_LIB.S9S_MB_2U(SCH_1):PAGE180
    U4 AJ24 VSS_AJ24 EMMITSBURG_REV0P9-GFNOCPU04302A     I9 @S9S_MB_2U_LIB.S9S_MB_2U(SCH_1):PAGE180
    U4 AJ29 VSS_AJ29 EMMITSBURG_REV0P9-GFNOCPU04302A     I9 @S9S_MB_2U_LIB.S9S_MB_2U(SCH_1):PAGE180
    U4 AJ36 VSS_AJ36 EMMITSBURG_REV0P9-GFNOCPU04302A     I9 @S9S_MB_2U_LIB.S9S_MB_2U(SCH_1):PAGE180
    U4 AJ39 VSS_AJ39 EMMITSBURG_REV0P9-GFNOCPU04302A     I9 @S9S_MB_2U_LIB.S9S_MB_2U(SCH_1):PAGE180
    U4  AK2 VSS_AK2 EMMITSBURG_REV0P9-GFNOCPU04302A     I9 @S9S_MB_2U_LIB.S9S_MB_2U(SCH_1):PAGE180
    U4  AK4 VSS_AK4 EMMITSBURG_REV0P9-GFNOCPU04302A     I9 @S9S_MB_2U_LIB.S9S_MB_2U(SCH_1):PAGE180
    U4 AK11 VSS_AK11 EMMITSBURG_REV0P9-GFNOCPU04302A     I9 @S9S_MB_2U_LIB.S9S_MB_2U(SCH_1):PAGE180
    U4 AK37 VSS_AK37 EMMITSBURG_REV0P9-GFNOCPU04302A     I9 @S9S_MB_2U_LIB.S9S_MB_2U(SCH_1):PAGE180
    U4 AL19 VSS_AL19 EMMITSBURG_REV0P9-GFNOCPU04302A     I9 @S9S_MB_2U_LIB.S9S_MB_2U(SCH_1):PAGE180
    U4 AL24 VSS_AL24 EMMITSBURG_REV0P9-GFNOCPU04302A     I9 @S9S_MB_2U_LIB.S9S_MB_2U(SCH_1):PAGE180
    U4 AL27 VSS_AL27 EMMITSBURG_REV0P9-GFNOCPU04302A     I9 @S9S_MB_2U_LIB.S9S_MB_2U(SCH_1):PAGE180
    U4 AL29 VSS_AL29 EMMITSBURG_REV0P9-GFNOCPU04302A     I9 @S9S_MB_2U_LIB.S9S_MB_2U(SCH_1):PAGE180
    U4 AL39 VSS_AL39 EMMITSBURG_REV0P9-GFNOCPU04302A     I9 @S9S_MB_2U_LIB.S9S_MB_2U(SCH_1):PAGE180
    U4  AM8 VSS_AM8 EMMITSBURG_REV0P9-GFNOCPU04302A     I9 @S9S_MB_2U_LIB.S9S_MB_2U(SCH_1):PAGE180
    U4 AM15 VSS_AM15 EMMITSBURG_REV0P9-GFNOCPU04302A     I9 @S9S_MB_2U_LIB.S9S_MB_2U(SCH_1):PAGE180
    U4 AM31 VSS_AM31 EMMITSBURG_REV0P9-GFNOCPU04302A     I9 @S9S_MB_2U_LIB.S9S_MB_2U(SCH_1):PAGE180
    U4 AN13 VSS_AN13 EMMITSBURG_REV0P9-GFNOCPU04302A     I9 @S9S_MB_2U_LIB.S9S_MB_2U(SCH_1):PAGE180
    U4 AN16 VSS_AN16 EMMITSBURG_REV0P9-GFNOCPU04302A     I9 @S9S_MB_2U_LIB.S9S_MB_2U(SCH_1):PAGE180
    U4 AN29 VSS_AN29 EMMITSBURG_REV0P9-GFNOCPU04302A     I9 @S9S_MB_2U_LIB.S9S_MB_2U(SCH_1):PAGE180
    U4 AN32 VSS_AN32 EMMITSBURG_REV0P9-GFNOCPU04302A     I9 @S9S_MB_2U_LIB.S9S_MB_2U(SCH_1):PAGE180
    U4  AP5 VSS_AP5 EMMITSBURG_REV0P9-GFNOCPU04302A     I9 @S9S_MB_2U_LIB.S9S_MB_2U(SCH_1):PAGE180
    U4 AP11 VSS_AP11 EMMITSBURG_REV0P9-GFNOCPU04302A     I9 @S9S_MB_2U_LIB.S9S_MB_2U(SCH_1):PAGE180
    U4 AP18 VSS_AP18 EMMITSBURG_REV0P9-GFNOCPU04302A     I9 @S9S_MB_2U_LIB.S9S_MB_2U(SCH_1):PAGE180
    U4 AP24 VSS_AP24 EMMITSBURG_REV0P9-GFNOCPU04302A     I9 @S9S_MB_2U_LIB.S9S_MB_2U(SCH_1):PAGE180
    U4 AP28 VSS_AP28 EMMITSBURG_REV0P9-GFNOCPU04302A     I9 @S9S_MB_2U_LIB.S9S_MB_2U(SCH_1):PAGE180
    U4 AP37 VSS_AP37 EMMITSBURG_REV0P9-GFNOCPU04302A     I9 @S9S_MB_2U_LIB.S9S_MB_2U(SCH_1):PAGE180
    U4 AP39 VSS_AP39 EMMITSBURG_REV0P9-GFNOCPU04302A     I9 @S9S_MB_2U_LIB.S9S_MB_2U(SCH_1):PAGE180
    U4 AR20 VSS_AR20 EMMITSBURG_REV0P9-GFNOCPU04302A     I9 @S9S_MB_2U_LIB.S9S_MB_2U(SCH_1):PAGE180
    U4 AR32 VSS_AR32 EMMITSBURG_REV0P9-GFNOCPU04302A     I9 @S9S_MB_2U_LIB.S9S_MB_2U(SCH_1):PAGE180
    U4  AT5 VSS_AT5 EMMITSBURG_REV0P9-GFNOCPU04302A     I9 @S9S_MB_2U_LIB.S9S_MB_2U(SCH_1):PAGE180
    U4  AT8 VSS_AT8 EMMITSBURG_REV0P9-GFNOCPU04302A     I9 @S9S_MB_2U_LIB.S9S_MB_2U(SCH_1):PAGE180
    U4 AT11 VSS_AT11 EMMITSBURG_REV0P9-GFNOCPU04302A     I9 @S9S_MB_2U_LIB.S9S_MB_2U(SCH_1):PAGE180
    U4 AT15 VSS_AT15 EMMITSBURG_REV0P9-GFNOCPU04302A     I9 @S9S_MB_2U_LIB.S9S_MB_2U(SCH_1):PAGE180
    U4 AT21 VSS_AT21 EMMITSBURG_REV0P9-GFNOCPU04302A     I9 @S9S_MB_2U_LIB.S9S_MB_2U(SCH_1):PAGE180
    U4 AT24 VSS_AT24 EMMITSBURG_REV0P9-GFNOCPU04302A     I9 @S9S_MB_2U_LIB.S9S_MB_2U(SCH_1):PAGE180
    U4 AT28 VSS_AT28 EMMITSBURG_REV0P9-GFNOCPU04302A     I9 @S9S_MB_2U_LIB.S9S_MB_2U(SCH_1):PAGE180
    U4 AT31 VSS_AT31 EMMITSBURG_REV0P9-GFNOCPU04302A     I9 @S9S_MB_2U_LIB.S9S_MB_2U(SCH_1):PAGE180
    U4 AT34 VSS_AT34 EMMITSBURG_REV0P9-GFNOCPU04302A     I9 @S9S_MB_2U_LIB.S9S_MB_2U(SCH_1):PAGE180
    U4 AT39 VSS_AT39 EMMITSBURG_REV0P9-GFNOCPU04302A     I9 @S9S_MB_2U_LIB.S9S_MB_2U(SCH_1):PAGE180
    U4 AU20 VSS_AU20 EMMITSBURG_REV0P9-GFNOCPU04302A     I9 @S9S_MB_2U_LIB.S9S_MB_2U(SCH_1):PAGE180
    U4 AU23 VSS_AU23 EMMITSBURG_REV0P9-GFNOCPU04302A     I9 @S9S_MB_2U_LIB.S9S_MB_2U(SCH_1):PAGE180
    U4 AU26 VSS_AU26 EMMITSBURG_REV0P9-GFNOCPU04302A     I9 @S9S_MB_2U_LIB.S9S_MB_2U(SCH_1):PAGE180
    U4 AU29 VSS_AU29 EMMITSBURG_REV0P9-GFNOCPU04302A     I9 @S9S_MB_2U_LIB.S9S_MB_2U(SCH_1):PAGE180
    U4 AU32 VSS_AU32 EMMITSBURG_REV0P9-GFNOCPU04302A     I9 @S9S_MB_2U_LIB.S9S_MB_2U(SCH_1):PAGE180
    U4 AU36 VSS_AU36 EMMITSBURG_REV0P9-GFNOCPU04302A     I9 @S9S_MB_2U_LIB.S9S_MB_2U(SCH_1):PAGE180
    U4  AV5 VSS_AV5 EMMITSBURG_REV0P9-GFNOCPU04302A     I9 @S9S_MB_2U_LIB.S9S_MB_2U(SCH_1):PAGE180
    U4  AV8 VSS_AV8 EMMITSBURG_REV0P9-GFNOCPU04302A     I9 @S9S_MB_2U_LIB.S9S_MB_2U(SCH_1):PAGE180
    U4 AV37 VSS_AV37 EMMITSBURG_REV0P9-GFNOCPU04302A     I9 @S9S_MB_2U_LIB.S9S_MB_2U(SCH_1):PAGE180
    U4 AV39 VSS_AV39 EMMITSBURG_REV0P9-GFNOCPU04302A     I9 @S9S_MB_2U_LIB.S9S_MB_2U(SCH_1):PAGE180
    U4  AW7 VSS_AW7 EMMITSBURG_REV0P9-GFNOCPU04302A     I9 @S9S_MB_2U_LIB.S9S_MB_2U(SCH_1):PAGE180
    U4 AY11 VSS_AY11 EMMITSBURG_REV0P9-GFNOCPU04302A     I9 @S9S_MB_2U_LIB.S9S_MB_2U(SCH_1):PAGE180
    U4 AY15 VSS_AY15 EMMITSBURG_REV0P9-GFNOCPU04302A     I9 @S9S_MB_2U_LIB.S9S_MB_2U(SCH_1):PAGE180
    U4 AY18 VSS_AY18 EMMITSBURG_REV0P9-GFNOCPU04302A     I9 @S9S_MB_2U_LIB.S9S_MB_2U(SCH_1):PAGE180
    U4 AY21 VSS_AY21 EMMITSBURG_REV0P9-GFNOCPU04302A     I9 @S9S_MB_2U_LIB.S9S_MB_2U(SCH_1):PAGE180
    U4 AY24 VSS_AY24 EMMITSBURG_REV0P9-GFNOCPU04302A     I9 @S9S_MB_2U_LIB.S9S_MB_2U(SCH_1):PAGE180
    U4  BB1 VSS_BB1 EMMITSBURG_REV0P9-GFNOCPU04302A     I9 @S9S_MB_2U_LIB.S9S_MB_2U(SCH_1):PAGE180
    U4  BC2 VSS_BC2 EMMITSBURG_REV0P9-GFNOCPU04302A     I9 @S9S_MB_2U_LIB.S9S_MB_2U(SCH_1):PAGE180
    U4 BC42 VSS_BC42 EMMITSBURG_REV0P9-GFNOCPU04302A     I9 @S9S_MB_2U_LIB.S9S_MB_2U(SCH_1):PAGE180
    U4  BD1 VSS_BD1 EMMITSBURG_REV0P9-GFNOCPU04302A     I9 @S9S_MB_2U_LIB.S9S_MB_2U(SCH_1):PAGE180
    U4  BD3 VSS_BD3 EMMITSBURG_REV0P9-GFNOCPU04302A     I9 @S9S_MB_2U_LIB.S9S_MB_2U(SCH_1):PAGE180
    U4 BD41 VSS_BD41 EMMITSBURG_REV0P9-GFNOCPU04302A     I9 @S9S_MB_2U_LIB.S9S_MB_2U(SCH_1):PAGE180
    U4 BD43 VSS_BD43 EMMITSBURG_REV0P9-GFNOCPU04302A     I9 @S9S_MB_2U_LIB.S9S_MB_2U(SCH_1):PAGE180
    U4  BE1 VSS_BE1 EMMITSBURG_REV0P9-GFNOCPU04302A     I9 @S9S_MB_2U_LIB.S9S_MB_2U(SCH_1):PAGE180
    U4  BE3 VSS_BE3 EMMITSBURG_REV0P9-GFNOCPU04302A     I9 @S9S_MB_2U_LIB.S9S_MB_2U(SCH_1):PAGE180
    U4 BE41 VSS_BE41 EMMITSBURG_REV0P9-GFNOCPU04302A     I9 @S9S_MB_2U_LIB.S9S_MB_2U(SCH_1):PAGE180
    U4 BE43 VSS_BE43 EMMITSBURG_REV0P9-GFNOCPU04302A     I9 @S9S_MB_2U_LIB.S9S_MB_2U(SCH_1):PAGE180
    U4  BG4 VSS_BG4 EMMITSBURG_REV0P9-GFNOCPU04302A     I9 @S9S_MB_2U_LIB.S9S_MB_2U(SCH_1):PAGE180
    U4  BG6 VSS_BG6 EMMITSBURG_REV0P9-GFNOCPU04302A     I9 @S9S_MB_2U_LIB.S9S_MB_2U(SCH_1):PAGE180
    U4 BG38 VSS_BG38 EMMITSBURG_REV0P9-GFNOCPU04302A     I9 @S9S_MB_2U_LIB.S9S_MB_2U(SCH_1):PAGE180
    U4 BG41 VSS_BG41 EMMITSBURG_REV0P9-GFNOCPU04302A     I9 @S9S_MB_2U_LIB.S9S_MB_2U(SCH_1):PAGE180
    U4   C3 VSS_C3 EMMITSBURG_REV0P9-GFNOCPU04302A     I9 @S9S_MB_2U_LIB.S9S_MB_2U(SCH_1):PAGE180
    U4  C41 VSS_C41 EMMITSBURG_REV0P9-GFNOCPU04302A     I9 @S9S_MB_2U_LIB.S9S_MB_2U(SCH_1):PAGE180
    U4  C43 VSS_C43 EMMITSBURG_REV0P9-GFNOCPU04302A     I9 @S9S_MB_2U_LIB.S9S_MB_2U(SCH_1):PAGE180
    U4   D1 VSS_D1 EMMITSBURG_REV0P9-GFNOCPU04302A     I9 @S9S_MB_2U_LIB.S9S_MB_2U(SCH_1):PAGE180
    U4   D3 VSS_D3 EMMITSBURG_REV0P9-GFNOCPU04302A     I9 @S9S_MB_2U_LIB.S9S_MB_2U(SCH_1):PAGE180
    U4  D41 VSS_D41 EMMITSBURG_REV0P9-GFNOCPU04302A     I9 @S9S_MB_2U_LIB.S9S_MB_2U(SCH_1):PAGE180
    U4  D43 VSS_D43 EMMITSBURG_REV0P9-GFNOCPU04302A     I9 @S9S_MB_2U_LIB.S9S_MB_2U(SCH_1):PAGE180
    U4   E2 VSS_E2 EMMITSBURG_REV0P9-GFNOCPU04302A     I9 @S9S_MB_2U_LIB.S9S_MB_2U(SCH_1):PAGE180
    U4  E42 VSS_E42 EMMITSBURG_REV0P9-GFNOCPU04302A     I9 @S9S_MB_2U_LIB.S9S_MB_2U(SCH_1):PAGE180
    U4  F43 VSS_F43 EMMITSBURG_REV0P9-GFNOCPU04302A     I9 @S9S_MB_2U_LIB.S9S_MB_2U(SCH_1):PAGE180
 C1178    2      B Q_CAP_C0603-22UF,4V,20%,X6S,CHA     I6 @S9S_MB_2U_LIB.S9S_MB_2U(SCH_1):PAGE181
 C1185    2      B Q_CAP_C0603-22UF,4V,20%,X6S,CHA     I7 @S9S_MB_2U_LIB.S9S_MB_2U(SCH_1):PAGE181
 C1192    2      B Q_CAP_C0603-22UF,4V,20%,X6S,CHA     I8 @S9S_MB_2U_LIB.S9S_MB_2U(SCH_1):PAGE181
 C1205    2      B Q_CAP_C0402-10UF,6.3V,20%,X6S,A    I12 @S9S_MB_2U_LIB.S9S_MB_2U(SCH_1):PAGE181
 C1228    2      B Q_CAP_C0402-10UF,6.3V,20%,X6S,A    I13 @S9S_MB_2U_LIB.S9S_MB_2U(SCH_1):PAGE181
 C1186    2      B Q_CAP_C0603-22UF,4V,20%,X6S,CHA    I25 @S9S_MB_2U_LIB.S9S_MB_2U(SCH_1):PAGE181
 C1181    2      B Q_CAP_C0603-22UF,4V,20%,X6S,CHA    I27 @S9S_MB_2U_LIB.S9S_MB_2U(SCH_1):PAGE181
 C1202    2      B Q_CAP_C0603-22UF,4V,20%,X6S,CHA    I29 @S9S_MB_2U_LIB.S9S_MB_2U(SCH_1):PAGE181
 C1197    2      B Q_CAP_C0603-22UF,4V,20%,X6S,CHA    I30 @S9S_MB_2U_LIB.S9S_MB_2U(SCH_1):PAGE181
 C1207    2      B Q_CAP_C0402-10UF,6.3V,20%,X6S,A    I32 @S9S_MB_2U_LIB.S9S_MB_2U(SCH_1):PAGE181
 C1187    2      B Q_CAP_C0603-22UF,4V,20%,X6S,CHA    I40 @S9S_MB_2U_LIB.S9S_MB_2U(SCH_1):PAGE181
 C1182    2      B Q_CAP_C0603-22UF,4V,20%,X6S,CHA    I42 @S9S_MB_2U_LIB.S9S_MB_2U(SCH_1):PAGE181
 C1198    2      B Q_CAP_C0603-22UF,4V,20%,X6S,CHA    I43 @S9S_MB_2U_LIB.S9S_MB_2U(SCH_1):PAGE181
 C1210    2      B Q_CAP_C0402-10UF,6.3V,20%,X6S,A    I45 @S9S_MB_2U_LIB.S9S_MB_2U(SCH_1):PAGE181
 C1203    2      B Q_CAP_C0402-10UF,6.3V,20%,X6S,A    I48 @S9S_MB_2U_LIB.S9S_MB_2U(SCH_1):PAGE181
 C1231    2      B Q_CAP_C0402-10UF,6.3V,20%,X6S,A    I49 @S9S_MB_2U_LIB.S9S_MB_2U(SCH_1):PAGE181
 C1183    2      B Q_CAP_C0402-2.2UF,10V,10%,X6S,A    I51 @S9S_MB_2U_LIB.S9S_MB_2U(SCH_1):PAGE181
 C1189    2      B Q_CAP_C0402-2.2UF,10V,10%,X6S,A    I58 @S9S_MB_2U_LIB.S9S_MB_2U(SCH_1):PAGE181
 C1200    2      B Q_CAP_C0402-2.2UF,10V,10%,X6S,A    I59 @S9S_MB_2U_LIB.S9S_MB_2U(SCH_1):PAGE181
 C1204    2      B Q_CAP_C0402-2.2UF,10V,10%,X6S,A    I60 @S9S_MB_2U_LIB.S9S_MB_2U(SCH_1):PAGE181
 C1214    2      B Q_CAP_C0402-2.2UF,10V,10%,X6S,A    I61 @S9S_MB_2U_LIB.S9S_MB_2U(SCH_1):PAGE181
 C1242    2      B Q_CAP_C0402-2.2UF,10V,10%,X6S,A    I63 @S9S_MB_2U_LIB.S9S_MB_2U(SCH_1):PAGE181
 C1206    2      B Q_CAP_C0402-10UF,6.3V,20%,X6S,A    I78 @S9S_MB_2U_LIB.S9S_MB_2U(SCH_1):PAGE181
 C1201    2      B Q_CAP_C0603-22UF,6.3V,20%,X6S,A    I87 @S9S_MB_2U_LIB.S9S_MB_2U(SCH_1):PAGE181
 C1191    2      B Q_CAP_C0603-22UF,6.3V,20%,X6S,A    I89 @S9S_MB_2U_LIB.S9S_MB_2U(SCH_1):PAGE181
 C1184    2      B Q_CAP_C0603-22UF,6.3V,20%,X6S,A    I91 @S9S_MB_2U_LIB.S9S_MB_2U(SCH_1):PAGE181
 C1262    2      B Q_CAP_C0402-10UF,6.3V,20%,X6S,A   I104 @S9S_MB_2U_LIB.S9S_MB_2U(SCH_1):PAGE181
 C1251    2      B Q_CAP_C0603-10UF,6.3V,20%,X6S,A   I110 @S9S_MB_2U_LIB.S9S_MB_2U(SCH_1):PAGE181
 C1254    2      B Q_CAP_C0603-10UF,6.3V,20%,X6S,A   I111 @S9S_MB_2U_LIB.S9S_MB_2U(SCH_1):PAGE181
 C1263    2      B Q_CAP_C0402-10UF,6.3V,20%,X6S,A   I119 @S9S_MB_2U_LIB.S9S_MB_2U(SCH_1):PAGE181
 C1255    2      B Q_CAP_C0603-10UF,6.3V,20%,X6S,A   I123 @S9S_MB_2U_LIB.S9S_MB_2U(SCH_1):PAGE181
 C1252    2      B Q_CAP_C0603-10UF,6.3V,20%,X6S,A   I125 @S9S_MB_2U_LIB.S9S_MB_2U(SCH_1):PAGE181
 C1266    2      B Q_CAP_C0402-10UF,6.3V,20%,X6S,A   I127 @S9S_MB_2U_LIB.S9S_MB_2U(SCH_1):PAGE181
 C1260    2      B Q_CAP_C0603-10UF,6.3V,20%,X6S,A   I131 @S9S_MB_2U_LIB.S9S_MB_2U(SCH_1):PAGE181
 C1264    2      B Q_CAP_0402-1UF,6.3V,10%,EMPTY,A   I133 @S9S_MB_2U_LIB.S9S_MB_2U(SCH_1):PAGE181
 C1256    2      B Q_CAP_0402-1UF,6.3V,10%,EMPTY,A   I136 @S9S_MB_2U_LIB.S9S_MB_2U(SCH_1):PAGE181
 C1250    2      B Q_CAP_0402-1UF,6.3V,10%,EMPTY,A   I137 @S9S_MB_2U_LIB.S9S_MB_2U(SCH_1):PAGE181
 C1265    2      B Q_CAP_0402-1UF,6.3V,10%,EMPTY,A   I140 @S9S_MB_2U_LIB.S9S_MB_2U(SCH_1):PAGE181
 C1261    2      B Q_CAP_C0603-10UF,6.3V,20%,X6S,A   I142 @S9S_MB_2U_LIB.S9S_MB_2U(SCH_1):PAGE181
 C1257    2      B Q_CAP_0402-1UF,6.3V,10%,EMPTY,A   I146 @S9S_MB_2U_LIB.S9S_MB_2U(SCH_1):PAGE181
 C1253    2      B Q_CAP_0402-1UF,6.3V,10%,EMPTY,A   I147 @S9S_MB_2U_LIB.S9S_MB_2U(SCH_1):PAGE181
 C1920    2      B Q_CAP_C0603-22UF,6.3V,20%,X6S,A    I88 @S9S_MB_2U_LIB.S9S_MB_2U(SCH_1):PAGE182
 C1921    2      B Q_CAP_C0603-22UF,6.3V,20%,X6S,A    I90 @S9S_MB_2U_LIB.S9S_MB_2U(SCH_1):PAGE182
 C1922    2      B Q_CAP_C0603-22UF,6.3V,20%,X6S,A    I96 @S9S_MB_2U_LIB.S9S_MB_2U(SCH_1):PAGE182
 C1923    2      B Q_CAP_0402-0.1UF,25V,10%,X7R,CA    I97 @S9S_MB_2U_LIB.S9S_MB_2U(SCH_1):PAGE182
 C1924    2      B Q_CAP_0402-0.1UF,25V,10%,X7R,CA    I98 @S9S_MB_2U_LIB.S9S_MB_2U(SCH_1):PAGE182
 C1925    2      B Q_CAP_0402-0.1UF,25V,10%,X7R,CA   I100 @S9S_MB_2U_LIB.S9S_MB_2U(SCH_1):PAGE182
 R1605    2      B Q_RES_0402LF-1K,1%,1/16W,CHIP,A   I105 @S9S_MB_2U_LIB.S9S_MB_2U(SCH_1):PAGE182
  R491    2      B Q_RES_0402LF-4.7K,1%,1/16W,EMPA   I164 @S9S_MB_2U_LIB.S9S_MB_2U(SCH_1):PAGE182
   J59   G1     G1 SCONN75K_APCI0155P004A-SCONN75A   I178 @S9S_MB_2U_LIB.S9S_MB_2U(SCH_1):PAGE182
   J59   G2     G2 SCONN75K_APCI0155P004A-SCONN75A   I178 @S9S_MB_2U_LIB.S9S_MB_2U(SCH_1):PAGE182
   J59    3   GND2 SCONN75K_APCI0155P004A-SCONN75A   I178 @S9S_MB_2U_LIB.S9S_MB_2U(SCH_1):PAGE182
   J59    9   GND3 SCONN75K_APCI0155P004A-SCONN75A   I178 @S9S_MB_2U_LIB.S9S_MB_2U(SCH_1):PAGE182
   J59   15   GND4 SCONN75K_APCI0155P004A-SCONN75A   I178 @S9S_MB_2U_LIB.S9S_MB_2U(SCH_1):PAGE182
   J59   21   GND5 SCONN75K_APCI0155P004A-SCONN75A   I178 @S9S_MB_2U_LIB.S9S_MB_2U(SCH_1):PAGE182
   J59   27   GND6 SCONN75K_APCI0155P004A-SCONN75A   I178 @S9S_MB_2U_LIB.S9S_MB_2U(SCH_1):PAGE182
   J59   33   GND7 SCONN75K_APCI0155P004A-SCONN75A   I178 @S9S_MB_2U_LIB.S9S_MB_2U(SCH_1):PAGE182
   J59   39   GND8 SCONN75K_APCI0155P004A-SCONN75A   I178 @S9S_MB_2U_LIB.S9S_MB_2U(SCH_1):PAGE182
   J59   45   GND9 SCONN75K_APCI0155P004A-SCONN75A   I178 @S9S_MB_2U_LIB.S9S_MB_2U(SCH_1):PAGE182
   J59   51  GND10 SCONN75K_APCI0155P004A-SCONN75A   I178 @S9S_MB_2U_LIB.S9S_MB_2U(SCH_1):PAGE182
   J59   57  GND11 SCONN75K_APCI0155P004A-SCONN75A   I178 @S9S_MB_2U_LIB.S9S_MB_2U(SCH_1):PAGE182
   J59   71  GND12 SCONN75K_APCI0155P004A-SCONN75A   I178 @S9S_MB_2U_LIB.S9S_MB_2U(SCH_1):PAGE182
   J59   73  GND13 SCONN75K_APCI0155P004A-SCONN75A   I178 @S9S_MB_2U_LIB.S9S_MB_2U(SCH_1):PAGE182
   J59   75  GND14 SCONN75K_APCI0155P004A-SCONN75A   I178 @S9S_MB_2U_LIB.S9S_MB_2U(SCH_1):PAGE182
   U98    1    GND PCA9306DP1-PCA9306DP1,SMLF,IC,A    I27 @S9S_MB_2U_LIB.S9S_MB_2U(SCH_1):PAGE183
 C1323    2      B Q_CAP_0402-0.1UF,25V,10%,X7R,CA    I28 @S9S_MB_2U_LIB.S9S_MB_2U(SCH_1):PAGE183
 C1305    2      B Q_CAP_0402-0.1UF,25V,10%,X7R,CA    I52 @S9S_MB_2U_LIB.S9S_MB_2U(SCH_1):PAGE183
  U142    2    GND NC7SB3157_SMLF-NC7SB3157P6X,NCA    I35 @S9S_MB_2U_LIB.S9S_MB_2U(SCH_1):PAGE185
 C1612    2      B Q_CAP_C0402-1UF,25V,10%,X6S,CHA    I36 @S9S_MB_2U_LIB.S9S_MB_2U(SCH_1):PAGE185
 R2252    2      B Q_RES_0402LF-100K,1%,1/16W,EMPA    I42 @S9S_MB_2U_LIB.S9S_MB_2U(SCH_1):PAGE185
  R372    2      B Q_RES_0402LF-10K,1%,1/16W,CHIPA    I46 @S9S_MB_2U_LIB.S9S_MB_2U(SCH_1):PAGE186
  R375    2      B Q_RES_0402LF-10K,1%,1/16W,CHIPA    I61 @S9S_MB_2U_LIB.S9S_MB_2U(SCH_1):PAGE186
  R379    2      B Q_RES_0402LF-1K,1%,1/16W,CHIP,A    I76 @S9S_MB_2U_LIB.S9S_MB_2U(SCH_1):PAGE186
  R381    2      B Q_RES_0402LF-10K,1%,1/16W,CHIPA    I81 @S9S_MB_2U_LIB.S9S_MB_2U(SCH_1):PAGE186
 R1810    2      B Q_RES_0402LF-1K,1%,1/16W,EMPTYA    I88 @S9S_MB_2U_LIB.S9S_MB_2U(SCH_1):PAGE186
 R1962    2      B Q_RES_0402LF-20K,1%,1/16W,EMPTA    I90 @S9S_MB_2U_LIB.S9S_MB_2U(SCH_1):PAGE186
  R624    2      B Q_RES_0402LF-10K,1%,1/16W,CHIPA    I14 @S9S_MB_2U_LIB.S9S_MB_2U(SCH_1):PAGE187
  R614    2      B Q_RES_0402LF-1K,1%,1/16W,EMPTYA    I23 @S9S_MB_2U_LIB.S9S_MB_2U(SCH_1):PAGE187
  R608    2      B Q_RES_0402LF-10K,1%,1/16W,CHIPA    I36 @S9S_MB_2U_LIB.S9S_MB_2U(SCH_1):PAGE187
  R610    2      B Q_RES_0402LF-10K,1%,1/16W,CHIPA    I40 @S9S_MB_2U_LIB.S9S_MB_2U(SCH_1):PAGE187
  R612    2      B Q_RES_0402LF-10K,1%,1/16W,EMPTA    I44 @S9S_MB_2U_LIB.S9S_MB_2U(SCH_1):PAGE187
  R618    2      B Q_RES_0402LF-10K,1%,1/16W,CHIPA    I53 @S9S_MB_2U_LIB.S9S_MB_2U(SCH_1):PAGE187
  R622    2      B Q_RES_0402LF-1K,1%,1/16W,CHIP,A    I56 @S9S_MB_2U_LIB.S9S_MB_2U(SCH_1):PAGE187
 R1299    2      B Q_RES_0402LF-10K,1%,1/16W,CHIPA    I21 @S9S_MB_2U_LIB.S9S_MB_2U(SCH_1):PAGE188
 R1311    2      B Q_RES_0402LF-10K,1%,1/16W,CHIPA    I31 @S9S_MB_2U_LIB.S9S_MB_2U(SCH_1):PAGE188
 R1457    2      B Q_RES_0402LF-10K,1%,1/16W,CHIPA    I36 @S9S_MB_2U_LIB.S9S_MB_2U(SCH_1):PAGE188
 R1476    2      B Q_RES_0402LF-1K,1%,1/16W,CHIP,A    I43 @S9S_MB_2U_LIB.S9S_MB_2U(SCH_1):PAGE188
 R1478    2      B Q_RES_0402LF-10K,1%,1/16W,CHIPA    I50 @S9S_MB_2U_LIB.S9S_MB_2U(SCH_1):PAGE188
 R1221    2      B Q_RES_0402LF-1K,1%,1/16W,CHIP,A    I64 @S9S_MB_2U_LIB.S9S_MB_2U(SCH_1):PAGE188
 R1497    2      B Q_RES_0402LF-12K,1%,1/16W,EMPTA    I70 @S9S_MB_2U_LIB.S9S_MB_2U(SCH_1):PAGE188
 R1499    2      B Q_RES_0402LF-1K,1%,1/16W,CHIP,A    I77 @S9S_MB_2U_LIB.S9S_MB_2U(SCH_1):PAGE188
   U60    2    GND NC7SB3157_SMLF-NC7SB3157P6X,NCA    I34 @S9S_MB_2U_LIB.S9S_MB_2U(SCH_1):PAGE190
  C607    2      B Q_CAP_0402-0.1UF,25V,10%,X7R,CA    I36 @S9S_MB_2U_LIB.S9S_MB_2U(SCH_1):PAGE190
  C605    2      B Q_CAP_C0402-1UF,25V,10%,X6S,CHA    I37 @S9S_MB_2U_LIB.S9S_MB_2U(SCH_1):PAGE190
   U61    2    GND NC7SB3157_SMLF-NC7SB3157P6X,NCA    I39 @S9S_MB_2U_LIB.S9S_MB_2U(SCH_1):PAGE190
  C608    2      B Q_CAP_0402-0.1UF,25V,10%,X7R,CA    I43 @S9S_MB_2U_LIB.S9S_MB_2U(SCH_1):PAGE190
  C606    2      B Q_CAP_C0402-1UF,25V,10%,X6S,CHA    I45 @S9S_MB_2U_LIB.S9S_MB_2U(SCH_1):PAGE190
 C1647    2      B Q_CAP_0402-0.1UF,25V,10%,X7R,CA    I84 @S9S_MB_2U_LIB.S9S_MB_2U(SCH_1):PAGE190
 R1749    2      B Q_RES_0402LF-10K,1%,1/16W,EMPTA    I89 @S9S_MB_2U_LIB.S9S_MB_2U(SCH_1):PAGE190
   U38   TH   EPAD 9QXL2001BNHGI8-9QXL2001BNHGI8,A   I119 @S9S_MB_2U_LIB.S9S_MB_2U(SCH_1):PAGE195
  C209    2      B Q_CAP_C0603-10UF,6.3V,20%,X6S,A   I164 @S9S_MB_2U_LIB.S9S_MB_2U(SCH_1):PAGE195
  C211    2      B Q_CAP_0402-0.1UF,25V,10%,X7R,CA   I165 @S9S_MB_2U_LIB.S9S_MB_2U(SCH_1):PAGE195
  C208    2      B Q_CAP_C0603-10UF,6.3V,20%,X6S,A   I167 @S9S_MB_2U_LIB.S9S_MB_2U(SCH_1):PAGE195
  C210    2      B Q_CAP_0402-0.1UF,25V,10%,X7R,CA   I168 @S9S_MB_2U_LIB.S9S_MB_2U(SCH_1):PAGE195
  C204    2      B Q_CAP_0402-0.1UF,25V,10%,X7R,CA   I171 @S9S_MB_2U_LIB.S9S_MB_2U(SCH_1):PAGE195
  C205    2      B Q_CAP_0402-0.1UF,25V,10%,X7R,CA   I172 @S9S_MB_2U_LIB.S9S_MB_2U(SCH_1):PAGE195
  C206    2      B Q_CAP_0402-0.1UF,25V,10%,X7R,CA   I173 @S9S_MB_2U_LIB.S9S_MB_2U(SCH_1):PAGE195
  C207    2      B Q_CAP_0402-0.1UF,25V,10%,X7R,CA   I174 @S9S_MB_2U_LIB.S9S_MB_2U(SCH_1):PAGE195
  R568    2      B Q_RES_0402LF-4.7K,1%,1/16W,CHIA   I178 @S9S_MB_2U_LIB.S9S_MB_2U(SCH_1):PAGE195
  R570    2      B Q_RES_0402LF-4.7K,1%,1/16W,CHIA   I187 @S9S_MB_2U_LIB.S9S_MB_2U(SCH_1):PAGE195
  R574    2      B Q_RES_0402LF-4.7K,1%,1/16W,CHIA   I197 @S9S_MB_2U_LIB.S9S_MB_2U(SCH_1):PAGE195
  R106    1      A Q_RES_0402LF-2K,1%,1/16W,CHIP,A   I304 @S9S_MB_2U_LIB.S9S_MB_2U(SCH_1):PAGE195
 C1409    2      B Q_CAP_C0603-10UF,6.3V,20%,X6S,A   I419 @S9S_MB_2U_LIB.S9S_MB_2U(SCH_1):PAGE195
   U13   C1   EPAD 9SQ440NQQI8-9SQ440NQQI8,SMLF,IA   I180 @S9S_MB_2U_LIB.S9S_MB_2U(SCH_1):PAGE197
   U13  B10   GNDS 9SQ440NQQI8-9SQ440NQQI8,SMLF,IA   I180 @S9S_MB_2U_LIB.S9S_MB_2U(SCH_1):PAGE197
   U13  A14 GNDXTAL 9SQ440NQQI8-9SQ440NQQI8,SMLF,IA   I180 @S9S_MB_2U_LIB.S9S_MB_2U(SCH_1):PAGE197
   U13  B12  NVGND 9SQ440NQQI8-9SQ440NQQI8,SMLF,IA   I180 @S9S_MB_2U_LIB.S9S_MB_2U(SCH_1):PAGE197
 R1484    2      B Q_RES_0402LF-1K,1%,1/16W,EMPTYA   I268 @S9S_MB_2U_LIB.S9S_MB_2U(SCH_1):PAGE197
 R1527    2      B Q_RES_0402LF-1K,1%,1/16W,CHIP,A   I269 @S9S_MB_2U_LIB.S9S_MB_2U(SCH_1):PAGE197
 R1502    2      B Q_RES_0402LF-4.75K,1%,1/16W,CHA   I270 @S9S_MB_2U_LIB.S9S_MB_2U(SCH_1):PAGE197
 R1500    2      B Q_RES_0402LF-4.75K,1%,1/16W,CHA   I271 @S9S_MB_2U_LIB.S9S_MB_2U(SCH_1):PAGE197
 R1462    2      B Q_RES_0402LF-1K,1%,1/16W,CHIP,A   I274 @S9S_MB_2U_LIB.S9S_MB_2U(SCH_1):PAGE197
 R1390    2      B Q_RES_0402LF-1K,1%,1/16W,EMPTYA   I275 @S9S_MB_2U_LIB.S9S_MB_2U(SCH_1):PAGE197
 R1267    2      B Q_RES_0402LF-1K,1%,1/16W,CHIP,A   I276 @S9S_MB_2U_LIB.S9S_MB_2U(SCH_1):PAGE197
 R1196    2      B Q_RES_0402LF-4.75K,1%,1/16W,CHA   I281 @S9S_MB_2U_LIB.S9S_MB_2U(SCH_1):PAGE197
  R953    2      B Q_RES_0402LF-4.75K,1%,1/16W,CHA   I282 @S9S_MB_2U_LIB.S9S_MB_2U(SCH_1):PAGE197
  R734    2      B Q_RES_0402LF-4.75K,1%,1/16W,CHA   I283 @S9S_MB_2U_LIB.S9S_MB_2U(SCH_1):PAGE197
 C1324    2      B Q_CAP_0402-0.1UF,25V,10%,EMPTYA   I286 @S9S_MB_2U_LIB.S9S_MB_2U(SCH_1):PAGE197
  C172    2      B Q_CAP_C0603-10UF,6.3V,20%,X6S,A     I6 @S9S_MB_2U_LIB.S9S_MB_2U(SCH_1):PAGE199
  C108    2      B Q_CAP_C0603-10UF,6.3V,20%,X6S,A    I19 @S9S_MB_2U_LIB.S9S_MB_2U(SCH_1):PAGE199
 C1311    2      B Q_CAP_C0402-1UF,25V,10%,X6S,CHA    I43 @S9S_MB_2U_LIB.S9S_MB_2U(SCH_1):PAGE199
 C1309    2      B Q_CAP_C0603-10UF,6.3V,20%,X6S,A    I44 @S9S_MB_2U_LIB.S9S_MB_2U(SCH_1):PAGE199
 C1313    2      B Q_CAP_C0603-10UF,6.3V,20%,X6S,A    I48 @S9S_MB_2U_LIB.S9S_MB_2U(SCH_1):PAGE199
 C1314    2      B Q_CAP_C0603-10UF,6.3V,20%,X6S,A    I53 @S9S_MB_2U_LIB.S9S_MB_2U(SCH_1):PAGE199
 C1312    2      B Q_CAP_C0402-1UF,25V,10%,X6S,CHA    I58 @S9S_MB_2U_LIB.S9S_MB_2U(SCH_1):PAGE199
 C1310    2      B Q_CAP_C0603-10UF,6.3V,20%,X6S,A    I59 @S9S_MB_2U_LIB.S9S_MB_2U(SCH_1):PAGE199
 C2331    2      B Q_CAP_C0603-10UF,6.3V,20%,X6S,A     I5 @S9S_MB_2U_LIB.S9S_MB_2U(SCH_1):PAGE200
 C2332    2      B Q_CAP_C0603-10UF,6.3V,20%,X6S,A    I10 @S9S_MB_2U_LIB.S9S_MB_2U(SCH_1):PAGE200
   U89    S SOURCE MOSFET_N_SMLF-BSS138K,BSS138K,A   I236 @S9S_MB_2U_LIB.S9S_MB_2U(SCH_1):PAGE207
 R2339    2      B Q_RES_0402LF-22,5%,1/16W,CHIP,A   I268 @S9S_MB_2U_LIB.S9S_MB_2U(SCH_1):PAGE207
 R1415    2      B Q_RES_0402LF-2K,1%,1/16W,EMPTYA     I4 @S9S_MB_2U_LIB.S9S_MB_2U(SCH_1):PAGE208
 R1416    2      B Q_RES_0402LF-2K,1%,1/16W,EMPTYA     I5 @S9S_MB_2U_LIB.S9S_MB_2U(SCH_1):PAGE208
 R1418    2      B Q_RES_0402LF-2K,1%,1/16W,CHIP,A     I6 @S9S_MB_2U_LIB.S9S_MB_2U(SCH_1):PAGE208
 R1417    2      B Q_RES_0402LF-2K,1%,1/16W,CHIP,A     I7 @S9S_MB_2U_LIB.S9S_MB_2U(SCH_1):PAGE208
 R1419    2      B Q_RES_0402LF-2K,1%,1/16W,CHIP,A     I8 @S9S_MB_2U_LIB.S9S_MB_2U(SCH_1):PAGE208
 R1420    2      B Q_RES_0402LF-2K,1%,1/16W,CHIP,A     I9 @S9S_MB_2U_LIB.S9S_MB_2U(SCH_1):PAGE208
 R1421    2      B Q_RES_0402LF-2K,1%,1/16W,CHIP,A    I10 @S9S_MB_2U_LIB.S9S_MB_2U(SCH_1):PAGE208
 R1326    2      B Q_RES_0402LF-2K,1%,1/16W,EMPTYA    I11 @S9S_MB_2U_LIB.S9S_MB_2U(SCH_1):PAGE208
 R1302    2      B Q_RES_0402LF-2K,1%,1/16W,EMPTYA    I12 @S9S_MB_2U_LIB.S9S_MB_2U(SCH_1):PAGE208
 R1328    2      B Q_RES_0402LF-2K,1%,1/16W,EMPTYA    I13 @S9S_MB_2U_LIB.S9S_MB_2U(SCH_1):PAGE208
 R1327    2      B Q_RES_0402LF-2K,1%,1/16W,EMPTYA    I14 @S9S_MB_2U_LIB.S9S_MB_2U(SCH_1):PAGE208
 R1329    2      B Q_RES_0402LF-2K,1%,1/16W,EMPTYA    I15 @S9S_MB_2U_LIB.S9S_MB_2U(SCH_1):PAGE208
 R1330    2      B Q_RES_0402LF-2K,1%,1/16W,EMPTYA    I16 @S9S_MB_2U_LIB.S9S_MB_2U(SCH_1):PAGE208
 R1388    2      B Q_RES_0402LF-2K,1%,1/16W,EMPTYA    I17 @S9S_MB_2U_LIB.S9S_MB_2U(SCH_1):PAGE208
  R990    2      B Q_RES_0402LF-2K,1%,1/16W,CHIP,A    I18 @S9S_MB_2U_LIB.S9S_MB_2U(SCH_1):PAGE208
 R4533    2      B Q_RES_0402LF-2K,1%,1/16W,EMPTYA    I19 @S9S_MB_2U_LIB.S9S_MB_2U(SCH_1):PAGE208
  R991    2      B Q_RES_0402LF-2K,1%,1/16W,CHIP,A    I20 @S9S_MB_2U_LIB.S9S_MB_2U(SCH_1):PAGE208
  R992    2      B Q_RES_0402LF-2K,1%,1/16W,EMPTYA    I21 @S9S_MB_2U_LIB.S9S_MB_2U(SCH_1):PAGE208
 R1398    2      B Q_RES_0402LF-2K,1%,1/16W,EMPTYA    I22 @S9S_MB_2U_LIB.S9S_MB_2U(SCH_1):PAGE208
 R1402    2      B Q_RES_0402LF-2K,1%,1/16W,CHIP,A    I23 @S9S_MB_2U_LIB.S9S_MB_2U(SCH_1):PAGE208
 R1403    2      B Q_RES_0402LF-2K,1%,1/16W,CHIP,A    I24 @S9S_MB_2U_LIB.S9S_MB_2U(SCH_1):PAGE208
 R1404    2      B Q_RES_0402LF-2K,1%,1/16W,CHIP,A    I25 @S9S_MB_2U_LIB.S9S_MB_2U(SCH_1):PAGE208
 R1405    2      B Q_RES_0402LF-2K,1%,1/16W,CHIP,A    I26 @S9S_MB_2U_LIB.S9S_MB_2U(SCH_1):PAGE208
 R1406    2      B Q_RES_0402LF-2K,1%,1/16W,CHIP,A    I51 @S9S_MB_2U_LIB.S9S_MB_2U(SCH_1):PAGE208
 R1407    2      B Q_RES_0402LF-2K,1%,1/16W,CHIP,A    I52 @S9S_MB_2U_LIB.S9S_MB_2U(SCH_1):PAGE208
 R1408    2      B Q_RES_0402LF-2K,1%,1/16W,CHIP,A    I53 @S9S_MB_2U_LIB.S9S_MB_2U(SCH_1):PAGE208
 R1410    2      B Q_RES_0402LF-2K,1%,1/16W,CHIP,A    I54 @S9S_MB_2U_LIB.S9S_MB_2U(SCH_1):PAGE208
 R1409    2      B Q_RES_0402LF-2K,1%,1/16W,CHIP,A    I55 @S9S_MB_2U_LIB.S9S_MB_2U(SCH_1):PAGE208
 R1411    2      B Q_RES_0402LF-2K,1%,1/16W,CHIP,A    I56 @S9S_MB_2U_LIB.S9S_MB_2U(SCH_1):PAGE208
 R1412    2      B Q_RES_0402LF-2K,1%,1/16W,CHIP,A    I57 @S9S_MB_2U_LIB.S9S_MB_2U(SCH_1):PAGE208
 R1414    2      B Q_RES_0402LF-2K,1%,1/16W,CHIP,A    I58 @S9S_MB_2U_LIB.S9S_MB_2U(SCH_1):PAGE208
 R1413    2      B Q_RES_0402LF-2K,1%,1/16W,CHIP,A    I59 @S9S_MB_2U_LIB.S9S_MB_2U(SCH_1):PAGE208
  R930    2      B Q_RES_0402LF-4.7K,1%,1/16W,CHIA    I63 @S9S_MB_2U_LIB.S9S_MB_2U(SCH_1):PAGE210
  R920    2      B Q_RES_0402LF-1K,1%,1/16W,EMPTYA    I76 @S9S_MB_2U_LIB.S9S_MB_2U(SCH_1):PAGE210
   U70    S SOURCE MOSFET_N_SMLF-BSS138K,BSS138K,A    I19 @S9S_MB_2U_LIB.S9S_MB_2U(SCH_1):PAGE212
 R1541    1      A Q_RES_0402LF-100K,1%,1/16W,CHIA    I92 @S9S_MB_2U_LIB.S9S_MB_2U(SCH_1):PAGE212
  R537    2      B Q_RES_0402LF-1K,1%,1/16W,CHIP,A     I2 @S9S_MB_2U_LIB.S9S_MB_2U(SCH_1):PAGE219
  R539    2      B Q_RES_0402LF-1K,1%,1/16W,CHIP,A     I6 @S9S_MB_2U_LIB.S9S_MB_2U(SCH_1):PAGE219
  C561    2      B Q_CAP_0402-0.1UF,25V,10%,X7R,CA    I18 @S9S_MB_2U_LIB.S9S_MB_2U(SCH_1):PAGE223
  C559    2      B Q_CAP_0402-0.1UF,25V,10%,X7R,CA    I20 @S9S_MB_2U_LIB.S9S_MB_2U(SCH_1):PAGE223
  C562    2      B Q_CAP_0402-0.1UF,25V,10%,X7R,CA    I31 @S9S_MB_2U_LIB.S9S_MB_2U(SCH_1):PAGE223
   U28    4    GND PCA9617ADP-PCA9617ADP,SMLF,IC,A    I39 @S9S_MB_2U_LIB.S9S_MB_2U(SCH_1):PAGE223
  C560    2      B Q_CAP_0402-0.1UF,25V,10%,X7R,CA    I42 @S9S_MB_2U_LIB.S9S_MB_2U(SCH_1):PAGE223
   U29    4    GND PCA9617ADP-PCA9617ADP,SMLF,IC,A    I43 @S9S_MB_2U_LIB.S9S_MB_2U(SCH_1):PAGE223
   JP7    2      2 CONN3_210HP1030BR1-CONN3_210-HB    I64 @S9S_MB_2U_LIB.S9S_MB_2U(SCH_1):PAGE223
  C569    2      B Q_CAP_0402-0.1UF,25V,10%,X7R,CA    I22 @S9S_MB_2U_LIB.S9S_MB_2U(SCH_1):PAGE224
  C567    2      B Q_CAP_0402-0.1UF,25V,10%,X7R,CA    I25 @S9S_MB_2U_LIB.S9S_MB_2U(SCH_1):PAGE224
   U30    4    GND PCA9517AD-PCA9517AD,SMLF,IC,ALA    I28 @S9S_MB_2U_LIB.S9S_MB_2U(SCH_1):PAGE224
  C570    2      B Q_CAP_0402-0.1UF,25V,10%,X7R,CA    I33 @S9S_MB_2U_LIB.S9S_MB_2U(SCH_1):PAGE224
  C568    2      B Q_CAP_0402-0.1UF,25V,10%,X7R,CA    I35 @S9S_MB_2U_LIB.S9S_MB_2U(SCH_1):PAGE224
   U31    4    GND PCA9517AD-PCA9517AD,SMLF,IC,ALA    I37 @S9S_MB_2U_LIB.S9S_MB_2U(SCH_1):PAGE224
 C1613    2      B Q_CAP_0402-0.1UF,25V,10%,X7R,CA    I68 @S9S_MB_2U_LIB.S9S_MB_2U(SCH_1):PAGE224
 R2309    2      B Q_RES_0402LF-1K,1%,1/16W,CHIP,A    I85 @S9S_MB_2U_LIB.S9S_MB_2U(SCH_1):PAGE224
 R2311    2      B Q_RES_0402LF-1K,1%,1/16W,CHIP,A    I86 @S9S_MB_2U_LIB.S9S_MB_2U(SCH_1):PAGE224
 R1347    2      B Q_RES_0402LF-1K,1%,1/16W,CHIP,A    I10 @S9S_MB_2U_LIB.S9S_MB_2U(SCH_1):PAGE226
 C1291    2      B Q_CAP_C0402-1UF,25V,10%,X6S,CHA    I16 @S9S_MB_2U_LIB.S9S_MB_2U(SCH_1):PAGE226
   U84    7  GND_0 GTL2014PW-GTL2014PW,SMLF,IC,ALA    I18 @S9S_MB_2U_LIB.S9S_MB_2U(SCH_1):PAGE226
   U84    8  GND_1 GTL2014PW-GTL2014PW,SMLF,IC,ALA    I18 @S9S_MB_2U_LIB.S9S_MB_2U(SCH_1):PAGE226
   U84   11  GND_2 GTL2014PW-GTL2014PW,SMLF,IC,ALA    I18 @S9S_MB_2U_LIB.S9S_MB_2U(SCH_1):PAGE226
 C1322    2      B Q_CAP_0402-0.1UF,25V,10%,X7R,CA    I27 @S9S_MB_2U_LIB.S9S_MB_2U(SCH_1):PAGE226
 R1346    2      B Q_RES_0402LF-100,1%,1/16W,CHIPA    I34 @S9S_MB_2U_LIB.S9S_MB_2U(SCH_1):PAGE226
   U97    5    GND NX3L2267GM-NX3L2267GM,SMLF,IC,A    I38 @S9S_MB_2U_LIB.S9S_MB_2U(SCH_1):PAGE226
 C1290    2      B Q_CAP_C0402-1UF,25V,10%,X6S,CHA    I43 @S9S_MB_2U_LIB.S9S_MB_2U(SCH_1):PAGE226
   U83    7  GND_0 GTL2014PW-GTL2014PW,SMLF,IC,ALA    I45 @S9S_MB_2U_LIB.S9S_MB_2U(SCH_1):PAGE226
   U83    8  GND_1 GTL2014PW-GTL2014PW,SMLF,IC,ALA    I45 @S9S_MB_2U_LIB.S9S_MB_2U(SCH_1):PAGE226
   U83   11  GND_2 GTL2014PW-GTL2014PW,SMLF,IC,ALA    I45 @S9S_MB_2U_LIB.S9S_MB_2U(SCH_1):PAGE226
 R1369    2      B Q_RES_0402LF-1K,1%,1/16W,CHIP,A    I47 @S9S_MB_2U_LIB.S9S_MB_2U(SCH_1):PAGE226
 R1368    2      B Q_RES_0402LF-1K,1%,1/16W,CHIP,A    I48 @S9S_MB_2U_LIB.S9S_MB_2U(SCH_1):PAGE226
 C1321    2      B Q_CAP_0402-0.1UF,25V,10%,X7R,CA    I55 @S9S_MB_2U_LIB.S9S_MB_2U(SCH_1):PAGE226
   U96    5    GND NX3L2267GM-NX3L2267GM,SMLF,IC,A    I68 @S9S_MB_2U_LIB.S9S_MB_2U(SCH_1):PAGE226
 R1814    2      B Q_RES_0402LF-1K,1%,1/16W,EMPTYA    I77 @S9S_MB_2U_LIB.S9S_MB_2U(SCH_1):PAGE226
   U64    4    VSS M24128BWMN6TP-M24128-BWMN6TP,SA    I35 @S9S_MB_2U_LIB.S9S_MB_2U(SCH_1):PAGE231
  R718    2      B Q_RES_0402LF-1K,1%,1/16W,CHIP,A    I50 @S9S_MB_2U_LIB.S9S_MB_2U(SCH_1):PAGE231
  R714    2      B Q_RES_0402LF-1K,1%,1/16W,CHIP,A    I52 @S9S_MB_2U_LIB.S9S_MB_2U(SCH_1):PAGE231
  C629    2      B Q_CAP_0402-0.1UF,25V,10%,X7R,CA    I55 @S9S_MB_2U_LIB.S9S_MB_2U(SCH_1):PAGE231
  R710    2      B Q_RES_0402LF-1K,1%,1/16W,CHIP,A    I57 @S9S_MB_2U_LIB.S9S_MB_2U(SCH_1):PAGE231
  R722    2      B Q_RES_0402LF-1K,1%,1/16W,EMPTYA    I61 @S9S_MB_2U_LIB.S9S_MB_2U(SCH_1):PAGE231
 C1319    2      B Q_CAP_C0402-1UF,25V,10%,X6S,CHA    I35 @S9S_MB_2U_LIB.S9S_MB_2U(SCH_1):PAGE232
 C1316    2      B Q_CAP_C0402-0.047UF,25V,10%,X7A    I47 @S9S_MB_2U_LIB.S9S_MB_2U(SCH_1):PAGE232
  U103    1   GND0 INA183A1IDBVR-INA183A1IDBVR,SMA    I22 @S9S_MB_2U_LIB.S9S_MB_2U(SCH_1):PAGE240
  U103    2   GND1 INA183A1IDBVR-INA183A1IDBVR,SMA    I22 @S9S_MB_2U_LIB.S9S_MB_2U(SCH_1):PAGE240
  C535    2      B Q_CAP_C0805-22UF,16V,20%,X6S,CA     I4 @S9S_MB_2U_LIB.S9S_MB_2U(SCH_1):PAGE243
  C513    2      B Q_CAP_C0805-22UF,16V,20%,X6S,CA     I5 @S9S_MB_2U_LIB.S9S_MB_2U(SCH_1):PAGE243
 R1764    2      B Q_RES_0402LF-1K,1%,1/16W,EMPTYA     I8 @S9S_MB_2U_LIB.S9S_MB_2U(SCH_1):PAGE243
  PR91    2      B Q_RES_0402LF-11.8K,0.1%,1/16W,A    I25 @S9S_MB_2U_LIB.S9S_MB_2U(SCH_1):PAGE244
PC1856    2      B Q_CAP_C0805-22UF,10V,20%,X6S,CA    I34 @S9S_MB_2U_LIB.S9S_MB_2U(SCH_1):PAGE244
PC2286    2      B Q_CAP_0402-1000PF,50V,5%,EMPTYA     I8 @S9S_MB_2U_LIB.S9S_MB_2U(SCH_1):PAGE248
PC1219    2      B Q_CAP_C0402-1UF,16V,10%,X6S,CHA    I30 @S9S_MB_2U_LIB.S9S_MB_2U(SCH_1):PAGE248
PC1227    2      B Q_CAPP_THLF-560UF,2.5V,20%,OSCA    I41 @S9S_MB_2U_LIB.S9S_MB_2U(SCH_1):PAGE248
  PU74   11   AGND NB682GDZ-NB682GD-Z,SMLF,IC,AL0A    I26 @S9S_MB_2U_LIB.S9S_MB_2U(SCH_1):PAGE249
  PU74    4     C0 NB682GDZ-NB682GD-Z,SMLF,IC,AL0A    I26 @S9S_MB_2U_LIB.S9S_MB_2U(SCH_1):PAGE249
  PU74    2   PGND NB682GDZ-NB682GD-Z,SMLF,IC,AL0A    I26 @S9S_MB_2U_LIB.S9S_MB_2U(SCH_1):PAGE249
PC1236    2      B Q_CAP_C0402-100NF,50V,10%,X7R,A    I28 @S9S_MB_2U_LIB.S9S_MB_2U(SCH_1):PAGE249
PC1240    2      B Q_CAP_C0805-22UF,4V,20%,X6S,CHA    I39 @S9S_MB_2U_LIB.S9S_MB_2U(SCH_1):PAGE249
PC1355    1      A Q_CAP_0402-0.1UF,25V,10%,X7R,CA    I11 @S9S_MB_2U_LIB.S9S_MB_2U(SCH_1):PAGE253
PC298_P0_2    2      B Q_CAP_C0402-1UF,16V,10%,X6S,CHA    I22 @S9S_MB_2U_LIB.S9S_MB_2U(SCH_1):PAGE253
PC304_P0_2    2      B Q_CAP_C0805-22UF,16V,20%,X6S,CA    I24 @S9S_MB_2U_LIB.S9S_MB_2U(SCH_1):PAGE253
 PC293    2      B Q_CAP_C0402-2.2UF,10V,10%,X6S,A    I36 @S9S_MB_2U_LIB.S9S_MB_2U(SCH_1):PAGE253
PC295_P0_1    2      B Q_CAP_C0402-2.2UF,10V,10%,X6S,A    I39 @S9S_MB_2U_LIB.S9S_MB_2U(SCH_1):PAGE253
PU13_P0_1    2   AGND ISL99390FRZTR5935-ISL99390FRZ-A    I40 @S9S_MB_2U_LIB.S9S_MB_2U(SCH_1):PAGE253
PU13_P0_1    5  PGND1 ISL99390FRZTR5935-ISL99390FRZ-A    I40 @S9S_MB_2U_LIB.S9S_MB_2U(SCH_1):PAGE253
PU13_P0_1 7_9-20_24  PGND2 ISL99390FRZTR5935-ISL99390FRZ-A    I40 @S9S_MB_2U_LIB.S9S_MB_2U(SCH_1):PAGE253
PU13_P0_1   40  PGND3 ISL99390FRZTR5935-ISL99390FRZ-A    I40 @S9S_MB_2U_LIB.S9S_MB_2U(SCH_1):PAGE253
PC306_P0_2    2      B Q_CAP_C0805-22UF,16V,20%,X6S,CA    I54 @S9S_MB_2U_LIB.S9S_MB_2U(SCH_1):PAGE253
  PC16    2      B Q_CAPP_THLF-560UF,2.5V,20%,OSCA    I56 @S9S_MB_2U_LIB.S9S_MB_2U(SCH_1):PAGE253
 PC319    2      B Q_CAPP_THLF-560UF,2.5V,20%,OSCA    I62 @S9S_MB_2U_LIB.S9S_MB_2U(SCH_1):PAGE253
PC310_P0_1    2      B Q_CAP_C0402-1UF,16V,10%,X6S,CHA    I84 @S9S_MB_2U_LIB.S9S_MB_2U(SCH_1):PAGE253
 PR144    2      B Q_RES_0402LF-8.87K,1%,1/16W,EMA     I2 @S9S_MB_2U_LIB.S9S_MB_2U(SCH_1):PAGE254
PU10_P0_4    2   AGND ISL99390FRZTR5935-ISL99390FRZ-A    I13 @S9S_MB_2U_LIB.S9S_MB_2U(SCH_1):PAGE254
PU10_P0_4    5  PGND1 ISL99390FRZTR5935-ISL99390FRZ-A    I13 @S9S_MB_2U_LIB.S9S_MB_2U(SCH_1):PAGE254
PU10_P0_4 7_9-20_24  PGND2 ISL99390FRZTR5935-ISL99390FRZ-A    I13 @S9S_MB_2U_LIB.S9S_MB_2U(SCH_1):PAGE254
PU10_P0_4   40  PGND3 ISL99390FRZTR5935-ISL99390FRZ-A    I13 @S9S_MB_2U_LIB.S9S_MB_2U(SCH_1):PAGE254
PC272_P0_4    2      B Q_CAP_C0402-2.2UF,10V,10%,X6S,A    I17 @S9S_MB_2U_LIB.S9S_MB_2U(SCH_1):PAGE254
PC1341    1      A Q_CAP_0402-0.1UF,25V,10%,X7R,CA    I26 @S9S_MB_2U_LIB.S9S_MB_2U(SCH_1):PAGE254
PC273_P0_3    2      B Q_CAP_C0402-2.2UF,10V,10%,X6S,A    I30 @S9S_MB_2U_LIB.S9S_MB_2U(SCH_1):PAGE254
PC274_P0_4    2      B Q_CAP_0402-3300PF,50V,10%,X7R,A    I35 @S9S_MB_2U_LIB.S9S_MB_2U(SCH_1):PAGE254
PC276_P0_4    2      B Q_CAP_C0402-1UF,16V,10%,X6S,CHA    I38 @S9S_MB_2U_LIB.S9S_MB_2U(SCH_1):PAGE254
PC280_P0_4    2      B Q_CAP_C0805-22UF,16V,20%,X6S,CA    I39 @S9S_MB_2U_LIB.S9S_MB_2U(SCH_1):PAGE254
PC282_P0_4    2      B Q_CAP_C0805-22UF,16V,20%,X6S,CA    I40 @S9S_MB_2U_LIB.S9S_MB_2U(SCH_1):PAGE254
PC275_P0_3    2      B Q_CAP_0402-3300PF,50V,10%,X7R,A    I48 @S9S_MB_2U_LIB.S9S_MB_2U(SCH_1):PAGE254
PC281_P0_3    2      B Q_CAP_C0805-22UF,16V,20%,X6S,CA    I53 @S9S_MB_2U_LIB.S9S_MB_2U(SCH_1):PAGE254
PC285_P0_3    2      B Q_CAP_C0805-22UF,16V,20%,X6S,CA    I56 @S9S_MB_2U_LIB.S9S_MB_2U(SCH_1):PAGE254
 PR138    2      B Q_RES_0402LF-8.87K,1%,1/16W,EMA     I2 @S9S_MB_2U_LIB.S9S_MB_2U(SCH_1):PAGE255
PC1342    1      A Q_CAP_0402-0.1UF,25V,10%,X7R,CA    I11 @S9S_MB_2U_LIB.S9S_MB_2U(SCH_1):PAGE255
PU8_P0_6    2   AGND ISL99390FRZTR5935-ISL99390FRZ-A    I12 @S9S_MB_2U_LIB.S9S_MB_2U(SCH_1):PAGE255
PU8_P0_6    5  PGND1 ISL99390FRZTR5935-ISL99390FRZ-A    I12 @S9S_MB_2U_LIB.S9S_MB_2U(SCH_1):PAGE255
PU8_P0_6 7_9-20_24  PGND2 ISL99390FRZTR5935-ISL99390FRZ-A    I12 @S9S_MB_2U_LIB.S9S_MB_2U(SCH_1):PAGE255
PU8_P0_6   40  PGND3 ISL99390FRZTR5935-ISL99390FRZ-A    I12 @S9S_MB_2U_LIB.S9S_MB_2U(SCH_1):PAGE255
PC250_P0_6    2      B Q_CAP_C0402-2.2UF,10V,10%,X6S,A    I17 @S9S_MB_2U_LIB.S9S_MB_2U(SCH_1):PAGE255
PC252_P0_6    2      B Q_CAP_0402-3300PF,50V,10%,X7R,A    I34 @S9S_MB_2U_LIB.S9S_MB_2U(SCH_1):PAGE255
PC254_P0_6    2      B Q_CAP_C0402-1UF,16V,10%,X6S,CHA    I37 @S9S_MB_2U_LIB.S9S_MB_2U(SCH_1):PAGE255
PC258_P0_6    2      B Q_CAP_C0805-22UF,16V,20%,X6S,CA    I38 @S9S_MB_2U_LIB.S9S_MB_2U(SCH_1):PAGE255
PC260_P0_6    2      B Q_CAP_C0805-22UF,16V,20%,X6S,CA    I39 @S9S_MB_2U_LIB.S9S_MB_2U(SCH_1):PAGE255
PC266_P0_6    2      B Q_CAP_C0805-22UF,4V,20%,X6S,CHA    I42 @S9S_MB_2U_LIB.S9S_MB_2U(SCH_1):PAGE255
PC268_P0_6    2      B Q_CAP_C0805-22UF,4V,20%,X6S,CHA    I59 @S9S_MB_2U_LIB.S9S_MB_2U(SCH_1):PAGE255
PU6_P0_8    2   AGND ISL99390FRZTR5935-ISL99390FRZ-A     I2 @S9S_MB_2U_LIB.S9S_MB_2U(SCH_1):PAGE256
PU6_P0_8    5  PGND1 ISL99390FRZTR5935-ISL99390FRZ-A     I2 @S9S_MB_2U_LIB.S9S_MB_2U(SCH_1):PAGE256
PU6_P0_8 7_9-20_24  PGND2 ISL99390FRZTR5935-ISL99390FRZ-A     I2 @S9S_MB_2U_LIB.S9S_MB_2U(SCH_1):PAGE256
PU6_P0_8   40  PGND3 ISL99390FRZTR5935-ISL99390FRZ-A     I2 @S9S_MB_2U_LIB.S9S_MB_2U(SCH_1):PAGE256
PC232_P0_8    2      B Q_CAP_C0402-1UF,16V,10%,X6S,CHA    I20 @S9S_MB_2U_LIB.S9S_MB_2U(SCH_1):PAGE256
PC229_P0_7    2      B Q_CAP_C0402-2.2UF,10V,10%,X6S,A    I36 @S9S_MB_2U_LIB.S9S_MB_2U(SCH_1):PAGE256
 PL105    2      2 Q_INDUCTOR_SMLF-120NH/69A,IND,A    I39 @S9S_MB_2U_LIB.S9S_MB_2U(SCH_1):PAGE256
PC242_P0_8    2      B Q_CAP_C0402-1UF,16V,10%,X6S,CHA    I52 @S9S_MB_2U_LIB.S9S_MB_2U(SCH_1):PAGE256
PC241_P0_7    2      B Q_CAP_C0805-22UF,16V,20%,X6S,CA    I64 @S9S_MB_2U_LIB.S9S_MB_2U(SCH_1):PAGE256
 PR353    2      B Q_RES_0402LF-8.87K,1%,1/16W,EMA     I2 @S9S_MB_2U_LIB.S9S_MB_2U(SCH_1):PAGE257
PC610_P0_1    2      B Q_CAP_C0805-22UF,16V,20%,X6S,CA    I48 @S9S_MB_2U_LIB.S9S_MB_2U(SCH_1):PAGE257
PC618_P0_2    2      B Q_CAP_C0805-22UF,4V,20%,X6S,CHA    I59 @S9S_MB_2U_LIB.S9S_MB_2U(SCH_1):PAGE257
 PC621    2      B Q_CAPP_THLF-560UF,2.5V,20%,OSCA    I62 @S9S_MB_2U_LIB.S9S_MB_2U(SCH_1):PAGE257
PC1171    2      B Q_CAP_C0402-2.2UF,10V,10%,X6S,A    I23 @S9S_MB_2U_LIB.S9S_MB_2U(SCH_1):PAGE258
PC1182_P0_4    2      B Q_CAP_C0805-22UF,16V,20%,X6S,CA    I36 @S9S_MB_2U_LIB.S9S_MB_2U(SCH_1):PAGE258
PC1183_P0_4    2      B Q_CAP_C0402-100NF,50V,10%,X7R,A    I40 @S9S_MB_2U_LIB.S9S_MB_2U(SCH_1):PAGE258
PC1173_P0_3    2      B Q_CAP_0402-3300PF,50V,10%,X7R,A    I44 @S9S_MB_2U_LIB.S9S_MB_2U(SCH_1):PAGE258
PC1175_P0_3    2      B Q_CAP_C0402-1UF,16V,10%,X6S,CHA    I46 @S9S_MB_2U_LIB.S9S_MB_2U(SCH_1):PAGE258
PC1183_P0_3    2      B Q_CAP_C0402-1UF,16V,10%,X6S,CHA    I55 @S9S_MB_2U_LIB.S9S_MB_2U(SCH_1):PAGE258
PC1188_P0_4    2      B Q_CAP_C0805-22UF,4V,20%,X6S,CHA    I61 @S9S_MB_2U_LIB.S9S_MB_2U(SCH_1):PAGE258
PC1186    2      B Q_CAPP_THLF-560UF,2.5V,20%,OSCA    I68 @S9S_MB_2U_LIB.S9S_MB_2U(SCH_1):PAGE258
 C3274    2      B Q_CAP_0402-1000PF,50V,5%,X7R,TA    I60 @S9S_MB_2U_LIB.S9S_MB_2U(SCH_1):PAGE260
 C3273    2      B Q_CAP_0402-1000PF,50V,5%,EMPTYA    I61 @S9S_MB_2U_LIB.S9S_MB_2U(SCH_1):PAGE260
   PU5   TH TH_GND ISL69260IRAZT-ISL69260IRAZ-T,SA    I65 @S9S_MB_2U_LIB.S9S_MB_2U(SCH_1):PAGE260
PR4228    2      B Q_RES_0402LF-0,5%,1/16W,EMPTY,A    I15 @S9S_MB_2U_LIB.S9S_MB_2U(SCH_1):PAGE262
 PC176    2      B Q_CAP_0402-3300PF,50V,10%,X7R,A    I24 @S9S_MB_2U_LIB.S9S_MB_2U(SCH_1):PAGE262
 PC177    2      B Q_CAP_C0402-1UF,16V,10%,X6S,CHA    I25 @S9S_MB_2U_LIB.S9S_MB_2U(SCH_1):PAGE262
 PC180    2      B Q_CAP_C0805-22UF,16V,20%,X6S,CA    I27 @S9S_MB_2U_LIB.S9S_MB_2U(SCH_1):PAGE262
 PC181    2      B Q_CAP_C0402-100NF,50V,10%,X7R,A    I28 @S9S_MB_2U_LIB.S9S_MB_2U(SCH_1):PAGE262
 PC184    2      B Q_CAP_C0805-22UF,4V,20%,X6S,CHA    I31 @S9S_MB_2U_LIB.S9S_MB_2U(SCH_1):PAGE262
 PR373    2      B Q_RES_0402LF-1K,1%,1/16W,EMPTYA    I48 @S9S_MB_2U_LIB.S9S_MB_2U(SCH_1):PAGE264
 PC629    2      B Q_CAP_C0402-100NF,50V,10%,EMPTA    I72 @S9S_MB_2U_LIB.S9S_MB_2U(SCH_1):PAGE264
 C1300    2      B Q_CAP_0402-1000PF,50V,5%,EMPTYA    I12 @S9S_MB_2U_LIB.S9S_MB_2U(SCH_1):PAGE267
PC1248    2      B Q_CAP_C0805-22UF,16V,20%,X6S,CA    I16 @S9S_MB_2U_LIB.S9S_MB_2U(SCH_1):PAGE267
PC1249    2      B Q_CAP_C0402-1UF,16V,10%,X6S,CHA    I17 @S9S_MB_2U_LIB.S9S_MB_2U(SCH_1):PAGE267
PR3335    2      B Q_RES_0402LF-30.1K,1%,1/16W,CHA    I18 @S9S_MB_2U_LIB.S9S_MB_2U(SCH_1):PAGE267
PC1254    2      B Q_CAP_0402-0.1UF,25V,10%,X7R,CA    I38 @S9S_MB_2U_LIB.S9S_MB_2U(SCH_1):PAGE267
PC1255    2      B Q_CAP_C0805-22UF,4V,20%,X6S,CHA    I42 @S9S_MB_2U_LIB.S9S_MB_2U(SCH_1):PAGE267
PC566_P1_2    2      B Q_CAP_C0805-22UF,16V,20%,X6S,CA    I22 @S9S_MB_2U_LIB.S9S_MB_2U(SCH_1):PAGE271
 PR326    2      B Q_RES_0402LF-8.87K,1%,1/16W,EMA    I29 @S9S_MB_2U_LIB.S9S_MB_2U(SCH_1):PAGE271
PC1990    2      B Q_CAPP_SMLF-330UF,2.5V,+10/-35A    I61 @S9S_MB_2U_LIB.S9S_MB_2U(SCH_1):PAGE271
 PC587    2      B Q_CAPP_SMLF-330UF,2.5V,+10/-35A    I65 @S9S_MB_2U_LIB.S9S_MB_2U(SCH_1):PAGE271
 PC586    2      B Q_CAPP_THLF-560UF,2.5V,20%,OSCA    I69 @S9S_MB_2U_LIB.S9S_MB_2U(SCH_1):PAGE271
PC1656    2      B Q_CAP_C0402-100NF,50V,10%,X7R,A    I79 @S9S_MB_2U_LIB.S9S_MB_2U(SCH_1):PAGE271
PC572_P1_1    2      B Q_CAP_C0402-100NF,50V,10%,X7R,A    I84 @S9S_MB_2U_LIB.S9S_MB_2U(SCH_1):PAGE271
 PC523    2      B Q_CAP_C0402-2.2UF,10V,10%,X6S,A    I11 @S9S_MB_2U_LIB.S9S_MB_2U(SCH_1):PAGE272
PC1359    1      A Q_CAP_0402-0.1UF,25V,10%,X7R,CA    I27 @S9S_MB_2U_LIB.S9S_MB_2U(SCH_1):PAGE272
PC529_P1_4    2      B Q_CAP_C0402-1UF,16V,10%,X6S,CHA    I35 @S9S_MB_2U_LIB.S9S_MB_2U(SCH_1):PAGE272
PC533_P1_4    2      B Q_CAP_C0805-22UF,16V,20%,X6S,CA    I36 @S9S_MB_2U_LIB.S9S_MB_2U(SCH_1):PAGE272
PC535_P1_4    2      B Q_CAP_C0805-22UF,16V,20%,X6S,CA    I41 @S9S_MB_2U_LIB.S9S_MB_2U(SCH_1):PAGE272
PC537_P1_4    2      B Q_CAP_C0805-22UF,16V,20%,X6S,CA    I42 @S9S_MB_2U_LIB.S9S_MB_2U(SCH_1):PAGE272
PC528_P1_3    2      B Q_CAP_0402-3300PF,50V,10%,X7R,A    I48 @S9S_MB_2U_LIB.S9S_MB_2U(SCH_1):PAGE272
PC530_P1_3    2      B Q_CAP_C0402-1UF,16V,10%,X6S,CHA    I49 @S9S_MB_2U_LIB.S9S_MB_2U(SCH_1):PAGE272
PC536_P1_3    2      B Q_CAP_C0805-22UF,16V,20%,X6S,CA    I54 @S9S_MB_2U_LIB.S9S_MB_2U(SCH_1):PAGE272
 PR291    2      B Q_RES_0402LF-8.87K,1%,1/16W,EMA     I2 @S9S_MB_2U_LIB.S9S_MB_2U(SCH_1):PAGE273
PC503_P1_6    2      B Q_CAP_C0402-2.2UF,10V,10%,X6S,A    I21 @S9S_MB_2U_LIB.S9S_MB_2U(SCH_1):PAGE273
PU26_P1_5    2   AGND ISL99390FRZTR5935-ISL99390FRZ-A    I23 @S9S_MB_2U_LIB.S9S_MB_2U(SCH_1):PAGE273
PU26_P1_5    5  PGND1 ISL99390FRZTR5935-ISL99390FRZ-A    I23 @S9S_MB_2U_LIB.S9S_MB_2U(SCH_1):PAGE273
PU26_P1_5 7_9-20_24  PGND2 ISL99390FRZTR5935-ISL99390FRZ-A    I23 @S9S_MB_2U_LIB.S9S_MB_2U(SCH_1):PAGE273
PU26_P1_5   40  PGND3 ISL99390FRZTR5935-ISL99390FRZ-A    I23 @S9S_MB_2U_LIB.S9S_MB_2U(SCH_1):PAGE273
PC505_P1_6    2      B Q_CAP_0402-3300PF,50V,10%,X7R,A    I29 @S9S_MB_2U_LIB.S9S_MB_2U(SCH_1):PAGE273
PC507_P1_6    2      B Q_CAP_C0402-1UF,16V,10%,X6S,CHA    I31 @S9S_MB_2U_LIB.S9S_MB_2U(SCH_1):PAGE273
PC513_P1_6    2      B Q_CAP_C0805-22UF,16V,20%,X6S,CA    I34 @S9S_MB_2U_LIB.S9S_MB_2U(SCH_1):PAGE273
PC1361    1      A Q_CAP_0402-0.1UF,25V,10%,X7R,CA    I36 @S9S_MB_2U_LIB.S9S_MB_2U(SCH_1):PAGE273
 PC502    2      B Q_CAP_C0402-2.2UF,10V,10%,X6S,A    I37 @S9S_MB_2U_LIB.S9S_MB_2U(SCH_1):PAGE273
PC504_P1_5    2      B Q_CAP_C0402-2.2UF,10V,10%,X6S,A    I41 @S9S_MB_2U_LIB.S9S_MB_2U(SCH_1):PAGE273
PC506_P1_5    2      B Q_CAP_0402-3300PF,50V,10%,X7R,A    I45 @S9S_MB_2U_LIB.S9S_MB_2U(SCH_1):PAGE273
PC512_P1_5    2      B Q_CAP_C0805-22UF,16V,20%,X6S,CA    I50 @S9S_MB_2U_LIB.S9S_MB_2U(SCH_1):PAGE273
PC519_P1_6    2      B Q_CAP_C0805-22UF,4V,20%,X6S,CHA    I54 @S9S_MB_2U_LIB.S9S_MB_2U(SCH_1):PAGE273
 PC479    2      B Q_CAP_C0402-2.2UF,10V,10%,X6S,A     I9 @S9S_MB_2U_LIB.S9S_MB_2U(SCH_1):PAGE274
PC481_P1_8    2      B Q_CAP_C0402-2.2UF,10V,10%,X6S,A    I18 @S9S_MB_2U_LIB.S9S_MB_2U(SCH_1):PAGE274
PC489_P1_8    2      B Q_CAP_C0805-22UF,16V,20%,X6S,CA    I28 @S9S_MB_2U_LIB.S9S_MB_2U(SCH_1):PAGE274
PC1363    1      A Q_CAP_0402-0.1UF,25V,10%,X7R,CA    I32 @S9S_MB_2U_LIB.S9S_MB_2U(SCH_1):PAGE274
 PC480    2      B Q_CAP_C0402-2.2UF,10V,10%,X6S,A    I34 @S9S_MB_2U_LIB.S9S_MB_2U(SCH_1):PAGE274
PC484_P1_7    2      B Q_CAP_0402-3300PF,50V,10%,X7R,A    I37 @S9S_MB_2U_LIB.S9S_MB_2U(SCH_1):PAGE274
PC486_P1_7    2      B Q_CAP_C0402-1UF,16V,10%,X6S,CHA    I40 @S9S_MB_2U_LIB.S9S_MB_2U(SCH_1):PAGE274
PC490_P1_7    2      B Q_CAP_C0805-22UF,16V,20%,X6S,CA    I41 @S9S_MB_2U_LIB.S9S_MB_2U(SCH_1):PAGE274
PC491_P1_8    2      B Q_CAP_C0805-22UF,16V,20%,X6S,CA    I46 @S9S_MB_2U_LIB.S9S_MB_2U(SCH_1):PAGE274
PC493_P1_8    2      B Q_CAP_C0805-22UF,16V,20%,X6S,CA    I47 @S9S_MB_2U_LIB.S9S_MB_2U(SCH_1):PAGE274
PC495_P1_8    2      B Q_CAP_C0402-1UF,16V,10%,X6S,CHA    I52 @S9S_MB_2U_LIB.S9S_MB_2U(SCH_1):PAGE274
PC497_P1_8    2      B Q_CAP_C0805-22UF,4V,20%,X6S,CHA    I53 @S9S_MB_2U_LIB.S9S_MB_2U(SCH_1):PAGE274
PC499_P1_8    2      B Q_CAP_C0805-22UF,4V,20%,X6S,CHA    I54 @S9S_MB_2U_LIB.S9S_MB_2U(SCH_1):PAGE274
PR1304    2      B Q_RES_0402LF-8.87K,1%,1/16W,EMA     I2 @S9S_MB_2U_LIB.S9S_MB_2U(SCH_1):PAGE276
PC1194_P1_4    2      B Q_CAP_0402-3300PF,50V,10%,X7R,A    I33 @S9S_MB_2U_LIB.S9S_MB_2U(SCH_1):PAGE276
PC1200_P1_4    2      B Q_CAP_C0805-22UF,16V,20%,X6S,CA    I36 @S9S_MB_2U_LIB.S9S_MB_2U(SCH_1):PAGE276
PC1201    2      B Q_CAPP_THLF-560UF,2.5V,20%,OSCA    I55 @S9S_MB_2U_LIB.S9S_MB_2U(SCH_1):PAGE276
PC1204_P1_3    2      B Q_CAP_C0402-1UF,16V,10%,X6S,CHA    I56 @S9S_MB_2U_LIB.S9S_MB_2U(SCH_1):PAGE276
PC1203    2      B Q_CAPP_THLF-560UF,2.5V,20%,OSCA    I67 @S9S_MB_2U_LIB.S9S_MB_2U(SCH_1):PAGE276
PC1208_P1_3    2      B Q_CAP_C0805-22UF,4V,20%,X6S,CHA    I68 @S9S_MB_2U_LIB.S9S_MB_2U(SCH_1):PAGE276
PC1682    2      B Q_CAP_C0805-22UF,16V,20%,X6S,CA    I77 @S9S_MB_2U_LIB.S9S_MB_2U(SCH_1):PAGE276
 PR275    2      B Q_RES_0402LF-0,5%,1/16W,CHIP,CA    I26 @S9S_MB_2U_LIB.S9S_MB_2U(SCH_1):PAGE278
PC458_P1_2    2      B Q_CAP_C0805-22UF,4V,20%,X6S,CHA    I33 @S9S_MB_2U_LIB.S9S_MB_2U(SCH_1):PAGE279
PR4247    2      B Q_RES_0402LF-499,1%,1/16W,CHIPA    I34 @S9S_MB_2U_LIB.S9S_MB_2U(SCH_1):PAGE279
PC443_P1_2    2      B Q_CAP_0402-3300PF,50V,10%,X7R,A    I36 @S9S_MB_2U_LIB.S9S_MB_2U(SCH_1):PAGE279
PU50_P1_1    2   AGND ISL99390FRZTR5935-ISL99390FRZ-A    I38 @S9S_MB_2U_LIB.S9S_MB_2U(SCH_1):PAGE279
PU50_P1_1    5  PGND1 ISL99390FRZTR5935-ISL99390FRZ-A    I38 @S9S_MB_2U_LIB.S9S_MB_2U(SCH_1):PAGE279
PU50_P1_1 7_9-20_24  PGND2 ISL99390FRZTR5935-ISL99390FRZ-A    I38 @S9S_MB_2U_LIB.S9S_MB_2U(SCH_1):PAGE279
PU50_P1_1   40  PGND3 ISL99390FRZTR5935-ISL99390FRZ-A    I38 @S9S_MB_2U_LIB.S9S_MB_2U(SCH_1):PAGE279
PC444_P1_1    2      B Q_CAP_C0402-1UF,16V,10%,X6S,CHA    I41 @S9S_MB_2U_LIB.S9S_MB_2U(SCH_1):PAGE279
PC449_P1_2    2      B Q_CAP_C0805-22UF,16V,20%,X6S,CA    I43 @S9S_MB_2U_LIB.S9S_MB_2U(SCH_1):PAGE279
PC448_P1_1    2      B Q_CAP_C0805-22UF,16V,20%,X6S,CA    I51 @S9S_MB_2U_LIB.S9S_MB_2U(SCH_1):PAGE279
PC1593    2      B Q_CAPP_THLF-560UF,2.5V,20%,OSCA    I59 @S9S_MB_2U_LIB.S9S_MB_2U(SCH_1):PAGE279
PC1594    2      B Q_CAPP_SMLF-330UF,2V,35%,SPCAPA    I62 @S9S_MB_2U_LIB.S9S_MB_2U(SCH_1):PAGE279
PC1659    2      B Q_CAP_C0402-100NF,50V,10%,X7R,A    I68 @S9S_MB_2U_LIB.S9S_MB_2U(SCH_1):PAGE279
 PC460    2      B Q_CAPP_THLF-270UF,16V,20%,OSCOA    I69 @S9S_MB_2U_LIB.S9S_MB_2U(SCH_1):PAGE279
  PU49 6_7-13_15-29   GND1 RAA2213404GNPHB0-RAA2213404GNPA    I14 @S9S_MB_2U_LIB.S9S_MB_2U(SCH_1):PAGE280
  PU49   23   GND2 RAA2213404GNPHB0-RAA2213404GNPA    I14 @S9S_MB_2U_LIB.S9S_MB_2U(SCH_1):PAGE280
  PU49   26   GND3 RAA2213404GNPHB0-RAA2213404GNPA    I14 @S9S_MB_2U_LIB.S9S_MB_2U(SCH_1):PAGE280
 PC429    2      B Q_CAP_0402-3300PF,50V,10%,X7R,A    I24 @S9S_MB_2U_LIB.S9S_MB_2U(SCH_1):PAGE280
 PC432    2      B Q_CAP_C0805-22UF,16V,20%,X6S,CA    I27 @S9S_MB_2U_LIB.S9S_MB_2U(SCH_1):PAGE280
 PC435    2      B Q_CAP_C0805-22UF,4V,20%,X6S,CHA    I30 @S9S_MB_2U_LIB.S9S_MB_2U(SCH_1):PAGE280
 PC437    2      B Q_CAP_C0805-22UF,4V,20%,X6S,CHA    I31 @S9S_MB_2U_LIB.S9S_MB_2U(SCH_1):PAGE280
PC1371    1      A Q_CAP_0402-0.1UF,25V,10%,X7R,CA     I8 @S9S_MB_2U_LIB.S9S_MB_2U(SCH_1):PAGE283
PC2951    2      B Q_CAP_C0402-2.2UF,10V,10%,X6S,A    I18 @S9S_MB_2U_LIB.S9S_MB_2U(SCH_1):PAGE283
 PC374    2      B Q_CAP_0402-3300PF,50V,10%,X7R,A    I20 @S9S_MB_2U_LIB.S9S_MB_2U(SCH_1):PAGE283
 PC377    2      B Q_CAP_C0805-22UF,16V,20%,X6S,CA    I23 @S9S_MB_2U_LIB.S9S_MB_2U(SCH_1):PAGE283
 PC379    2      B Q_CAP_C0402-100NF,50V,10%,X7R,A    I27 @S9S_MB_2U_LIB.S9S_MB_2U(SCH_1):PAGE283
 PC381    2      B Q_CAP_C0805-22UF,4V,20%,X6S,CHA    I28 @S9S_MB_2U_LIB.S9S_MB_2U(SCH_1):PAGE283
PC1260    2      B Q_CAP_C0805-22UF,16V,20%,X6S,CA    I15 @S9S_MB_2U_LIB.S9S_MB_2U(SCH_1):PAGE285
PR3336    2      B Q_RES_0402LF-30.1K,1%,1/16W,CHA    I18 @S9S_MB_2U_LIB.S9S_MB_2U(SCH_1):PAGE285
 C2460    2      B Q_CAP_0402-1000PF,50V,5%,X7R,TA    I36 @S9S_MB_2U_LIB.S9S_MB_2U(SCH_1):PAGE285
   H76    1      1 HOLE_TH-EMPTY,HOLE1187    I18 @S9S_MB_2U_LIB.S9S_MB_2U(SCH_1):PAGE289
   H32    1      1 HOLE_TH-EMPTY,HOLE1248    I54 @S9S_MB_2U_LIB.S9S_MB_2U(SCH_1):PAGE289
   H31    1      1 HOLE_TH-EMPTY,HOLE1248    I56 @S9S_MB_2U_LIB.S9S_MB_2U(SCH_1):PAGE289
   H77    1      1 HOLE_TH-EMPTY,HOLE1187    I87 @S9S_MB_2U_LIB.S9S_MB_2U(SCH_1):PAGE289
 R2514    2      B Q_RES_0402LF-1K,1%,1/16W,EMPTYA    I89 @S9S_MB_2U_LIB.S9S_MB_2U(SCH_1):PAGE226
 R2513    2      B Q_RES_0402LF-0,5%,1/16W,CHIP,CA    I90 @S9S_MB_2U_LIB.S9S_MB_2U(SCH_1):PAGE226
 C1664    2      B Q_CAP_0402-0.1UF,25V,10%,X7R,CA    I93 @S9S_MB_2U_LIB.S9S_MB_2U(SCH_1):PAGE226
  R410    2      B Q_RES_0402LF-4.7K,1%,1/16W,CHIA     I2 @S9S_MB_2U_LIB.S9S_MB_2U(SCH_1):PAGE150
  R415    2      B Q_RES_0402LF-4.7K,1%,1/16W,CHIA     I4 @S9S_MB_2U_LIB.S9S_MB_2U(SCH_1):PAGE150
 R3132    1      A Q_RES_0402LF-100K,1%,1/16W,CHIA    I35 @S9S_MB_2U_LIB.S9S_MB_2U(SCH_1):PAGE150
 R1930    1      A Q_RES_0402LF-10K,1%,1/16W,CHIPA    I36 @S9S_MB_2U_LIB.S9S_MB_2U(SCH_1):PAGE150
 R1929    1      A Q_RES_0402LF-10K,1%,1/16W,CHIPA    I37 @S9S_MB_2U_LIB.S9S_MB_2U(SCH_1):PAGE150
 C1213    2      B Q_CAP_C0805-22UF,16V,20%,X6S,CB    I89 @S9S_MB_2U_LIB.S9S_MB_2U(SCH_1):PAGE150
 C1232    2      B Q_CAP_C0805-22UF,16V,20%,X6S,CB    I90 @S9S_MB_2U_LIB.S9S_MB_2U(SCH_1):PAGE150
 C1233    2      B Q_CAP_0402-0.1UF,25V,10%,X7R,CA    I91 @S9S_MB_2U_LIB.S9S_MB_2U(SCH_1):PAGE150
 C1234    2      B Q_CAP_0402-0.1UF,25V,10%,X7R,CA   I110 @S9S_MB_2U_LIB.S9S_MB_2U(SCH_1):PAGE150
 C1235    2      B Q_CAP_0402-0.1UF,25V,10%,X7R,CA   I111 @S9S_MB_2U_LIB.S9S_MB_2U(SCH_1):PAGE150
 C1236    2      B Q_CAP_0402-0.1UF,25V,10%,X7R,CA   I113 @S9S_MB_2U_LIB.S9S_MB_2U(SCH_1):PAGE150
 C1237    2      B Q_CAP_0402-0.1UF,25V,10%,X7R,CA   I114 @S9S_MB_2U_LIB.S9S_MB_2U(SCH_1):PAGE150
 C1238    2      B Q_CAP_0402-0.1UF,25V,10%,X7R,CA   I115 @S9S_MB_2U_LIB.S9S_MB_2U(SCH_1):PAGE150
 C1239    2      B Q_CAP_0402-0.1UF,25V,10%,X7R,CA   I116 @S9S_MB_2U_LIB.S9S_MB_2U(SCH_1):PAGE150
 R1895    2      B Q_RES_0402LF-100,1%,1/16W,CHIPA   I149 @S9S_MB_2U_LIB.S9S_MB_2U(SCH_1):PAGE150
 C1240    2      B Q_CAP_0402-0.1UF,25V,10%,X7R,CA   I168 @S9S_MB_2U_LIB.S9S_MB_2U(SCH_1):PAGE150
  J111   A6     A6 CONN112_10137002101LF-CONN112_A    I74 @S9S_MB_2U_LIB.S9S_MB_2U(SCH_1):PAGE148
  J111   A8     A8 CONN112_10137002101LF-CONN112_A    I74 @S9S_MB_2U_LIB.S9S_MB_2U(SCH_1):PAGE148
  J111   B5     B5 CONN112_10137002101LF-CONN112_A    I74 @S9S_MB_2U_LIB.S9S_MB_2U(SCH_1):PAGE148
  J111   B7     B7 CONN112_10137002101LF-CONN112_A    I74 @S9S_MB_2U_LIB.S9S_MB_2U(SCH_1):PAGE148
  J111   D6     D6 CONN112_10137002101LF-CONN112_A    I74 @S9S_MB_2U_LIB.S9S_MB_2U(SCH_1):PAGE148
  J111   D8     D8 CONN112_10137002101LF-CONN112_A    I74 @S9S_MB_2U_LIB.S9S_MB_2U(SCH_1):PAGE148
  J111   E5     E5 CONN112_10137002101LF-CONN112_A    I74 @S9S_MB_2U_LIB.S9S_MB_2U(SCH_1):PAGE148
  J111   E7     E7 CONN112_10137002101LF-CONN112_A    I74 @S9S_MB_2U_LIB.S9S_MB_2U(SCH_1):PAGE148
  J111   G6     G6 CONN112_10137002101LF-CONN112_A    I74 @S9S_MB_2U_LIB.S9S_MB_2U(SCH_1):PAGE148
  J111   G8     G8 CONN112_10137002101LF-CONN112_A    I74 @S9S_MB_2U_LIB.S9S_MB_2U(SCH_1):PAGE148
  J111   H5     H5 CONN112_10137002101LF-CONN112_A    I74 @S9S_MB_2U_LIB.S9S_MB_2U(SCH_1):PAGE148
  J111   H7     H7 CONN112_10137002101LF-CONN112_A    I74 @S9S_MB_2U_LIB.S9S_MB_2U(SCH_1):PAGE148
  J111   J6     J6 CONN112_10137002101LF-CONN112_A    I74 @S9S_MB_2U_LIB.S9S_MB_2U(SCH_1):PAGE148
  J111   J8     J8 CONN112_10137002101LF-CONN112_A    I74 @S9S_MB_2U_LIB.S9S_MB_2U(SCH_1):PAGE148
  J111   K5     K5 CONN112_10137002101LF-CONN112_A    I74 @S9S_MB_2U_LIB.S9S_MB_2U(SCH_1):PAGE148
  J111   K7     K7 CONN112_10137002101LF-CONN112_A    I74 @S9S_MB_2U_LIB.S9S_MB_2U(SCH_1):PAGE148
  J111   M6     M6 CONN112_10137002101LF-CONN112_A    I74 @S9S_MB_2U_LIB.S9S_MB_2U(SCH_1):PAGE148
  J111   M8     M8 CONN112_10137002101LF-CONN112_A    I74 @S9S_MB_2U_LIB.S9S_MB_2U(SCH_1):PAGE148
  J111   N5     N5 CONN112_10137002101LF-CONN112_A    I74 @S9S_MB_2U_LIB.S9S_MB_2U(SCH_1):PAGE148
  J111   N7     N7 CONN112_10137002101LF-CONN112_A    I74 @S9S_MB_2U_LIB.S9S_MB_2U(SCH_1):PAGE148
  J112   A6     A6 CONN160_10131762101LF-CONN160_A    I75 @S9S_MB_2U_LIB.S9S_MB_2U(SCH_1):PAGE149
  J112   A8     A8 CONN160_10131762101LF-CONN160_A    I75 @S9S_MB_2U_LIB.S9S_MB_2U(SCH_1):PAGE149
  J112   B5     B5 CONN160_10131762101LF-CONN160_A    I75 @S9S_MB_2U_LIB.S9S_MB_2U(SCH_1):PAGE149
  J112   B7     B7 CONN160_10131762101LF-CONN160_A    I75 @S9S_MB_2U_LIB.S9S_MB_2U(SCH_1):PAGE149
  J112   D6     D6 CONN160_10131762101LF-CONN160_A    I75 @S9S_MB_2U_LIB.S9S_MB_2U(SCH_1):PAGE149
  J112   D8     D8 CONN160_10131762101LF-CONN160_A    I75 @S9S_MB_2U_LIB.S9S_MB_2U(SCH_1):PAGE149
  J112   E5     E5 CONN160_10131762101LF-CONN160_A    I75 @S9S_MB_2U_LIB.S9S_MB_2U(SCH_1):PAGE149
  J112   E7     E7 CONN160_10131762101LF-CONN160_A    I75 @S9S_MB_2U_LIB.S9S_MB_2U(SCH_1):PAGE149
  J112   G6     G6 CONN160_10131762101LF-CONN160_A    I75 @S9S_MB_2U_LIB.S9S_MB_2U(SCH_1):PAGE149
  J112   G8     G8 CONN160_10131762101LF-CONN160_A    I75 @S9S_MB_2U_LIB.S9S_MB_2U(SCH_1):PAGE149
  J112   H5     H5 CONN160_10131762101LF-CONN160_A    I75 @S9S_MB_2U_LIB.S9S_MB_2U(SCH_1):PAGE149
  J112   H7     H7 CONN160_10131762101LF-CONN160_A    I75 @S9S_MB_2U_LIB.S9S_MB_2U(SCH_1):PAGE149
  J112   J6     J6 CONN160_10131762101LF-CONN160_A    I75 @S9S_MB_2U_LIB.S9S_MB_2U(SCH_1):PAGE149
  J112   J8     J8 CONN160_10131762101LF-CONN160_A    I75 @S9S_MB_2U_LIB.S9S_MB_2U(SCH_1):PAGE149
  J112   K5     K5 CONN160_10131762101LF-CONN160_A    I75 @S9S_MB_2U_LIB.S9S_MB_2U(SCH_1):PAGE149
  J112   K7     K7 CONN160_10131762101LF-CONN160_A    I75 @S9S_MB_2U_LIB.S9S_MB_2U(SCH_1):PAGE149
  J112   M6     M6 CONN160_10131762101LF-CONN160_A    I75 @S9S_MB_2U_LIB.S9S_MB_2U(SCH_1):PAGE149
  J112   M8     M8 CONN160_10131762101LF-CONN160_A    I75 @S9S_MB_2U_LIB.S9S_MB_2U(SCH_1):PAGE149
  J112   N5     N5 CONN160_10131762101LF-CONN160_A    I75 @S9S_MB_2U_LIB.S9S_MB_2U(SCH_1):PAGE149
  J112   N7     N7 CONN160_10131762101LF-CONN160_A    I75 @S9S_MB_2U_LIB.S9S_MB_2U(SCH_1):PAGE149
  J112   P6     P6 CONN160_10131762101LF-CONN160_A    I75 @S9S_MB_2U_LIB.S9S_MB_2U(SCH_1):PAGE149
  J112   P8     P8 CONN160_10131762101LF-CONN160_A    I75 @S9S_MB_2U_LIB.S9S_MB_2U(SCH_1):PAGE149
  J112   Q5     Q5 CONN160_10131762101LF-CONN160_A    I75 @S9S_MB_2U_LIB.S9S_MB_2U(SCH_1):PAGE149
  J112   Q7     Q7 CONN160_10131762101LF-CONN160_A    I75 @S9S_MB_2U_LIB.S9S_MB_2U(SCH_1):PAGE149
  J112   S6     S6 CONN160_10131762101LF-CONN160_A    I75 @S9S_MB_2U_LIB.S9S_MB_2U(SCH_1):PAGE149
  J112   S8     S8 CONN160_10131762101LF-CONN160_A    I75 @S9S_MB_2U_LIB.S9S_MB_2U(SCH_1):PAGE149
  J112   T5     T5 CONN160_10131762101LF-CONN160_A    I75 @S9S_MB_2U_LIB.S9S_MB_2U(SCH_1):PAGE149
  J112   T7     T7 CONN160_10131762101LF-CONN160_A    I75 @S9S_MB_2U_LIB.S9S_MB_2U(SCH_1):PAGE149
  J112   A2     A2 CONN160_10131762101LF-CONN160_A    I76 @S9S_MB_2U_LIB.S9S_MB_2U(SCH_1):PAGE149
  J112   A4     A4 CONN160_10131762101LF-CONN160_A    I76 @S9S_MB_2U_LIB.S9S_MB_2U(SCH_1):PAGE149
  J112   B1     B1 CONN160_10131762101LF-CONN160_A    I76 @S9S_MB_2U_LIB.S9S_MB_2U(SCH_1):PAGE149
  J112   B3     B3 CONN160_10131762101LF-CONN160_A    I76 @S9S_MB_2U_LIB.S9S_MB_2U(SCH_1):PAGE149
  J112   D2     D2 CONN160_10131762101LF-CONN160_A    I76 @S9S_MB_2U_LIB.S9S_MB_2U(SCH_1):PAGE149
  J112   D4     D4 CONN160_10131762101LF-CONN160_A    I76 @S9S_MB_2U_LIB.S9S_MB_2U(SCH_1):PAGE149
  J112   E1     E1 CONN160_10131762101LF-CONN160_A    I76 @S9S_MB_2U_LIB.S9S_MB_2U(SCH_1):PAGE149
  J112   E3     E3 CONN160_10131762101LF-CONN160_A    I76 @S9S_MB_2U_LIB.S9S_MB_2U(SCH_1):PAGE149
  J112   G2     G2 CONN160_10131762101LF-CONN160_A    I76 @S9S_MB_2U_LIB.S9S_MB_2U(SCH_1):PAGE149
  J112   G4     G4 CONN160_10131762101LF-CONN160_A    I76 @S9S_MB_2U_LIB.S9S_MB_2U(SCH_1):PAGE149
  J112   H1     H1 CONN160_10131762101LF-CONN160_A    I76 @S9S_MB_2U_LIB.S9S_MB_2U(SCH_1):PAGE149
  J112   H3     H3 CONN160_10131762101LF-CONN160_A    I76 @S9S_MB_2U_LIB.S9S_MB_2U(SCH_1):PAGE149
  J112   J2     J2 CONN160_10131762101LF-CONN160_A    I76 @S9S_MB_2U_LIB.S9S_MB_2U(SCH_1):PAGE149
  J112   J4     J4 CONN160_10131762101LF-CONN160_A    I76 @S9S_MB_2U_LIB.S9S_MB_2U(SCH_1):PAGE149
  J112   K1     K1 CONN160_10131762101LF-CONN160_A    I76 @S9S_MB_2U_LIB.S9S_MB_2U(SCH_1):PAGE149
  J112   K3     K3 CONN160_10131762101LF-CONN160_A    I76 @S9S_MB_2U_LIB.S9S_MB_2U(SCH_1):PAGE149
  J112   M2     M2 CONN160_10131762101LF-CONN160_A    I76 @S9S_MB_2U_LIB.S9S_MB_2U(SCH_1):PAGE149
  J112   M4     M4 CONN160_10131762101LF-CONN160_A    I76 @S9S_MB_2U_LIB.S9S_MB_2U(SCH_1):PAGE149
  J112   N1     N1 CONN160_10131762101LF-CONN160_A    I76 @S9S_MB_2U_LIB.S9S_MB_2U(SCH_1):PAGE149
  J112   N3     N3 CONN160_10131762101LF-CONN160_A    I76 @S9S_MB_2U_LIB.S9S_MB_2U(SCH_1):PAGE149
  J112   P2     P2 CONN160_10131762101LF-CONN160_A    I76 @S9S_MB_2U_LIB.S9S_MB_2U(SCH_1):PAGE149
  J112   P4     P4 CONN160_10131762101LF-CONN160_A    I76 @S9S_MB_2U_LIB.S9S_MB_2U(SCH_1):PAGE149
  J112   Q1     Q1 CONN160_10131762101LF-CONN160_A    I76 @S9S_MB_2U_LIB.S9S_MB_2U(SCH_1):PAGE149
  J112   Q3     Q3 CONN160_10131762101LF-CONN160_A    I76 @S9S_MB_2U_LIB.S9S_MB_2U(SCH_1):PAGE149
  J112   S2     S2 CONN160_10131762101LF-CONN160_A    I76 @S9S_MB_2U_LIB.S9S_MB_2U(SCH_1):PAGE149
  J112   S4     S4 CONN160_10131762101LF-CONN160_A    I76 @S9S_MB_2U_LIB.S9S_MB_2U(SCH_1):PAGE149
  J112   T1     T1 CONN160_10131762101LF-CONN160_A    I76 @S9S_MB_2U_LIB.S9S_MB_2U(SCH_1):PAGE149
  J112   T3     T3 CONN160_10131762101LF-CONN160_A    I76 @S9S_MB_2U_LIB.S9S_MB_2U(SCH_1):PAGE149
  J111   A2     A2 CONN112_10137002101LF-CONN112_A    I75 @S9S_MB_2U_LIB.S9S_MB_2U(SCH_1):PAGE148
  J111   A4     A4 CONN112_10137002101LF-CONN112_A    I75 @S9S_MB_2U_LIB.S9S_MB_2U(SCH_1):PAGE148
  J111   B1     B1 CONN112_10137002101LF-CONN112_A    I75 @S9S_MB_2U_LIB.S9S_MB_2U(SCH_1):PAGE148
  J111   B3     B3 CONN112_10137002101LF-CONN112_A    I75 @S9S_MB_2U_LIB.S9S_MB_2U(SCH_1):PAGE148
  J111   D2     D2 CONN112_10137002101LF-CONN112_A    I75 @S9S_MB_2U_LIB.S9S_MB_2U(SCH_1):PAGE148
  J111   D4     D4 CONN112_10137002101LF-CONN112_A    I75 @S9S_MB_2U_LIB.S9S_MB_2U(SCH_1):PAGE148
  J111   E1     E1 CONN112_10137002101LF-CONN112_A    I75 @S9S_MB_2U_LIB.S9S_MB_2U(SCH_1):PAGE148
  J111   E3     E3 CONN112_10137002101LF-CONN112_A    I75 @S9S_MB_2U_LIB.S9S_MB_2U(SCH_1):PAGE148
  J111   G2     G2 CONN112_10137002101LF-CONN112_A    I75 @S9S_MB_2U_LIB.S9S_MB_2U(SCH_1):PAGE148
  J111   G4     G4 CONN112_10137002101LF-CONN112_A    I75 @S9S_MB_2U_LIB.S9S_MB_2U(SCH_1):PAGE148
  J111   H1     H1 CONN112_10137002101LF-CONN112_A    I75 @S9S_MB_2U_LIB.S9S_MB_2U(SCH_1):PAGE148
  J111   H3     H3 CONN112_10137002101LF-CONN112_A    I75 @S9S_MB_2U_LIB.S9S_MB_2U(SCH_1):PAGE148
  J111   J2     J2 CONN112_10137002101LF-CONN112_A    I75 @S9S_MB_2U_LIB.S9S_MB_2U(SCH_1):PAGE148
  J111   J4     J4 CONN112_10137002101LF-CONN112_A    I75 @S9S_MB_2U_LIB.S9S_MB_2U(SCH_1):PAGE148
  J111   K1     K1 CONN112_10137002101LF-CONN112_A    I75 @S9S_MB_2U_LIB.S9S_MB_2U(SCH_1):PAGE148
  J111   K3     K3 CONN112_10137002101LF-CONN112_A    I75 @S9S_MB_2U_LIB.S9S_MB_2U(SCH_1):PAGE148
  J111   M2     M2 CONN112_10137002101LF-CONN112_A    I75 @S9S_MB_2U_LIB.S9S_MB_2U(SCH_1):PAGE148
  J111   M4     M4 CONN112_10137002101LF-CONN112_A    I75 @S9S_MB_2U_LIB.S9S_MB_2U(SCH_1):PAGE148
  J111   N1     N1 CONN112_10137002101LF-CONN112_A    I75 @S9S_MB_2U_LIB.S9S_MB_2U(SCH_1):PAGE148
  J111   N3     N3 CONN112_10137002101LF-CONN112_A    I75 @S9S_MB_2U_LIB.S9S_MB_2U(SCH_1):PAGE148
  J105   A2     A2 CONN112_10137002101LF-CONN112_A    I65 @S9S_MB_2U_LIB.S9S_MB_2U(SCH_1):PAGE142
  J105   A4     A4 CONN112_10137002101LF-CONN112_A    I65 @S9S_MB_2U_LIB.S9S_MB_2U(SCH_1):PAGE142
  J105   B1     B1 CONN112_10137002101LF-CONN112_A    I65 @S9S_MB_2U_LIB.S9S_MB_2U(SCH_1):PAGE142
  J105   B3     B3 CONN112_10137002101LF-CONN112_A    I65 @S9S_MB_2U_LIB.S9S_MB_2U(SCH_1):PAGE142
  J105   D2     D2 CONN112_10137002101LF-CONN112_A    I65 @S9S_MB_2U_LIB.S9S_MB_2U(SCH_1):PAGE142
  J105   D4     D4 CONN112_10137002101LF-CONN112_A    I65 @S9S_MB_2U_LIB.S9S_MB_2U(SCH_1):PAGE142
  J105   E1     E1 CONN112_10137002101LF-CONN112_A    I65 @S9S_MB_2U_LIB.S9S_MB_2U(SCH_1):PAGE142
  J105   E3     E3 CONN112_10137002101LF-CONN112_A    I65 @S9S_MB_2U_LIB.S9S_MB_2U(SCH_1):PAGE142
  J105   G2     G2 CONN112_10137002101LF-CONN112_A    I65 @S9S_MB_2U_LIB.S9S_MB_2U(SCH_1):PAGE142
  J105   G4     G4 CONN112_10137002101LF-CONN112_A    I65 @S9S_MB_2U_LIB.S9S_MB_2U(SCH_1):PAGE142
  J105   H1     H1 CONN112_10137002101LF-CONN112_A    I65 @S9S_MB_2U_LIB.S9S_MB_2U(SCH_1):PAGE142
  J105   H3     H3 CONN112_10137002101LF-CONN112_A    I65 @S9S_MB_2U_LIB.S9S_MB_2U(SCH_1):PAGE142
  J105   J2     J2 CONN112_10137002101LF-CONN112_A    I65 @S9S_MB_2U_LIB.S9S_MB_2U(SCH_1):PAGE142
  J105   J4     J4 CONN112_10137002101LF-CONN112_A    I65 @S9S_MB_2U_LIB.S9S_MB_2U(SCH_1):PAGE142
  J105   K1     K1 CONN112_10137002101LF-CONN112_A    I65 @S9S_MB_2U_LIB.S9S_MB_2U(SCH_1):PAGE142
  J105   K3     K3 CONN112_10137002101LF-CONN112_A    I65 @S9S_MB_2U_LIB.S9S_MB_2U(SCH_1):PAGE142
  J105   M2     M2 CONN112_10137002101LF-CONN112_A    I65 @S9S_MB_2U_LIB.S9S_MB_2U(SCH_1):PAGE142
  J105   M4     M4 CONN112_10137002101LF-CONN112_A    I65 @S9S_MB_2U_LIB.S9S_MB_2U(SCH_1):PAGE142
  J105   N1     N1 CONN112_10137002101LF-CONN112_A    I65 @S9S_MB_2U_LIB.S9S_MB_2U(SCH_1):PAGE142
  J105   N3     N3 CONN112_10137002101LF-CONN112_A    I65 @S9S_MB_2U_LIB.S9S_MB_2U(SCH_1):PAGE142
  J105   A6     A6 CONN112_10137002101LF-CONN112_A    I68 @S9S_MB_2U_LIB.S9S_MB_2U(SCH_1):PAGE142
  J105   A8     A8 CONN112_10137002101LF-CONN112_A    I68 @S9S_MB_2U_LIB.S9S_MB_2U(SCH_1):PAGE142
  J105   B5     B5 CONN112_10137002101LF-CONN112_A    I68 @S9S_MB_2U_LIB.S9S_MB_2U(SCH_1):PAGE142
  J105   B7     B7 CONN112_10137002101LF-CONN112_A    I68 @S9S_MB_2U_LIB.S9S_MB_2U(SCH_1):PAGE142
  J105   D6     D6 CONN112_10137002101LF-CONN112_A    I68 @S9S_MB_2U_LIB.S9S_MB_2U(SCH_1):PAGE142
  J105   D8     D8 CONN112_10137002101LF-CONN112_A    I68 @S9S_MB_2U_LIB.S9S_MB_2U(SCH_1):PAGE142
  J105   E5     E5 CONN112_10137002101LF-CONN112_A    I68 @S9S_MB_2U_LIB.S9S_MB_2U(SCH_1):PAGE142
  J105   E7     E7 CONN112_10137002101LF-CONN112_A    I68 @S9S_MB_2U_LIB.S9S_MB_2U(SCH_1):PAGE142
  J105   G6     G6 CONN112_10137002101LF-CONN112_A    I68 @S9S_MB_2U_LIB.S9S_MB_2U(SCH_1):PAGE142
  J105   G8     G8 CONN112_10137002101LF-CONN112_A    I68 @S9S_MB_2U_LIB.S9S_MB_2U(SCH_1):PAGE142
  J105   H5     H5 CONN112_10137002101LF-CONN112_A    I68 @S9S_MB_2U_LIB.S9S_MB_2U(SCH_1):PAGE142
  J105   H7     H7 CONN112_10137002101LF-CONN112_A    I68 @S9S_MB_2U_LIB.S9S_MB_2U(SCH_1):PAGE142
  J105   J6     J6 CONN112_10137002101LF-CONN112_A    I68 @S9S_MB_2U_LIB.S9S_MB_2U(SCH_1):PAGE142
  J105   J8     J8 CONN112_10137002101LF-CONN112_A    I68 @S9S_MB_2U_LIB.S9S_MB_2U(SCH_1):PAGE142
  J105   K5     K5 CONN112_10137002101LF-CONN112_A    I68 @S9S_MB_2U_LIB.S9S_MB_2U(SCH_1):PAGE142
  J105   K7     K7 CONN112_10137002101LF-CONN112_A    I68 @S9S_MB_2U_LIB.S9S_MB_2U(SCH_1):PAGE142
  J105   M6     M6 CONN112_10137002101LF-CONN112_A    I68 @S9S_MB_2U_LIB.S9S_MB_2U(SCH_1):PAGE142
  J105   M8     M8 CONN112_10137002101LF-CONN112_A    I68 @S9S_MB_2U_LIB.S9S_MB_2U(SCH_1):PAGE142
  J105   N5     N5 CONN112_10137002101LF-CONN112_A    I68 @S9S_MB_2U_LIB.S9S_MB_2U(SCH_1):PAGE142
  J105   N7     N7 CONN112_10137002101LF-CONN112_A    I68 @S9S_MB_2U_LIB.S9S_MB_2U(SCH_1):PAGE142
  J106   A2     A2 CONN112_10137002101LF-CONN112_A    I65 @S9S_MB_2U_LIB.S9S_MB_2U(SCH_1):PAGE144
  J106   A4     A4 CONN112_10137002101LF-CONN112_A    I65 @S9S_MB_2U_LIB.S9S_MB_2U(SCH_1):PAGE144
  J106   B1     B1 CONN112_10137002101LF-CONN112_A    I65 @S9S_MB_2U_LIB.S9S_MB_2U(SCH_1):PAGE144
  J106   B3     B3 CONN112_10137002101LF-CONN112_A    I65 @S9S_MB_2U_LIB.S9S_MB_2U(SCH_1):PAGE144
  J106   D2     D2 CONN112_10137002101LF-CONN112_A    I65 @S9S_MB_2U_LIB.S9S_MB_2U(SCH_1):PAGE144
  J106   D4     D4 CONN112_10137002101LF-CONN112_A    I65 @S9S_MB_2U_LIB.S9S_MB_2U(SCH_1):PAGE144
  J106   E1     E1 CONN112_10137002101LF-CONN112_A    I65 @S9S_MB_2U_LIB.S9S_MB_2U(SCH_1):PAGE144
  J106   E3     E3 CONN112_10137002101LF-CONN112_A    I65 @S9S_MB_2U_LIB.S9S_MB_2U(SCH_1):PAGE144
  J106   G2     G2 CONN112_10137002101LF-CONN112_A    I65 @S9S_MB_2U_LIB.S9S_MB_2U(SCH_1):PAGE144
  J106   G4     G4 CONN112_10137002101LF-CONN112_A    I65 @S9S_MB_2U_LIB.S9S_MB_2U(SCH_1):PAGE144
  J106   H1     H1 CONN112_10137002101LF-CONN112_A    I65 @S9S_MB_2U_LIB.S9S_MB_2U(SCH_1):PAGE144
  J106   H3     H3 CONN112_10137002101LF-CONN112_A    I65 @S9S_MB_2U_LIB.S9S_MB_2U(SCH_1):PAGE144
  J106   J2     J2 CONN112_10137002101LF-CONN112_A    I65 @S9S_MB_2U_LIB.S9S_MB_2U(SCH_1):PAGE144
  J106   J4     J4 CONN112_10137002101LF-CONN112_A    I65 @S9S_MB_2U_LIB.S9S_MB_2U(SCH_1):PAGE144
  J106   K1     K1 CONN112_10137002101LF-CONN112_A    I65 @S9S_MB_2U_LIB.S9S_MB_2U(SCH_1):PAGE144
  J106   K3     K3 CONN112_10137002101LF-CONN112_A    I65 @S9S_MB_2U_LIB.S9S_MB_2U(SCH_1):PAGE144
  J106   M2     M2 CONN112_10137002101LF-CONN112_A    I65 @S9S_MB_2U_LIB.S9S_MB_2U(SCH_1):PAGE144
  J106   M4     M4 CONN112_10137002101LF-CONN112_A    I65 @S9S_MB_2U_LIB.S9S_MB_2U(SCH_1):PAGE144
  J106   N1     N1 CONN112_10137002101LF-CONN112_A    I65 @S9S_MB_2U_LIB.S9S_MB_2U(SCH_1):PAGE144
  J106   N3     N3 CONN112_10137002101LF-CONN112_A    I65 @S9S_MB_2U_LIB.S9S_MB_2U(SCH_1):PAGE144
  J106   A6     A6 CONN112_10137002101LF-CONN112_A    I68 @S9S_MB_2U_LIB.S9S_MB_2U(SCH_1):PAGE144
  J106   A8     A8 CONN112_10137002101LF-CONN112_A    I68 @S9S_MB_2U_LIB.S9S_MB_2U(SCH_1):PAGE144
  J106   B5     B5 CONN112_10137002101LF-CONN112_A    I68 @S9S_MB_2U_LIB.S9S_MB_2U(SCH_1):PAGE144
  J106   B7     B7 CONN112_10137002101LF-CONN112_A    I68 @S9S_MB_2U_LIB.S9S_MB_2U(SCH_1):PAGE144
  J106   D6     D6 CONN112_10137002101LF-CONN112_A    I68 @S9S_MB_2U_LIB.S9S_MB_2U(SCH_1):PAGE144
  J106   D8     D8 CONN112_10137002101LF-CONN112_A    I68 @S9S_MB_2U_LIB.S9S_MB_2U(SCH_1):PAGE144
  J106   E5     E5 CONN112_10137002101LF-CONN112_A    I68 @S9S_MB_2U_LIB.S9S_MB_2U(SCH_1):PAGE144
  J106   E7     E7 CONN112_10137002101LF-CONN112_A    I68 @S9S_MB_2U_LIB.S9S_MB_2U(SCH_1):PAGE144
  J106   G6     G6 CONN112_10137002101LF-CONN112_A    I68 @S9S_MB_2U_LIB.S9S_MB_2U(SCH_1):PAGE144
  J106   G8     G8 CONN112_10137002101LF-CONN112_A    I68 @S9S_MB_2U_LIB.S9S_MB_2U(SCH_1):PAGE144
  J106   H5     H5 CONN112_10137002101LF-CONN112_A    I68 @S9S_MB_2U_LIB.S9S_MB_2U(SCH_1):PAGE144
  J106   H7     H7 CONN112_10137002101LF-CONN112_A    I68 @S9S_MB_2U_LIB.S9S_MB_2U(SCH_1):PAGE144
  J106   J6     J6 CONN112_10137002101LF-CONN112_A    I68 @S9S_MB_2U_LIB.S9S_MB_2U(SCH_1):PAGE144
  J106   J8     J8 CONN112_10137002101LF-CONN112_A    I68 @S9S_MB_2U_LIB.S9S_MB_2U(SCH_1):PAGE144
  J106   K5     K5 CONN112_10137002101LF-CONN112_A    I68 @S9S_MB_2U_LIB.S9S_MB_2U(SCH_1):PAGE144
  J106   K7     K7 CONN112_10137002101LF-CONN112_A    I68 @S9S_MB_2U_LIB.S9S_MB_2U(SCH_1):PAGE144
  J106   M6     M6 CONN112_10137002101LF-CONN112_A    I68 @S9S_MB_2U_LIB.S9S_MB_2U(SCH_1):PAGE144
  J106   M8     M8 CONN112_10137002101LF-CONN112_A    I68 @S9S_MB_2U_LIB.S9S_MB_2U(SCH_1):PAGE144
  J106   N5     N5 CONN112_10137002101LF-CONN112_A    I68 @S9S_MB_2U_LIB.S9S_MB_2U(SCH_1):PAGE144
  J106   N7     N7 CONN112_10137002101LF-CONN112_A    I68 @S9S_MB_2U_LIB.S9S_MB_2U(SCH_1):PAGE144
 R2666    2      B Q_RES_0402LF-10K,1%,1/16W,CHIPA    I16 @S9S_MB_2U_LIB.S9S_MB_2U(SCH_1):PAGE222
 C1708    2      B Q_CAP_0402-0.1UF,25V,10%,EMPTYA    I34 @S9S_MB_2U_LIB.S9S_MB_2U(SCH_1):PAGE222
   Q67    1     S1 MOSFET_NCH_DUAL-PJT138K,SMLF,IA    I33 @S9S_MB_2U_LIB.S9S_MB_2U(SCH_1):PAGE145
   Q70    1     S1 MOSFET_NCH_DUAL-PJT138K,SMLF,IA    I35 @S9S_MB_2U_LIB.S9S_MB_2U(SCH_1):PAGE145
   Q72    1     S1 MOSFET_NCH_DUAL-PJT138K,SMLF,IA    I37 @S9S_MB_2U_LIB.S9S_MB_2U(SCH_1):PAGE145
 R2831    2      B Q_RES_0402LF-100K,1%,1/16W,EMPA    I56 @S9S_MB_2U_LIB.S9S_MB_2U(SCH_1):PAGE145
 R2829    2      B Q_RES_0402LF-100K,1%,1/16W,EMPA    I58 @S9S_MB_2U_LIB.S9S_MB_2U(SCH_1):PAGE145
 R2833    2      B Q_RES_0402LF-100K,1%,1/16W,EMPA    I60 @S9S_MB_2U_LIB.S9S_MB_2U(SCH_1):PAGE145
 R2838    2      B Q_RES_0402LF-100K,1%,1/16W,CHIA    I62 @S9S_MB_2U_LIB.S9S_MB_2U(SCH_1):PAGE145
 C1766    2      B Q_CAP_0402-0.1UF,25V,10%,X7R,CA    I66 @S9S_MB_2U_LIB.S9S_MB_2U(SCH_1):PAGE222
  U193    4   AIN8 MAX11617EEET-MAX11617EEE+T,SMLA    I57 @S9S_MB_2U_LIB.S9S_MB_2U(SCH_1):PAGE239
  U193    3   AIN9 MAX11617EEET-MAX11617EEE+T,SMLA    I57 @S9S_MB_2U_LIB.S9S_MB_2U(SCH_1):PAGE239
  U193    2  AIN10 MAX11617EEET-MAX11617EEE+T,SMLA    I57 @S9S_MB_2U_LIB.S9S_MB_2U(SCH_1):PAGE239
  U193   15    GND MAX11617EEET-MAX11617EEE+T,SMLA    I57 @S9S_MB_2U_LIB.S9S_MB_2U(SCH_1):PAGE239
 C1757    2      B Q_CAP_0402-0.1UF,25V,10%,EMPTYA    I58 @S9S_MB_2U_LIB.S9S_MB_2U(SCH_1):PAGE239
 C1768    2      B Q_CAP_C0805-10UF,16V,10%,EMPTYA    I61 @S9S_MB_2U_LIB.S9S_MB_2U(SCH_1):PAGE239
 C1767    2      B Q_CAP_C0805-10UF,16V,10%,EMPTYA    I68 @S9S_MB_2U_LIB.S9S_MB_2U(SCH_1):PAGE239
 C1347    2      B Q_CAP_0402-0.1UF,25V,10%,EMPTYA    I70 @S9S_MB_2U_LIB.S9S_MB_2U(SCH_1):PAGE239
  U210    3    GND 74LVC1G08W57-74LVC1G08W5-7,SMLA   I189 @S9S_MB_2U_LIB.S9S_MB_2U(SCH_1):PAGE154
  U208    3    GND 74LVC1G08W57-74LVC1G08W5-7,SMLA   I190 @S9S_MB_2U_LIB.S9S_MB_2U(SCH_1):PAGE154
  U181   12    VSS PCA9539RPW-PCA9539RPW,SMLF,IC,A    I66 @S9S_MB_2U_LIB.S9S_MB_2U(SCH_1):PAGE214
 R2696    2      B Q_RES_0402LF-1K,1%,1/16W,CHIP,A    I75 @S9S_MB_2U_LIB.S9S_MB_2U(SCH_1):PAGE214
 R2694    2      B Q_RES_0402LF-1K,1%,1/16W,CHIP,A    I77 @S9S_MB_2U_LIB.S9S_MB_2U(SCH_1):PAGE214
 C1713    2      B Q_CAP_0402-0.1UF,25V,10%,X7R,CA    I87 @S9S_MB_2U_LIB.S9S_MB_2U(SCH_1):PAGE214
  U195    2    GND 74LVC2G17GW-74LVC2G17GW,SMLF,IA    I65 @S9S_MB_2U_LIB.S9S_MB_2U(SCH_1):PAGE140
 C1769    2      B Q_CAP_0402-0.1UF,25V,10%,X7R,CA    I89 @S9S_MB_2U_LIB.S9S_MB_2U(SCH_1):PAGE140
 R2915    2      B Q_RES_0402LF-4.7K,5%,1/16W,CHIA    I92 @S9S_MB_2U_LIB.S9S_MB_2U(SCH_1):PAGE140
 R2916    2      B Q_RES_0402LF-4.7K,5%,1/16W,EMPA    I93 @S9S_MB_2U_LIB.S9S_MB_2U(SCH_1):PAGE140
 R2926    2      B Q_RES_0402LF-4.7K,5%,1/16W,CHIA   I121 @S9S_MB_2U_LIB.S9S_MB_2U(SCH_1):PAGE140
  U196    2    GND 74LVC2G17GW-74LVC2G17GW,SMLF,IA   I127 @S9S_MB_2U_LIB.S9S_MB_2U(SCH_1):PAGE140
 C1770    2      B Q_CAP_0402-0.1UF,25V,10%,X7R,CA   I140 @S9S_MB_2U_LIB.S9S_MB_2U(SCH_1):PAGE140
   Q67    4     S2 MOSFET_NCH_DUAL-PJT138K,SMLF,IA    I82 @S9S_MB_2U_LIB.S9S_MB_2U(SCH_1):PAGE145
   Q69    4     S2 MOSFET_NCH_DUAL-PJT138K,SMLF,IA    I88 @S9S_MB_2U_LIB.S9S_MB_2U(SCH_1):PAGE145
 C1754    2      B Q_CAP_0402-1000PF,50V,5%,EMPTYA    I92 @S9S_MB_2U_LIB.S9S_MB_2U(SCH_1):PAGE145
   Q71    4     S2 MOSFET_NCH_DUAL-PJT138K,SMLF,IA   I100 @S9S_MB_2U_LIB.S9S_MB_2U(SCH_1):PAGE145
 C1756    2      B Q_CAP_0402-1000PF,50V,5%,EMPTYA   I105 @S9S_MB_2U_LIB.S9S_MB_2U(SCH_1):PAGE145
 C1774    2      B Q_CAP_0402-1000PF,50V,5%,EMPTYA   I111 @S9S_MB_2U_LIB.S9S_MB_2U(SCH_1):PAGE145
 C1773    2      B Q_CAP_0402-1000PF,50V,5%,EMPTYA   I114 @S9S_MB_2U_LIB.S9S_MB_2U(SCH_1):PAGE145
 C1772    2      B Q_CAP_0402-1000PF,50V,5%,EMPTYA   I116 @S9S_MB_2U_LIB.S9S_MB_2U(SCH_1):PAGE145
   Q69    1     S1 MOSFET_NCH_DUAL-PJT138K,SMLF,IA   I117 @S9S_MB_2U_LIB.S9S_MB_2U(SCH_1):PAGE145
   Q71    1     S1 MOSFET_NCH_DUAL-PJT138K,SMLF,IA   I118 @S9S_MB_2U_LIB.S9S_MB_2U(SCH_1):PAGE145
   Q72    4     S2 MOSFET_NCH_DUAL-PJT138K,SMLF,IA   I119 @S9S_MB_2U_LIB.S9S_MB_2U(SCH_1):PAGE145
   Q70    4     S2 MOSFET_NCH_DUAL-PJT138K,SMLF,IA   I120 @S9S_MB_2U_LIB.S9S_MB_2U(SCH_1):PAGE145
 R2937    2      B Q_RES_0402LF-4.7K,5%,1/16W,CHIA   I160 @S9S_MB_2U_LIB.S9S_MB_2U(SCH_1):PAGE140
 C1775    2      B Q_CAP_0402-0.1UF,25V,10%,X7R,CA    I14 @S9S_MB_2U_LIB.S9S_MB_2U(SCH_1):PAGE230
 R2941    2      B Q_RES_0402LF-100K,1%,1/16W,CHIA    I29 @S9S_MB_2U_LIB.S9S_MB_2U(SCH_1):PAGE230
 R2948    2      B Q_RES_0402LF-4.7K,5%,1/16W,EMPA    I30 @S9S_MB_2U_LIB.S9S_MB_2U(SCH_1):PAGE230
 C5232    2      B Q_CAP_0402-0.1UF,25V,10%,EMPTYA    I81 @S9S_MB_2U_LIB.S9S_MB_2U(SCH_1):PAGE155
 R5238    2      B Q_RES_0402LF-3.9K,5%,1/16W,EMPA    I83 @S9S_MB_2U_LIB.S9S_MB_2U(SCH_1):PAGE155
 U5201   10    GND TUSB211IRWBR-TUSB211IRWBR,SMLFA    I84 @S9S_MB_2U_LIB.S9S_MB_2U(SCH_1):PAGE155
 C5236    2      B Q_CAP_0402-0.1UF,25V,10%,EMPTYA    I87 @S9S_MB_2U_LIB.S9S_MB_2U(SCH_1):PAGE155
 C5229    2      B Q_CAP_C0402-1UF,25V,10%,EMPTY,A    I88 @S9S_MB_2U_LIB.S9S_MB_2U(SCH_1):PAGE155
 C5234    2      B Q_CAP_0402-0.1UF,25V,10%,EMPTYA    I92 @S9S_MB_2U_LIB.S9S_MB_2U(SCH_1):PAGE155
   Q74    1     S1 MOSFET_NCH_DUAL-PJT138K,SMLF,IA   I121 @S9S_MB_2U_LIB.S9S_MB_2U(SCH_1):PAGE145
   Q74    4     S2 MOSFET_NCH_DUAL-PJT138K,SMLF,IA   I122 @S9S_MB_2U_LIB.S9S_MB_2U(SCH_1):PAGE145
 C1804    2      B Q_CAP_0402-1000PF,50V,5%,EMPTYA   I125 @S9S_MB_2U_LIB.S9S_MB_2U(SCH_1):PAGE145
 R3032    2      B Q_RES_0402LF-100K,1%,1/16W,EMPA   I134 @S9S_MB_2U_LIB.S9S_MB_2U(SCH_1):PAGE145
 R3028    2      B Q_RES_0402LF-100K,1%,1/16W,EMPA   I139 @S9S_MB_2U_LIB.S9S_MB_2U(SCH_1):PAGE145
 C1802    2      B Q_CAP_0402-1000PF,50V,5%,EMPTYA   I148 @S9S_MB_2U_LIB.S9S_MB_2U(SCH_1):PAGE145
   Q75    4     S2 MOSFET_NCH_DUAL-PJT138K,SMLF,IA   I151 @S9S_MB_2U_LIB.S9S_MB_2U(SCH_1):PAGE145
   Q75    1     S1 MOSFET_NCH_DUAL-PJT138K,SMLF,IA   I152 @S9S_MB_2U_LIB.S9S_MB_2U(SCH_1):PAGE145
   Q80    4     S2 MOSFET_NCH_DUAL-PJT138K,SMLF,IA     I2 @S9S_MB_2U_LIB.S9S_MB_2U(SCH_1):PAGE305
   Q80    1     S1 MOSFET_NCH_DUAL-PJT138K,SMLF,IA     I4 @S9S_MB_2U_LIB.S9S_MB_2U(SCH_1):PAGE305
   Q79    4     S2 MOSFET_NCH_DUAL-PJT138K,SMLF,IA     I7 @S9S_MB_2U_LIB.S9S_MB_2U(SCH_1):PAGE305
   Q79    1     S1 MOSFET_NCH_DUAL-PJT138K,SMLF,IA     I8 @S9S_MB_2U_LIB.S9S_MB_2U(SCH_1):PAGE305
   Q83    1     S1 MOSFET_NCH_DUAL-PJT138K,SMLF,IA    I32 @S9S_MB_2U_LIB.S9S_MB_2U(SCH_1):PAGE305
   Q81    4     S2 MOSFET_NCH_DUAL-PJT138K,SMLF,IA    I40 @S9S_MB_2U_LIB.S9S_MB_2U(SCH_1):PAGE305
   Q81    1     S1 MOSFET_NCH_DUAL-PJT138K,SMLF,IA    I41 @S9S_MB_2U_LIB.S9S_MB_2U(SCH_1):PAGE305
   Q88    1     S1 MOSFET_NCH_DUAL-PJT138K,SMLF,IA     I8 @S9S_MB_2U_LIB.S9S_MB_2U(SCH_1):PAGE241
   Q87    4     S2 MOSFET_NCH_DUAL-PJT138K,SMLF,IA    I16 @S9S_MB_2U_LIB.S9S_MB_2U(SCH_1):PAGE241
   Q87    1     S1 MOSFET_NCH_DUAL-PJT138K,SMLF,IA    I17 @S9S_MB_2U_LIB.S9S_MB_2U(SCH_1):PAGE241
   Q76    4     S2 MOSFET_NCH_DUAL-PJT138K,SMLF,IA     I8 @S9S_MB_2U_LIB.S9S_MB_2U(SCH_1):PAGE242
   Q96    4     S2 MOSFET_NCH_DUAL-PJT138K,SMLF,IA   I159 @S9S_MB_2U_LIB.S9S_MB_2U(SCH_1):PAGE145
   Q85    4     S2 MOSFET_NCH_DUAL-PJT138K,SMLF,IA     I3 @S9S_MB_2U_LIB.S9S_MB_2U(SCH_1):PAGE306
   Q85    1     S1 MOSFET_NCH_DUAL-PJT138K,SMLF,IA     I6 @S9S_MB_2U_LIB.S9S_MB_2U(SCH_1):PAGE306
   Q84    4     S2 MOSFET_NCH_DUAL-PJT138K,SMLF,IA     I8 @S9S_MB_2U_LIB.S9S_MB_2U(SCH_1):PAGE306
   Q84    1     S1 MOSFET_NCH_DUAL-PJT138K,SMLF,IA    I18 @S9S_MB_2U_LIB.S9S_MB_2U(SCH_1):PAGE306
   Q86    4     S2 MOSFET_NCH_DUAL-PJT138K,SMLF,IA    I27 @S9S_MB_2U_LIB.S9S_MB_2U(SCH_1):PAGE306
   Q86    1     S1 MOSFET_NCH_DUAL-PJT138K,SMLF,IA    I35 @S9S_MB_2U_LIB.S9S_MB_2U(SCH_1):PAGE306
   Q77    4     S2 MOSFET_NCH_DUAL-PJT138K,SMLF,IA     I3 @S9S_MB_2U_LIB.S9S_MB_2U(SCH_1):PAGE242
   Q77    1     S1 MOSFET_NCH_DUAL-PJT138K,SMLF,IA     I6 @S9S_MB_2U_LIB.S9S_MB_2U(SCH_1):PAGE242
   Q76    1     S1 MOSFET_NCH_DUAL-PJT138K,SMLF,IA    I17 @S9S_MB_2U_LIB.S9S_MB_2U(SCH_1):PAGE242
   Q78    4     S2 MOSFET_NCH_DUAL-PJT138K,SMLF,IA    I26 @S9S_MB_2U_LIB.S9S_MB_2U(SCH_1):PAGE242
   Q78    1     S1 MOSFET_NCH_DUAL-PJT138K,SMLF,IA    I34 @S9S_MB_2U_LIB.S9S_MB_2U(SCH_1):PAGE242
   D97    C      C Q_LED_SMLF-LED_BLUE,LTST-C281TA    I52 @S9S_MB_2U_LIB.S9S_MB_2U(SCH_1):PAGE242
   D98    C      C Q_LED_SMLF-LED_BLUE,LTST-C281TA    I53 @S9S_MB_2U_LIB.S9S_MB_2U(SCH_1):PAGE242
   D99    C      C Q_LED_SMLF-LED_BLUE,LTST-C281TA    I60 @S9S_MB_2U_LIB.S9S_MB_2U(SCH_1):PAGE242
  U158    S      S MOSFET_NCH_GDS_ESD_PROTECTED-2A     I6 @S9S_MB_2U_LIB.S9S_MB_2U(SCH_1):PAGE234
   Q83    4     S2 MOSFET_NCH_DUAL-PJT138K,SMLF,IA    I43 @S9S_MB_2U_LIB.S9S_MB_2U(SCH_1):PAGE306
   Q88    4     S2 MOSFET_NCH_DUAL-PJT138K,SMLF,IA    I42 @S9S_MB_2U_LIB.S9S_MB_2U(SCH_1):PAGE241
  J100    2      2 SCONN20_513860200CV01-SCONN20_A    I32 @S9S_MB_2U_LIB.S9S_MB_2U(SCH_1):PAGE215
  J100    6      6 SCONN20_513860200CV01-SCONN20_A    I32 @S9S_MB_2U_LIB.S9S_MB_2U(SCH_1):PAGE215
  J100   10     10 SCONN20_513860200CV01-SCONN20_A    I32 @S9S_MB_2U_LIB.S9S_MB_2U(SCH_1):PAGE215
  J100   12     12 SCONN20_513860200CV01-SCONN20_A    I32 @S9S_MB_2U_LIB.S9S_MB_2U(SCH_1):PAGE215
  J100   15     15 SCONN20_513860200CV01-SCONN20_A    I32 @S9S_MB_2U_LIB.S9S_MB_2U(SCH_1):PAGE215
  J100   17     17 SCONN20_513860200CV01-SCONN20_A    I32 @S9S_MB_2U_LIB.S9S_MB_2U(SCH_1):PAGE215
  OSC1    2    GND Q_OSC4P_SMLF-50MHZ,OSC,BF65000A    I76 @S9S_MB_2U_LIB.S9S_MB_2U(SCH_1):PAGE152
    J1   G1     G1 SCONN288_ADR50017P130CC-SCONN2A   I203 @S9S_MB_2U_LIB.S9S_MB_2U(SCH_1):PAGE82
    J1   G2     G2 SCONN288_ADR50017P130CC-SCONN2A   I203 @S9S_MB_2U_LIB.S9S_MB_2U(SCH_1):PAGE82
    J1   G3     G3 SCONN288_ADR50017P130CC-SCONN2A   I203 @S9S_MB_2U_LIB.S9S_MB_2U(SCH_1):PAGE82
    J1    6   VSS0 SCONN288_ADR50017P130CC-SCONN2A   I203 @S9S_MB_2U_LIB.S9S_MB_2U(SCH_1):PAGE82
    J1    8   VSS1 SCONN288_ADR50017P130CC-SCONN2A   I203 @S9S_MB_2U_LIB.S9S_MB_2U(SCH_1):PAGE82
    J1   10   VSS2 SCONN288_ADR50017P130CC-SCONN2A   I203 @S9S_MB_2U_LIB.S9S_MB_2U(SCH_1):PAGE82
    J1   13   VSS3 SCONN288_ADR50017P130CC-SCONN2A   I203 @S9S_MB_2U_LIB.S9S_MB_2U(SCH_1):PAGE82
    J1   15   VSS4 SCONN288_ADR50017P130CC-SCONN2A   I203 @S9S_MB_2U_LIB.S9S_MB_2U(SCH_1):PAGE82
    J1   17   VSS5 SCONN288_ADR50017P130CC-SCONN2A   I203 @S9S_MB_2U_LIB.S9S_MB_2U(SCH_1):PAGE82
    J1   19   VSS6 SCONN288_ADR50017P130CC-SCONN2A   I203 @S9S_MB_2U_LIB.S9S_MB_2U(SCH_1):PAGE82
    J1   21   VSS7 SCONN288_ADR50017P130CC-SCONN2A   I203 @S9S_MB_2U_LIB.S9S_MB_2U(SCH_1):PAGE82
    J1   24   VSS8 SCONN288_ADR50017P130CC-SCONN2A   I203 @S9S_MB_2U_LIB.S9S_MB_2U(SCH_1):PAGE82
    J1   26   VSS9 SCONN288_ADR50017P130CC-SCONN2A   I203 @S9S_MB_2U_LIB.S9S_MB_2U(SCH_1):PAGE82
    J1   28  VSS10 SCONN288_ADR50017P130CC-SCONN2A   I203 @S9S_MB_2U_LIB.S9S_MB_2U(SCH_1):PAGE82
    J1   30  VSS11 SCONN288_ADR50017P130CC-SCONN2A   I203 @S9S_MB_2U_LIB.S9S_MB_2U(SCH_1):PAGE82
    J1   32  VSS12 SCONN288_ADR50017P130CC-SCONN2A   I203 @S9S_MB_2U_LIB.S9S_MB_2U(SCH_1):PAGE82
    J1   35  VSS13 SCONN288_ADR50017P130CC-SCONN2A   I203 @S9S_MB_2U_LIB.S9S_MB_2U(SCH_1):PAGE82
    J1   37  VSS14 SCONN288_ADR50017P130CC-SCONN2A   I203 @S9S_MB_2U_LIB.S9S_MB_2U(SCH_1):PAGE82
    J1   39  VSS15 SCONN288_ADR50017P130CC-SCONN2A   I203 @S9S_MB_2U_LIB.S9S_MB_2U(SCH_1):PAGE82
    J1   41  VSS16 SCONN288_ADR50017P130CC-SCONN2A   I203 @S9S_MB_2U_LIB.S9S_MB_2U(SCH_1):PAGE82
    J1   43  VSS17 SCONN288_ADR50017P130CC-SCONN2A   I203 @S9S_MB_2U_LIB.S9S_MB_2U(SCH_1):PAGE82
    J1   46  VSS18 SCONN288_ADR50017P130CC-SCONN2A   I203 @S9S_MB_2U_LIB.S9S_MB_2U(SCH_1):PAGE82
    J1   48  VSS19 SCONN288_ADR50017P130CC-SCONN2A   I203 @S9S_MB_2U_LIB.S9S_MB_2U(SCH_1):PAGE82
    J1   50  VSS20 SCONN288_ADR50017P130CC-SCONN2A   I203 @S9S_MB_2U_LIB.S9S_MB_2U(SCH_1):PAGE82
    J1   52  VSS21 SCONN288_ADR50017P130CC-SCONN2A   I203 @S9S_MB_2U_LIB.S9S_MB_2U(SCH_1):PAGE82
    J1   54  VSS22 SCONN288_ADR50017P130CC-SCONN2A   I203 @S9S_MB_2U_LIB.S9S_MB_2U(SCH_1):PAGE82
    J1   57  VSS23 SCONN288_ADR50017P130CC-SCONN2A   I203 @S9S_MB_2U_LIB.S9S_MB_2U(SCH_1):PAGE82
    J1   59  VSS24 SCONN288_ADR50017P130CC-SCONN2A   I203 @S9S_MB_2U_LIB.S9S_MB_2U(SCH_1):PAGE82
    J1   61  VSS25 SCONN288_ADR50017P130CC-SCONN2A   I203 @S9S_MB_2U_LIB.S9S_MB_2U(SCH_1):PAGE82
    J1   63  VSS26 SCONN288_ADR50017P130CC-SCONN2A   I203 @S9S_MB_2U_LIB.S9S_MB_2U(SCH_1):PAGE82
    J1   65  VSS27 SCONN288_ADR50017P130CC-SCONN2A   I203 @S9S_MB_2U_LIB.S9S_MB_2U(SCH_1):PAGE82
    J1   67  VSS28 SCONN288_ADR50017P130CC-SCONN2A   I203 @S9S_MB_2U_LIB.S9S_MB_2U(SCH_1):PAGE82
    J1   69  VSS29 SCONN288_ADR50017P130CC-SCONN2A   I203 @S9S_MB_2U_LIB.S9S_MB_2U(SCH_1):PAGE82
    J1   71  VSS30 SCONN288_ADR50017P130CC-SCONN2A   I203 @S9S_MB_2U_LIB.S9S_MB_2U(SCH_1):PAGE82
    J1   73  VSS31 SCONN288_ADR50017P130CC-SCONN2A   I203 @S9S_MB_2U_LIB.S9S_MB_2U(SCH_1):PAGE82
    J1   75  VSS32 SCONN288_ADR50017P130CC-SCONN2A   I203 @S9S_MB_2U_LIB.S9S_MB_2U(SCH_1):PAGE82
    J1   77  VSS33 SCONN288_ADR50017P130CC-SCONN2A   I203 @S9S_MB_2U_LIB.S9S_MB_2U(SCH_1):PAGE82
    J1   79  VSS34 SCONN288_ADR50017P130CC-SCONN2A   I203 @S9S_MB_2U_LIB.S9S_MB_2U(SCH_1):PAGE82
    J1   81  VSS35 SCONN288_ADR50017P130CC-SCONN2A   I203 @S9S_MB_2U_LIB.S9S_MB_2U(SCH_1):PAGE82
    J1   83  VSS36 SCONN288_ADR50017P130CC-SCONN2A   I203 @S9S_MB_2U_LIB.S9S_MB_2U(SCH_1):PAGE82
    J1   85  VSS37 SCONN288_ADR50017P130CC-SCONN2A   I203 @S9S_MB_2U_LIB.S9S_MB_2U(SCH_1):PAGE82
    J1   88  VSS38 SCONN288_ADR50017P130CC-SCONN2A   I203 @S9S_MB_2U_LIB.S9S_MB_2U(SCH_1):PAGE82
    J1   90  VSS39 SCONN288_ADR50017P130CC-SCONN2A   I203 @S9S_MB_2U_LIB.S9S_MB_2U(SCH_1):PAGE82
    J1   92  VSS40 SCONN288_ADR50017P130CC-SCONN2A   I203 @S9S_MB_2U_LIB.S9S_MB_2U(SCH_1):PAGE82
    J1   95  VSS41 SCONN288_ADR50017P130CC-SCONN2A   I203 @S9S_MB_2U_LIB.S9S_MB_2U(SCH_1):PAGE82
    J1   97  VSS42 SCONN288_ADR50017P130CC-SCONN2A   I203 @S9S_MB_2U_LIB.S9S_MB_2U(SCH_1):PAGE82
    J1   99  VSS43 SCONN288_ADR50017P130CC-SCONN2A   I203 @S9S_MB_2U_LIB.S9S_MB_2U(SCH_1):PAGE82
    J1  101  VSS44 SCONN288_ADR50017P130CC-SCONN2A   I203 @S9S_MB_2U_LIB.S9S_MB_2U(SCH_1):PAGE82
    J1  103  VSS45 SCONN288_ADR50017P130CC-SCONN2A   I203 @S9S_MB_2U_LIB.S9S_MB_2U(SCH_1):PAGE82
    J1  106  VSS46 SCONN288_ADR50017P130CC-SCONN2A   I203 @S9S_MB_2U_LIB.S9S_MB_2U(SCH_1):PAGE82
    J1  108  VSS47 SCONN288_ADR50017P130CC-SCONN2A   I203 @S9S_MB_2U_LIB.S9S_MB_2U(SCH_1):PAGE82
    J1  110  VSS48 SCONN288_ADR50017P130CC-SCONN2A   I203 @S9S_MB_2U_LIB.S9S_MB_2U(SCH_1):PAGE82
    J1  112  VSS49 SCONN288_ADR50017P130CC-SCONN2A   I203 @S9S_MB_2U_LIB.S9S_MB_2U(SCH_1):PAGE82
    J1  114  VSS50 SCONN288_ADR50017P130CC-SCONN2A   I203 @S9S_MB_2U_LIB.S9S_MB_2U(SCH_1):PAGE82
    J1  117  VSS51 SCONN288_ADR50017P130CC-SCONN2A   I203 @S9S_MB_2U_LIB.S9S_MB_2U(SCH_1):PAGE82
    J1  119  VSS52 SCONN288_ADR50017P130CC-SCONN2A   I203 @S9S_MB_2U_LIB.S9S_MB_2U(SCH_1):PAGE82
    J1  121  VSS53 SCONN288_ADR50017P130CC-SCONN2A   I203 @S9S_MB_2U_LIB.S9S_MB_2U(SCH_1):PAGE82
    J1  123  VSS54 SCONN288_ADR50017P130CC-SCONN2A   I203 @S9S_MB_2U_LIB.S9S_MB_2U(SCH_1):PAGE82
    J1  125  VSS55 SCONN288_ADR50017P130CC-SCONN2A   I203 @S9S_MB_2U_LIB.S9S_MB_2U(SCH_1):PAGE82
    J1  128  VSS56 SCONN288_ADR50017P130CC-SCONN2A   I203 @S9S_MB_2U_LIB.S9S_MB_2U(SCH_1):PAGE82
    J1  130  VSS57 SCONN288_ADR50017P130CC-SCONN2A   I203 @S9S_MB_2U_LIB.S9S_MB_2U(SCH_1):PAGE82
    J1  132  VSS58 SCONN288_ADR50017P130CC-SCONN2A   I203 @S9S_MB_2U_LIB.S9S_MB_2U(SCH_1):PAGE82
    J1  134  VSS59 SCONN288_ADR50017P130CC-SCONN2A   I203 @S9S_MB_2U_LIB.S9S_MB_2U(SCH_1):PAGE82
    J1  136  VSS60 SCONN288_ADR50017P130CC-SCONN2A   I203 @S9S_MB_2U_LIB.S9S_MB_2U(SCH_1):PAGE82
    J1  139  VSS61 SCONN288_ADR50017P130CC-SCONN2A   I203 @S9S_MB_2U_LIB.S9S_MB_2U(SCH_1):PAGE82
    J1  141  VSS62 SCONN288_ADR50017P130CC-SCONN2A   I203 @S9S_MB_2U_LIB.S9S_MB_2U(SCH_1):PAGE82
    J1  143  VSS63 SCONN288_ADR50017P130CC-SCONN2A   I203 @S9S_MB_2U_LIB.S9S_MB_2U(SCH_1):PAGE82
    J1  151  VSS64 SCONN288_ADR50017P130CC-SCONN2A   I203 @S9S_MB_2U_LIB.S9S_MB_2U(SCH_1):PAGE82
    J1  153  VSS65 SCONN288_ADR50017P130CC-SCONN2A   I203 @S9S_MB_2U_LIB.S9S_MB_2U(SCH_1):PAGE82
    J1  155  VSS66 SCONN288_ADR50017P130CC-SCONN2A   I203 @S9S_MB_2U_LIB.S9S_MB_2U(SCH_1):PAGE82
    J1  158  VSS67 SCONN288_ADR50017P130CC-SCONN2A   I203 @S9S_MB_2U_LIB.S9S_MB_2U(SCH_1):PAGE82
    J1  160  VSS68 SCONN288_ADR50017P130CC-SCONN2A   I203 @S9S_MB_2U_LIB.S9S_MB_2U(SCH_1):PAGE82
    J1  162  VSS69 SCONN288_ADR50017P130CC-SCONN2A   I203 @S9S_MB_2U_LIB.S9S_MB_2U(SCH_1):PAGE82
    J1  164  VSS70 SCONN288_ADR50017P130CC-SCONN2A   I203 @S9S_MB_2U_LIB.S9S_MB_2U(SCH_1):PAGE82
    J1  166  VSS71 SCONN288_ADR50017P130CC-SCONN2A   I203 @S9S_MB_2U_LIB.S9S_MB_2U(SCH_1):PAGE82
    J1  169  VSS72 SCONN288_ADR50017P130CC-SCONN2A   I203 @S9S_MB_2U_LIB.S9S_MB_2U(SCH_1):PAGE82
    J1  171  VSS73 SCONN288_ADR50017P130CC-SCONN2A   I203 @S9S_MB_2U_LIB.S9S_MB_2U(SCH_1):PAGE82
    J1  173  VSS74 SCONN288_ADR50017P130CC-SCONN2A   I203 @S9S_MB_2U_LIB.S9S_MB_2U(SCH_1):PAGE82
    J1  175  VSS75 SCONN288_ADR50017P130CC-SCONN2A   I203 @S9S_MB_2U_LIB.S9S_MB_2U(SCH_1):PAGE82
    J1  177  VSS76 SCONN288_ADR50017P130CC-SCONN2A   I203 @S9S_MB_2U_LIB.S9S_MB_2U(SCH_1):PAGE82
    J1  180  VSS77 SCONN288_ADR50017P130CC-SCONN2A   I203 @S9S_MB_2U_LIB.S9S_MB_2U(SCH_1):PAGE82
    J1  182  VSS78 SCONN288_ADR50017P130CC-SCONN2A   I203 @S9S_MB_2U_LIB.S9S_MB_2U(SCH_1):PAGE82
    J1  184  VSS79 SCONN288_ADR50017P130CC-SCONN2A   I203 @S9S_MB_2U_LIB.S9S_MB_2U(SCH_1):PAGE82
    J1  186  VSS80 SCONN288_ADR50017P130CC-SCONN2A   I203 @S9S_MB_2U_LIB.S9S_MB_2U(SCH_1):PAGE82
    J1  188  VSS81 SCONN288_ADR50017P130CC-SCONN2A   I203 @S9S_MB_2U_LIB.S9S_MB_2U(SCH_1):PAGE82
    J1  191  VSS82 SCONN288_ADR50017P130CC-SCONN2A   I203 @S9S_MB_2U_LIB.S9S_MB_2U(SCH_1):PAGE82
    J1  193  VSS83 SCONN288_ADR50017P130CC-SCONN2A   I203 @S9S_MB_2U_LIB.S9S_MB_2U(SCH_1):PAGE82
    J1  195  VSS84 SCONN288_ADR50017P130CC-SCONN2A   I203 @S9S_MB_2U_LIB.S9S_MB_2U(SCH_1):PAGE82
    J1  197  VSS85 SCONN288_ADR50017P130CC-SCONN2A   I203 @S9S_MB_2U_LIB.S9S_MB_2U(SCH_1):PAGE82
    J1  199  VSS86 SCONN288_ADR50017P130CC-SCONN2A   I203 @S9S_MB_2U_LIB.S9S_MB_2U(SCH_1):PAGE82
    J1  202  VSS87 SCONN288_ADR50017P130CC-SCONN2A   I203 @S9S_MB_2U_LIB.S9S_MB_2U(SCH_1):PAGE82
    J1  204  VSS88 SCONN288_ADR50017P130CC-SCONN2A   I203 @S9S_MB_2U_LIB.S9S_MB_2U(SCH_1):PAGE82
    J1  206  VSS89 SCONN288_ADR50017P130CC-SCONN2A   I203 @S9S_MB_2U_LIB.S9S_MB_2U(SCH_1):PAGE82
    J1  208  VSS90 SCONN288_ADR50017P130CC-SCONN2A   I203 @S9S_MB_2U_LIB.S9S_MB_2U(SCH_1):PAGE82
    J1  210  VSS91 SCONN288_ADR50017P130CC-SCONN2A   I203 @S9S_MB_2U_LIB.S9S_MB_2U(SCH_1):PAGE82
    J1  212  VSS92 SCONN288_ADR50017P130CC-SCONN2A   I203 @S9S_MB_2U_LIB.S9S_MB_2U(SCH_1):PAGE82
    J1  214  VSS93 SCONN288_ADR50017P130CC-SCONN2A   I203 @S9S_MB_2U_LIB.S9S_MB_2U(SCH_1):PAGE82
    J1  216  VSS94 SCONN288_ADR50017P130CC-SCONN2A   I203 @S9S_MB_2U_LIB.S9S_MB_2U(SCH_1):PAGE82
    J1  219  VSS95 SCONN288_ADR50017P130CC-SCONN2A   I203 @S9S_MB_2U_LIB.S9S_MB_2U(SCH_1):PAGE82
    J1  222  VSS96 SCONN288_ADR50017P130CC-SCONN2A   I203 @S9S_MB_2U_LIB.S9S_MB_2U(SCH_1):PAGE82
    J1  224  VSS97 SCONN288_ADR50017P130CC-SCONN2A   I203 @S9S_MB_2U_LIB.S9S_MB_2U(SCH_1):PAGE82
    J1  226  VSS98 SCONN288_ADR50017P130CC-SCONN2A   I203 @S9S_MB_2U_LIB.S9S_MB_2U(SCH_1):PAGE82
    J1  228  VSS99 SCONN288_ADR50017P130CC-SCONN2A   I203 @S9S_MB_2U_LIB.S9S_MB_2U(SCH_1):PAGE82
    J1  230 VSS100 SCONN288_ADR50017P130CC-SCONN2A   I203 @S9S_MB_2U_LIB.S9S_MB_2U(SCH_1):PAGE82
    J1  233 VSS101 SCONN288_ADR50017P130CC-SCONN2A   I203 @S9S_MB_2U_LIB.S9S_MB_2U(SCH_1):PAGE82
    J1  235 VSS102 SCONN288_ADR50017P130CC-SCONN2A   I203 @S9S_MB_2U_LIB.S9S_MB_2U(SCH_1):PAGE82
    J1  237 VSS103 SCONN288_ADR50017P130CC-SCONN2A   I203 @S9S_MB_2U_LIB.S9S_MB_2U(SCH_1):PAGE82
    J1  240 VSS104 SCONN288_ADR50017P130CC-SCONN2A   I203 @S9S_MB_2U_LIB.S9S_MB_2U(SCH_1):PAGE82
    J1  242 VSS105 SCONN288_ADR50017P130CC-SCONN2A   I203 @S9S_MB_2U_LIB.S9S_MB_2U(SCH_1):PAGE82
    J1  244 VSS106 SCONN288_ADR50017P130CC-SCONN2A   I203 @S9S_MB_2U_LIB.S9S_MB_2U(SCH_1):PAGE82
    J1  246 VSS107 SCONN288_ADR50017P130CC-SCONN2A   I203 @S9S_MB_2U_LIB.S9S_MB_2U(SCH_1):PAGE82
    J1  248 VSS108 SCONN288_ADR50017P130CC-SCONN2A   I203 @S9S_MB_2U_LIB.S9S_MB_2U(SCH_1):PAGE82
    J1  251 VSS109 SCONN288_ADR50017P130CC-SCONN2A   I203 @S9S_MB_2U_LIB.S9S_MB_2U(SCH_1):PAGE82
    J1  253 VSS110 SCONN288_ADR50017P130CC-SCONN2A   I203 @S9S_MB_2U_LIB.S9S_MB_2U(SCH_1):PAGE82
    J1  255 VSS111 SCONN288_ADR50017P130CC-SCONN2A   I203 @S9S_MB_2U_LIB.S9S_MB_2U(SCH_1):PAGE82
    J1  257 VSS112 SCONN288_ADR50017P130CC-SCONN2A   I203 @S9S_MB_2U_LIB.S9S_MB_2U(SCH_1):PAGE82
    J1  259 VSS113 SCONN288_ADR50017P130CC-SCONN2A   I203 @S9S_MB_2U_LIB.S9S_MB_2U(SCH_1):PAGE82
    J1  262 VSS114 SCONN288_ADR50017P130CC-SCONN2A   I203 @S9S_MB_2U_LIB.S9S_MB_2U(SCH_1):PAGE82
    J1  264 VSS115 SCONN288_ADR50017P130CC-SCONN2A   I203 @S9S_MB_2U_LIB.S9S_MB_2U(SCH_1):PAGE82
    J1  266 VSS116 SCONN288_ADR50017P130CC-SCONN2A   I203 @S9S_MB_2U_LIB.S9S_MB_2U(SCH_1):PAGE82
    J1  268 VSS117 SCONN288_ADR50017P130CC-SCONN2A   I203 @S9S_MB_2U_LIB.S9S_MB_2U(SCH_1):PAGE82
    J1  270 VSS118 SCONN288_ADR50017P130CC-SCONN2A   I203 @S9S_MB_2U_LIB.S9S_MB_2U(SCH_1):PAGE82
    J1  273 VSS119 SCONN288_ADR50017P130CC-SCONN2A   I203 @S9S_MB_2U_LIB.S9S_MB_2U(SCH_1):PAGE82
    J1  275 VSS120 SCONN288_ADR50017P130CC-SCONN2A   I203 @S9S_MB_2U_LIB.S9S_MB_2U(SCH_1):PAGE82
    J1  277 VSS121 SCONN288_ADR50017P130CC-SCONN2A   I203 @S9S_MB_2U_LIB.S9S_MB_2U(SCH_1):PAGE82
    J1  279 VSS122 SCONN288_ADR50017P130CC-SCONN2A   I203 @S9S_MB_2U_LIB.S9S_MB_2U(SCH_1):PAGE82
    J1  281 VSS123 SCONN288_ADR50017P130CC-SCONN2A   I203 @S9S_MB_2U_LIB.S9S_MB_2U(SCH_1):PAGE82
    J1  284 VSS124 SCONN288_ADR50017P130CC-SCONN2A   I203 @S9S_MB_2U_LIB.S9S_MB_2U(SCH_1):PAGE82
    J1  286 VSS125 SCONN288_ADR50017P130CC-SCONN2A   I203 @S9S_MB_2U_LIB.S9S_MB_2U(SCH_1):PAGE82
    J1  288 VSS126 SCONN288_ADR50017P130CC-SCONN2A   I203 @S9S_MB_2U_LIB.S9S_MB_2U(SCH_1):PAGE82
  C579    2      B Q_CAP_0402-0.1UF,25V,10%,X7R,CA   I192 @S9S_MB_2U_LIB.S9S_MB_2U(SCH_1):PAGE154
  U143   10    VSS PCA9545APW-PCA9545APW,SMLF,IC,A   I106 @S9S_MB_2U_LIB.S9S_MB_2U(SCH_1):PAGE224
 C1809    2      B Q_CAP_0402-0.1UF,25V,10%,X7R,CA    I26 @S9S_MB_2U_LIB.S9S_MB_2U(SCH_1):PAGE131
  Q119    1     S1 MOSFET_NCH_DUAL-PJT138K,SMLF,IA    I38 @S9S_MB_2U_LIB.S9S_MB_2U(SCH_1):PAGE131
   U50    3    GND 74LVC1G08W57-74LVC1G08W5-7,SMLA     I9 @S9S_MB_2U_LIB.S9S_MB_2U(SCH_1):PAGE132
 C1818    2      B Q_CAP_0402-0.1UF,25V,10%,X7R,CA    I15 @S9S_MB_2U_LIB.S9S_MB_2U(SCH_1):PAGE132
   U53    3    GND 74LVC1G08W57-74LVC1G08W5-7,SMLA    I56 @S9S_MB_2U_LIB.S9S_MB_2U(SCH_1):PAGE132
 R3154    2      B Q_RES_0402LF-1K,1%,1/16W,CHIP,A    I65 @S9S_MB_2U_LIB.S9S_MB_2U(SCH_1):PAGE132
  U215    S SOURCE MOSFET_N_SMLF-BSS138K,BSS138K,A     I3 @S9S_MB_2U_LIB.S9S_MB_2U(SCH_1):PAGE132
 R3150    2      B Q_RES_0402LF-1K,1%,1/16W,CHIP,A    I25 @S9S_MB_2U_LIB.S9S_MB_2U(SCH_1):PAGE132
 R3152    2      B Q_RES_0402LF-1K,1%,1/16W,CHIP,A    I27 @S9S_MB_2U_LIB.S9S_MB_2U(SCH_1):PAGE132
 C1817    2      B Q_CAP_0402-0.1UF,25V,10%,X7R,CA    I39 @S9S_MB_2U_LIB.S9S_MB_2U(SCH_1):PAGE132
 C1820    2      B Q_CAP_0402-0.1UF,25V,10%,X7R,CA    I58 @S9S_MB_2U_LIB.S9S_MB_2U(SCH_1):PAGE132
 R3167    2      B Q_RES_0402LF-4.7K,1%,1/16W,CHIA    I20 @S9S_MB_2U_LIB.S9S_MB_2U(SCH_1):PAGE146
 R3163    2      B Q_RES_0402LF-4.7K,1%,1/16W,EMPA    I25 @S9S_MB_2U_LIB.S9S_MB_2U(SCH_1):PAGE146
 C1821    2      B Q_CAP_0402-0.1UF,25V,10%,X7R,CA    I12 @S9S_MB_2U_LIB.S9S_MB_2U(SCH_1):PAGE156
 C1822    2      B Q_CAP_0402-0.1UF,25V,10%,X7R,CA    I27 @S9S_MB_2U_LIB.S9S_MB_2U(SCH_1):PAGE156
  U218    3    GND 74LVC1G07GV-74LVC1G07GV,SMLF,IA    I31 @S9S_MB_2U_LIB.S9S_MB_2U(SCH_1):PAGE156
 C1823    2      B Q_CAP_0402-0.1UF,25V,10%,X7R,CA    I33 @S9S_MB_2U_LIB.S9S_MB_2U(SCH_1):PAGE156
  U207    3    GND 74LVC1G17GW-74LVC1G17GW,SMLF,IA    I35 @S9S_MB_2U_LIB.S9S_MB_2U(SCH_1):PAGE156
 C1824    2      B Q_CAP_0402-0.1UF,25V,10%,X7R,CA    I47 @S9S_MB_2U_LIB.S9S_MB_2U(SCH_1):PAGE156
  U219    3    GND 74LVC1G07GV-74LVC1G07GV,SMLF,IA    I61 @S9S_MB_2U_LIB.S9S_MB_2U(SCH_1):PAGE156
 R3207    2      B Q_RES_0402LF-100K,1%,1/16W,CHIA    I15 @S9S_MB_2U_LIB.S9S_MB_2U(SCH_1):PAGE307
 C1825    2      B Q_CAP_0402-0.1UF,25V,10%,X7R,CA    I17 @S9S_MB_2U_LIB.S9S_MB_2U(SCH_1):PAGE307
  U222    7    GND 74CBTLV3126PW-74CBTLV3126PW,SMA    I32 @S9S_MB_2U_LIB.S9S_MB_2U(SCH_1):PAGE307
 C1826    2      B Q_CAP_0402-0.1UF,25V,10%,X7R,CA    I33 @S9S_MB_2U_LIB.S9S_MB_2U(SCH_1):PAGE307
 R3208    2      B Q_RES_0402LF-100,1%,1/16W,CHIPA    I37 @S9S_MB_2U_LIB.S9S_MB_2U(SCH_1):PAGE307
 R3216    2      B Q_RES_0402LF-100,1%,1/16W,CHIPA    I38 @S9S_MB_2U_LIB.S9S_MB_2U(SCH_1):PAGE307
 R3217    2      B Q_RES_0402LF-100,1%,1/16W,CHIPA    I40 @S9S_MB_2U_LIB.S9S_MB_2U(SCH_1):PAGE307
 C1827    2      B Q_CAP_0402-0.1UF,25V,10%,X7R,CA    I77 @S9S_MB_2U_LIB.S9S_MB_2U(SCH_1):PAGE307
  U223    7    GND 74CBTLV3126PW-74CBTLV3126PW,SMA    I78 @S9S_MB_2U_LIB.S9S_MB_2U(SCH_1):PAGE307
 R3165    1      A Q_RES_0402LF-10K,1%,1/16W,CHIPA    I37 @S9S_MB_2U_LIB.S9S_MB_2U(SCH_1):PAGE146
 R3164    1      A Q_RES_0402LF-10K,1%,1/16W,CHIPA    I38 @S9S_MB_2U_LIB.S9S_MB_2U(SCH_1):PAGE146
  R413    1      A Q_RES_0402LF-100K,1%,1/16W,CHIA    I43 @S9S_MB_2U_LIB.S9S_MB_2U(SCH_1):PAGE146
 R3180    2      B Q_RES_0402LF-100,1%,1/16W,CHIPA   I152 @S9S_MB_2U_LIB.S9S_MB_2U(SCH_1):PAGE146
 C1829    2      B Q_CAP_C0805-22UF,16V,20%,X6S,CB   I166 @S9S_MB_2U_LIB.S9S_MB_2U(SCH_1):PAGE146
 C1830    2      B Q_CAP_C0805-22UF,16V,20%,X6S,CB   I167 @S9S_MB_2U_LIB.S9S_MB_2U(SCH_1):PAGE146
 C1831    2      B Q_CAP_0402-0.1UF,25V,10%,X7R,CA   I168 @S9S_MB_2U_LIB.S9S_MB_2U(SCH_1):PAGE146
 C1833    2      B Q_CAP_0402-0.1UF,25V,10%,X7R,CA   I169 @S9S_MB_2U_LIB.S9S_MB_2U(SCH_1):PAGE146
 C1834    2      B Q_CAP_0402-0.1UF,25V,10%,X7R,CA   I171 @S9S_MB_2U_LIB.S9S_MB_2U(SCH_1):PAGE146
 C1835    2      B Q_CAP_0402-0.1UF,25V,10%,X7R,CA   I173 @S9S_MB_2U_LIB.S9S_MB_2U(SCH_1):PAGE146
 C1836    2      B Q_CAP_0402-0.1UF,25V,10%,X7R,CA   I174 @S9S_MB_2U_LIB.S9S_MB_2U(SCH_1):PAGE146
 C1837    2      B Q_CAP_0402-0.1UF,25V,10%,X7R,CA   I175 @S9S_MB_2U_LIB.S9S_MB_2U(SCH_1):PAGE146
 C1838    2      B Q_CAP_0402-0.1UF,25V,10%,X7R,CA   I177 @S9S_MB_2U_LIB.S9S_MB_2U(SCH_1):PAGE146
 C1832    2      B Q_CAP_0402-0.1UF,25V,10%,X7R,CA   I179 @S9S_MB_2U_LIB.S9S_MB_2U(SCH_1):PAGE146
 C1839    2      B Q_CAP_0402-0.1UF,25V,10%,X7R,CA   I180 @S9S_MB_2U_LIB.S9S_MB_2U(SCH_1):PAGE146
 C1841    2      B Q_CAP_0402-0.1UF,25V,10%,X7R,CA    I65 @S9S_MB_2U_LIB.S9S_MB_2U(SCH_1):PAGE156
 R3235    2      B Q_RES_0402LF-100K,1%,1/16W,CHIA    I72 @S9S_MB_2U_LIB.S9S_MB_2U(SCH_1):PAGE156
   J43    7      7 CONN8_210HP1080BR1-CONN8_210-HA    I79 @S9S_MB_2U_LIB.S9S_MB_2U(SCH_1):PAGE210
  C554    2      B Q_CAP_0402-0.1UF,25V,10%,X7R,CA    I86 @S9S_MB_2U_LIB.S9S_MB_2U(SCH_1):PAGE210
  C563    2      B Q_CAP_C0805-10UF,25V,10%,X6S,CA    I88 @S9S_MB_2U_LIB.S9S_MB_2U(SCH_1):PAGE210
  U235    4    GND PCA9617ADP-PCA9617ADP,SMLF,IC,A     I5 @S9S_MB_2U_LIB.S9S_MB_2U(SCH_1):PAGE216
 C1859    2      B Q_CAP_0402-0.1UF,25V,10%,X7R,CA    I10 @S9S_MB_2U_LIB.S9S_MB_2U(SCH_1):PAGE216
 C1861    2      B Q_CAP_0402-0.1UF,25V,10%,X7R,CA    I11 @S9S_MB_2U_LIB.S9S_MB_2U(SCH_1):PAGE216
 C1860    2      B Q_CAP_0402-0.1UF,25V,10%,X7R,CA    I17 @S9S_MB_2U_LIB.S9S_MB_2U(SCH_1):PAGE216
 C1862    2      B Q_CAP_0402-0.1UF,25V,10%,X7R,CA    I23 @S9S_MB_2U_LIB.S9S_MB_2U(SCH_1):PAGE216
  U236    4    GND PCA9617ADP-PCA9617ADP,SMLF,IC,A    I28 @S9S_MB_2U_LIB.S9S_MB_2U(SCH_1):PAGE216
 R3279    2      B Q_RES_0402LF-68K,1%,1/16W,EMPTA    I23 @S9S_MB_2U_LIB.S9S_MB_2U(SCH_1):PAGE136
 R3281    2      B Q_RES_0402LF-1K,1%,1/16W,EMPTYA    I25 @S9S_MB_2U_LIB.S9S_MB_2U(SCH_1):PAGE136
 C1867    2      B Q_CAP_C0805-10UF,25V,10%,X6S,CA    I48 @S9S_MB_2U_LIB.S9S_MB_2U(SCH_1):PAGE136
 R3290    2      B Q_RES_0402LF-1K,1%,1/16W,EMPTYA    I68 @S9S_MB_2U_LIB.S9S_MB_2U(SCH_1):PAGE136
 R3293    2      B Q_RES_0402LF-4.7K,1%,1/16W,EMPA    I88 @S9S_MB_2U_LIB.S9S_MB_2U(SCH_1):PAGE136
  U241    4    GND 74LVC2G08DP-74LVC2G08DP,SMLF,IA     I1 @S9S_MB_2U_LIB.S9S_MB_2U(SCH_1):PAGE170
  U240    4    GND 74LVC2G08DP-74LVC2G08DP,SMLF,IA    I11 @S9S_MB_2U_LIB.S9S_MB_2U(SCH_1):PAGE170
  U242    4    GND 74LVC2G08DP-74LVC2G08DP,SMLF,IA    I13 @S9S_MB_2U_LIB.S9S_MB_2U(SCH_1):PAGE170
  U243    2    GND NC7SB3157_SMLF-NC7SB3157P6X,NCB    I15 @S9S_MB_2U_LIB.S9S_MB_2U(SCH_1):PAGE170
  U244    2    GND NC7SB3157_SMLF-NC7SB3157P6X,NCB    I16 @S9S_MB_2U_LIB.S9S_MB_2U(SCH_1):PAGE170
  U246    2    GND NC7SB3157_SMLF-NC7SB3157P6X,NCB    I17 @S9S_MB_2U_LIB.S9S_MB_2U(SCH_1):PAGE170
  U245    2    GND NC7SB3157_SMLF-NC7SB3157P6X,NCB    I18 @S9S_MB_2U_LIB.S9S_MB_2U(SCH_1):PAGE170
 C1875    2      B Q_CAP_0402-0.1UF,25V,10%,X7R,CA    I21 @S9S_MB_2U_LIB.S9S_MB_2U(SCH_1):PAGE170
 C1874    2      B Q_CAP_0402-0.1UF,25V,10%,X7R,CA    I22 @S9S_MB_2U_LIB.S9S_MB_2U(SCH_1):PAGE170
 C1880    2      B Q_CAP_0402-0.1UF,25V,10%,X7R,CA    I27 @S9S_MB_2U_LIB.S9S_MB_2U(SCH_1):PAGE170
 C1879    2      B Q_CAP_0402-0.1UF,25V,10%,X7R,CA    I31 @S9S_MB_2U_LIB.S9S_MB_2U(SCH_1):PAGE170
 C1877    2      B Q_CAP_0402-0.1UF,25V,10%,X7R,CA    I34 @S9S_MB_2U_LIB.S9S_MB_2U(SCH_1):PAGE170
 C1878    2      B Q_CAP_0402-0.1UF,25V,10%,X7R,CA    I37 @S9S_MB_2U_LIB.S9S_MB_2U(SCH_1):PAGE170
 C1876    2      B Q_CAP_0402-0.1UF,25V,10%,X7R,CA    I41 @S9S_MB_2U_LIB.S9S_MB_2U(SCH_1):PAGE170
 R1324    1      A Q_RES_0402LF-1K,1%,1/16W,CHIP,A    I87 @S9S_MB_2U_LIB.S9S_MB_2U(SCH_1):PAGE189
 R1341    2      B Q_RES_0402LF-10K,1%,1/16W,CHIPA   I106 @S9S_MB_2U_LIB.S9S_MB_2U(SCH_1):PAGE189
 R1338    2      B Q_RES_0402LF-10K,1%,1/16W,CHIPA   I107 @S9S_MB_2U_LIB.S9S_MB_2U(SCH_1):PAGE189
 R2134    2      B Q_RES_0402LF-10K,1%,1/16W,CHIPA   I109 @S9S_MB_2U_LIB.S9S_MB_2U(SCH_1):PAGE189
 R1333    1      A Q_RES_0402LF-1K,1%,1/16W,CHIP,A   I123 @S9S_MB_2U_LIB.S9S_MB_2U(SCH_1):PAGE189
 C1177    2      B Q_CAP_C0402-1UF,25V,10%,X6S,CHA   I128 @S9S_MB_2U_LIB.S9S_MB_2U(SCH_1):PAGE189
 R3039    1      A Q_RES_0402LF-1K,1%,1/16W,CHIP,A   I132 @S9S_MB_2U_LIB.S9S_MB_2U(SCH_1):PAGE189
 R1335    1      A Q_RES_0402LF-1K,1%,1/16W,CHIP,A   I133 @S9S_MB_2U_LIB.S9S_MB_2U(SCH_1):PAGE189
   Q98    1     S1 MOSFET_NCH_DUAL-NX6008NBKS,SMLA    I68 @S9S_MB_2U_LIB.S9S_MB_2U(SCH_1):PAGE304
   Q98    4     S2 MOSFET_NCH_DUAL-NX6008NBKS,SMLA    I69 @S9S_MB_2U_LIB.S9S_MB_2U(SCH_1):PAGE304
   Q97    4     S2 MOSFET_NCH_DUAL-NX6008NBKS,SMLA    I70 @S9S_MB_2U_LIB.S9S_MB_2U(SCH_1):PAGE304
   Q97    1     S1 MOSFET_NCH_DUAL-NX6008NBKS,SMLA    I71 @S9S_MB_2U_LIB.S9S_MB_2U(SCH_1):PAGE304
   Q99    1     S1 MOSFET_NCH_DUAL-NX6008NBKS,SMLA    I72 @S9S_MB_2U_LIB.S9S_MB_2U(SCH_1):PAGE304
  Q100    1     S1 MOSFET_NCH_DUAL-NX6008NBKS,SMLA    I74 @S9S_MB_2U_LIB.S9S_MB_2U(SCH_1):PAGE304
  Q100    4     S2 MOSFET_NCH_DUAL-NX6008NBKS,SMLA    I75 @S9S_MB_2U_LIB.S9S_MB_2U(SCH_1):PAGE304
 R3325    2      B Q_RES_0402LF-10K,1%,1/16W,CHIPA    I92 @S9S_MB_2U_LIB.S9S_MB_2U(SCH_1):PAGE186
 C1883    2      B Q_CAP_C0805-10UF,25V,10%,X6S,CA    I16 @S9S_MB_2U_LIB.S9S_MB_2U(SCH_1):PAGE201
 C1886    2      B Q_CAP_0402-0.1UF,25V,10%,X7R,CA    I18 @S9S_MB_2U_LIB.S9S_MB_2U(SCH_1):PAGE201
 C1889    2      B Q_CAP_0402-0.1UF,25V,10%,X7R,CA    I19 @S9S_MB_2U_LIB.S9S_MB_2U(SCH_1):PAGE201
   Q96    1     S1 MOSFET_NCH_DUAL-PJT138K,SMLF,IA   I154 @S9S_MB_2U_LIB.S9S_MB_2U(SCH_1):PAGE145
 C1881    2      B Q_CAP_0402-1000PF,50V,5%,EMPTYA   I156 @S9S_MB_2U_LIB.S9S_MB_2U(SCH_1):PAGE145
 C1803    2      B Q_CAP_0402-0.1UF,25V,10%,X7R,CA   I166 @S9S_MB_2U_LIB.S9S_MB_2U(SCH_1):PAGE140
  J107   A6     A6 CONN112_10137002101LF-CONN112_A    I38 @S9S_MB_2U_LIB.S9S_MB_2U(SCH_1):PAGE317
  J107   A8     A8 CONN112_10137002101LF-CONN112_A    I38 @S9S_MB_2U_LIB.S9S_MB_2U(SCH_1):PAGE317
  J107   B5     B5 CONN112_10137002101LF-CONN112_A    I38 @S9S_MB_2U_LIB.S9S_MB_2U(SCH_1):PAGE317
  J107   B7     B7 CONN112_10137002101LF-CONN112_A    I38 @S9S_MB_2U_LIB.S9S_MB_2U(SCH_1):PAGE317
  J107   D6     D6 CONN112_10137002101LF-CONN112_A    I38 @S9S_MB_2U_LIB.S9S_MB_2U(SCH_1):PAGE317
  J107   D8     D8 CONN112_10137002101LF-CONN112_A    I38 @S9S_MB_2U_LIB.S9S_MB_2U(SCH_1):PAGE317
  J107   E5     E5 CONN112_10137002101LF-CONN112_A    I38 @S9S_MB_2U_LIB.S9S_MB_2U(SCH_1):PAGE317
  J107   E7     E7 CONN112_10137002101LF-CONN112_A    I38 @S9S_MB_2U_LIB.S9S_MB_2U(SCH_1):PAGE317
  J107   G6     G6 CONN112_10137002101LF-CONN112_A    I38 @S9S_MB_2U_LIB.S9S_MB_2U(SCH_1):PAGE317
  J107   G8     G8 CONN112_10137002101LF-CONN112_A    I38 @S9S_MB_2U_LIB.S9S_MB_2U(SCH_1):PAGE317
  J107   H5     H5 CONN112_10137002101LF-CONN112_A    I38 @S9S_MB_2U_LIB.S9S_MB_2U(SCH_1):PAGE317
  J107   H7     H7 CONN112_10137002101LF-CONN112_A    I38 @S9S_MB_2U_LIB.S9S_MB_2U(SCH_1):PAGE317
  J107   J6     J6 CONN112_10137002101LF-CONN112_A    I38 @S9S_MB_2U_LIB.S9S_MB_2U(SCH_1):PAGE317
  J107   J8     J8 CONN112_10137002101LF-CONN112_A    I38 @S9S_MB_2U_LIB.S9S_MB_2U(SCH_1):PAGE317
  J107   K5     K5 CONN112_10137002101LF-CONN112_A    I38 @S9S_MB_2U_LIB.S9S_MB_2U(SCH_1):PAGE317
  J107   K7     K7 CONN112_10137002101LF-CONN112_A    I38 @S9S_MB_2U_LIB.S9S_MB_2U(SCH_1):PAGE317
  J107   M6     M6 CONN112_10137002101LF-CONN112_A    I38 @S9S_MB_2U_LIB.S9S_MB_2U(SCH_1):PAGE317
  J107   M8     M8 CONN112_10137002101LF-CONN112_A    I38 @S9S_MB_2U_LIB.S9S_MB_2U(SCH_1):PAGE317
  J107   N5     N5 CONN112_10137002101LF-CONN112_A    I38 @S9S_MB_2U_LIB.S9S_MB_2U(SCH_1):PAGE317
  J107   N7     N7 CONN112_10137002101LF-CONN112_A    I38 @S9S_MB_2U_LIB.S9S_MB_2U(SCH_1):PAGE317
  J107   A2     A2 CONN112_10137002101LF-CONN112_A    I58 @S9S_MB_2U_LIB.S9S_MB_2U(SCH_1):PAGE317
  J107   A4     A4 CONN112_10137002101LF-CONN112_A    I58 @S9S_MB_2U_LIB.S9S_MB_2U(SCH_1):PAGE317
  J107   B1     B1 CONN112_10137002101LF-CONN112_A    I58 @S9S_MB_2U_LIB.S9S_MB_2U(SCH_1):PAGE317
  J107   B3     B3 CONN112_10137002101LF-CONN112_A    I58 @S9S_MB_2U_LIB.S9S_MB_2U(SCH_1):PAGE317
  J107   D2     D2 CONN112_10137002101LF-CONN112_A    I58 @S9S_MB_2U_LIB.S9S_MB_2U(SCH_1):PAGE317
  J107   D4     D4 CONN112_10137002101LF-CONN112_A    I58 @S9S_MB_2U_LIB.S9S_MB_2U(SCH_1):PAGE317
  J107   E1     E1 CONN112_10137002101LF-CONN112_A    I58 @S9S_MB_2U_LIB.S9S_MB_2U(SCH_1):PAGE317
  J107   E3     E3 CONN112_10137002101LF-CONN112_A    I58 @S9S_MB_2U_LIB.S9S_MB_2U(SCH_1):PAGE317
  J107   G2     G2 CONN112_10137002101LF-CONN112_A    I58 @S9S_MB_2U_LIB.S9S_MB_2U(SCH_1):PAGE317
  J107   G4     G4 CONN112_10137002101LF-CONN112_A    I58 @S9S_MB_2U_LIB.S9S_MB_2U(SCH_1):PAGE317
  J107   H1     H1 CONN112_10137002101LF-CONN112_A    I58 @S9S_MB_2U_LIB.S9S_MB_2U(SCH_1):PAGE317
  J107   H3     H3 CONN112_10137002101LF-CONN112_A    I58 @S9S_MB_2U_LIB.S9S_MB_2U(SCH_1):PAGE317
  J107   J2     J2 CONN112_10137002101LF-CONN112_A    I58 @S9S_MB_2U_LIB.S9S_MB_2U(SCH_1):PAGE317
  J107   J4     J4 CONN112_10137002101LF-CONN112_A    I58 @S9S_MB_2U_LIB.S9S_MB_2U(SCH_1):PAGE317
  J107   K1     K1 CONN112_10137002101LF-CONN112_A    I58 @S9S_MB_2U_LIB.S9S_MB_2U(SCH_1):PAGE317
  J107   K3     K3 CONN112_10137002101LF-CONN112_A    I58 @S9S_MB_2U_LIB.S9S_MB_2U(SCH_1):PAGE317
  J107   M2     M2 CONN112_10137002101LF-CONN112_A    I58 @S9S_MB_2U_LIB.S9S_MB_2U(SCH_1):PAGE317
  J107   M4     M4 CONN112_10137002101LF-CONN112_A    I58 @S9S_MB_2U_LIB.S9S_MB_2U(SCH_1):PAGE317
  J107   N1     N1 CONN112_10137002101LF-CONN112_A    I58 @S9S_MB_2U_LIB.S9S_MB_2U(SCH_1):PAGE317
  J107   N3     N3 CONN112_10137002101LF-CONN112_A    I58 @S9S_MB_2U_LIB.S9S_MB_2U(SCH_1):PAGE317
  J108   A2     A2 CONN112_10137002101LF-CONN112_A    I57 @S9S_MB_2U_LIB.S9S_MB_2U(SCH_1):PAGE320
  J108   A4     A4 CONN112_10137002101LF-CONN112_A    I57 @S9S_MB_2U_LIB.S9S_MB_2U(SCH_1):PAGE320
  J108   B1     B1 CONN112_10137002101LF-CONN112_A    I57 @S9S_MB_2U_LIB.S9S_MB_2U(SCH_1):PAGE320
  J108   B3     B3 CONN112_10137002101LF-CONN112_A    I57 @S9S_MB_2U_LIB.S9S_MB_2U(SCH_1):PAGE320
  J108   D2     D2 CONN112_10137002101LF-CONN112_A    I57 @S9S_MB_2U_LIB.S9S_MB_2U(SCH_1):PAGE320
  J108   D4     D4 CONN112_10137002101LF-CONN112_A    I57 @S9S_MB_2U_LIB.S9S_MB_2U(SCH_1):PAGE320
  J108   E1     E1 CONN112_10137002101LF-CONN112_A    I57 @S9S_MB_2U_LIB.S9S_MB_2U(SCH_1):PAGE320
  J108   E3     E3 CONN112_10137002101LF-CONN112_A    I57 @S9S_MB_2U_LIB.S9S_MB_2U(SCH_1):PAGE320
  J108   G2     G2 CONN112_10137002101LF-CONN112_A    I57 @S9S_MB_2U_LIB.S9S_MB_2U(SCH_1):PAGE320
  J108   G4     G4 CONN112_10137002101LF-CONN112_A    I57 @S9S_MB_2U_LIB.S9S_MB_2U(SCH_1):PAGE320
  J108   H1     H1 CONN112_10137002101LF-CONN112_A    I57 @S9S_MB_2U_LIB.S9S_MB_2U(SCH_1):PAGE320
  J108   H3     H3 CONN112_10137002101LF-CONN112_A    I57 @S9S_MB_2U_LIB.S9S_MB_2U(SCH_1):PAGE320
  J108   J2     J2 CONN112_10137002101LF-CONN112_A    I57 @S9S_MB_2U_LIB.S9S_MB_2U(SCH_1):PAGE320
  J108   J4     J4 CONN112_10137002101LF-CONN112_A    I57 @S9S_MB_2U_LIB.S9S_MB_2U(SCH_1):PAGE320
  J108   K1     K1 CONN112_10137002101LF-CONN112_A    I57 @S9S_MB_2U_LIB.S9S_MB_2U(SCH_1):PAGE320
  J108   K3     K3 CONN112_10137002101LF-CONN112_A    I57 @S9S_MB_2U_LIB.S9S_MB_2U(SCH_1):PAGE320
  J108   M2     M2 CONN112_10137002101LF-CONN112_A    I57 @S9S_MB_2U_LIB.S9S_MB_2U(SCH_1):PAGE320
  J108   M4     M4 CONN112_10137002101LF-CONN112_A    I57 @S9S_MB_2U_LIB.S9S_MB_2U(SCH_1):PAGE320
  J108   N1     N1 CONN112_10137002101LF-CONN112_A    I57 @S9S_MB_2U_LIB.S9S_MB_2U(SCH_1):PAGE320
  J108   N3     N3 CONN112_10137002101LF-CONN112_A    I57 @S9S_MB_2U_LIB.S9S_MB_2U(SCH_1):PAGE320
  J108   A6     A6 CONN112_10137002101LF-CONN112_A    I76 @S9S_MB_2U_LIB.S9S_MB_2U(SCH_1):PAGE320
  J108   A8     A8 CONN112_10137002101LF-CONN112_A    I76 @S9S_MB_2U_LIB.S9S_MB_2U(SCH_1):PAGE320
  J108   B5     B5 CONN112_10137002101LF-CONN112_A    I76 @S9S_MB_2U_LIB.S9S_MB_2U(SCH_1):PAGE320
  J108   B7     B7 CONN112_10137002101LF-CONN112_A    I76 @S9S_MB_2U_LIB.S9S_MB_2U(SCH_1):PAGE320
  J108   D6     D6 CONN112_10137002101LF-CONN112_A    I76 @S9S_MB_2U_LIB.S9S_MB_2U(SCH_1):PAGE320
  J108   D8     D8 CONN112_10137002101LF-CONN112_A    I76 @S9S_MB_2U_LIB.S9S_MB_2U(SCH_1):PAGE320
  J108   E5     E5 CONN112_10137002101LF-CONN112_A    I76 @S9S_MB_2U_LIB.S9S_MB_2U(SCH_1):PAGE320
  J108   E7     E7 CONN112_10137002101LF-CONN112_A    I76 @S9S_MB_2U_LIB.S9S_MB_2U(SCH_1):PAGE320
  J108   G6     G6 CONN112_10137002101LF-CONN112_A    I76 @S9S_MB_2U_LIB.S9S_MB_2U(SCH_1):PAGE320
  J108   G8     G8 CONN112_10137002101LF-CONN112_A    I76 @S9S_MB_2U_LIB.S9S_MB_2U(SCH_1):PAGE320
  J108   H5     H5 CONN112_10137002101LF-CONN112_A    I76 @S9S_MB_2U_LIB.S9S_MB_2U(SCH_1):PAGE320
  J108   H7     H7 CONN112_10137002101LF-CONN112_A    I76 @S9S_MB_2U_LIB.S9S_MB_2U(SCH_1):PAGE320
  J108   J6     J6 CONN112_10137002101LF-CONN112_A    I76 @S9S_MB_2U_LIB.S9S_MB_2U(SCH_1):PAGE320
  J108   J8     J8 CONN112_10137002101LF-CONN112_A    I76 @S9S_MB_2U_LIB.S9S_MB_2U(SCH_1):PAGE320
  J108   K5     K5 CONN112_10137002101LF-CONN112_A    I76 @S9S_MB_2U_LIB.S9S_MB_2U(SCH_1):PAGE320
  J108   K7     K7 CONN112_10137002101LF-CONN112_A    I76 @S9S_MB_2U_LIB.S9S_MB_2U(SCH_1):PAGE320
  J108   M6     M6 CONN112_10137002101LF-CONN112_A    I76 @S9S_MB_2U_LIB.S9S_MB_2U(SCH_1):PAGE320
  J108   M8     M8 CONN112_10137002101LF-CONN112_A    I76 @S9S_MB_2U_LIB.S9S_MB_2U(SCH_1):PAGE320
  J108   N5     N5 CONN112_10137002101LF-CONN112_A    I76 @S9S_MB_2U_LIB.S9S_MB_2U(SCH_1):PAGE320
  J108   N7     N7 CONN112_10137002101LF-CONN112_A    I76 @S9S_MB_2U_LIB.S9S_MB_2U(SCH_1):PAGE320
  J110   A6     A6 CONN112_10137002101LF-CONN112_A    I16 @S9S_MB_2U_LIB.S9S_MB_2U(SCH_1):PAGE318
  J110   A8     A8 CONN112_10137002101LF-CONN112_A    I16 @S9S_MB_2U_LIB.S9S_MB_2U(SCH_1):PAGE318
  J110   B5     B5 CONN112_10137002101LF-CONN112_A    I16 @S9S_MB_2U_LIB.S9S_MB_2U(SCH_1):PAGE318
  J110   B7     B7 CONN112_10137002101LF-CONN112_A    I16 @S9S_MB_2U_LIB.S9S_MB_2U(SCH_1):PAGE318
  J110   D6     D6 CONN112_10137002101LF-CONN112_A    I16 @S9S_MB_2U_LIB.S9S_MB_2U(SCH_1):PAGE318
  J110   D8     D8 CONN112_10137002101LF-CONN112_A    I16 @S9S_MB_2U_LIB.S9S_MB_2U(SCH_1):PAGE318
  J110   E5     E5 CONN112_10137002101LF-CONN112_A    I16 @S9S_MB_2U_LIB.S9S_MB_2U(SCH_1):PAGE318
  J110   E7     E7 CONN112_10137002101LF-CONN112_A    I16 @S9S_MB_2U_LIB.S9S_MB_2U(SCH_1):PAGE318
  J110   G6     G6 CONN112_10137002101LF-CONN112_A    I16 @S9S_MB_2U_LIB.S9S_MB_2U(SCH_1):PAGE318
  J110   G8     G8 CONN112_10137002101LF-CONN112_A    I16 @S9S_MB_2U_LIB.S9S_MB_2U(SCH_1):PAGE318
  J110   H5     H5 CONN112_10137002101LF-CONN112_A    I16 @S9S_MB_2U_LIB.S9S_MB_2U(SCH_1):PAGE318
  J110   H7     H7 CONN112_10137002101LF-CONN112_A    I16 @S9S_MB_2U_LIB.S9S_MB_2U(SCH_1):PAGE318
  J110   J6     J6 CONN112_10137002101LF-CONN112_A    I16 @S9S_MB_2U_LIB.S9S_MB_2U(SCH_1):PAGE318
  J110   J8     J8 CONN112_10137002101LF-CONN112_A    I16 @S9S_MB_2U_LIB.S9S_MB_2U(SCH_1):PAGE318
  J110   K5     K5 CONN112_10137002101LF-CONN112_A    I16 @S9S_MB_2U_LIB.S9S_MB_2U(SCH_1):PAGE318
  J110   K7     K7 CONN112_10137002101LF-CONN112_A    I16 @S9S_MB_2U_LIB.S9S_MB_2U(SCH_1):PAGE318
  J110   M6     M6 CONN112_10137002101LF-CONN112_A    I16 @S9S_MB_2U_LIB.S9S_MB_2U(SCH_1):PAGE318
  J110   M8     M8 CONN112_10137002101LF-CONN112_A    I16 @S9S_MB_2U_LIB.S9S_MB_2U(SCH_1):PAGE318
  J110   N5     N5 CONN112_10137002101LF-CONN112_A    I16 @S9S_MB_2U_LIB.S9S_MB_2U(SCH_1):PAGE318
  J110   N7     N7 CONN112_10137002101LF-CONN112_A    I16 @S9S_MB_2U_LIB.S9S_MB_2U(SCH_1):PAGE318
  J110   A2     A2 CONN112_10137002101LF-CONN112_A    I54 @S9S_MB_2U_LIB.S9S_MB_2U(SCH_1):PAGE318
  J110   A4     A4 CONN112_10137002101LF-CONN112_A    I54 @S9S_MB_2U_LIB.S9S_MB_2U(SCH_1):PAGE318
  J110   B1     B1 CONN112_10137002101LF-CONN112_A    I54 @S9S_MB_2U_LIB.S9S_MB_2U(SCH_1):PAGE318
  J110   B3     B3 CONN112_10137002101LF-CONN112_A    I54 @S9S_MB_2U_LIB.S9S_MB_2U(SCH_1):PAGE318
  J110   D2     D2 CONN112_10137002101LF-CONN112_A    I54 @S9S_MB_2U_LIB.S9S_MB_2U(SCH_1):PAGE318
  J110   D4     D4 CONN112_10137002101LF-CONN112_A    I54 @S9S_MB_2U_LIB.S9S_MB_2U(SCH_1):PAGE318
  J110   E1     E1 CONN112_10137002101LF-CONN112_A    I54 @S9S_MB_2U_LIB.S9S_MB_2U(SCH_1):PAGE318
  J110   E3     E3 CONN112_10137002101LF-CONN112_A    I54 @S9S_MB_2U_LIB.S9S_MB_2U(SCH_1):PAGE318
  J110   G2     G2 CONN112_10137002101LF-CONN112_A    I54 @S9S_MB_2U_LIB.S9S_MB_2U(SCH_1):PAGE318
  J110   G4     G4 CONN112_10137002101LF-CONN112_A    I54 @S9S_MB_2U_LIB.S9S_MB_2U(SCH_1):PAGE318
  J110   H1     H1 CONN112_10137002101LF-CONN112_A    I54 @S9S_MB_2U_LIB.S9S_MB_2U(SCH_1):PAGE318
  J110   H3     H3 CONN112_10137002101LF-CONN112_A    I54 @S9S_MB_2U_LIB.S9S_MB_2U(SCH_1):PAGE318
  J110   J2     J2 CONN112_10137002101LF-CONN112_A    I54 @S9S_MB_2U_LIB.S9S_MB_2U(SCH_1):PAGE318
  J110   J4     J4 CONN112_10137002101LF-CONN112_A    I54 @S9S_MB_2U_LIB.S9S_MB_2U(SCH_1):PAGE318
  J110   K1     K1 CONN112_10137002101LF-CONN112_A    I54 @S9S_MB_2U_LIB.S9S_MB_2U(SCH_1):PAGE318
  J110   K3     K3 CONN112_10137002101LF-CONN112_A    I54 @S9S_MB_2U_LIB.S9S_MB_2U(SCH_1):PAGE318
  J110   M2     M2 CONN112_10137002101LF-CONN112_A    I54 @S9S_MB_2U_LIB.S9S_MB_2U(SCH_1):PAGE318
  J110   M4     M4 CONN112_10137002101LF-CONN112_A    I54 @S9S_MB_2U_LIB.S9S_MB_2U(SCH_1):PAGE318
  J110   N1     N1 CONN112_10137002101LF-CONN112_A    I54 @S9S_MB_2U_LIB.S9S_MB_2U(SCH_1):PAGE318
  J110   N3     N3 CONN112_10137002101LF-CONN112_A    I54 @S9S_MB_2U_LIB.S9S_MB_2U(SCH_1):PAGE318
  J109   A2     A2 CONN112_10137002101LF-CONN112_A    I53 @S9S_MB_2U_LIB.S9S_MB_2U(SCH_1):PAGE319
  J109   A4     A4 CONN112_10137002101LF-CONN112_A    I53 @S9S_MB_2U_LIB.S9S_MB_2U(SCH_1):PAGE319
  J109   B1     B1 CONN112_10137002101LF-CONN112_A    I53 @S9S_MB_2U_LIB.S9S_MB_2U(SCH_1):PAGE319
  J109   B3     B3 CONN112_10137002101LF-CONN112_A    I53 @S9S_MB_2U_LIB.S9S_MB_2U(SCH_1):PAGE319
  J109   D2     D2 CONN112_10137002101LF-CONN112_A    I53 @S9S_MB_2U_LIB.S9S_MB_2U(SCH_1):PAGE319
  J109   D4     D4 CONN112_10137002101LF-CONN112_A    I53 @S9S_MB_2U_LIB.S9S_MB_2U(SCH_1):PAGE319
  J109   E1     E1 CONN112_10137002101LF-CONN112_A    I53 @S9S_MB_2U_LIB.S9S_MB_2U(SCH_1):PAGE319
  J109   E3     E3 CONN112_10137002101LF-CONN112_A    I53 @S9S_MB_2U_LIB.S9S_MB_2U(SCH_1):PAGE319
  J109   G2     G2 CONN112_10137002101LF-CONN112_A    I53 @S9S_MB_2U_LIB.S9S_MB_2U(SCH_1):PAGE319
  J109   G4     G4 CONN112_10137002101LF-CONN112_A    I53 @S9S_MB_2U_LIB.S9S_MB_2U(SCH_1):PAGE319
  J109   H1     H1 CONN112_10137002101LF-CONN112_A    I53 @S9S_MB_2U_LIB.S9S_MB_2U(SCH_1):PAGE319
  J109   H3     H3 CONN112_10137002101LF-CONN112_A    I53 @S9S_MB_2U_LIB.S9S_MB_2U(SCH_1):PAGE319
  J109   J2     J2 CONN112_10137002101LF-CONN112_A    I53 @S9S_MB_2U_LIB.S9S_MB_2U(SCH_1):PAGE319
  J109   J4     J4 CONN112_10137002101LF-CONN112_A    I53 @S9S_MB_2U_LIB.S9S_MB_2U(SCH_1):PAGE319
  J109   K1     K1 CONN112_10137002101LF-CONN112_A    I53 @S9S_MB_2U_LIB.S9S_MB_2U(SCH_1):PAGE319
  J109   K3     K3 CONN112_10137002101LF-CONN112_A    I53 @S9S_MB_2U_LIB.S9S_MB_2U(SCH_1):PAGE319
  J109   M2     M2 CONN112_10137002101LF-CONN112_A    I53 @S9S_MB_2U_LIB.S9S_MB_2U(SCH_1):PAGE319
  J109   M4     M4 CONN112_10137002101LF-CONN112_A    I53 @S9S_MB_2U_LIB.S9S_MB_2U(SCH_1):PAGE319
  J109   N1     N1 CONN112_10137002101LF-CONN112_A    I53 @S9S_MB_2U_LIB.S9S_MB_2U(SCH_1):PAGE319
  J109   N3     N3 CONN112_10137002101LF-CONN112_A    I53 @S9S_MB_2U_LIB.S9S_MB_2U(SCH_1):PAGE319
  J109   A6     A6 CONN112_10137002101LF-CONN112_A    I76 @S9S_MB_2U_LIB.S9S_MB_2U(SCH_1):PAGE319
  J109   A8     A8 CONN112_10137002101LF-CONN112_A    I76 @S9S_MB_2U_LIB.S9S_MB_2U(SCH_1):PAGE319
  J109   B5     B5 CONN112_10137002101LF-CONN112_A    I76 @S9S_MB_2U_LIB.S9S_MB_2U(SCH_1):PAGE319
  J109   B7     B7 CONN112_10137002101LF-CONN112_A    I76 @S9S_MB_2U_LIB.S9S_MB_2U(SCH_1):PAGE319
  J109   D6     D6 CONN112_10137002101LF-CONN112_A    I76 @S9S_MB_2U_LIB.S9S_MB_2U(SCH_1):PAGE319
  J109   D8     D8 CONN112_10137002101LF-CONN112_A    I76 @S9S_MB_2U_LIB.S9S_MB_2U(SCH_1):PAGE319
  J109   E5     E5 CONN112_10137002101LF-CONN112_A    I76 @S9S_MB_2U_LIB.S9S_MB_2U(SCH_1):PAGE319
  J109   E7     E7 CONN112_10137002101LF-CONN112_A    I76 @S9S_MB_2U_LIB.S9S_MB_2U(SCH_1):PAGE319
  J109   G6     G6 CONN112_10137002101LF-CONN112_A    I76 @S9S_MB_2U_LIB.S9S_MB_2U(SCH_1):PAGE319
  J109   G8     G8 CONN112_10137002101LF-CONN112_A    I76 @S9S_MB_2U_LIB.S9S_MB_2U(SCH_1):PAGE319
  J109   H5     H5 CONN112_10137002101LF-CONN112_A    I76 @S9S_MB_2U_LIB.S9S_MB_2U(SCH_1):PAGE319
  J109   H7     H7 CONN112_10137002101LF-CONN112_A    I76 @S9S_MB_2U_LIB.S9S_MB_2U(SCH_1):PAGE319
  J109   J6     J6 CONN112_10137002101LF-CONN112_A    I76 @S9S_MB_2U_LIB.S9S_MB_2U(SCH_1):PAGE319
  J109   J8     J8 CONN112_10137002101LF-CONN112_A    I76 @S9S_MB_2U_LIB.S9S_MB_2U(SCH_1):PAGE319
  J109   K5     K5 CONN112_10137002101LF-CONN112_A    I76 @S9S_MB_2U_LIB.S9S_MB_2U(SCH_1):PAGE319
  J109   K7     K7 CONN112_10137002101LF-CONN112_A    I76 @S9S_MB_2U_LIB.S9S_MB_2U(SCH_1):PAGE319
  J109   M6     M6 CONN112_10137002101LF-CONN112_A    I76 @S9S_MB_2U_LIB.S9S_MB_2U(SCH_1):PAGE319
  J109   M8     M8 CONN112_10137002101LF-CONN112_A    I76 @S9S_MB_2U_LIB.S9S_MB_2U(SCH_1):PAGE319
  J109   N5     N5 CONN112_10137002101LF-CONN112_A    I76 @S9S_MB_2U_LIB.S9S_MB_2U(SCH_1):PAGE319
  J109   N7     N7 CONN112_10137002101LF-CONN112_A    I76 @S9S_MB_2U_LIB.S9S_MB_2U(SCH_1):PAGE319
 C1882    2      B Q_CAP_0402-0.1UF,25V,10%,X7R,CA    I80 @S9S_MB_2U_LIB.S9S_MB_2U(SCH_1):PAGE201
 C1320    2      B Q_CAP_0402-0.1UF,25V,10%,X7R,CA   I126 @S9S_MB_2U_LIB.S9S_MB_2U(SCH_1):PAGE313
  OSC2    2    GND Q_OSC4P_SMLF-25MHZ,OSC,BF62500A   I127 @S9S_MB_2U_LIB.S9S_MB_2U(SCH_1):PAGE313
   Q50    4     S2 MOSFET_NCH_DUAL-PJT138K,SMLF,IA    I49 @S9S_MB_2U_LIB.S9S_MB_2U(SCH_1):PAGE314
 C1325    2      B Q_CAP_0402-0.1UF,25V,10%,X7R,CA    I39 @S9S_MB_2U_LIB.S9S_MB_2U(SCH_1):PAGE312
  U249   A1   GND1 LCMXO3LF9400C5BG484C-LCMXO3LF-A     I1 @S9S_MB_2U_LIB.S9S_MB_2U(SCH_1):PAGE202
  U249  A22   GND2 LCMXO3LF9400C5BG484C-LCMXO3LF-A     I1 @S9S_MB_2U_LIB.S9S_MB_2U(SCH_1):PAGE202
  U249   B7   GND3 LCMXO3LF9400C5BG484C-LCMXO3LF-A     I1 @S9S_MB_2U_LIB.S9S_MB_2U(SCH_1):PAGE202
  U249  B16   GND4 LCMXO3LF9400C5BG484C-LCMXO3LF-A     I1 @S9S_MB_2U_LIB.S9S_MB_2U(SCH_1):PAGE202
  U249   C2   GND5 LCMXO3LF9400C5BG484C-LCMXO3LF-A     I1 @S9S_MB_2U_LIB.S9S_MB_2U(SCH_1):PAGE202
  U249  C11   GND6 LCMXO3LF9400C5BG484C-LCMXO3LF-A     I1 @S9S_MB_2U_LIB.S9S_MB_2U(SCH_1):PAGE202
  U249   E5   GND7 LCMXO3LF9400C5BG484C-LCMXO3LF-A     I1 @S9S_MB_2U_LIB.S9S_MB_2U(SCH_1):PAGE202
  U249  E18   GND8 LCMXO3LF9400C5BG484C-LCMXO3LF-A     I1 @S9S_MB_2U_LIB.S9S_MB_2U(SCH_1):PAGE202
  U249   F2   GND9 LCMXO3LF9400C5BG484C-LCMXO3LF-A     I1 @S9S_MB_2U_LIB.S9S_MB_2U(SCH_1):PAGE202
  U249  F21  GND10 LCMXO3LF9400C5BG484C-LCMXO3LF-A     I1 @S9S_MB_2U_LIB.S9S_MB_2U(SCH_1):PAGE202
  U249   H8  GND11 LCMXO3LF9400C5BG484C-LCMXO3LF-A     I1 @S9S_MB_2U_LIB.S9S_MB_2U(SCH_1):PAGE202
  U249  H10  GND12 LCMXO3LF9400C5BG484C-LCMXO3LF-A     I1 @S9S_MB_2U_LIB.S9S_MB_2U(SCH_1):PAGE202
  U249  H13  GND13 LCMXO3LF9400C5BG484C-LCMXO3LF-A     I1 @S9S_MB_2U_LIB.S9S_MB_2U(SCH_1):PAGE202
  U249  H15  GND14 LCMXO3LF9400C5BG484C-LCMXO3LF-A     I1 @S9S_MB_2U_LIB.S9S_MB_2U(SCH_1):PAGE202
  U249   J9  GND15 LCMXO3LF9400C5BG484C-LCMXO3LF-A     I1 @S9S_MB_2U_LIB.S9S_MB_2U(SCH_1):PAGE202
  U249  J10  GND16 LCMXO3LF9400C5BG484C-LCMXO3LF-A     I1 @S9S_MB_2U_LIB.S9S_MB_2U(SCH_1):PAGE202
  U249  J11  GND17 LCMXO3LF9400C5BG484C-LCMXO3LF-A     I1 @S9S_MB_2U_LIB.S9S_MB_2U(SCH_1):PAGE202
  U249  J12  GND18 LCMXO3LF9400C5BG484C-LCMXO3LF-A     I1 @S9S_MB_2U_LIB.S9S_MB_2U(SCH_1):PAGE202
  U249  J13  GND19 LCMXO3LF9400C5BG484C-LCMXO3LF-A     I1 @S9S_MB_2U_LIB.S9S_MB_2U(SCH_1):PAGE202
  U249  J14  GND20 LCMXO3LF9400C5BG484C-LCMXO3LF-A     I1 @S9S_MB_2U_LIB.S9S_MB_2U(SCH_1):PAGE202
  U249   K9  GND21 LCMXO3LF9400C5BG484C-LCMXO3LF-A     I1 @S9S_MB_2U_LIB.S9S_MB_2U(SCH_1):PAGE202
  U249  K14  GND22 LCMXO3LF9400C5BG484C-LCMXO3LF-A     I1 @S9S_MB_2U_LIB.S9S_MB_2U(SCH_1):PAGE202
  U249  K21  GND23 LCMXO3LF9400C5BG484C-LCMXO3LF-A     I1 @S9S_MB_2U_LIB.S9S_MB_2U(SCH_1):PAGE202
  U249   L2  GND24 LCMXO3LF9400C5BG484C-LCMXO3LF-A     I1 @S9S_MB_2U_LIB.S9S_MB_2U(SCH_1):PAGE202
  U249   L9  GND25 LCMXO3LF9400C5BG484C-LCMXO3LF-A     I1 @S9S_MB_2U_LIB.S9S_MB_2U(SCH_1):PAGE202
  U249  L10  GND26 LCMXO3LF9400C5BG484C-LCMXO3LF-A     I1 @S9S_MB_2U_LIB.S9S_MB_2U(SCH_1):PAGE202
  U249  L13  GND27 LCMXO3LF9400C5BG484C-LCMXO3LF-A     I1 @S9S_MB_2U_LIB.S9S_MB_2U(SCH_1):PAGE202
  U249  L14  GND28 LCMXO3LF9400C5BG484C-LCMXO3LF-A     I1 @S9S_MB_2U_LIB.S9S_MB_2U(SCH_1):PAGE202
  U249  L18  GND29 LCMXO3LF9400C5BG484C-LCMXO3LF-A     I1 @S9S_MB_2U_LIB.S9S_MB_2U(SCH_1):PAGE202
  U249   M4  GND30 LCMXO3LF9400C5BG484C-LCMXO3LF-A     I1 @S9S_MB_2U_LIB.S9S_MB_2U(SCH_1):PAGE202
  U249   M9  GND31 LCMXO3LF9400C5BG484C-LCMXO3LF-A     I1 @S9S_MB_2U_LIB.S9S_MB_2U(SCH_1):PAGE202
  U249  M10  GND32 LCMXO3LF9400C5BG484C-LCMXO3LF-A     I1 @S9S_MB_2U_LIB.S9S_MB_2U(SCH_1):PAGE202
  U249  M13  GND33 LCMXO3LF9400C5BG484C-LCMXO3LF-A     I1 @S9S_MB_2U_LIB.S9S_MB_2U(SCH_1):PAGE202
  U249  M14  GND34 LCMXO3LF9400C5BG484C-LCMXO3LF-A     I1 @S9S_MB_2U_LIB.S9S_MB_2U(SCH_1):PAGE202
  U249   N9  GND35 LCMXO3LF9400C5BG484C-LCMXO3LF-A     I1 @S9S_MB_2U_LIB.S9S_MB_2U(SCH_1):PAGE202
  U249  N14  GND36 LCMXO3LF9400C5BG484C-LCMXO3LF-A     I1 @S9S_MB_2U_LIB.S9S_MB_2U(SCH_1):PAGE202
  U249  N21  GND37 LCMXO3LF9400C5BG484C-LCMXO3LF-A     I1 @S9S_MB_2U_LIB.S9S_MB_2U(SCH_1):PAGE202
  U249   P9  GND38 LCMXO3LF9400C5BG484C-LCMXO3LF-A     I1 @S9S_MB_2U_LIB.S9S_MB_2U(SCH_1):PAGE202
  U249  P10  GND39 LCMXO3LF9400C5BG484C-LCMXO3LF-A     I1 @S9S_MB_2U_LIB.S9S_MB_2U(SCH_1):PAGE202
  U249  P11  GND40 LCMXO3LF9400C5BG484C-LCMXO3LF-A     I1 @S9S_MB_2U_LIB.S9S_MB_2U(SCH_1):PAGE202
  U249  P12  GND41 LCMXO3LF9400C5BG484C-LCMXO3LF-A     I1 @S9S_MB_2U_LIB.S9S_MB_2U(SCH_1):PAGE202
  U249  P13  GND42 LCMXO3LF9400C5BG484C-LCMXO3LF-A     I1 @S9S_MB_2U_LIB.S9S_MB_2U(SCH_1):PAGE202
  U249  P14  GND43 LCMXO3LF9400C5BG484C-LCMXO3LF-A     I1 @S9S_MB_2U_LIB.S9S_MB_2U(SCH_1):PAGE202
  U249   R8  GND44 LCMXO3LF9400C5BG484C-LCMXO3LF-A     I1 @S9S_MB_2U_LIB.S9S_MB_2U(SCH_1):PAGE202
  U249  R15  GND45 LCMXO3LF9400C5BG484C-LCMXO3LF-A     I1 @S9S_MB_2U_LIB.S9S_MB_2U(SCH_1):PAGE202
  U249   V2  GND46 LCMXO3LF9400C5BG484C-LCMXO3LF-A     I1 @S9S_MB_2U_LIB.S9S_MB_2U(SCH_1):PAGE202
  U249  V21  GND47 LCMXO3LF9400C5BG484C-LCMXO3LF-A     I1 @S9S_MB_2U_LIB.S9S_MB_2U(SCH_1):PAGE202
  U249  W12  GND48 LCMXO3LF9400C5BG484C-LCMXO3LF-A     I1 @S9S_MB_2U_LIB.S9S_MB_2U(SCH_1):PAGE202
  U249   Y7  GND49 LCMXO3LF9400C5BG484C-LCMXO3LF-A     I1 @S9S_MB_2U_LIB.S9S_MB_2U(SCH_1):PAGE202
  U249  Y16  GND50 LCMXO3LF9400C5BG484C-LCMXO3LF-A     I1 @S9S_MB_2U_LIB.S9S_MB_2U(SCH_1):PAGE202
  U249  AB1  GND51 LCMXO3LF9400C5BG484C-LCMXO3LF-A     I1 @S9S_MB_2U_LIB.S9S_MB_2U(SCH_1):PAGE202
  U249 AB22  GND52 LCMXO3LF9400C5BG484C-LCMXO3LF-A     I1 @S9S_MB_2U_LIB.S9S_MB_2U(SCH_1):PAGE202
 C1154    2      B Q_CAP_C0402-0.01UF,50V,10%,X7RA     I3 @S9S_MB_2U_LIB.S9S_MB_2U(SCH_1):PAGE202
 C1152    2      B Q_CAP_C0402-0.01UF,50V,10%,X7RA     I5 @S9S_MB_2U_LIB.S9S_MB_2U(SCH_1):PAGE202
 C1932    2      B Q_CAP_C0402-0.01UF,50V,10%,X7RA     I9 @S9S_MB_2U_LIB.S9S_MB_2U(SCH_1):PAGE202
 C1933    2      B Q_CAP_C0402-0.01UF,50V,10%,X7RA    I12 @S9S_MB_2U_LIB.S9S_MB_2U(SCH_1):PAGE202
 C1146    2      B Q_CAP_C0402-0.01UF,50V,10%,X7RA    I15 @S9S_MB_2U_LIB.S9S_MB_2U(SCH_1):PAGE202
 C1904    2      B Q_CAP_C0402-0.01UF,50V,10%,X7RA    I18 @S9S_MB_2U_LIB.S9S_MB_2U(SCH_1):PAGE202
 C1898    2      B Q_CAP_C0402-0.01UF,50V,10%,X7RA    I20 @S9S_MB_2U_LIB.S9S_MB_2U(SCH_1):PAGE202
 C1931    2      B Q_CAP_C0402-0.01UF,50V,10%,X7RA    I21 @S9S_MB_2U_LIB.S9S_MB_2U(SCH_1):PAGE202
 C1928    2      B Q_CAP_C0402-0.01UF,50V,10%,X7RA    I22 @S9S_MB_2U_LIB.S9S_MB_2U(SCH_1):PAGE202
 C1919    2      B Q_CAP_C0402-0.01UF,50V,10%,X7RA    I23 @S9S_MB_2U_LIB.S9S_MB_2U(SCH_1):PAGE202
 C1916    2      B Q_CAP_C0402-0.01UF,50V,10%,X7RA    I24 @S9S_MB_2U_LIB.S9S_MB_2U(SCH_1):PAGE202
 C1907    2      B Q_CAP_0402-0.1UF,25V,10%,X7R,CA    I25 @S9S_MB_2U_LIB.S9S_MB_2U(SCH_1):PAGE202
 C1903    2      B Q_CAP_C0402-0.01UF,50V,10%,X7RA    I26 @S9S_MB_2U_LIB.S9S_MB_2U(SCH_1):PAGE202
 C1897    2      B Q_CAP_C0402-0.01UF,50V,10%,X7RA    I27 @S9S_MB_2U_LIB.S9S_MB_2U(SCH_1):PAGE202
 C1912    2      B Q_CAP_C0402-0.01UF,50V,10%,X7RA    I28 @S9S_MB_2U_LIB.S9S_MB_2U(SCH_1):PAGE202
 C1943    2      B Q_CAP_0402-0.1UF,25V,10%,X7R,CA    I29 @S9S_MB_2U_LIB.S9S_MB_2U(SCH_1):PAGE202
 C1936    2      B Q_CAP_C0402-10UF,6.3V,20%,X6S,A    I30 @S9S_MB_2U_LIB.S9S_MB_2U(SCH_1):PAGE202
 C1929    2      B Q_CAP_C0402-0.01UF,50V,10%,X7RA    I33 @S9S_MB_2U_LIB.S9S_MB_2U(SCH_1):PAGE202
 C1926    2      B Q_CAP_C0402-0.01UF,50V,10%,X7RA    I34 @S9S_MB_2U_LIB.S9S_MB_2U(SCH_1):PAGE202
 C1917    2      B Q_CAP_C0402-0.01UF,50V,10%,X7RA    I35 @S9S_MB_2U_LIB.S9S_MB_2U(SCH_1):PAGE202
 C1914    2      B Q_CAP_C0402-0.01UF,50V,10%,X7RA    I36 @S9S_MB_2U_LIB.S9S_MB_2U(SCH_1):PAGE202
 C1930    2      B Q_CAP_C0402-0.01UF,50V,10%,X7RA    I37 @S9S_MB_2U_LIB.S9S_MB_2U(SCH_1):PAGE202
 C1927    2      B Q_CAP_C0402-0.01UF,50V,10%,X7RA    I38 @S9S_MB_2U_LIB.S9S_MB_2U(SCH_1):PAGE202
 C1918    2      B Q_CAP_C0402-0.01UF,50V,10%,X7RA    I39 @S9S_MB_2U_LIB.S9S_MB_2U(SCH_1):PAGE202
 C1915    2      B Q_CAP_C0402-0.01UF,50V,10%,X7RA    I40 @S9S_MB_2U_LIB.S9S_MB_2U(SCH_1):PAGE202
 C1905    2      B Q_CAP_0402-0.1UF,25V,10%,X7R,CA    I41 @S9S_MB_2U_LIB.S9S_MB_2U(SCH_1):PAGE202
 C1901    2      B Q_CAP_C0402-0.01UF,50V,10%,X7RA    I42 @S9S_MB_2U_LIB.S9S_MB_2U(SCH_1):PAGE202
 C1895    2      B Q_CAP_C0402-0.01UF,50V,10%,X7RA    I43 @S9S_MB_2U_LIB.S9S_MB_2U(SCH_1):PAGE202
 C1910    2      B Q_CAP_C0402-0.01UF,50V,10%,X7RA    I44 @S9S_MB_2U_LIB.S9S_MB_2U(SCH_1):PAGE202
 C1906    2      B Q_CAP_0402-0.1UF,25V,10%,X7R,CA    I45 @S9S_MB_2U_LIB.S9S_MB_2U(SCH_1):PAGE202
 C1902    2      B Q_CAP_C0402-0.01UF,50V,10%,X7RA    I46 @S9S_MB_2U_LIB.S9S_MB_2U(SCH_1):PAGE202
 C1896    2      B Q_CAP_C0402-0.01UF,50V,10%,X7RA    I47 @S9S_MB_2U_LIB.S9S_MB_2U(SCH_1):PAGE202
 C1911    2      B Q_CAP_C0402-0.01UF,50V,10%,X7RA    I48 @S9S_MB_2U_LIB.S9S_MB_2U(SCH_1):PAGE202
 C1142    2      B Q_CAP_C0402-0.01UF,50V,10%,X7RA    I49 @S9S_MB_2U_LIB.S9S_MB_2U(SCH_1):PAGE202
 C1138    2      B Q_CAP_C0402-0.01UF,50V,10%,X7RA    I50 @S9S_MB_2U_LIB.S9S_MB_2U(SCH_1):PAGE202
 C1133    2      B Q_CAP_C0402-0.01UF,50V,10%,X7RA    I51 @S9S_MB_2U_LIB.S9S_MB_2U(SCH_1):PAGE202
 C1127    2      B Q_CAP_C0402-0.01UF,50V,10%,X7RA    I52 @S9S_MB_2U_LIB.S9S_MB_2U(SCH_1):PAGE202
 C1913    2      B Q_CAP_C0402-0.01UF,50V,10%,X7RA    I53 @S9S_MB_2U_LIB.S9S_MB_2U(SCH_1):PAGE202
 C1947    2      B Q_CAP_0402-0.1UF,25V,10%,X7R,CA    I54 @S9S_MB_2U_LIB.S9S_MB_2U(SCH_1):PAGE202
 C1940    2      B Q_CAP_C0402-10UF,6.3V,20%,X6S,A    I55 @S9S_MB_2U_LIB.S9S_MB_2U(SCH_1):PAGE202
 C1122    2      B Q_CAP_0402-0.1UF,25V,10%,X7R,CA    I56 @S9S_MB_2U_LIB.S9S_MB_2U(SCH_1):PAGE202
 C1900    2      B Q_CAP_C0402-0.01UF,50V,10%,X7RA    I57 @S9S_MB_2U_LIB.S9S_MB_2U(SCH_1):PAGE202
 C1894    2      B Q_CAP_C0402-0.01UF,50V,10%,X7RA    I58 @S9S_MB_2U_LIB.S9S_MB_2U(SCH_1):PAGE202
 C1909    2      B Q_CAP_C0402-0.01UF,50V,10%,X7RA    I59 @S9S_MB_2U_LIB.S9S_MB_2U(SCH_1):PAGE202
 C1945    2      B Q_CAP_0402-0.1UF,25V,10%,X7R,CA    I62 @S9S_MB_2U_LIB.S9S_MB_2U(SCH_1):PAGE202
 C1938    2      B Q_CAP_C0402-10UF,6.3V,20%,X6S,A    I64 @S9S_MB_2U_LIB.S9S_MB_2U(SCH_1):PAGE202
 C1946    2      B Q_CAP_0402-0.1UF,25V,10%,X7R,CA    I65 @S9S_MB_2U_LIB.S9S_MB_2U(SCH_1):PAGE202
 C1939    2      B Q_CAP_C0402-10UF,6.3V,20%,X6S,A    I66 @S9S_MB_2U_LIB.S9S_MB_2U(SCH_1):PAGE202
 C1944    2      B Q_CAP_0402-0.1UF,25V,10%,X7R,CA    I70 @S9S_MB_2U_LIB.S9S_MB_2U(SCH_1):PAGE202
 C1937    2      B Q_CAP_C0402-10UF,6.3V,20%,X6S,A    I71 @S9S_MB_2U_LIB.S9S_MB_2U(SCH_1):PAGE202
 C1899    2      B Q_CAP_C0402-0.01UF,50V,10%,X7RA    I74 @S9S_MB_2U_LIB.S9S_MB_2U(SCH_1):PAGE202
 C1893    2      B Q_CAP_C0402-0.01UF,50V,10%,X7RA    I76 @S9S_MB_2U_LIB.S9S_MB_2U(SCH_1):PAGE202
 C1908    2      B Q_CAP_C0402-0.01UF,50V,10%,X7RA    I77 @S9S_MB_2U_LIB.S9S_MB_2U(SCH_1):PAGE202
 C1942    2      B Q_CAP_0402-0.1UF,25V,10%,X7R,CA    I80 @S9S_MB_2U_LIB.S9S_MB_2U(SCH_1):PAGE202
 C1935    2      B Q_CAP_C0402-10UF,6.3V,20%,X6S,A    I82 @S9S_MB_2U_LIB.S9S_MB_2U(SCH_1):PAGE202
 C1118    2      B Q_CAP_C0402-0.01UF,50V,10%,X7RA    I97 @S9S_MB_2U_LIB.S9S_MB_2U(SCH_1):PAGE202
 C1113    2      B Q_CAP_C0402-0.01UF,50V,10%,X7RA    I99 @S9S_MB_2U_LIB.S9S_MB_2U(SCH_1):PAGE202
 C1124    2      B Q_CAP_C0402-0.01UF,50V,10%,X7RA   I100 @S9S_MB_2U_LIB.S9S_MB_2U(SCH_1):PAGE202
 C1941    2      B Q_CAP_0402-0.1UF,25V,10%,X7R,CA   I101 @S9S_MB_2U_LIB.S9S_MB_2U(SCH_1):PAGE202
 C1842    2      B Q_CAP_C0402-10UF,6.3V,20%,X6S,A   I107 @S9S_MB_2U_LIB.S9S_MB_2U(SCH_1):PAGE202
PC603_P0_2    2      B Q_CAP_0402-3300PF,50V,10%,X7R,A    I27 @S9S_MB_2U_LIB.S9S_MB_2U(SCH_1):PAGE257
PC602_P0_1    2      B Q_CAP_0402-3300PF,50V,10%,X7R,A    I44 @S9S_MB_2U_LIB.S9S_MB_2U(SCH_1):PAGE257
PC604_P0_1    2      B Q_CAP_C0402-1UF,16V,10%,X6S,CHA    I45 @S9S_MB_2U_LIB.S9S_MB_2U(SCH_1):PAGE257
PC723_P0_4    2      B Q_CAP_C0805-22UF,16V,20%,X6S,CA    I41 @S9S_MB_2U_LIB.S9S_MB_2U(SCH_1):PAGE258
PC1675    2      B Q_CAP_C0805-22UF,16V,20%,X6S,CA    I77 @S9S_MB_2U_LIB.S9S_MB_2U(SCH_1):PAGE258
 C2860    2      B Q_CAP_0402-1000PF,50V,5%,X7R,TA    I67 @S9S_MB_2U_LIB.S9S_MB_2U(SCH_1):PAGE270
 PR224    2      B Q_RES_0402LF-8.87K,1%,1/16W,EMA     I2 @S9S_MB_2U_LIB.S9S_MB_2U(SCH_1):PAGE275
PU76_P1_2    2   AGND ISL99390FRZTR5935-ISL99390FRZ-A     I9 @S9S_MB_2U_LIB.S9S_MB_2U(SCH_1):PAGE275
PU76_P1_2    5  PGND1 ISL99390FRZTR5935-ISL99390FRZ-A     I9 @S9S_MB_2U_LIB.S9S_MB_2U(SCH_1):PAGE275
PU76_P1_2 7_9-20_24  PGND2 ISL99390FRZTR5935-ISL99390FRZ-A     I9 @S9S_MB_2U_LIB.S9S_MB_2U(SCH_1):PAGE275
PU76_P1_2   40  PGND3 ISL99390FRZTR5935-ISL99390FRZ-A     I9 @S9S_MB_2U_LIB.S9S_MB_2U(SCH_1):PAGE275
 PC395    2      B Q_CAP_C0402-2.2UF,10V,10%,X6S,A    I27 @S9S_MB_2U_LIB.S9S_MB_2U(SCH_1):PAGE275
PC398_P1_2    2      B Q_CAP_0402-3300PF,50V,10%,X7R,A    I37 @S9S_MB_2U_LIB.S9S_MB_2U(SCH_1):PAGE275
PC400_P1_2    2      B Q_CAP_C0402-1UF,16V,10%,X6S,CHA    I39 @S9S_MB_2U_LIB.S9S_MB_2U(SCH_1):PAGE275
PC725_P1_2    2      B Q_CAP_C0805-22UF,16V,20%,X6S,CA    I46 @S9S_MB_2U_LIB.S9S_MB_2U(SCH_1):PAGE275
PC397_P1_1    2      B Q_CAP_0402-3300PF,50V,10%,X7R,A    I49 @S9S_MB_2U_LIB.S9S_MB_2U(SCH_1):PAGE275
PC621_P1_1    2      B Q_CAP_C0402-100NF,50V,10%,X7R,A    I60 @S9S_MB_2U_LIB.S9S_MB_2U(SCH_1):PAGE275
PC413_P1_2    2      B Q_CAP_C0805-22UF,4V,20%,X6S,CHA    I63 @S9S_MB_2U_LIB.S9S_MB_2U(SCH_1):PAGE275
 PC416    2      B Q_CAPP_THLF-560UF,2.5V,20%,OSCA    I68 @S9S_MB_2U_LIB.S9S_MB_2U(SCH_1):PAGE275
PC1679    2      B Q_CAP_C0805-22UF,16V,20%,X6S,CA    I84 @S9S_MB_2U_LIB.S9S_MB_2U(SCH_1):PAGE275
PC1193_P1_3    2      B Q_CAP_0402-3300PF,50V,10%,X7R,A    I38 @S9S_MB_2U_LIB.S9S_MB_2U(SCH_1):PAGE276
PC1199_P1_3    2      B Q_CAP_C0805-22UF,16V,20%,X6S,CA    I41 @S9S_MB_2U_LIB.S9S_MB_2U(SCH_1):PAGE276
 R4653    2      B Q_RES_0402LF-1K,1%,1/16W,CHIP,A     I2 @S9S_MB_2U_LIB.S9S_MB_2U(SCH_1):PAGE159
 R4647    2      B Q_RES_0402LF-1K,1%,1/16W,CHIP,A     I4 @S9S_MB_2U_LIB.S9S_MB_2U(SCH_1):PAGE159
 R4646    2      B Q_RES_0402LF-1K,1%,1/16W,EMPTYA    I15 @S9S_MB_2U_LIB.S9S_MB_2U(SCH_1):PAGE159
 R4654    2      B Q_RES_0402LF-1K,1%,1/16W,CHIP,A    I67 @S9S_MB_2U_LIB.S9S_MB_2U(SCH_1):PAGE159
  U328   25 TH_GND DS125BR111RTWR-DS125BR111RTWR,A    I95 @S9S_MB_2U_LIB.S9S_MB_2U(SCH_1):PAGE159
  U328   16 VDD_SEL DS125BR111RTWR-DS125BR111RTWR,A    I95 @S9S_MB_2U_LIB.S9S_MB_2U(SCH_1):PAGE159
 R3430    2      B Q_RES_0402LF-100K,1%,1/16W,EMPA     I3 @S9S_MB_2U_LIB.S9S_MB_2U(SCH_1):PAGE299
 R3428    2      B Q_RES_0402LF-100K,1%,1/16W,EMPA    I17 @S9S_MB_2U_LIB.S9S_MB_2U(SCH_1):PAGE299
  Q104    1     S1 MOSFET_NCH_DUAL-PJT138K,SMLF,IA    I21 @S9S_MB_2U_LIB.S9S_MB_2U(SCH_1):PAGE299
  Q104    4     S2 MOSFET_NCH_DUAL-PJT138K,SMLF,IA    I26 @S9S_MB_2U_LIB.S9S_MB_2U(SCH_1):PAGE299
 C1976    2      B Q_CAP_0402-1000PF,50V,5%,EMPTYA    I30 @S9S_MB_2U_LIB.S9S_MB_2U(SCH_1):PAGE299
  Q103    1     S1 MOSFET_NCH_DUAL-PJT138K,SMLF,IA    I37 @S9S_MB_2U_LIB.S9S_MB_2U(SCH_1):PAGE299
  Q102    1     S1 MOSFET_NCH_DUAL-PJT138K,SMLF,IA    I40 @S9S_MB_2U_LIB.S9S_MB_2U(SCH_1):PAGE299
  Q103    4     S2 MOSFET_NCH_DUAL-PJT138K,SMLF,IA    I43 @S9S_MB_2U_LIB.S9S_MB_2U(SCH_1):PAGE299
  Q102    4     S2 MOSFET_NCH_DUAL-PJT138K,SMLF,IA    I48 @S9S_MB_2U_LIB.S9S_MB_2U(SCH_1):PAGE299
  Q101    1     S1 MOSFET_NCH_DUAL-PJT138K,SMLF,IA    I52 @S9S_MB_2U_LIB.S9S_MB_2U(SCH_1):PAGE299
  Q101    4     S2 MOSFET_NCH_DUAL-PJT138K,SMLF,IA    I57 @S9S_MB_2U_LIB.S9S_MB_2U(SCH_1):PAGE299
 C1973    2      B Q_CAP_0402-1000PF,50V,5%,EMPTYA    I71 @S9S_MB_2U_LIB.S9S_MB_2U(SCH_1):PAGE299
 C1974    2      B Q_CAP_0402-1000PF,50V,5%,EMPTYA    I74 @S9S_MB_2U_LIB.S9S_MB_2U(SCH_1):PAGE299
 C1975    2      B Q_CAP_0402-1000PF,50V,5%,EMPTYA   I129 @S9S_MB_2U_LIB.S9S_MB_2U(SCH_1):PAGE299
  U253    2    GND 74LVC2G17GW-74LVC2G17GW,SMLF,IA    I26 @S9S_MB_2U_LIB.S9S_MB_2U(SCH_1):PAGE160
 C1958    2      B Q_CAP_0402-0.1UF,25V,10%,X7R,CA    I29 @S9S_MB_2U_LIB.S9S_MB_2U(SCH_1):PAGE160
 R3443    2      B Q_RES_0402LF-0,5%,1/16W,CHIP,CA     I5 @S9S_MB_2U_LIB.S9S_MB_2U(SCH_1):PAGE147
 R3440    2      B Q_RES_0402LF-0,5%,1/16W,EMPTY,A     I8 @S9S_MB_2U_LIB.S9S_MB_2U(SCH_1):PAGE147
 R2656    2      B Q_RES_0402LF-100,1%,1/16W,EMPTA    I11 @S9S_MB_2U_LIB.S9S_MB_2U(SCH_1):PAGE147
 R3452    2      B Q_RES_0402LF-100K,1%,1/16W,CHIA    I95 @S9S_MB_2U_LIB.S9S_MB_2U(SCH_1):PAGE160
 R3457    2      B Q_RES_0402LF-10K,1%,1/16W,CHIPA   I123 @S9S_MB_2U_LIB.S9S_MB_2U(SCH_1):PAGE160
 R3463    2      B Q_RES_0402LF-54.9K,1%,1/16W,CHA   I131 @S9S_MB_2U_LIB.S9S_MB_2U(SCH_1):PAGE299
 R3431    2      B Q_RES_0402LF-100K,1%,1/16W,EMPA   I133 @S9S_MB_2U_LIB.S9S_MB_2U(SCH_1):PAGE299
 R3455    2      B Q_RES_0402LF-10K,1%,1/16W,CHIPA   I139 @S9S_MB_2U_LIB.S9S_MB_2U(SCH_1):PAGE160
 C1957    2      B Q_CAP_0402-0.1UF,25V,10%,X7R,CA   I148 @S9S_MB_2U_LIB.S9S_MB_2U(SCH_1):PAGE160
  U252    2    GND 74LVC2G17GW-74LVC2G17GW,SMLF,IA   I153 @S9S_MB_2U_LIB.S9S_MB_2U(SCH_1):PAGE160
 C1963    2      B Q_CAP_0402-0.1UF,25V,10%,X7R,CA    I13 @S9S_MB_2U_LIB.S9S_MB_2U(SCH_1):PAGE296
  U255    2    GND 74LVC2G07DW7-74LVC2G07DW-7,SMLA    I16 @S9S_MB_2U_LIB.S9S_MB_2U(SCH_1):PAGE296
 R3460    2      B Q_RES_0402LF-100K,1%,1/16W,EMPA    I31 @S9S_MB_2U_LIB.S9S_MB_2U(SCH_1):PAGE296
 R3462    2      B Q_RES_0402LF-100K,1%,1/16W,EMPA    I33 @S9S_MB_2U_LIB.S9S_MB_2U(SCH_1):PAGE296
  Q105    1     S1 MOSFET_NCH_DUAL-NX6008NBKS,SMLA    I76 @S9S_MB_2U_LIB.S9S_MB_2U(SCH_1):PAGE304
 R3454    2      B Q_RES_0402LF-1K,1%,1/16W,CHIP,A   I165 @S9S_MB_2U_LIB.S9S_MB_2U(SCH_1):PAGE160
 R3449    2      B Q_RES_0402LF-100K,1%,1/16W,CHIA   I170 @S9S_MB_2U_LIB.S9S_MB_2U(SCH_1):PAGE160
  U256    2    GND 74LVC2G17GW-74LVC2G17GW,SMLF,IA   I173 @S9S_MB_2U_LIB.S9S_MB_2U(SCH_1):PAGE160
 C1977    2      B Q_CAP_0402-0.1UF,25V,10%,X7R,CA   I175 @S9S_MB_2U_LIB.S9S_MB_2U(SCH_1):PAGE160
 R3467    2      B Q_RES_0402LF-10K,1%,1/16W,CHIPA   I181 @S9S_MB_2U_LIB.S9S_MB_2U(SCH_1):PAGE160
 R3466    2      B Q_RES_0402LF-10K,1%,1/16W,CHIPA   I184 @S9S_MB_2U_LIB.S9S_MB_2U(SCH_1):PAGE160
  Q106    1     S1 MOSFET_NCH_DUAL-PJT138K,SMLF,IA   I135 @S9S_MB_2U_LIB.S9S_MB_2U(SCH_1):PAGE299
 R3471    2      B Q_RES_0402LF-10K,1%,1/16W,CHIPA   I144 @S9S_MB_2U_LIB.S9S_MB_2U(SCH_1):PAGE299
 R3472    1      A Q_RES_0402LF-0,5%,1/16W,EMPTY,A   I147 @S9S_MB_2U_LIB.S9S_MB_2U(SCH_1):PAGE299
 C1978    2      B Q_CAP_0402-1000PF,50V,5%,EMPTYA   I152 @S9S_MB_2U_LIB.S9S_MB_2U(SCH_1):PAGE299
  Q107    4     S2 MOSFET_NCH_DUAL-PJT138K,SMLF,IA   I157 @S9S_MB_2U_LIB.S9S_MB_2U(SCH_1):PAGE299
  Q107    1     S1 MOSFET_NCH_DUAL-PJT138K,SMLF,IA   I160 @S9S_MB_2U_LIB.S9S_MB_2U(SCH_1):PAGE299
 R3473    2      B Q_RES_0402LF-100K,1%,1/16W,EMPA   I163 @S9S_MB_2U_LIB.S9S_MB_2U(SCH_1):PAGE299
 R3489    2      B Q_RES_0402LF-100K,1%,1/16W,EMPA    I42 @S9S_MB_2U_LIB.S9S_MB_2U(SCH_1):PAGE296
 R3493    2      B Q_RES_0402LF-100K,1%,1/16W,EMPA    I48 @S9S_MB_2U_LIB.S9S_MB_2U(SCH_1):PAGE296
  U257    3     2A 74LVC2G07DW7-74LVC2G07DW-7,SMLA    I50 @S9S_MB_2U_LIB.S9S_MB_2U(SCH_1):PAGE296
  U257    2    GND 74LVC2G07DW7-74LVC2G07DW-7,SMLA    I50 @S9S_MB_2U_LIB.S9S_MB_2U(SCH_1):PAGE296
 R3495    2      B Q_RES_0402LF-100K,1%,1/16W,EMPA    I62 @S9S_MB_2U_LIB.S9S_MB_2U(SCH_1):PAGE296
 C1979    2      B Q_CAP_0402-0.1UF,25V,10%,X7R,CA    I67 @S9S_MB_2U_LIB.S9S_MB_2U(SCH_1):PAGE296
 R3491    2      B Q_RES_0402LF-100K,1%,1/16W,EMPA    I70 @S9S_MB_2U_LIB.S9S_MB_2U(SCH_1):PAGE296
 R3511    2      B Q_RES_0402LF-54.9K,1%,1/16W,CHA   I172 @S9S_MB_2U_LIB.S9S_MB_2U(SCH_1):PAGE145
 R3513    2      B Q_RES_0402LF-54.9K,1%,1/16W,CHA   I173 @S9S_MB_2U_LIB.S9S_MB_2U(SCH_1):PAGE145
 R3509    2      B Q_RES_0402LF-10K,1%,1/16W,CHIPA   I191 @S9S_MB_2U_LIB.S9S_MB_2U(SCH_1):PAGE140
 R3507    2      B Q_RES_0402LF-10K,1%,1/16W,CHIPA   I192 @S9S_MB_2U_LIB.S9S_MB_2U(SCH_1):PAGE140
 R3508    2      B Q_RES_0402LF-54.9K,1%,1/16W,CHA   I194 @S9S_MB_2U_LIB.S9S_MB_2U(SCH_1):PAGE140
  Q108    4     S2 MOSFET_NCH_DUAL-PJT138K,SMLF,IA   I168 @S9S_MB_2U_LIB.S9S_MB_2U(SCH_1):PAGE299
  Q108    1     S1 MOSFET_NCH_DUAL-PJT138K,SMLF,IA   I169 @S9S_MB_2U_LIB.S9S_MB_2U(SCH_1):PAGE299
 C1988    2      B Q_CAP_0402-1000PF,50V,5%,EMPTYA   I171 @S9S_MB_2U_LIB.S9S_MB_2U(SCH_1):PAGE299
 R3502    2      B Q_RES_0402LF-100K,1%,1/16W,EMPA   I181 @S9S_MB_2U_LIB.S9S_MB_2U(SCH_1):PAGE299
 R2918    2      B Q_RES_0402LF-4.7K,5%,1/16W,CHIA   I188 @S9S_MB_2U_LIB.S9S_MB_2U(SCH_1):PAGE160
 R2932    2      B Q_RES_0402LF-4.7K,5%,1/16W,CHIA   I195 @S9S_MB_2U_LIB.S9S_MB_2U(SCH_1):PAGE160
 C1998    2      B Q_CAP_0402-0.1UF,25V,10%,X7R,CA    I82 @S9S_MB_2U_LIB.S9S_MB_2U(SCH_1):PAGE183
 C1997    2      B Q_CAP_0402-0.1UF,25V,10%,X7R,CA    I89 @S9S_MB_2U_LIB.S9S_MB_2U(SCH_1):PAGE183
  U268   TH     TH GL852GOHY60-GL852G-OHY60,SMLF,A   I100 @S9S_MB_2U_LIB.S9S_MB_2U(SCH_1):PAGE155
 C2018    2      B Q_CAP_0402-0.1UF,25V,10%,X7R,CA    I26 @S9S_MB_2U_LIB.S9S_MB_2U(SCH_1):PAGE163
 R3611    1      A Q_RES_0402LF-4.7K,1%,1/16W,CHIA    I36 @S9S_MB_2U_LIB.S9S_MB_2U(SCH_1):PAGE163
 C2013    2      B Q_CAP_0402-0.1UF,25V,10%,X7R,CA    I42 @S9S_MB_2U_LIB.S9S_MB_2U(SCH_1):PAGE163
 R3610    1      A Q_RES_0402LF-4.7K,1%,1/16W,EMPA    I45 @S9S_MB_2U_LIB.S9S_MB_2U(SCH_1):PAGE163
  U264   10    GND INA230AIRGTR-INA230AIRGTR,SMLFB    I46 @S9S_MB_2U_LIB.S9S_MB_2U(SCH_1):PAGE163
  U264   TH     TH INA230AIRGTR-INA230AIRGTR,SMLFB    I46 @S9S_MB_2U_LIB.S9S_MB_2U(SCH_1):PAGE163
 C2019    2      B Q_CAP_0402-0.1UF,25V,10%,X7R,CA    I49 @S9S_MB_2U_LIB.S9S_MB_2U(SCH_1):PAGE163
 R3613    1      A Q_RES_0402LF-4.7K,1%,1/16W,EMPA    I59 @S9S_MB_2U_LIB.S9S_MB_2U(SCH_1):PAGE163
 C2014    2      B Q_CAP_0402-0.1UF,25V,10%,X7R,CA    I65 @S9S_MB_2U_LIB.S9S_MB_2U(SCH_1):PAGE163
 R3612    1      A Q_RES_0402LF-4.7K,1%,1/16W,EMPA    I68 @S9S_MB_2U_LIB.S9S_MB_2U(SCH_1):PAGE163
  U265   10    GND INA230AIRGTR-INA230AIRGTR,SMLFB    I69 @S9S_MB_2U_LIB.S9S_MB_2U(SCH_1):PAGE163
  U265   TH     TH INA230AIRGTR-INA230AIRGTR,SMLFB    I69 @S9S_MB_2U_LIB.S9S_MB_2U(SCH_1):PAGE163
  U266   10    GND INA230AIRGTR-INA230AIRGTR,SMLFB    I30 @S9S_MB_2U_LIB.S9S_MB_2U(SCH_1):PAGE295
  U266   TH     TH INA230AIRGTR-INA230AIRGTR,SMLFB    I30 @S9S_MB_2U_LIB.S9S_MB_2U(SCH_1):PAGE295
 R3616    1      A Q_RES_0402LF-4.7K,1%,1/16W,CHIA    I31 @S9S_MB_2U_LIB.S9S_MB_2U(SCH_1):PAGE295
 C2015    2      B Q_CAP_0402-0.1UF,25V,10%,X7R,CA    I34 @S9S_MB_2U_LIB.S9S_MB_2U(SCH_1):PAGE295
 R3617    1      A Q_RES_0402LF-4.7K,1%,1/16W,EMPA    I40 @S9S_MB_2U_LIB.S9S_MB_2U(SCH_1):PAGE295
 C2024    2      B Q_CAP_0402-0.1UF,25V,10%,X7R,CA    I50 @S9S_MB_2U_LIB.S9S_MB_2U(SCH_1):PAGE295
PC2147    1      A Q_CAP_C0402-1UF,25V,10%,X6S,CHA    I87 @S9S_MB_2U_LIB.S9S_MB_2U(SCH_1):PAGE131
 R3653    2      B Q_RES_0402LF-680,1%,1/16W,CHIPA   I139 @S9S_MB_2U_LIB.S9S_MB_2U(SCH_1):PAGE155
 C2034    2      B Q_CAP_0402-0.1UF,25V,10%,X7R,CA   I142 @S9S_MB_2U_LIB.S9S_MB_2U(SCH_1):PAGE155
 C2033    2      B Q_CAP_0402-0.1UF,25V,10%,X7R,CA   I143 @S9S_MB_2U_LIB.S9S_MB_2U(SCH_1):PAGE155
 C2032    2      B Q_CAP_0402-0.1UF,25V,10%,X7R,CA   I145 @S9S_MB_2U_LIB.S9S_MB_2U(SCH_1):PAGE155
 C2035    2      B Q_CAP_C0402-1UF,25V,10%,X6S,CHA   I147 @S9S_MB_2U_LIB.S9S_MB_2U(SCH_1):PAGE155
 C2031    2      B Q_CAP_C0402-1UF,25V,10%,X6S,CHA   I148 @S9S_MB_2U_LIB.S9S_MB_2U(SCH_1):PAGE155
 C2041    2      B Q_CAP_C0402-1UF,25V,10%,X6S,CHA   I158 @S9S_MB_2U_LIB.S9S_MB_2U(SCH_1):PAGE155
 C2040    2      B Q_CAP_0402-0.1UF,25V,10%,X7R,CA   I162 @S9S_MB_2U_LIB.S9S_MB_2U(SCH_1):PAGE155
 C2039    2      B Q_CAP_0402-0.1UF,25V,10%,X7R,CA   I163 @S9S_MB_2U_LIB.S9S_MB_2U(SCH_1):PAGE155
 C2038    2      B Q_CAP_C0402-10UF,6.3V,20%,X6S,A   I164 @S9S_MB_2U_LIB.S9S_MB_2U(SCH_1):PAGE155
 R3665    2      B Q_RES_0402LF-100K,1%,1/16W,CHIA   I182 @S9S_MB_2U_LIB.S9S_MB_2U(SCH_1):PAGE155
 R3664    2      B Q_RES_0402LF-10K,1%,1/16W,EMPTA   I187 @S9S_MB_2U_LIB.S9S_MB_2U(SCH_1):PAGE155
 R3666    2      B Q_RES_0402LF-0,5%,1/16W,CHIP,CA   I199 @S9S_MB_2U_LIB.S9S_MB_2U(SCH_1):PAGE155
  U269    4    GND ADC128D818CIMTXNOPB-ADC128D818A   I103 @S9S_MB_2U_LIB.S9S_MB_2U(SCH_1):PAGE239
 C2051    2      B Q_CAP_0402-0.1UF,25V,10%,X7R,CA   I127 @S9S_MB_2U_LIB.S9S_MB_2U(SCH_1):PAGE239
 C2052    2      B Q_CAP_0402-0.1UF,25V,10%,X7R,CA   I128 @S9S_MB_2U_LIB.S9S_MB_2U(SCH_1):PAGE239
 R3690    2      B Q_RES_0402LF-4.7K,1%,1/16W,EMPA   I131 @S9S_MB_2U_LIB.S9S_MB_2U(SCH_1):PAGE239
 R1785    2      B Q_RES_0402LF-4.7K,1%,1/16W,CHIA   I149 @S9S_MB_2U_LIB.S9S_MB_2U(SCH_1):PAGE239
 R2843    2      B Q_RES_0402LF-4.7K,1%,1/16W,CHIA   I162 @S9S_MB_2U_LIB.S9S_MB_2U(SCH_1):PAGE239
 R1791    2      B Q_RES_0402LF-9.09K,1%,1/16W,CHA   I163 @S9S_MB_2U_LIB.S9S_MB_2U(SCH_1):PAGE239
 R1800    2      B Q_RES_0402LF-1.21K,1%,1/16W,CHA   I174 @S9S_MB_2U_LIB.S9S_MB_2U(SCH_1):PAGE239
 C2042    2      B Q_CAP_0402-100PF,50V,5%,EMPTY,A   I180 @S9S_MB_2U_LIB.S9S_MB_2U(SCH_1):PAGE239
 C2047    2      B Q_CAP_0402-0.1UF,25V,10%,X7R,CA   I181 @S9S_MB_2U_LIB.S9S_MB_2U(SCH_1):PAGE239
 C2044    2      B Q_CAP_0402-100PF,50V,5%,EMPTY,A   I187 @S9S_MB_2U_LIB.S9S_MB_2U(SCH_1):PAGE239
 C2049    2      B Q_CAP_0402-0.1UF,25V,10%,X7R,CA   I188 @S9S_MB_2U_LIB.S9S_MB_2U(SCH_1):PAGE239
 C2043    2      B Q_CAP_0402-100PF,50V,5%,EMPTY,A   I196 @S9S_MB_2U_LIB.S9S_MB_2U(SCH_1):PAGE239
 C2048    2      B Q_CAP_0402-0.1UF,25V,10%,X7R,CA   I197 @S9S_MB_2U_LIB.S9S_MB_2U(SCH_1):PAGE239
 C1344    2      B Q_CAP_0402-100PF,50V,5%,EMPTY,A   I205 @S9S_MB_2U_LIB.S9S_MB_2U(SCH_1):PAGE239
 C2046    2      B Q_CAP_0402-0.1UF,25V,10%,X7R,CA   I207 @S9S_MB_2U_LIB.S9S_MB_2U(SCH_1):PAGE239
 R3668    2      B Q_RES_0402LF-1K,1%,1/16W,CHIP,A   I223 @S9S_MB_2U_LIB.S9S_MB_2U(SCH_1):PAGE239
 R3670    2      B Q_RES_0402LF-1K,1%,1/16W,CHIP,A   I227 @S9S_MB_2U_LIB.S9S_MB_2U(SCH_1):PAGE239
 C2045    2      B Q_CAP_0402-100PF,50V,5%,EMPTY,A   I236 @S9S_MB_2U_LIB.S9S_MB_2U(SCH_1):PAGE239
 C2050    2      B Q_CAP_0402-0.1UF,25V,10%,X7R,CA   I238 @S9S_MB_2U_LIB.S9S_MB_2U(SCH_1):PAGE239
 C2010    2      B Q_CAP_0402-0.1UF,25V,10%,X7R,CA    I16 @S9S_MB_2U_LIB.S9S_MB_2U(SCH_1):PAGE161
 R3704    2      B Q_RES_0402LF-1K,1%,1/16W,CHIP,A     I2 @S9S_MB_2U_LIB.S9S_MB_2U(SCH_1):PAGE221
 R3707    2      B Q_RES_0402LF-1K,1%,1/16W,CHIP,A     I6 @S9S_MB_2U_LIB.S9S_MB_2U(SCH_1):PAGE221
 R3709    2      B Q_RES_0402LF-1K,1%,1/16W,CHIP,A     I8 @S9S_MB_2U_LIB.S9S_MB_2U(SCH_1):PAGE221
 C2067    2      B Q_CAP_0402-0.1UF,25V,10%,X7R,CA   I125 @S9S_MB_2U_LIB.S9S_MB_2U(SCH_1):PAGE295
  U276   10    GND INA230AIRGTR-INA230AIRGTR,SMLFB   I129 @S9S_MB_2U_LIB.S9S_MB_2U(SCH_1):PAGE295
  U276   TH     TH INA230AIRGTR-INA230AIRGTR,SMLFB   I129 @S9S_MB_2U_LIB.S9S_MB_2U(SCH_1):PAGE295
 R3764    1      A Q_RES_0402LF-4.7K,1%,1/16W,EMPA   I135 @S9S_MB_2U_LIB.S9S_MB_2U(SCH_1):PAGE295
 R3763    1      A Q_RES_0402LF-4.7K,1%,1/16W,CHIA   I136 @S9S_MB_2U_LIB.S9S_MB_2U(SCH_1):PAGE295
 C2069    2      B Q_CAP_0402-0.1UF,25V,10%,X7R,CA   I142 @S9S_MB_2U_LIB.S9S_MB_2U(SCH_1):PAGE295
  U263   10    GND INA230AIRGTR-INA230AIRGTR,SMLFB    I94 @S9S_MB_2U_LIB.S9S_MB_2U(SCH_1):PAGE163
  U263   TH     TH INA230AIRGTR-INA230AIRGTR,SMLFB    I94 @S9S_MB_2U_LIB.S9S_MB_2U(SCH_1):PAGE163
 C2012    2      B Q_CAP_0402-0.1UF,25V,10%,X7R,CA    I98 @S9S_MB_2U_LIB.S9S_MB_2U(SCH_1):PAGE163
 R3608    1      A Q_RES_0402LF-4.7K,1%,1/16W,CHIA   I103 @S9S_MB_2U_LIB.S9S_MB_2U(SCH_1):PAGE163
 R3609    1      A Q_RES_0402LF-4.7K,1%,1/16W,EMPA   I104 @S9S_MB_2U_LIB.S9S_MB_2U(SCH_1):PAGE163
 C2017    2      B Q_CAP_0402-0.1UF,25V,10%,X7R,CA   I114 @S9S_MB_2U_LIB.S9S_MB_2U(SCH_1):PAGE163
   J37   G1     G1 SCONN168_ME1016810202011-SCONNA   I199 @S9S_MB_2U_LIB.S9S_MB_2U(SCH_1):PAGE150
   J37   G2     G2 SCONN168_ME1016810202011-SCONNA   I199 @S9S_MB_2U_LIB.S9S_MB_2U(SCH_1):PAGE150
   J37   G3     G3 SCONN168_ME1016810202011-SCONNA   I199 @S9S_MB_2U_LIB.S9S_MB_2U(SCH_1):PAGE150
   J37   G4     G4 SCONN168_ME1016810202011-SCONNA   I199 @S9S_MB_2U_LIB.S9S_MB_2U(SCH_1):PAGE150
   J37   G5     G5 SCONN168_ME1016810202011-SCONNA   I199 @S9S_MB_2U_LIB.S9S_MB_2U(SCH_1):PAGE150
   J37   A1 GND_A1 SCONN168_ME1016810202011-SCONNA   I199 @S9S_MB_2U_LIB.S9S_MB_2U(SCH_1):PAGE150
   J37   A2 GND_A2 SCONN168_ME1016810202011-SCONNA   I199 @S9S_MB_2U_LIB.S9S_MB_2U(SCH_1):PAGE150
   J37   A3 GND_A3 SCONN168_ME1016810202011-SCONNA   I199 @S9S_MB_2U_LIB.S9S_MB_2U(SCH_1):PAGE150
   J37   A4 GND_A4 SCONN168_ME1016810202011-SCONNA   I199 @S9S_MB_2U_LIB.S9S_MB_2U(SCH_1):PAGE150
   J37   A5 GND_A5 SCONN168_ME1016810202011-SCONNA   I199 @S9S_MB_2U_LIB.S9S_MB_2U(SCH_1):PAGE150
   J37   A6 GND_A6 SCONN168_ME1016810202011-SCONNA   I199 @S9S_MB_2U_LIB.S9S_MB_2U(SCH_1):PAGE150
   J37  A13 GND_A13 SCONN168_ME1016810202011-SCONNA   I199 @S9S_MB_2U_LIB.S9S_MB_2U(SCH_1):PAGE150
   J37  A16 GND_A16 SCONN168_ME1016810202011-SCONNA   I199 @S9S_MB_2U_LIB.S9S_MB_2U(SCH_1):PAGE150
   J37  A19 GND_A19 SCONN168_ME1016810202011-SCONNA   I199 @S9S_MB_2U_LIB.S9S_MB_2U(SCH_1):PAGE150
   J37  A22 GND_A22 SCONN168_ME1016810202011-SCONNA   I199 @S9S_MB_2U_LIB.S9S_MB_2U(SCH_1):PAGE150
   J37  A25 GND_A25 SCONN168_ME1016810202011-SCONNA   I199 @S9S_MB_2U_LIB.S9S_MB_2U(SCH_1):PAGE150
   J37  A28 GND_A28 SCONN168_ME1016810202011-SCONNA   I199 @S9S_MB_2U_LIB.S9S_MB_2U(SCH_1):PAGE150
   J37  A29 GND_A29 SCONN168_ME1016810202011-SCONNA   I199 @S9S_MB_2U_LIB.S9S_MB_2U(SCH_1):PAGE150
   J37  A32 GND_A32 SCONN168_ME1016810202011-SCONNA   I199 @S9S_MB_2U_LIB.S9S_MB_2U(SCH_1):PAGE150
   J37  A35 GND_A35 SCONN168_ME1016810202011-SCONNA   I199 @S9S_MB_2U_LIB.S9S_MB_2U(SCH_1):PAGE150
   J37  A38 GND_A38 SCONN168_ME1016810202011-SCONNA   I199 @S9S_MB_2U_LIB.S9S_MB_2U(SCH_1):PAGE150
   J37  A41 GND_A41 SCONN168_ME1016810202011-SCONNA   I199 @S9S_MB_2U_LIB.S9S_MB_2U(SCH_1):PAGE150
   J37  A43 GND_A43 SCONN168_ME1016810202011-SCONNA   I199 @S9S_MB_2U_LIB.S9S_MB_2U(SCH_1):PAGE150
   J37  A46 GND_A46 SCONN168_ME1016810202011-SCONNA   I199 @S9S_MB_2U_LIB.S9S_MB_2U(SCH_1):PAGE150
   J37  A49 GND_A49 SCONN168_ME1016810202011-SCONNA   I199 @S9S_MB_2U_LIB.S9S_MB_2U(SCH_1):PAGE150
   J37  A52 GND_A52 SCONN168_ME1016810202011-SCONNA   I199 @S9S_MB_2U_LIB.S9S_MB_2U(SCH_1):PAGE150
   J37  A55 GND_A55 SCONN168_ME1016810202011-SCONNA   I199 @S9S_MB_2U_LIB.S9S_MB_2U(SCH_1):PAGE150
   J37  A58 GND_A58 SCONN168_ME1016810202011-SCONNA   I199 @S9S_MB_2U_LIB.S9S_MB_2U(SCH_1):PAGE150
   J37  A61 GND_A61 SCONN168_ME1016810202011-SCONNA   I199 @S9S_MB_2U_LIB.S9S_MB_2U(SCH_1):PAGE150
   J37  A64 GND_A64 SCONN168_ME1016810202011-SCONNA   I199 @S9S_MB_2U_LIB.S9S_MB_2U(SCH_1):PAGE150
   J37  A67 GND_A67 SCONN168_ME1016810202011-SCONNA   I199 @S9S_MB_2U_LIB.S9S_MB_2U(SCH_1):PAGE150
   J37  B13 GND_B13 SCONN168_ME1016810202011-SCONNA   I199 @S9S_MB_2U_LIB.S9S_MB_2U(SCH_1):PAGE150
   J37  B16 GND_B16 SCONN168_ME1016810202011-SCONNA   I199 @S9S_MB_2U_LIB.S9S_MB_2U(SCH_1):PAGE150
   J37  B19 GND_B19 SCONN168_ME1016810202011-SCONNA   I199 @S9S_MB_2U_LIB.S9S_MB_2U(SCH_1):PAGE150
   J37  B22 GND_B22 SCONN168_ME1016810202011-SCONNA   I199 @S9S_MB_2U_LIB.S9S_MB_2U(SCH_1):PAGE150
   J37  B25 GND_B25 SCONN168_ME1016810202011-SCONNA   I199 @S9S_MB_2U_LIB.S9S_MB_2U(SCH_1):PAGE150
   J37  B28 GND_B28 SCONN168_ME1016810202011-SCONNA   I199 @S9S_MB_2U_LIB.S9S_MB_2U(SCH_1):PAGE150
   J37  B29 GND_B29 SCONN168_ME1016810202011-SCONNA   I199 @S9S_MB_2U_LIB.S9S_MB_2U(SCH_1):PAGE150
   J37  B32 GND_B32 SCONN168_ME1016810202011-SCONNA   I199 @S9S_MB_2U_LIB.S9S_MB_2U(SCH_1):PAGE150
   J37  B35 GND_B35 SCONN168_ME1016810202011-SCONNA   I199 @S9S_MB_2U_LIB.S9S_MB_2U(SCH_1):PAGE150
   J37  B38 GND_B38 SCONN168_ME1016810202011-SCONNA   I199 @S9S_MB_2U_LIB.S9S_MB_2U(SCH_1):PAGE150
   J37  B41 GND_B41 SCONN168_ME1016810202011-SCONNA   I199 @S9S_MB_2U_LIB.S9S_MB_2U(SCH_1):PAGE150
   J37  B43 GND_B43 SCONN168_ME1016810202011-SCONNA   I199 @S9S_MB_2U_LIB.S9S_MB_2U(SCH_1):PAGE150
   J37  B46 GND_B46 SCONN168_ME1016810202011-SCONNA   I199 @S9S_MB_2U_LIB.S9S_MB_2U(SCH_1):PAGE150
   J37  B49 GND_B49 SCONN168_ME1016810202011-SCONNA   I199 @S9S_MB_2U_LIB.S9S_MB_2U(SCH_1):PAGE150
   J37  B52 GND_B52 SCONN168_ME1016810202011-SCONNA   I199 @S9S_MB_2U_LIB.S9S_MB_2U(SCH_1):PAGE150
   J37  B55 GND_B55 SCONN168_ME1016810202011-SCONNA   I199 @S9S_MB_2U_LIB.S9S_MB_2U(SCH_1):PAGE150
   J37  B58 GND_B58 SCONN168_ME1016810202011-SCONNA   I199 @S9S_MB_2U_LIB.S9S_MB_2U(SCH_1):PAGE150
   J37  B61 GND_B61 SCONN168_ME1016810202011-SCONNA   I199 @S9S_MB_2U_LIB.S9S_MB_2U(SCH_1):PAGE150
   J37  B64 GND_B64 SCONN168_ME1016810202011-SCONNA   I199 @S9S_MB_2U_LIB.S9S_MB_2U(SCH_1):PAGE150
   J37  B67 GND_B67 SCONN168_ME1016810202011-SCONNA   I199 @S9S_MB_2U_LIB.S9S_MB_2U(SCH_1):PAGE150
   J37 OA10 GND_OA10 SCONN168_ME1016810202011-SCONNA   I199 @S9S_MB_2U_LIB.S9S_MB_2U(SCH_1):PAGE150
   J37 OA13 GND_OA13 SCONN168_ME1016810202011-SCONNA   I199 @S9S_MB_2U_LIB.S9S_MB_2U(SCH_1):PAGE150
   J37 OB10 GND_OB10 SCONN168_ME1016810202011-SCONNA   I199 @S9S_MB_2U_LIB.S9S_MB_2U(SCH_1):PAGE150
   J37 OB13 GND_OB13 SCONN168_ME1016810202011-SCONNA   I199 @S9S_MB_2U_LIB.S9S_MB_2U(SCH_1):PAGE150
   J35   G1     G1 SCONN168_ME1016810202011-SCONNA   I303 @S9S_MB_2U_LIB.S9S_MB_2U(SCH_1):PAGE146
   J35   G2     G2 SCONN168_ME1016810202011-SCONNA   I303 @S9S_MB_2U_LIB.S9S_MB_2U(SCH_1):PAGE146
   J35   G3     G3 SCONN168_ME1016810202011-SCONNA   I303 @S9S_MB_2U_LIB.S9S_MB_2U(SCH_1):PAGE146
   J35   G4     G4 SCONN168_ME1016810202011-SCONNA   I303 @S9S_MB_2U_LIB.S9S_MB_2U(SCH_1):PAGE146
   J35   G5     G5 SCONN168_ME1016810202011-SCONNA   I303 @S9S_MB_2U_LIB.S9S_MB_2U(SCH_1):PAGE146
   J35   A1 GND_A1 SCONN168_ME1016810202011-SCONNA   I303 @S9S_MB_2U_LIB.S9S_MB_2U(SCH_1):PAGE146
   J35   A2 GND_A2 SCONN168_ME1016810202011-SCONNA   I303 @S9S_MB_2U_LIB.S9S_MB_2U(SCH_1):PAGE146
   J35   A3 GND_A3 SCONN168_ME1016810202011-SCONNA   I303 @S9S_MB_2U_LIB.S9S_MB_2U(SCH_1):PAGE146
   J35   A4 GND_A4 SCONN168_ME1016810202011-SCONNA   I303 @S9S_MB_2U_LIB.S9S_MB_2U(SCH_1):PAGE146
   J35   A5 GND_A5 SCONN168_ME1016810202011-SCONNA   I303 @S9S_MB_2U_LIB.S9S_MB_2U(SCH_1):PAGE146
   J35   A6 GND_A6 SCONN168_ME1016810202011-SCONNA   I303 @S9S_MB_2U_LIB.S9S_MB_2U(SCH_1):PAGE146
   J35  A13 GND_A13 SCONN168_ME1016810202011-SCONNA   I303 @S9S_MB_2U_LIB.S9S_MB_2U(SCH_1):PAGE146
   J35  A16 GND_A16 SCONN168_ME1016810202011-SCONNA   I303 @S9S_MB_2U_LIB.S9S_MB_2U(SCH_1):PAGE146
   J35  A19 GND_A19 SCONN168_ME1016810202011-SCONNA   I303 @S9S_MB_2U_LIB.S9S_MB_2U(SCH_1):PAGE146
   J35  A22 GND_A22 SCONN168_ME1016810202011-SCONNA   I303 @S9S_MB_2U_LIB.S9S_MB_2U(SCH_1):PAGE146
   J35  A25 GND_A25 SCONN168_ME1016810202011-SCONNA   I303 @S9S_MB_2U_LIB.S9S_MB_2U(SCH_1):PAGE146
   J35  A28 GND_A28 SCONN168_ME1016810202011-SCONNA   I303 @S9S_MB_2U_LIB.S9S_MB_2U(SCH_1):PAGE146
   J35  A29 GND_A29 SCONN168_ME1016810202011-SCONNA   I303 @S9S_MB_2U_LIB.S9S_MB_2U(SCH_1):PAGE146
   J35  A32 GND_A32 SCONN168_ME1016810202011-SCONNA   I303 @S9S_MB_2U_LIB.S9S_MB_2U(SCH_1):PAGE146
   J35  A35 GND_A35 SCONN168_ME1016810202011-SCONNA   I303 @S9S_MB_2U_LIB.S9S_MB_2U(SCH_1):PAGE146
   J35  A38 GND_A38 SCONN168_ME1016810202011-SCONNA   I303 @S9S_MB_2U_LIB.S9S_MB_2U(SCH_1):PAGE146
   J35  A41 GND_A41 SCONN168_ME1016810202011-SCONNA   I303 @S9S_MB_2U_LIB.S9S_MB_2U(SCH_1):PAGE146
   J35  A43 GND_A43 SCONN168_ME1016810202011-SCONNA   I303 @S9S_MB_2U_LIB.S9S_MB_2U(SCH_1):PAGE146
   J35  A46 GND_A46 SCONN168_ME1016810202011-SCONNA   I303 @S9S_MB_2U_LIB.S9S_MB_2U(SCH_1):PAGE146
   J35  A49 GND_A49 SCONN168_ME1016810202011-SCONNA   I303 @S9S_MB_2U_LIB.S9S_MB_2U(SCH_1):PAGE146
   J35  A52 GND_A52 SCONN168_ME1016810202011-SCONNA   I303 @S9S_MB_2U_LIB.S9S_MB_2U(SCH_1):PAGE146
   J35  A55 GND_A55 SCONN168_ME1016810202011-SCONNA   I303 @S9S_MB_2U_LIB.S9S_MB_2U(SCH_1):PAGE146
   J35  A58 GND_A58 SCONN168_ME1016810202011-SCONNA   I303 @S9S_MB_2U_LIB.S9S_MB_2U(SCH_1):PAGE146
   J35  A61 GND_A61 SCONN168_ME1016810202011-SCONNA   I303 @S9S_MB_2U_LIB.S9S_MB_2U(SCH_1):PAGE146
   J35  A64 GND_A64 SCONN168_ME1016810202011-SCONNA   I303 @S9S_MB_2U_LIB.S9S_MB_2U(SCH_1):PAGE146
   J35  A67 GND_A67 SCONN168_ME1016810202011-SCONNA   I303 @S9S_MB_2U_LIB.S9S_MB_2U(SCH_1):PAGE146
   J35  B13 GND_B13 SCONN168_ME1016810202011-SCONNA   I303 @S9S_MB_2U_LIB.S9S_MB_2U(SCH_1):PAGE146
   J35  B16 GND_B16 SCONN168_ME1016810202011-SCONNA   I303 @S9S_MB_2U_LIB.S9S_MB_2U(SCH_1):PAGE146
   J35  B19 GND_B19 SCONN168_ME1016810202011-SCONNA   I303 @S9S_MB_2U_LIB.S9S_MB_2U(SCH_1):PAGE146
   J35  B22 GND_B22 SCONN168_ME1016810202011-SCONNA   I303 @S9S_MB_2U_LIB.S9S_MB_2U(SCH_1):PAGE146
   J35  B25 GND_B25 SCONN168_ME1016810202011-SCONNA   I303 @S9S_MB_2U_LIB.S9S_MB_2U(SCH_1):PAGE146
   J35  B28 GND_B28 SCONN168_ME1016810202011-SCONNA   I303 @S9S_MB_2U_LIB.S9S_MB_2U(SCH_1):PAGE146
   J35  B29 GND_B29 SCONN168_ME1016810202011-SCONNA   I303 @S9S_MB_2U_LIB.S9S_MB_2U(SCH_1):PAGE146
   J35  B32 GND_B32 SCONN168_ME1016810202011-SCONNA   I303 @S9S_MB_2U_LIB.S9S_MB_2U(SCH_1):PAGE146
   J35  B35 GND_B35 SCONN168_ME1016810202011-SCONNA   I303 @S9S_MB_2U_LIB.S9S_MB_2U(SCH_1):PAGE146
   J35  B38 GND_B38 SCONN168_ME1016810202011-SCONNA   I303 @S9S_MB_2U_LIB.S9S_MB_2U(SCH_1):PAGE146
   J35  B41 GND_B41 SCONN168_ME1016810202011-SCONNA   I303 @S9S_MB_2U_LIB.S9S_MB_2U(SCH_1):PAGE146
   J35  B43 GND_B43 SCONN168_ME1016810202011-SCONNA   I303 @S9S_MB_2U_LIB.S9S_MB_2U(SCH_1):PAGE146
   J35  B46 GND_B46 SCONN168_ME1016810202011-SCONNA   I303 @S9S_MB_2U_LIB.S9S_MB_2U(SCH_1):PAGE146
   J35  B49 GND_B49 SCONN168_ME1016810202011-SCONNA   I303 @S9S_MB_2U_LIB.S9S_MB_2U(SCH_1):PAGE146
   J35  B52 GND_B52 SCONN168_ME1016810202011-SCONNA   I303 @S9S_MB_2U_LIB.S9S_MB_2U(SCH_1):PAGE146
   J35  B55 GND_B55 SCONN168_ME1016810202011-SCONNA   I303 @S9S_MB_2U_LIB.S9S_MB_2U(SCH_1):PAGE146
   J35  B58 GND_B58 SCONN168_ME1016810202011-SCONNA   I303 @S9S_MB_2U_LIB.S9S_MB_2U(SCH_1):PAGE146
   J35  B61 GND_B61 SCONN168_ME1016810202011-SCONNA   I303 @S9S_MB_2U_LIB.S9S_MB_2U(SCH_1):PAGE146
   J35  B64 GND_B64 SCONN168_ME1016810202011-SCONNA   I303 @S9S_MB_2U_LIB.S9S_MB_2U(SCH_1):PAGE146
   J35  B67 GND_B67 SCONN168_ME1016810202011-SCONNA   I303 @S9S_MB_2U_LIB.S9S_MB_2U(SCH_1):PAGE146
   J35 OA10 GND_OA10 SCONN168_ME1016810202011-SCONNA   I303 @S9S_MB_2U_LIB.S9S_MB_2U(SCH_1):PAGE146
   J35 OA13 GND_OA13 SCONN168_ME1016810202011-SCONNA   I303 @S9S_MB_2U_LIB.S9S_MB_2U(SCH_1):PAGE146
   J35 OB10 GND_OB10 SCONN168_ME1016810202011-SCONNA   I303 @S9S_MB_2U_LIB.S9S_MB_2U(SCH_1):PAGE146
   J35 OB13 GND_OB13 SCONN168_ME1016810202011-SCONNA   I303 @S9S_MB_2U_LIB.S9S_MB_2U(SCH_1):PAGE146
  U278    3    GND 74LVC1G08W57-74LVC1G08W5-7,SMLA    I31 @S9S_MB_2U_LIB.S9S_MB_2U(SCH_1):PAGE230
    Y4    2     G1 Q_XTAL_4P_13BI_24GND-12MHZ,SMLA   I200 @S9S_MB_2U_LIB.S9S_MB_2U(SCH_1):PAGE155
    Y4    4     G2 Q_XTAL_4P_13BI_24GND-12MHZ,SMLA   I200 @S9S_MB_2U_LIB.S9S_MB_2U(SCH_1):PAGE155
  U145    3    GND 74LVC1G126SE7-74LVC1G126SE-7,SA   I163 @S9S_MB_2U_LIB.S9S_MB_2U(SCH_1):PAGE297
 R2457    2      B Q_RES_0402LF-100K,1%,1/16W,CHIA   I165 @S9S_MB_2U_LIB.S9S_MB_2U(SCH_1):PAGE297
 C1614    2      B Q_CAP_0402-0.1UF,25V,10%,X7R,CA   I170 @S9S_MB_2U_LIB.S9S_MB_2U(SCH_1):PAGE297
 R3297    2      B Q_RES_0402LF-10K,1%,1/16W,CHIPA   I303 @S9S_MB_2U_LIB.S9S_MB_2U(SCH_1):PAGE182
 C1873    2      B Q_CAP_0402-0.1UF,25V,10%,X7R,CA   I308 @S9S_MB_2U_LIB.S9S_MB_2U(SCH_1):PAGE182
  U239    3    GND 74LVC1G126SE7-74LVC1G126SE-7,SA   I315 @S9S_MB_2U_LIB.S9S_MB_2U(SCH_1):PAGE182
 C2007    2      B Q_CAP_C0402-1UF,25V,10%,X6S,CHA   I326 @S9S_MB_2U_LIB.S9S_MB_2U(SCH_1):PAGE182
  U259    2    GND SN74LVC2G07DCKR_SMLF-SN74LVC2GA   I327 @S9S_MB_2U_LIB.S9S_MB_2U(SCH_1):PAGE182
  U279    4    GND PCA9617ADP-PCA9617ADP,SMLF,IC,A    I93 @S9S_MB_2U_LIB.S9S_MB_2U(SCH_1):PAGE183
 C1277    2      B Q_CAP_C0805-22UF,16V,20%,X6S,CA   I237 @S9S_MB_2U_LIB.S9S_MB_2U(SCH_1):PAGE297
 C1283    2      B Q_CAP_0402-0.1UF,25V,10%,X7R,CA   I245 @S9S_MB_2U_LIB.S9S_MB_2U(SCH_1):PAGE297
 C1282    2      B Q_CAP_0402-0.1UF,25V,10%,X7R,CA   I247 @S9S_MB_2U_LIB.S9S_MB_2U(SCH_1):PAGE297
 C1279    2      B Q_CAP_0402-0.1UF,25V,10%,X7R,CA   I252 @S9S_MB_2U_LIB.S9S_MB_2U(SCH_1):PAGE297
 C1278    2      B Q_CAP_0402-0.1UF,25V,10%,X7R,CA   I258 @S9S_MB_2U_LIB.S9S_MB_2U(SCH_1):PAGE297
 C1276    2      B Q_CAP_C0805-22UF,16V,20%,X6S,CA   I260 @S9S_MB_2U_LIB.S9S_MB_2U(SCH_1):PAGE297
 R2296    2      B Q_RES_0402LF-1K,1%,1/16W,CHIP,A   I293 @S9S_MB_2U_LIB.S9S_MB_2U(SCH_1):PAGE297
 C1592    2      B Q_CAP_0402-0.1UF,25V,10%,X7R,CA   I304 @S9S_MB_2U_LIB.S9S_MB_2U(SCH_1):PAGE297
  U134    2    GND 74LVC2G07DW7-74LVC2G07DW-7,SMLA   I305 @S9S_MB_2U_LIB.S9S_MB_2U(SCH_1):PAGE297
  U150    2    GND 74LVC2G17GW-74LVC2G17GW,SMLF,IA     I2 @S9S_MB_2U_LIB.S9S_MB_2U(SCH_1):PAGE213
 C1619    2      B Q_CAP_0402-0.1UF,25V,10%,X7R,CA     I5 @S9S_MB_2U_LIB.S9S_MB_2U(SCH_1):PAGE213
PR3821    2      B Q_RES_0402LF-30.1K,1%,1/16W,EMA    I59 @S9S_MB_2U_LIB.S9S_MB_2U(SCH_1):PAGE131
 R2426    2      B Q_RES_0402LF-100,1%,1/16W,EMPTA   I311 @S9S_MB_2U_LIB.S9S_MB_2U(SCH_1):PAGE297
 R3661    1      A Q_RES_0402LF-47K,0.1%,1/16W,EMA   I201 @S9S_MB_2U_LIB.S9S_MB_2U(SCH_1):PAGE155
  U286    3    GND 74LVC1G126SE7-74LVC1G126SE-7,SA    I80 @S9S_MB_2U_LIB.S9S_MB_2U(SCH_1):PAGE307
  U225    3    GND 74LVC1G126SE7-74LVC1G126SE-7,SA    I74 @S9S_MB_2U_LIB.S9S_MB_2U(SCH_1):PAGE156
  U217    3    GND 74LVC1G126SE7-74LVC1G126SE-7,SA    I79 @S9S_MB_2U_LIB.S9S_MB_2U(SCH_1):PAGE156
   U82    3    GND 74LVC1G126SE7-74LVC1G126SE-7,SA    I79 @S9S_MB_2U_LIB.S9S_MB_2U(SCH_1):PAGE152
  U204    3    GND 74LVC1G126SE7-74LVC1G126SE-7,SA   I195 @S9S_MB_2U_LIB.S9S_MB_2U(SCH_1):PAGE140
  U154    3    GND 74LVC1G07SE7-74LVC1G07SE-7,SMLA    I95 @S9S_MB_2U_LIB.S9S_MB_2U(SCH_1):PAGE190
   Q46    S      S MOSFET_NCH_GDS_ESD_PROTECTED-2A   I316 @S9S_MB_2U_LIB.S9S_MB_2U(SCH_1):PAGE297
   Q54    S      S MOSFET_NCH_GDS_ESD_PROTECTED-2A    I14 @S9S_MB_2U_LIB.S9S_MB_2U(SCH_1):PAGE234
   H91    1      1 HOLE_TH-EMPTY,HOLE596   I147 @S9S_MB_2U_LIB.S9S_MB_2U(SCH_1):PAGE289
   H97    1      1 HOLE_TH-EMPTY,HOLE596   I149 @S9S_MB_2U_LIB.S9S_MB_2U(SCH_1):PAGE289
   H99    1      1 HOLE_TH-EMPTY,HOLE596   I155 @S9S_MB_2U_LIB.S9S_MB_2U(SCH_1):PAGE289
  H102    1      1 HOLE_TH-EMPTY,HOLE596   I158 @S9S_MB_2U_LIB.S9S_MB_2U(SCH_1):PAGE289
   H98    1      1 HOLE_TH-EMPTY,HOLE596   I160 @S9S_MB_2U_LIB.S9S_MB_2U(SCH_1):PAGE289
   H92    1      1 HOLE_TH-EMPTY,HOLE596   I166 @S9S_MB_2U_LIB.S9S_MB_2U(SCH_1):PAGE289
   H87    1      1 HOLE_TH-EMPTY,HOLE596   I168 @S9S_MB_2U_LIB.S9S_MB_2U(SCH_1):PAGE289
  H104    1      1 HOLE_TH-EMPTY,HOLE596   I175 @S9S_MB_2U_LIB.S9S_MB_2U(SCH_1):PAGE289
   H86    1      1 HOLE_TH-EMPTY,HOLE596   I140 @S9S_MB_2U_LIB.S9S_MB_2U(SCH_1):PAGE289
   H88    1      1 HOLE_TH-EMPTY,HOLE596   I144 @S9S_MB_2U_LIB.S9S_MB_2U(SCH_1):PAGE289
   H93    1      1 HOLE_TH-EMPTY,HOLE596   I148 @S9S_MB_2U_LIB.S9S_MB_2U(SCH_1):PAGE289
   H95    1      1 HOLE_TH-EMPTY,HOLE596   I150 @S9S_MB_2U_LIB.S9S_MB_2U(SCH_1):PAGE289
  H101    1      1 HOLE_TH-EMPTY,HOLE596   I154 @S9S_MB_2U_LIB.S9S_MB_2U(SCH_1):PAGE289
  H100    1      1 HOLE_TH-EMPTY,HOLE596   I159 @S9S_MB_2U_LIB.S9S_MB_2U(SCH_1):PAGE289
   H96    1      1 HOLE_TH-EMPTY,HOLE596   I161 @S9S_MB_2U_LIB.S9S_MB_2U(SCH_1):PAGE289
   H94    1      1 HOLE_TH-EMPTY,HOLE596   I165 @S9S_MB_2U_LIB.S9S_MB_2U(SCH_1):PAGE289
   H89    1      1 HOLE_TH-EMPTY,HOLE596   I167 @S9S_MB_2U_LIB.S9S_MB_2U(SCH_1):PAGE289
  H103    1      1 HOLE_TH-EMPTY,HOLE596   I174 @S9S_MB_2U_LIB.S9S_MB_2U(SCH_1):PAGE289
  H106    1      1 HOLE_TH-EMPTY,HOLE596   I190 @S9S_MB_2U_LIB.S9S_MB_2U(SCH_1):PAGE289
  H105    1      1 HOLE_TH-EMPTY,HOLE596   I192 @S9S_MB_2U_LIB.S9S_MB_2U(SCH_1):PAGE289
 C2176    2      B Q_CAP_0402-100PF,50V,5%,EMPTY,A   I304 @S9S_MB_2U_LIB.S9S_MB_2U(SCH_1):PAGE239
 C2178    2      B Q_CAP_0402-0.1UF,25V,10%,X7R,CA   I305 @S9S_MB_2U_LIB.S9S_MB_2U(SCH_1):PAGE239
 C2175    2      B Q_CAP_0402-100PF,50V,5%,EMPTY,A   I309 @S9S_MB_2U_LIB.S9S_MB_2U(SCH_1):PAGE239
 C2177    2      B Q_CAP_0402-0.1UF,25V,10%,X7R,CA   I311 @S9S_MB_2U_LIB.S9S_MB_2U(SCH_1):PAGE239
PR3969    2      B Q_RES_0402LF-2.49K,1%,1/16W,CHA    I34 @S9S_MB_2U_LIB.S9S_MB_2U(SCH_1):PAGE324
PC2216    2      B Q_CAP_C0402-6800PF,50V,10%,X7RA    I45 @S9S_MB_2U_LIB.S9S_MB_2U(SCH_1):PAGE324
 PD113    A      A SCHOTTKY_AC-B340A-13-F,SMLF,ICA    I46 @S9S_MB_2U_LIB.S9S_MB_2U(SCH_1):PAGE324
 PU294   A7   CDLY MAX15090BEWIT-MAX15090BEWI+T,SA    I62 @S9S_MB_2U_LIB.S9S_MB_2U(SCH_1):PAGE324
 PU294   B7    EN# MAX15090BEWIT-MAX15090BEWI+T,SA    I62 @S9S_MB_2U_LIB.S9S_MB_2U(SCH_1):PAGE324
 PU294   B2 GND_B2 MAX15090BEWIT-MAX15090BEWI+T,SA    I62 @S9S_MB_2U_LIB.S9S_MB_2U(SCH_1):PAGE324
 PU294   C1 GND_C1 MAX15090BEWIT-MAX15090BEWI+T,SA    I62 @S9S_MB_2U_LIB.S9S_MB_2U(SCH_1):PAGE324
 PU294   C2 GND_C2 MAX15090BEWIT-MAX15090BEWI+T,SA    I62 @S9S_MB_2U_LIB.S9S_MB_2U(SCH_1):PAGE324
 PD112    A      A SCHOTTKY_AC-B340A-13-F,SMLF,ICA    I71 @S9S_MB_2U_LIB.S9S_MB_2U(SCH_1):PAGE324
PC2197    2      B Q_CAP_C0402-39PF,50V,5%,EMPTY,A     I3 @S9S_MB_2U_LIB.S9S_MB_2U(SCH_1):PAGE323
PC2200    2      B Q_CAP_C0402-1UF,25V,10%,EMPTY,A     I9 @S9S_MB_2U_LIB.S9S_MB_2U(SCH_1):PAGE323
PC2204    2      B Q_CAP_C0805-10UF,16V,10%,EMPTYB    I34 @S9S_MB_2U_LIB.S9S_MB_2U(SCH_1):PAGE323
 C2195    2      B Q_CAP_0402-100PF,50V,5%,EMPTY,A   I333 @S9S_MB_2U_LIB.S9S_MB_2U(SCH_1):PAGE239
 C2194    2      B Q_CAP_0402-0.1UF,25V,10%,X7R,CA   I336 @S9S_MB_2U_LIB.S9S_MB_2U(SCH_1):PAGE239
PR4004    2      B Q_RES_0402LF-17.8K,1%,1/16W,EMA    I63 @S9S_MB_2U_LIB.S9S_MB_2U(SCH_1):PAGE229
PR4008    2      B Q_RES_0402LF-1.33K,1%,1/16W,EMA    I72 @S9S_MB_2U_LIB.S9S_MB_2U(SCH_1):PAGE229
 R4029    2      B Q_RES_0402LF-1K,1%,1/16W,CHIP,A    I77 @S9S_MB_2U_LIB.S9S_MB_2U(SCH_1):PAGE321
 C2249    2      B Q_CAP_0402-0.1UF,25V,10%,X7R,CA    I83 @S9S_MB_2U_LIB.S9S_MB_2U(SCH_1):PAGE321
 C2243    2      B Q_CAP_C0402-1UF,25V,10%,X6S,CHA    I85 @S9S_MB_2U_LIB.S9S_MB_2U(SCH_1):PAGE321
  U301    7  GND_0 GTL2014PW-GTL2014PW,SMLF,IC,ALA    I91 @S9S_MB_2U_LIB.S9S_MB_2U(SCH_1):PAGE321
  U301    8  GND_1 GTL2014PW-GTL2014PW,SMLF,IC,ALA    I91 @S9S_MB_2U_LIB.S9S_MB_2U(SCH_1):PAGE321
  U301   11  GND_2 GTL2014PW-GTL2014PW,SMLF,IC,ALA    I91 @S9S_MB_2U_LIB.S9S_MB_2U(SCH_1):PAGE321
 C2246    2      B Q_CAP_C0402-1UF,25V,10%,X6S,CHA     I9 @S9S_MB_2U_LIB.S9S_MB_2U(SCH_1):PAGE322
  U304    7  GND_0 GTL2014PW-GTL2014PW,SMLF,IC,ALA    I27 @S9S_MB_2U_LIB.S9S_MB_2U(SCH_1):PAGE322
  U304    8  GND_1 GTL2014PW-GTL2014PW,SMLF,IC,ALA    I27 @S9S_MB_2U_LIB.S9S_MB_2U(SCH_1):PAGE322
  U304   11  GND_2 GTL2014PW-GTL2014PW,SMLF,IC,ALA    I27 @S9S_MB_2U_LIB.S9S_MB_2U(SCH_1):PAGE322
  U305    7  GND_0 GTL2014PW-GTL2014PW,SMLF,IC,ALA    I44 @S9S_MB_2U_LIB.S9S_MB_2U(SCH_1):PAGE322
  U305    8  GND_1 GTL2014PW-GTL2014PW,SMLF,IC,ALA    I44 @S9S_MB_2U_LIB.S9S_MB_2U(SCH_1):PAGE322
  U305   11  GND_2 GTL2014PW-GTL2014PW,SMLF,IC,ALA    I44 @S9S_MB_2U_LIB.S9S_MB_2U(SCH_1):PAGE322
 C2247    2      B Q_CAP_C0402-1UF,25V,10%,X6S,CHA    I59 @S9S_MB_2U_LIB.S9S_MB_2U(SCH_1):PAGE322
 R4053    2      B Q_RES_0402LF-1K,1%,1/16W,CHIP,A    I66 @S9S_MB_2U_LIB.S9S_MB_2U(SCH_1):PAGE322
 R4054    2      B Q_RES_0402LF-1K,1%,1/16W,CHIP,A    I67 @S9S_MB_2U_LIB.S9S_MB_2U(SCH_1):PAGE322
  U306    7  GND_0 GTL2014PW-GTL2014PW,SMLF,IC,ALA    I80 @S9S_MB_2U_LIB.S9S_MB_2U(SCH_1):PAGE322
  U306    8  GND_1 GTL2014PW-GTL2014PW,SMLF,IC,ALA    I80 @S9S_MB_2U_LIB.S9S_MB_2U(SCH_1):PAGE322
  U306   11  GND_2 GTL2014PW-GTL2014PW,SMLF,IC,ALA    I80 @S9S_MB_2U_LIB.S9S_MB_2U(SCH_1):PAGE322
 C2248    2      B Q_CAP_C0402-1UF,25V,10%,X6S,CHA    I83 @S9S_MB_2U_LIB.S9S_MB_2U(SCH_1):PAGE322
 R4055    2      B Q_RES_0402LF-1K,1%,1/16W,CHIP,A    I91 @S9S_MB_2U_LIB.S9S_MB_2U(SCH_1):PAGE322
 C2252    2      B Q_CAP_0402-0.1UF,25V,10%,X7R,CA   I101 @S9S_MB_2U_LIB.S9S_MB_2U(SCH_1):PAGE322
 C2253    2      B Q_CAP_0402-0.1UF,25V,10%,X7R,CA   I106 @S9S_MB_2U_LIB.S9S_MB_2U(SCH_1):PAGE322
 C2254    2      B Q_CAP_0402-0.1UF,25V,10%,X7R,CA   I111 @S9S_MB_2U_LIB.S9S_MB_2U(SCH_1):PAGE322
  H115    2   GND2 GND_HOLE_TH-EMPTY,GND_HOLE514   I202 @S9S_MB_2U_LIB.S9S_MB_2U(SCH_1):PAGE289
  H115    3   GND3 GND_HOLE_TH-EMPTY,GND_HOLE514   I202 @S9S_MB_2U_LIB.S9S_MB_2U(SCH_1):PAGE289
  H115    4   GND4 GND_HOLE_TH-EMPTY,GND_HOLE514   I202 @S9S_MB_2U_LIB.S9S_MB_2U(SCH_1):PAGE289
  H115    5   GND5 GND_HOLE_TH-EMPTY,GND_HOLE514   I202 @S9S_MB_2U_LIB.S9S_MB_2U(SCH_1):PAGE289
  H115    6   GND6 GND_HOLE_TH-EMPTY,GND_HOLE514   I202 @S9S_MB_2U_LIB.S9S_MB_2U(SCH_1):PAGE289
  H115    7   GND7 GND_HOLE_TH-EMPTY,GND_HOLE514   I202 @S9S_MB_2U_LIB.S9S_MB_2U(SCH_1):PAGE289
  H115    8   GND8 GND_HOLE_TH-EMPTY,GND_HOLE514   I202 @S9S_MB_2U_LIB.S9S_MB_2U(SCH_1):PAGE289
  H115    9   GND9 GND_HOLE_TH-EMPTY,GND_HOLE514   I202 @S9S_MB_2U_LIB.S9S_MB_2U(SCH_1):PAGE289
  H111    2   GND2 GND_HOLE_TH-EMPTY,GND_HOLE140   I204 @S9S_MB_2U_LIB.S9S_MB_2U(SCH_1):PAGE289
  H111    3   GND3 GND_HOLE_TH-EMPTY,GND_HOLE140   I204 @S9S_MB_2U_LIB.S9S_MB_2U(SCH_1):PAGE289
  H111    4   GND4 GND_HOLE_TH-EMPTY,GND_HOLE140   I204 @S9S_MB_2U_LIB.S9S_MB_2U(SCH_1):PAGE289
  H111    5   GND5 GND_HOLE_TH-EMPTY,GND_HOLE140   I204 @S9S_MB_2U_LIB.S9S_MB_2U(SCH_1):PAGE289
  H111    6   GND6 GND_HOLE_TH-EMPTY,GND_HOLE140   I204 @S9S_MB_2U_LIB.S9S_MB_2U(SCH_1):PAGE289
  H111    7   GND7 GND_HOLE_TH-EMPTY,GND_HOLE140   I204 @S9S_MB_2U_LIB.S9S_MB_2U(SCH_1):PAGE289
  H111    8   GND8 GND_HOLE_TH-EMPTY,GND_HOLE140   I204 @S9S_MB_2U_LIB.S9S_MB_2U(SCH_1):PAGE289
  H111    9   GND9 GND_HOLE_TH-EMPTY,GND_HOLE140   I204 @S9S_MB_2U_LIB.S9S_MB_2U(SCH_1):PAGE289
  H112    2   GND2 GND_HOLE_TH-EMPTY,GND_HOLE140   I207 @S9S_MB_2U_LIB.S9S_MB_2U(SCH_1):PAGE289
  H112    3   GND3 GND_HOLE_TH-EMPTY,GND_HOLE140   I207 @S9S_MB_2U_LIB.S9S_MB_2U(SCH_1):PAGE289
  H112    4   GND4 GND_HOLE_TH-EMPTY,GND_HOLE140   I207 @S9S_MB_2U_LIB.S9S_MB_2U(SCH_1):PAGE289
  H112    5   GND5 GND_HOLE_TH-EMPTY,GND_HOLE140   I207 @S9S_MB_2U_LIB.S9S_MB_2U(SCH_1):PAGE289
  H112    6   GND6 GND_HOLE_TH-EMPTY,GND_HOLE140   I207 @S9S_MB_2U_LIB.S9S_MB_2U(SCH_1):PAGE289
  H112    7   GND7 GND_HOLE_TH-EMPTY,GND_HOLE140   I207 @S9S_MB_2U_LIB.S9S_MB_2U(SCH_1):PAGE289
  H112    8   GND8 GND_HOLE_TH-EMPTY,GND_HOLE140   I207 @S9S_MB_2U_LIB.S9S_MB_2U(SCH_1):PAGE289
  H112    9   GND9 GND_HOLE_TH-EMPTY,GND_HOLE140   I207 @S9S_MB_2U_LIB.S9S_MB_2U(SCH_1):PAGE289
 C1934    2      B Q_CAP_C0402-0.01UF,50V,10%,X7RA   I120 @S9S_MB_2U_LIB.S9S_MB_2U(SCH_1):PAGE202
 C1150    2      B Q_CAP_0402-0.1UF,25V,10%,X7R,CA   I121 @S9S_MB_2U_LIB.S9S_MB_2U(SCH_1):PAGE202
 C1884    2      B Q_CAP_C0402-1UF,25V,10%,X6S,CHA   I103 @S9S_MB_2U_LIB.S9S_MB_2U(SCH_1):PAGE201
 C2257    2      B Q_CAP_0402-0.1UF,25V,10%,X7R,CA   I104 @S9S_MB_2U_LIB.S9S_MB_2U(SCH_1):PAGE201
 C2258    2      B Q_CAP_0402-0.1UF,25V,10%,X7R,CA   I105 @S9S_MB_2U_LIB.S9S_MB_2U(SCH_1):PAGE201
 C2259    2      B Q_CAP_0402-0.1UF,25V,10%,X7R,CA   I106 @S9S_MB_2U_LIB.S9S_MB_2U(SCH_1):PAGE201
 R4079    2      B Q_RES_0402LF-10K,1%,1/16W,CHIPA   I128 @S9S_MB_2U_LIB.S9S_MB_2U(SCH_1):PAGE201
 R4082    2      B Q_RES_0402LF-10K,1%,1/16W,EMPTA   I134 @S9S_MB_2U_LIB.S9S_MB_2U(SCH_1):PAGE201
  C110    2      B Q_CAP_C0402-0.047UF,25V,10%,X7A    I76 @S9S_MB_2U_LIB.S9S_MB_2U(SCH_1):PAGE199
  C171    2      B Q_CAP_C0402-0.047UF,25V,10%,X7A    I77 @S9S_MB_2U_LIB.S9S_MB_2U(SCH_1):PAGE199
  C173    2      B Q_CAP_C0402-0.047UF,25V,10%,X7A    I78 @S9S_MB_2U_LIB.S9S_MB_2U(SCH_1):PAGE199
  C114    2      B Q_CAP_C0402-0.047UF,25V,10%,X7A    I79 @S9S_MB_2U_LIB.S9S_MB_2U(SCH_1):PAGE199
  C112    2      B Q_CAP_C0402-0.047UF,25V,10%,X7A    I80 @S9S_MB_2U_LIB.S9S_MB_2U(SCH_1):PAGE199
  C111    2      B Q_CAP_C0402-0.047UF,25V,10%,X7A    I81 @S9S_MB_2U_LIB.S9S_MB_2U(SCH_1):PAGE199
  C107    2      B Q_CAP_C0402-1UF,25V,10%,X6S,CHA    I82 @S9S_MB_2U_LIB.S9S_MB_2U(SCH_1):PAGE199
  C120    2      B Q_CAP_C0402-0.047UF,25V,10%,X7A    I85 @S9S_MB_2U_LIB.S9S_MB_2U(SCH_1):PAGE199
  C119    2      B Q_CAP_C0402-0.047UF,25V,10%,X7A    I86 @S9S_MB_2U_LIB.S9S_MB_2U(SCH_1):PAGE199
  C117    2      B Q_CAP_C0402-0.047UF,25V,10%,X7A    I87 @S9S_MB_2U_LIB.S9S_MB_2U(SCH_1):PAGE199
  C116    2      B Q_CAP_C0402-0.047UF,25V,10%,X7A    I88 @S9S_MB_2U_LIB.S9S_MB_2U(SCH_1):PAGE199
  C115    2      B Q_CAP_C0402-0.047UF,25V,10%,X7A    I89 @S9S_MB_2U_LIB.S9S_MB_2U(SCH_1):PAGE199
  C400    2      B Q_CAP_C0402-22UF,4V,20%,X6S,CHA     I1 @S9S_MB_2U_LIB.S9S_MB_2U(SCH_1):PAGE74
  C402    2      B Q_CAP_C0402-22UF,4V,20%,X6S,CHA     I3 @S9S_MB_2U_LIB.S9S_MB_2U(SCH_1):PAGE74
  C404    2      B Q_CAP_C0402-22UF,4V,20%,X6S,CHA     I4 @S9S_MB_2U_LIB.S9S_MB_2U(SCH_1):PAGE74
  C406    2      B Q_CAP_C0402-22UF,4V,20%,X6S,CHA     I5 @S9S_MB_2U_LIB.S9S_MB_2U(SCH_1):PAGE74
  C399    2      B Q_CAP_C0402-22UF,4V,20%,X6S,CHA    I11 @S9S_MB_2U_LIB.S9S_MB_2U(SCH_1):PAGE74
  C967    2      B Q_CAP_C0402-10UF,6.3V,20%,X6S,B    I25 @S9S_MB_2U_LIB.S9S_MB_2U(SCH_1):PAGE74
  C966    2      B Q_CAP_C0402-10UF,6.3V,20%,X6S,B    I27 @S9S_MB_2U_LIB.S9S_MB_2U(SCH_1):PAGE74
  C972    2      B Q_CAP_C0402-10UF,6.3V,20%,X6S,B    I28 @S9S_MB_2U_LIB.S9S_MB_2U(SCH_1):PAGE74
  C970    2      B Q_CAP_C0402-10UF,6.3V,20%,X6S,B    I31 @S9S_MB_2U_LIB.S9S_MB_2U(SCH_1):PAGE74
  C405    2      B Q_CAP_C0402-22UF,4V,20%,X6S,CHA    I34 @S9S_MB_2U_LIB.S9S_MB_2U(SCH_1):PAGE74
  C217    2      B Q_CAP_C0805-47UF,4V,20%,X6S,CHA    I43 @S9S_MB_2U_LIB.S9S_MB_2U(SCH_1):PAGE74
  C989    2      B Q_CAP_C0402-10UF,6.3V,20%,X6S,B    I45 @S9S_MB_2U_LIB.S9S_MB_2U(SCH_1):PAGE74
  C992    2      B Q_CAP_C0402-10UF,6.3V,20%,X6S,B    I55 @S9S_MB_2U_LIB.S9S_MB_2U(SCH_1):PAGE74
  C987    2      B Q_CAP_C0402-10UF,6.3V,20%,X6S,B    I57 @S9S_MB_2U_LIB.S9S_MB_2U(SCH_1):PAGE74
  C994    2      B Q_CAP_C0402-10UF,6.3V,20%,X6S,B    I62 @S9S_MB_2U_LIB.S9S_MB_2U(SCH_1):PAGE74
 C1004    2      B Q_CAP_C0402-10UF,6.3V,20%,X6S,B    I83 @S9S_MB_2U_LIB.S9S_MB_2U(SCH_1):PAGE74
  C420    2      B Q_CAP_C0402-22UF,4V,20%,X6S,CHA   I100 @S9S_MB_2U_LIB.S9S_MB_2U(SCH_1):PAGE74
 C1021    2      B Q_CAP_C0402-22UF,4V,20%,X6S,CHA   I106 @S9S_MB_2U_LIB.S9S_MB_2U(SCH_1):PAGE74
  C422    2      B Q_CAP_C0402-22UF,4V,20%,X6S,CHA   I107 @S9S_MB_2U_LIB.S9S_MB_2U(SCH_1):PAGE74
 C1025    2      B Q_CAP_C0402-22UF,4V,20%,X6S,CHA   I108 @S9S_MB_2U_LIB.S9S_MB_2U(SCH_1):PAGE74
 C1029    2      B Q_CAP_C0402-22UF,4V,20%,X6S,CHA   I109 @S9S_MB_2U_LIB.S9S_MB_2U(SCH_1):PAGE74
 C1033    2      B Q_CAP_C0402-22UF,4V,20%,X6S,CHA   I110 @S9S_MB_2U_LIB.S9S_MB_2U(SCH_1):PAGE74
 C1018    2      B Q_CAP_C0402-22UF,4V,20%,X6S,CHA   I116 @S9S_MB_2U_LIB.S9S_MB_2U(SCH_1):PAGE74
 C1024    2      B Q_CAP_C0402-22UF,4V,20%,X6S,CHA   I117 @S9S_MB_2U_LIB.S9S_MB_2U(SCH_1):PAGE74
 C1028    2      B Q_CAP_C0402-22UF,4V,20%,X6S,CHA   I118 @S9S_MB_2U_LIB.S9S_MB_2U(SCH_1):PAGE74
 C1032    2      B Q_CAP_C0402-22UF,4V,20%,X6S,CHA   I119 @S9S_MB_2U_LIB.S9S_MB_2U(SCH_1):PAGE74
 C1023    2      B Q_CAP_C0402-22UF,4V,20%,X6S,CHA   I120 @S9S_MB_2U_LIB.S9S_MB_2U(SCH_1):PAGE74
 C1027    2      B Q_CAP_C0402-22UF,4V,20%,X6S,CHA   I121 @S9S_MB_2U_LIB.S9S_MB_2U(SCH_1):PAGE74
 C1022    2      B Q_CAP_C0402-22UF,4V,20%,X6S,CHA   I122 @S9S_MB_2U_LIB.S9S_MB_2U(SCH_1):PAGE74
 C1026    2      B Q_CAP_C0402-22UF,4V,20%,X6S,CHA   I123 @S9S_MB_2U_LIB.S9S_MB_2U(SCH_1):PAGE74
 C1031    2      B Q_CAP_C0402-22UF,4V,20%,X6S,CHA   I124 @S9S_MB_2U_LIB.S9S_MB_2U(SCH_1):PAGE74
 C1030    2      B Q_CAP_C0402-22UF,4V,20%,X6S,CHA   I125 @S9S_MB_2U_LIB.S9S_MB_2U(SCH_1):PAGE74
 C1037    2      B Q_CAP_C0402-22UF,4V,20%,X6S,CHA   I127 @S9S_MB_2U_LIB.S9S_MB_2U(SCH_1):PAGE74
 C1041    2      B Q_CAP_C0402-22UF,4V,20%,X6S,CHA   I128 @S9S_MB_2U_LIB.S9S_MB_2U(SCH_1):PAGE74
 C1045    2      B Q_CAP_C0402-22UF,4V,20%,X6S,CHA   I130 @S9S_MB_2U_LIB.S9S_MB_2U(SCH_1):PAGE74
  C505    2      B Q_CAP_C0805-47UF,4V,20%,X6S,CHA     I6 @S9S_MB_2U_LIB.S9S_MB_2U(SCH_1):PAGE75
  C509    2      B Q_CAP_C0603-47UF,2.5V,20%,X6S,A     I8 @S9S_MB_2U_LIB.S9S_MB_2U(SCH_1):PAGE75
  C522    2      B Q_CAP_C0805-47UF,4V,20%,X6S,CHA     I9 @S9S_MB_2U_LIB.S9S_MB_2U(SCH_1):PAGE75
  C492    2      B Q_CAP_C0805-47UF,4V,20%,X6S,CHA    I11 @S9S_MB_2U_LIB.S9S_MB_2U(SCH_1):PAGE75
  C491    2      B Q_CAP_C0805-47UF,4V,20%,X6S,CHA    I13 @S9S_MB_2U_LIB.S9S_MB_2U(SCH_1):PAGE75
  C496    2      B Q_CAP_C0805-47UF,4V,20%,X6S,CHA    I16 @S9S_MB_2U_LIB.S9S_MB_2U(SCH_1):PAGE75
  C533    2      B Q_CAP_C0603-47UF,2.5V,20%,X6S,A    I17 @S9S_MB_2U_LIB.S9S_MB_2U(SCH_1):PAGE75
  C495    2      B Q_CAP_C0805-47UF,4V,20%,X6S,CHA    I18 @S9S_MB_2U_LIB.S9S_MB_2U(SCH_1):PAGE75
  C515    2      B Q_CAP_C0805-47UF,4V,20%,X6S,CHA    I19 @S9S_MB_2U_LIB.S9S_MB_2U(SCH_1):PAGE75
  C356    2      B Q_CAP_C0805-47UF,4V,20%,X6S,CHA    I21 @S9S_MB_2U_LIB.S9S_MB_2U(SCH_1):PAGE75
  C355    2      B Q_CAP_C0805-47UF,4V,20%,X6S,CHA    I23 @S9S_MB_2U_LIB.S9S_MB_2U(SCH_1):PAGE75
  C534    2      B Q_CAP_C0402-22UF,4V,20%,X6S,CHA    I29 @S9S_MB_2U_LIB.S9S_MB_2U(SCH_1):PAGE75
  C518    2      B Q_CAP_C0805-47UF,4V,20%,X6S,CHA    I31 @S9S_MB_2U_LIB.S9S_MB_2U(SCH_1):PAGE75
  C365    2      B Q_CAP_C0805-47UF,4V,20%,X6S,CHA    I32 @S9S_MB_2U_LIB.S9S_MB_2U(SCH_1):PAGE75
  C364    2      B Q_CAP_C0805-47UF,4V,20%,X6S,CHA    I34 @S9S_MB_2U_LIB.S9S_MB_2U(SCH_1):PAGE75
  C367    2      B Q_CAP_C0805-47UF,4V,20%,X6S,CHA    I35 @S9S_MB_2U_LIB.S9S_MB_2U(SCH_1):PAGE75
  C371    2      B Q_CAP_C0805-47UF,4V,20%,X6S,CHA    I36 @S9S_MB_2U_LIB.S9S_MB_2U(SCH_1):PAGE75
  C397    2      B Q_CAP_C0805-47UF,4V,20%,X6S,CHA    I37 @S9S_MB_2U_LIB.S9S_MB_2U(SCH_1):PAGE75
  C357    2      B Q_CAP_C0805-47UF,4V,20%,X6S,CHA    I38 @S9S_MB_2U_LIB.S9S_MB_2U(SCH_1):PAGE75
  C370    2      B Q_CAP_C0805-47UF,4V,20%,X6S,CHA    I39 @S9S_MB_2U_LIB.S9S_MB_2U(SCH_1):PAGE75
  C373    2      B Q_CAP_C0805-47UF,4V,20%,X6S,CHA    I40 @S9S_MB_2U_LIB.S9S_MB_2U(SCH_1):PAGE75
  C376    2      B Q_CAP_C0805-47UF,4V,20%,X6S,CHA    I41 @S9S_MB_2U_LIB.S9S_MB_2U(SCH_1):PAGE75
  C395    2      B Q_CAP_C0805-47UF,4V,20%,X6S,CHA    I46 @S9S_MB_2U_LIB.S9S_MB_2U(SCH_1):PAGE75
 C1405    2      B Q_CAP_C0603-47UF,2.5V,20%,X6S,A    I47 @S9S_MB_2U_LIB.S9S_MB_2U(SCH_1):PAGE75
  C389    2      B Q_CAP_C0805-47UF,4V,20%,X6S,CHA    I48 @S9S_MB_2U_LIB.S9S_MB_2U(SCH_1):PAGE75
  C382    2      B Q_CAP_C0805-47UF,4V,20%,X6S,CHA    I51 @S9S_MB_2U_LIB.S9S_MB_2U(SCH_1):PAGE75
  C385    2      B Q_CAP_C0805-47UF,4V,20%,X6S,CHA    I55 @S9S_MB_2U_LIB.S9S_MB_2U(SCH_1):PAGE75
  C387    2      B Q_CAP_C0805-47UF,4V,20%,X6S,CHA    I56 @S9S_MB_2U_LIB.S9S_MB_2U(SCH_1):PAGE75
 C1398    2      B Q_CAP_C0805-47UF,4V,20%,X6S,CHA    I58 @S9S_MB_2U_LIB.S9S_MB_2U(SCH_1):PAGE75
 C1436    2      B Q_CAP_C0201-0.22UF,6.3V,10%,X6A    I59 @S9S_MB_2U_LIB.S9S_MB_2U(SCH_1):PAGE75
 C1406    2      B Q_CAP_C0603-47UF,2.5V,20%,X6S,A    I61 @S9S_MB_2U_LIB.S9S_MB_2U(SCH_1):PAGE75
 C1407    2      B Q_CAP_C0603-47UF,2.5V,20%,X6S,A    I62 @S9S_MB_2U_LIB.S9S_MB_2U(SCH_1):PAGE75
  C363    2      B Q_CAP_C0805-47UF,4V,20%,X6S,CHA    I64 @S9S_MB_2U_LIB.S9S_MB_2U(SCH_1):PAGE75
  C527    2      B Q_CAP_C0805-47UF,4V,20%,X6S,CHA    I68 @S9S_MB_2U_LIB.S9S_MB_2U(SCH_1):PAGE75
  C498    2      B Q_CAP_C0805-47UF,4V,20%,X6S,CHA     I2 @S9S_MB_2U_LIB.S9S_MB_2U(SCH_1):PAGE76
  C502    2      B Q_CAP_C0805-47UF,4V,20%,X6S,CHA     I3 @S9S_MB_2U_LIB.S9S_MB_2U(SCH_1):PAGE76
  C525    2      B Q_CAP_C0805-47UF,4V,20%,X6S,CHA     I5 @S9S_MB_2U_LIB.S9S_MB_2U(SCH_1):PAGE76
  C500    2      B Q_CAP_C0805-47UF,4V,20%,X6S,CHA     I9 @S9S_MB_2U_LIB.S9S_MB_2U(SCH_1):PAGE76
  C504    2      B Q_CAP_C0805-47UF,4V,20%,X6S,CHA    I10 @S9S_MB_2U_LIB.S9S_MB_2U(SCH_1):PAGE76
  C508    2      B Q_CAP_C0805-47UF,4V,20%,X6S,CHA    I11 @S9S_MB_2U_LIB.S9S_MB_2U(SCH_1):PAGE76
 C1400    2      B Q_CAP_C0805-47UF,4V,20%,X6S,CHA    I14 @S9S_MB_2U_LIB.S9S_MB_2U(SCH_1):PAGE76
 C1362    2      B Q_CAP_C0402-22UF,4V,20%,X6S,CHA    I16 @S9S_MB_2U_LIB.S9S_MB_2U(SCH_1):PAGE76
  C507    2      B Q_CAP_C0805-47UF,4V,20%,X6S,CHA    I21 @S9S_MB_2U_LIB.S9S_MB_2U(SCH_1):PAGE76
  C386    2      B Q_CAP_C0805-47UF,4V,20%,X6S,CHA    I22 @S9S_MB_2U_LIB.S9S_MB_2U(SCH_1):PAGE76
  C388    2      B Q_CAP_C0805-47UF,4V,20%,X6S,CHA    I23 @S9S_MB_2U_LIB.S9S_MB_2U(SCH_1):PAGE76
  C390    2      B Q_CAP_C0805-47UF,4V,20%,X6S,CHA    I25 @S9S_MB_2U_LIB.S9S_MB_2U(SCH_1):PAGE76
  C506    2      B Q_CAP_C0805-47UF,4V,20%,X6S,CHA    I26 @S9S_MB_2U_LIB.S9S_MB_2U(SCH_1):PAGE76
  C512    2      B Q_CAP_C0805-47UF,4V,20%,X6S,CHA    I32 @S9S_MB_2U_LIB.S9S_MB_2U(SCH_1):PAGE76
  C516    2      B Q_CAP_C0603-47UF,2.5V,20%,X6S,A    I33 @S9S_MB_2U_LIB.S9S_MB_2U(SCH_1):PAGE76
  C519    2      B Q_CAP_C0603-47UF,2.5V,20%,X6S,A    I35 @S9S_MB_2U_LIB.S9S_MB_2U(SCH_1):PAGE76
  C520    2      B Q_CAP_C0805-47UF,4V,20%,X6S,CHA    I36 @S9S_MB_2U_LIB.S9S_MB_2U(SCH_1):PAGE76
  C521    2      B Q_CAP_C0805-47UF,4V,20%,X6S,CHA    I37 @S9S_MB_2U_LIB.S9S_MB_2U(SCH_1):PAGE76
  C523    2      B Q_CAP_C0805-47UF,4V,20%,X6S,CHA    I38 @S9S_MB_2U_LIB.S9S_MB_2U(SCH_1):PAGE76
  C526    2      B Q_CAP_C0805-47UF,4V,20%,X6S,CHA    I39 @S9S_MB_2U_LIB.S9S_MB_2U(SCH_1):PAGE76
  C511    2      B Q_CAP_C0805-47UF,4V,20%,X6S,CHA    I43 @S9S_MB_2U_LIB.S9S_MB_2U(SCH_1):PAGE76
  C392    2      B Q_CAP_C0805-47UF,4V,20%,X6S,CHA    I44 @S9S_MB_2U_LIB.S9S_MB_2U(SCH_1):PAGE76
  C394    2      B Q_CAP_C0805-47UF,4V,20%,X6S,CHA    I45 @S9S_MB_2U_LIB.S9S_MB_2U(SCH_1):PAGE76
  C366    2      B Q_CAP_C0805-47UF,4V,20%,X6S,CHA    I48 @S9S_MB_2U_LIB.S9S_MB_2U(SCH_1):PAGE76
  C369    2      B Q_CAP_C0805-47UF,4V,20%,X6S,CHA    I49 @S9S_MB_2U_LIB.S9S_MB_2U(SCH_1):PAGE76
  C372    2      B Q_CAP_C0805-47UF,4V,20%,X6S,CHA    I50 @S9S_MB_2U_LIB.S9S_MB_2U(SCH_1):PAGE76
  C374    2      B Q_CAP_C0805-47UF,4V,20%,X6S,CHA    I51 @S9S_MB_2U_LIB.S9S_MB_2U(SCH_1):PAGE76
  C377    2      B Q_CAP_C0805-47UF,4V,20%,X6S,CHA    I52 @S9S_MB_2U_LIB.S9S_MB_2U(SCH_1):PAGE76
  C380    2      B Q_CAP_C0805-47UF,4V,20%,X6S,CHA    I53 @S9S_MB_2U_LIB.S9S_MB_2U(SCH_1):PAGE76
  C383    2      B Q_CAP_C0805-47UF,4V,20%,X6S,CHA    I54 @S9S_MB_2U_LIB.S9S_MB_2U(SCH_1):PAGE76
  C426    2      B Q_CAP_C0402-22UF,4V,20%,X6S,CHA     I2 @S9S_MB_2U_LIB.S9S_MB_2U(SCH_1):PAGE77
  C229    2      B Q_CAP_C0402-10UF,6.3V,20%,X6S,B    I14 @S9S_MB_2U_LIB.S9S_MB_2U(SCH_1):PAGE77
  C235    2      B Q_CAP_C0805-47UF,4V,20%,X6S,CHA    I16 @S9S_MB_2U_LIB.S9S_MB_2U(SCH_1):PAGE77
  C227    2      B Q_CAP_C0402-10UF,6.3V,20%,X6S,B    I26 @S9S_MB_2U_LIB.S9S_MB_2U(SCH_1):PAGE77
  C437    2      B Q_CAP_C0402-22UF,4V,20%,X6S,CHA    I40 @S9S_MB_2U_LIB.S9S_MB_2U(SCH_1):PAGE77
  C269    2      B Q_CAP_C0402-10UF,6.3V,20%,X6S,B    I64 @S9S_MB_2U_LIB.S9S_MB_2U(SCH_1):PAGE77
  C443    2      B Q_CAP_C0402-22UF,4V,20%,X6S,CHA    I67 @S9S_MB_2U_LIB.S9S_MB_2U(SCH_1):PAGE77
  C310    2      B Q_CAP_C0402-22UF,4V,20%,X6S,CHA    I70 @S9S_MB_2U_LIB.S9S_MB_2U(SCH_1):PAGE77
  C243    2      B Q_CAP_C0402-10UF,6.3V,20%,X6S,B    I74 @S9S_MB_2U_LIB.S9S_MB_2U(SCH_1):PAGE77
  C241    2      B Q_CAP_C0402-10UF,6.3V,20%,X6S,B    I77 @S9S_MB_2U_LIB.S9S_MB_2U(SCH_1):PAGE77
  C253    2      B Q_CAP_C0402-10UF,6.3V,20%,X6S,B    I80 @S9S_MB_2U_LIB.S9S_MB_2U(SCH_1):PAGE77
  C252    2      B Q_CAP_C0402-10UF,6.3V,20%,X6S,B    I82 @S9S_MB_2U_LIB.S9S_MB_2U(SCH_1):PAGE77
  C256    2      B Q_CAP_C0402-10UF,6.3V,20%,X6S,B    I85 @S9S_MB_2U_LIB.S9S_MB_2U(SCH_1):PAGE77
  C273    2      B Q_CAP_C0402-22UF,4V,20%,X6S,CHA    I91 @S9S_MB_2U_LIB.S9S_MB_2U(SCH_1):PAGE77
  C267    2      B Q_CAP_C0402-10UF,6.3V,20%,X6S,B    I94 @S9S_MB_2U_LIB.S9S_MB_2U(SCH_1):PAGE77
  C266    2      B Q_CAP_C0402-10UF,6.3V,20%,X6S,B    I97 @S9S_MB_2U_LIB.S9S_MB_2U(SCH_1):PAGE77
  C287    2      B Q_CAP_C0402-22UF,4V,20%,X6S,CHA   I124 @S9S_MB_2U_LIB.S9S_MB_2U(SCH_1):PAGE77
  C292    2      B Q_CAP_C0402-22UF,4V,20%,X6S,CHA   I127 @S9S_MB_2U_LIB.S9S_MB_2U(SCH_1):PAGE77
  C291    2      B Q_CAP_C0402-22UF,4V,20%,X6S,CHA   I128 @S9S_MB_2U_LIB.S9S_MB_2U(SCH_1):PAGE77
  C303    2      B Q_CAP_C0402-22UF,4V,20%,X6S,CHA   I139 @S9S_MB_2U_LIB.S9S_MB_2U(SCH_1):PAGE77
  C307    2      B Q_CAP_C0402-22UF,4V,20%,X6S,CHA   I142 @S9S_MB_2U_LIB.S9S_MB_2U(SCH_1):PAGE77
  C449    2      B Q_CAP_C0805-47UF,4V,20%,X6S,CHA     I1 @S9S_MB_2U_LIB.S9S_MB_2U(SCH_1):PAGE78
  C457    2      B Q_CAP_C0805-47UF,4V,20%,X6S,CHA     I4 @S9S_MB_2U_LIB.S9S_MB_2U(SCH_1):PAGE78
  C478    2      B Q_CAP_C0805-47UF,4V,20%,X6S,CHA     I8 @S9S_MB_2U_LIB.S9S_MB_2U(SCH_1):PAGE78
  C448    2      B Q_CAP_C0805-47UF,4V,20%,X6S,CHA    I10 @S9S_MB_2U_LIB.S9S_MB_2U(SCH_1):PAGE78
  C447    2      B Q_CAP_C0805-47UF,4V,20%,X6S,CHA    I12 @S9S_MB_2U_LIB.S9S_MB_2U(SCH_1):PAGE78
  C312    2      B Q_CAP_C0805-47UF,4V,20%,X6S,CHA    I14 @S9S_MB_2U_LIB.S9S_MB_2U(SCH_1):PAGE78
  C311    2      B Q_CAP_C0805-47UF,4V,20%,X6S,CHA    I16 @S9S_MB_2U_LIB.S9S_MB_2U(SCH_1):PAGE78
  C488    2      B Q_CAP_C0603-47UF,2.5V,20%,X6S,A    I18 @S9S_MB_2U_LIB.S9S_MB_2U(SCH_1):PAGE78
  C489    2      B Q_CAP_C0603-47UF,2.5V,20%,X6S,A    I19 @S9S_MB_2U_LIB.S9S_MB_2U(SCH_1):PAGE78
  C452    2      B Q_CAP_C0805-47UF,4V,20%,X6S,CHA    I21 @S9S_MB_2U_LIB.S9S_MB_2U(SCH_1):PAGE78
  C471    2      B Q_CAP_C0805-47UF,4V,20%,X6S,CHA    I25 @S9S_MB_2U_LIB.S9S_MB_2U(SCH_1):PAGE78
  C315    2      B Q_CAP_C0805-47UF,4V,20%,X6S,CHA    I26 @S9S_MB_2U_LIB.S9S_MB_2U(SCH_1):PAGE78
  C321    2      B Q_CAP_C0805-47UF,4V,20%,X6S,CHA    I30 @S9S_MB_2U_LIB.S9S_MB_2U(SCH_1):PAGE78
  C324    2      B Q_CAP_C0805-47UF,4V,20%,X6S,CHA    I31 @S9S_MB_2U_LIB.S9S_MB_2U(SCH_1):PAGE78
  C330    2      B Q_CAP_C0805-47UF,4V,20%,X6S,CHA    I33 @S9S_MB_2U_LIB.S9S_MB_2U(SCH_1):PAGE78
  C333    2      B Q_CAP_C0805-47UF,4V,20%,X6S,CHA    I34 @S9S_MB_2U_LIB.S9S_MB_2U(SCH_1):PAGE78
  C339    2      B Q_CAP_C0805-47UF,4V,20%,X6S,CHA    I36 @S9S_MB_2U_LIB.S9S_MB_2U(SCH_1):PAGE78
  C317    2      B Q_CAP_C0805-47UF,4V,20%,X6S,CHA    I38 @S9S_MB_2U_LIB.S9S_MB_2U(SCH_1):PAGE78
  C329    2      B Q_CAP_C0805-47UF,4V,20%,X6S,CHA    I42 @S9S_MB_2U_LIB.S9S_MB_2U(SCH_1):PAGE78
  C332    2      B Q_CAP_C0805-47UF,4V,20%,X6S,CHA    I43 @S9S_MB_2U_LIB.S9S_MB_2U(SCH_1):PAGE78
  C335    2      B Q_CAP_C0805-47UF,4V,20%,X6S,CHA    I44 @S9S_MB_2U_LIB.S9S_MB_2U(SCH_1):PAGE78
  C338    2      B Q_CAP_C0805-47UF,4V,20%,X6S,CHA    I45 @S9S_MB_2U_LIB.S9S_MB_2U(SCH_1):PAGE78
 C1388    2      B Q_CAP_C0805-47UF,4V,20%,X6S,CHA    I46 @S9S_MB_2U_LIB.S9S_MB_2U(SCH_1):PAGE78
 C1390    2      B Q_CAP_C0805-47UF,4V,20%,X6S,CHA    I48 @S9S_MB_2U_LIB.S9S_MB_2U(SCH_1):PAGE78
 C1387    2      B Q_CAP_C0805-47UF,4V,20%,X6S,CHA    I49 @S9S_MB_2U_LIB.S9S_MB_2U(SCH_1):PAGE78
 C1389    2      B Q_CAP_C0603-47UF,2.5V,20%,X6S,A    I51 @S9S_MB_2U_LIB.S9S_MB_2U(SCH_1):PAGE78
 C1392    2      B Q_CAP_C0805-47UF,4V,20%,X6S,CHA    I53 @S9S_MB_2U_LIB.S9S_MB_2U(SCH_1):PAGE78
 C1437    2      B Q_CAP_C0201-0.22UF,6.3V,10%,X6A    I55 @S9S_MB_2U_LIB.S9S_MB_2U(SCH_1):PAGE78
 C1393    2      B Q_CAP_C0603-47UF,2.5V,20%,X6S,A    I57 @S9S_MB_2U_LIB.S9S_MB_2U(SCH_1):PAGE78
  C349    2      B Q_CAP_C0805-47UF,4V,20%,X6S,CHA    I63 @S9S_MB_2U_LIB.S9S_MB_2U(SCH_1):PAGE78
  C351    2      B Q_CAP_C0805-47UF,4V,20%,X6S,CHA    I64 @S9S_MB_2U_LIB.S9S_MB_2U(SCH_1):PAGE78
  C484    2      B Q_CAP_C0805-47UF,4V,20%,X6S,CHA    I12 @S9S_MB_2U_LIB.S9S_MB_2U(SCH_1):PAGE79
  C481    2      B Q_CAP_C0805-47UF,4V,20%,X6S,CHA    I13 @S9S_MB_2U_LIB.S9S_MB_2U(SCH_1):PAGE79
  C456    2      B Q_CAP_C0805-47UF,4V,20%,X6S,CHA    I15 @S9S_MB_2U_LIB.S9S_MB_2U(SCH_1):PAGE79
  C460    2      B Q_CAP_C0805-47UF,4V,20%,X6S,CHA    I16 @S9S_MB_2U_LIB.S9S_MB_2U(SCH_1):PAGE79
  C464    2      B Q_CAP_C0805-47UF,4V,20%,X6S,CHA    I17 @S9S_MB_2U_LIB.S9S_MB_2U(SCH_1):PAGE79
  C455    2      B Q_CAP_C0805-47UF,4V,20%,X6S,CHA    I19 @S9S_MB_2U_LIB.S9S_MB_2U(SCH_1):PAGE79
  C459    2      B Q_CAP_C0805-47UF,4V,20%,X6S,CHA    I20 @S9S_MB_2U_LIB.S9S_MB_2U(SCH_1):PAGE79
  C463    2      B Q_CAP_C0805-47UF,4V,20%,X6S,CHA    I21 @S9S_MB_2U_LIB.S9S_MB_2U(SCH_1):PAGE79
  C342    2      B Q_CAP_C0805-47UF,4V,20%,X6S,CHA    I23 @S9S_MB_2U_LIB.S9S_MB_2U(SCH_1):PAGE79
  C344    2      B Q_CAP_C0805-47UF,4V,20%,X6S,CHA    I24 @S9S_MB_2U_LIB.S9S_MB_2U(SCH_1):PAGE79
  C346    2      B Q_CAP_C0805-47UF,4V,20%,X6S,CHA    I25 @S9S_MB_2U_LIB.S9S_MB_2U(SCH_1):PAGE79
  C468    2      B Q_CAP_C0805-47UF,4V,20%,X6S,CHA    I26 @S9S_MB_2U_LIB.S9S_MB_2U(SCH_1):PAGE79
  C472    2      B Q_CAP_C0603-47UF,2.5V,20%,X6S,A    I27 @S9S_MB_2U_LIB.S9S_MB_2U(SCH_1):PAGE79
  C475    2      B Q_CAP_C0603-47UF,2.5V,20%,X6S,A    I29 @S9S_MB_2U_LIB.S9S_MB_2U(SCH_1):PAGE79
  C467    2      B Q_CAP_C0805-47UF,4V,20%,X6S,CHA    I31 @S9S_MB_2U_LIB.S9S_MB_2U(SCH_1):PAGE79
  C348    2      B Q_CAP_C0805-47UF,4V,20%,X6S,CHA    I32 @S9S_MB_2U_LIB.S9S_MB_2U(SCH_1):PAGE79
  C350    2      B Q_CAP_C0805-47UF,4V,20%,X6S,CHA    I33 @S9S_MB_2U_LIB.S9S_MB_2U(SCH_1):PAGE79
  C352    2      B Q_CAP_C0805-47UF,4V,20%,X6S,CHA    I34 @S9S_MB_2U_LIB.S9S_MB_2U(SCH_1):PAGE79
  C354    2      B Q_CAP_C0805-47UF,4V,20%,X6S,CHA    I35 @S9S_MB_2U_LIB.S9S_MB_2U(SCH_1):PAGE79
  C476    2      B Q_CAP_C0805-47UF,4V,20%,X6S,CHA    I37 @S9S_MB_2U_LIB.S9S_MB_2U(SCH_1):PAGE79
  C477    2      B Q_CAP_C0805-47UF,4V,20%,X6S,CHA    I38 @S9S_MB_2U_LIB.S9S_MB_2U(SCH_1):PAGE79
  C479    2      B Q_CAP_C0805-47UF,4V,20%,X6S,CHA    I39 @S9S_MB_2U_LIB.S9S_MB_2U(SCH_1):PAGE79
  C482    2      B Q_CAP_C0805-47UF,4V,20%,X6S,CHA    I41 @S9S_MB_2U_LIB.S9S_MB_2U(SCH_1):PAGE79
  C485    2      B Q_CAP_C0805-47UF,4V,20%,X6S,CHA    I42 @S9S_MB_2U_LIB.S9S_MB_2U(SCH_1):PAGE79
 C1403    2      B Q_CAP_C0805-47UF,4V,20%,X6S,CHA    I43 @S9S_MB_2U_LIB.S9S_MB_2U(SCH_1):PAGE79
 C1404    2      B Q_CAP_C0805-47UF,4V,20%,X6S,CHA    I44 @S9S_MB_2U_LIB.S9S_MB_2U(SCH_1):PAGE79
  C322    2      B Q_CAP_C0805-47UF,4V,20%,X6S,CHA    I46 @S9S_MB_2U_LIB.S9S_MB_2U(SCH_1):PAGE79
  C325    2      B Q_CAP_C0805-47UF,4V,20%,X6S,CHA    I47 @S9S_MB_2U_LIB.S9S_MB_2U(SCH_1):PAGE79
 C1353    2      B Q_CAP_C0402-22UF,4V,20%,X6S,CHA    I49 @S9S_MB_2U_LIB.S9S_MB_2U(SCH_1):PAGE79
  C328    2      B Q_CAP_C0805-47UF,4V,20%,X6S,CHA    I50 @S9S_MB_2U_LIB.S9S_MB_2U(SCH_1):PAGE79
  C341    2      B Q_CAP_C0805-47UF,4V,20%,X6S,CHA    I51 @S9S_MB_2U_LIB.S9S_MB_2U(SCH_1):PAGE79
  C343    2      B Q_CAP_C0805-47UF,4V,20%,X6S,CHA    I52 @S9S_MB_2U_LIB.S9S_MB_2U(SCH_1):PAGE79
  C345    2      B Q_CAP_C0805-47UF,4V,20%,X6S,CHA    I53 @S9S_MB_2U_LIB.S9S_MB_2U(SCH_1):PAGE79
  C347    2      B Q_CAP_C0805-47UF,4V,20%,X6S,CHA    I55 @S9S_MB_2U_LIB.S9S_MB_2U(SCH_1):PAGE79
 C1363    2      B Q_CAP_C0402-22UF,4V,20%,X6S,CHA     I5 @S9S_MB_2U_LIB.S9S_MB_2U(SCH_1):PAGE80
PR5484    2      B Q_RES_0402LF-30.1K,1%,1/16W,EMA    I49 @S9S_MB_2U_LIB.S9S_MB_2U(SCH_1):PAGE153
PC2087    1      A Q_CAP_C0402-1UF,25V,10%,EMPTY,A    I54 @S9S_MB_2U_LIB.S9S_MB_2U(SCH_1):PAGE153
PC2085    2      B Q_CAP_C0402-1UF,25V,10%,EMPTY,A    I55 @S9S_MB_2U_LIB.S9S_MB_2U(SCH_1):PAGE153
PR3781    2      B Q_RES_0402LF-845,1%,1/16W,EMPTA    I80 @S9S_MB_2U_LIB.S9S_MB_2U(SCH_1):PAGE153
PC2092    2      B Q_CAP_0402-0.1UF,25V,10%,X7R,CA    I93 @S9S_MB_2U_LIB.S9S_MB_2U(SCH_1):PAGE153
PC2082    2      B Q_CAP_C0805-10UF,16V,10%,X6S,CC    I96 @S9S_MB_2U_LIB.S9S_MB_2U(SCH_1):PAGE153
PC2089    2      B Q_CAP_C0402-6800PF,50V,10%,X7RA   I107 @S9S_MB_2U_LIB.S9S_MB_2U(SCH_1):PAGE153
PC2157    2      B Q_CAP_C0402-39PF,50V,5%,EMPTY,A    I42 @S9S_MB_2U_LIB.S9S_MB_2U(SCH_1):PAGE236
PC2162    2      B Q_CAP_0402-100PF,50V,5%,EMPTY,A    I52 @S9S_MB_2U_LIB.S9S_MB_2U(SCH_1):PAGE236
PR3812    2      B Q_RES_0402LF-15K,1%,1/16W,CHIPA    I48 @S9S_MB_2U_LIB.S9S_MB_2U(SCH_1):PAGE131
  Q126    4     S2 MOSFET_NCH_DUAL-PJT138K,SMLF,IA     I4 @S9S_MB_2U_LIB.S9S_MB_2U(SCH_1):PAGE324
 R4073    2      B Q_RES_0402LF-4.7K,5%,1/16W,CHIA     I9 @S9S_MB_2U_LIB.S9S_MB_2U(SCH_1):PAGE324
PR3965    2      B Q_RES_0402LF-15K,1%,1/16W,CHIPA    I13 @S9S_MB_2U_LIB.S9S_MB_2U(SCH_1):PAGE324
PC2208    2      B Q_CAP_C0402-1UF,25V,10%,X6S,CHA    I17 @S9S_MB_2U_LIB.S9S_MB_2U(SCH_1):PAGE324
PC2209    2      B Q_CAP_C0402-1UF,25V,10%,EMPTY,A    I60 @S9S_MB_2U_LIB.S9S_MB_2U(SCH_1):PAGE324
PC2215    2      B Q_CAP_C0402-3900PF,50V,10%,EMPA    I66 @S9S_MB_2U_LIB.S9S_MB_2U(SCH_1):PAGE324
PR3945    2      B Q_RES_0402LF-71.5K,1%,1/16W,EMA     I4 @S9S_MB_2U_LIB.S9S_MB_2U(SCH_1):PAGE323
  Q125    1     S1 MOSFET_NCH_DUAL-PJT138K,SMLF,EA    I21 @S9S_MB_2U_LIB.S9S_MB_2U(SCH_1):PAGE229
PR4005    2      B Q_RES_0402LF-30.1K,1%,1/16W,CHA    I34 @S9S_MB_2U_LIB.S9S_MB_2U(SCH_1):PAGE229
PC2231    2      B Q_CAP_C0402-1UF,25V,10%,X6S,CHA    I37 @S9S_MB_2U_LIB.S9S_MB_2U(SCH_1):PAGE229
PC2235    2      B Q_CAP_C0402-100NF,50V,10%,X7R,A    I42 @S9S_MB_2U_LIB.S9S_MB_2U(SCH_1):PAGE229
PR4011    2      B Q_RES_0402LF-10K,1%,1/16W,CHIPA    I50 @S9S_MB_2U_LIB.S9S_MB_2U(SCH_1):PAGE229
 C1172    2      B Q_CAP_C0402-100NF,50V,10%,X7R,A     I2 @S9S_MB_2U_LIB.S9S_MB_2U(SCH_1):PAGE246
   U99    2    GND RT9818C44GV-RT9818C-44GV,SMLF,A     I4 @S9S_MB_2U_LIB.S9S_MB_2U(SCH_1):PAGE246
 C1042    2      B Q_CAP_C0402-100NF,50V,10%,X7R,A    I11 @S9S_MB_2U_LIB.S9S_MB_2U(SCH_1):PAGE246
 R1641    2      B Q_RES_0402LF-100K,1%,1/16W,CHIA    I14 @S9S_MB_2U_LIB.S9S_MB_2U(SCH_1):PAGE246
 C1170    2      B Q_CAP_C0805-10UF,16V,10%,X6S,CA    I24 @S9S_MB_2U_LIB.S9S_MB_2U(SCH_1):PAGE246
 C1171    2      B Q_CAP_C0805-10UF,16V,10%,EMPTYA    I25 @S9S_MB_2U_LIB.S9S_MB_2U(SCH_1):PAGE246
 C1227    2      B Q_CAP_C0402-100NF,50V,10%,X7R,A    I44 @S9S_MB_2U_LIB.S9S_MB_2U(SCH_1):PAGE246
 C1331    2      B Q_CAP_C0805-10UF,16V,10%,X6S,CA    I45 @S9S_MB_2U_LIB.S9S_MB_2U(SCH_1):PAGE246
 C1332    2      B Q_CAP_C0402-100NF,50V,10%,X7R,A    I48 @S9S_MB_2U_LIB.S9S_MB_2U(SCH_1):PAGE246
 C1333    2      B Q_CAP_C0805-10UF,16V,10%,X6S,CA    I49 @S9S_MB_2U_LIB.S9S_MB_2U(SCH_1):PAGE246
 C1338    2      B Q_CAP_C0805-10UF,16V,10%,EMPTYA    I50 @S9S_MB_2U_LIB.S9S_MB_2U(SCH_1):PAGE246
 C1339    2      B Q_CAP_C0402-100NF,50V,10%,X7R,A    I58 @S9S_MB_2U_LIB.S9S_MB_2U(SCH_1):PAGE246
 C1340    2      B Q_CAP_C0805-10UF,16V,10%,X6S,CA    I61 @S9S_MB_2U_LIB.S9S_MB_2U(SCH_1):PAGE246
PR1649    2      B Q_RES_0402LF-2K,1%,1/16W,CHIP,A     I9 @S9S_MB_2U_LIB.S9S_MB_2U(SCH_1):PAGE248
PC1215    2      B Q_CAPP_SMLF-100UF,16V,20%,OSCOA    I23 @S9S_MB_2U_LIB.S9S_MB_2U(SCH_1):PAGE248
PC1225    2      B Q_CAP_C0805-47UF,4V,20%,X6S,CHA    I44 @S9S_MB_2U_LIB.S9S_MB_2U(SCH_1):PAGE248
PC1651    2      B Q_CAP_C0402-100NF,50V,10%,X7R,A    I14 @S9S_MB_2U_LIB.S9S_MB_2U(SCH_1):PAGE249
PR1330    2      B Q_RES_0402LF-150K,1%,1/16W,CHIA    I24 @S9S_MB_2U_LIB.S9S_MB_2U(SCH_1):PAGE249
 PR586    2      B Q_RES_0402LF-100,1%,1/16W,CHIPA    I15 @S9S_MB_2U_LIB.S9S_MB_2U(SCH_1):PAGE252
PR4217    2      B Q_RES_0402LF-0,5%,1/16W,EMPTY,A    I74 @S9S_MB_2U_LIB.S9S_MB_2U(SCH_1):PAGE252
PC305_P0_1    2      B Q_CAP_C0805-22UF,16V,20%,X6S,CA    I50 @S9S_MB_2U_LIB.S9S_MB_2U(SCH_1):PAGE253
 PC316    2      B Q_CAPP_THLF-560UF,2.5V,20%,OSCA    I61 @S9S_MB_2U_LIB.S9S_MB_2U(SCH_1):PAGE253
 PC323    2      B Q_CAPP_SMLF-330UF,2.5V,+10/-35A    I64 @S9S_MB_2U_LIB.S9S_MB_2U(SCH_1):PAGE253
 PC325    2      B Q_CAPP_THLF-560UF,2.5V,20%,OSCA    I70 @S9S_MB_2U_LIB.S9S_MB_2U(SCH_1):PAGE253
PC314_P0_1    2      B Q_CAP_C0805-22UF,4V,20%,X6S,CHA    I86 @S9S_MB_2U_LIB.S9S_MB_2U(SCH_1):PAGE253
 PC315    2      B Q_CAPP_THLF-270UF,16V,20%,OSCOA    I91 @S9S_MB_2U_LIB.S9S_MB_2U(SCH_1):PAGE253
 PC318    2      B Q_CAPP_THLF-270UF,16V,20%,OSCOA    I92 @S9S_MB_2U_LIB.S9S_MB_2U(SCH_1):PAGE253
PC2345    2      B Q_CAPP_THLF-270UF,16V,20%,OSCOA    I95 @S9S_MB_2U_LIB.S9S_MB_2U(SCH_1):PAGE253
 PR145    2      B Q_RES_0402LF-8.87K,1%,1/16W,EMA     I4 @S9S_MB_2U_LIB.S9S_MB_2U(SCH_1):PAGE254
 PC270    2      B Q_CAP_C0402-2.2UF,10V,10%,X6S,A    I11 @S9S_MB_2U_LIB.S9S_MB_2U(SCH_1):PAGE254
PC1340    1      A Q_CAP_0402-0.1UF,25V,10%,X7R,CA    I12 @S9S_MB_2U_LIB.S9S_MB_2U(SCH_1):PAGE254
PU11_P0_3    2   AGND ISL99390FRZTR5935-ISL99390FRZ-A    I20 @S9S_MB_2U_LIB.S9S_MB_2U(SCH_1):PAGE254
PU11_P0_3    5  PGND1 ISL99390FRZTR5935-ISL99390FRZ-A    I20 @S9S_MB_2U_LIB.S9S_MB_2U(SCH_1):PAGE254
PU11_P0_3 7_9-20_24  PGND2 ISL99390FRZTR5935-ISL99390FRZ-A    I20 @S9S_MB_2U_LIB.S9S_MB_2U(SCH_1):PAGE254
PU11_P0_3   40  PGND3 ISL99390FRZTR5935-ISL99390FRZ-A    I20 @S9S_MB_2U_LIB.S9S_MB_2U(SCH_1):PAGE254
 PC271    2      B Q_CAP_C0402-2.2UF,10V,10%,X6S,A    I25 @S9S_MB_2U_LIB.S9S_MB_2U(SCH_1):PAGE254
PC284_P0_4    2      B Q_CAP_C0805-22UF,16V,20%,X6S,CA    I43 @S9S_MB_2U_LIB.S9S_MB_2U(SCH_1):PAGE254
PC277_P0_3    2      B Q_CAP_C0402-1UF,16V,10%,X6S,CHA    I52 @S9S_MB_2U_LIB.S9S_MB_2U(SCH_1):PAGE254
PC283_P0_3    2      B Q_CAP_C0805-22UF,16V,20%,X6S,CA    I54 @S9S_MB_2U_LIB.S9S_MB_2U(SCH_1):PAGE254
PC289_P0_3    2      B Q_CAP_C0805-22UF,4V,20%,X6S,CHA    I59 @S9S_MB_2U_LIB.S9S_MB_2U(SCH_1):PAGE254
PC288_P0_4    2      B Q_CAP_C0805-22UF,4V,20%,X6S,CHA    I60 @S9S_MB_2U_LIB.S9S_MB_2U(SCH_1):PAGE254
PC290_P0_4    2      B Q_CAP_C0805-22UF,4V,20%,X6S,CHA    I61 @S9S_MB_2U_LIB.S9S_MB_2U(SCH_1):PAGE254
PC291_P0_3    2      B Q_CAP_C0805-22UF,4V,20%,X6S,CHA    I65 @S9S_MB_2U_LIB.S9S_MB_2U(SCH_1):PAGE254
 PR139    2      B Q_RES_0402LF-8.87K,1%,1/16W,EMA     I4 @S9S_MB_2U_LIB.S9S_MB_2U(SCH_1):PAGE255
 PC248    2      B Q_CAP_C0402-2.2UF,10V,10%,X6S,A    I13 @S9S_MB_2U_LIB.S9S_MB_2U(SCH_1):PAGE255
 PC249    2      B Q_CAP_C0402-2.2UF,10V,10%,X6S,A    I24 @S9S_MB_2U_LIB.S9S_MB_2U(SCH_1):PAGE255
PC1343    1      A Q_CAP_0402-0.1UF,25V,10%,X7R,CA    I25 @S9S_MB_2U_LIB.S9S_MB_2U(SCH_1):PAGE255
PC251_P0_5    2      B Q_CAP_C0402-2.2UF,10V,10%,X6S,A    I29 @S9S_MB_2U_LIB.S9S_MB_2U(SCH_1):PAGE255
PC262_P0_6    2      B Q_CAP_C0805-22UF,16V,20%,X6S,CA    I43 @S9S_MB_2U_LIB.S9S_MB_2U(SCH_1):PAGE255
PC253_P0_5    2      B Q_CAP_0402-3300PF,50V,10%,X7R,A    I48 @S9S_MB_2U_LIB.S9S_MB_2U(SCH_1):PAGE255
PC255_P0_5    2      B Q_CAP_C0402-1UF,16V,10%,X6S,CHA    I52 @S9S_MB_2U_LIB.S9S_MB_2U(SCH_1):PAGE255
PC259_P0_5    2      B Q_CAP_C0805-22UF,16V,20%,X6S,CA    I53 @S9S_MB_2U_LIB.S9S_MB_2U(SCH_1):PAGE255
PC261_P0_5    2      B Q_CAP_C0805-22UF,16V,20%,X6S,CA    I54 @S9S_MB_2U_LIB.S9S_MB_2U(SCH_1):PAGE255
PC263_P0_5    2      B Q_CAP_C0805-22UF,16V,20%,X6S,CA    I56 @S9S_MB_2U_LIB.S9S_MB_2U(SCH_1):PAGE255
PC267_P0_5    2      B Q_CAP_C0805-22UF,4V,20%,X6S,CHA    I63 @S9S_MB_2U_LIB.S9S_MB_2U(SCH_1):PAGE255
PC269_P0_5    2      B Q_CAP_C0805-22UF,4V,20%,X6S,CHA    I64 @S9S_MB_2U_LIB.S9S_MB_2U(SCH_1):PAGE255
PU9_P0_5    2   AGND ISL99390FRZTR5935-ISL99390FRZ-A    I66 @S9S_MB_2U_LIB.S9S_MB_2U(SCH_1):PAGE255
PU9_P0_5    5  PGND1 ISL99390FRZTR5935-ISL99390FRZ-A    I66 @S9S_MB_2U_LIB.S9S_MB_2U(SCH_1):PAGE255
PU9_P0_5 7_9-20_24  PGND2 ISL99390FRZTR5935-ISL99390FRZ-A    I66 @S9S_MB_2U_LIB.S9S_MB_2U(SCH_1):PAGE255
PU9_P0_5   40  PGND3 ISL99390FRZTR5935-ISL99390FRZ-A    I66 @S9S_MB_2U_LIB.S9S_MB_2U(SCH_1):PAGE255
 PR132    2      B Q_RES_0402LF-8.87K,1%,1/16W,EMA     I4 @S9S_MB_2U_LIB.S9S_MB_2U(SCH_1):PAGE256
PC1344    1      A Q_CAP_0402-0.1UF,25V,10%,X7R,CA     I7 @S9S_MB_2U_LIB.S9S_MB_2U(SCH_1):PAGE256
 PC226    2      B Q_CAP_C0402-2.2UF,10V,10%,X6S,A    I11 @S9S_MB_2U_LIB.S9S_MB_2U(SCH_1):PAGE256
PC228_P0_8    2      B Q_CAP_C0402-2.2UF,10V,10%,X6S,A    I15 @S9S_MB_2U_LIB.S9S_MB_2U(SCH_1):PAGE256
PC230_P0_8    2      B Q_CAP_0402-3300PF,50V,10%,X7R,A    I17 @S9S_MB_2U_LIB.S9S_MB_2U(SCH_1):PAGE256
PC236_P0_8    2      B Q_CAP_C0805-22UF,16V,20%,X6S,CA    I21 @S9S_MB_2U_LIB.S9S_MB_2U(SCH_1):PAGE256
 PR133    2      B Q_RES_0402LF-8.87K,1%,1/16W,EMA    I23 @S9S_MB_2U_LIB.S9S_MB_2U(SCH_1):PAGE256
PC1345    1      A Q_CAP_0402-0.1UF,25V,10%,X7R,CA    I29 @S9S_MB_2U_LIB.S9S_MB_2U(SCH_1):PAGE256
 PC227    2      B Q_CAP_C0402-2.2UF,10V,10%,X6S,A    I31 @S9S_MB_2U_LIB.S9S_MB_2U(SCH_1):PAGE256
PU7_P0_7    2   AGND ISL99390FRZTR5935-ISL99390FRZ-A    I32 @S9S_MB_2U_LIB.S9S_MB_2U(SCH_1):PAGE256
PU7_P0_7    5  PGND1 ISL99390FRZTR5935-ISL99390FRZ-A    I32 @S9S_MB_2U_LIB.S9S_MB_2U(SCH_1):PAGE256
PU7_P0_7 7_9-20_24  PGND2 ISL99390FRZTR5935-ISL99390FRZ-A    I32 @S9S_MB_2U_LIB.S9S_MB_2U(SCH_1):PAGE256
PU7_P0_7   40  PGND3 ISL99390FRZTR5935-ISL99390FRZ-A    I32 @S9S_MB_2U_LIB.S9S_MB_2U(SCH_1):PAGE256
PC231_P0_7    2      B Q_CAP_0402-3300PF,50V,10%,X7R,A    I41 @S9S_MB_2U_LIB.S9S_MB_2U(SCH_1):PAGE256
PC233_P0_7    2      B Q_CAP_C0402-1UF,16V,10%,X6S,CHA    I42 @S9S_MB_2U_LIB.S9S_MB_2U(SCH_1):PAGE256
PC237_P0_7    2      B Q_CAP_C0805-22UF,16V,20%,X6S,CA    I43 @S9S_MB_2U_LIB.S9S_MB_2U(SCH_1):PAGE256
   PL7    3      3 Q_INDUCTOR4P_14-150NH,SMLF,INDA    I44 @S9S_MB_2U_LIB.S9S_MB_2U(SCH_1):PAGE256
PC238_P0_8    2      B Q_CAP_C0805-22UF,16V,20%,X6S,CA    I47 @S9S_MB_2U_LIB.S9S_MB_2U(SCH_1):PAGE256
PC240_P0_8    2      B Q_CAP_C0805-22UF,16V,20%,X6S,CA    I48 @S9S_MB_2U_LIB.S9S_MB_2U(SCH_1):PAGE256
PC244_P0_8    2      B Q_CAP_C0805-22UF,4V,20%,X6S,CHA    I53 @S9S_MB_2U_LIB.S9S_MB_2U(SCH_1):PAGE256
PC246_P0_8    2      B Q_CAP_C0805-22UF,4V,20%,X6S,CHA    I54 @S9S_MB_2U_LIB.S9S_MB_2U(SCH_1):PAGE256
PC243_P0_7    2      B Q_CAP_C0402-1UF,16V,10%,X6S,CHA    I62 @S9S_MB_2U_LIB.S9S_MB_2U(SCH_1):PAGE256
PC239_P0_7    2      B Q_CAP_C0805-22UF,16V,20%,X6S,CA    I63 @S9S_MB_2U_LIB.S9S_MB_2U(SCH_1):PAGE256
PC245_P0_7    2      B Q_CAP_C0805-22UF,4V,20%,X6S,CHA    I66 @S9S_MB_2U_LIB.S9S_MB_2U(SCH_1):PAGE256
PC247_P0_7    2      B Q_CAP_C0805-22UF,4V,20%,X6S,CHA    I67 @S9S_MB_2U_LIB.S9S_MB_2U(SCH_1):PAGE256
PC608_P0_1    2      B Q_CAP_C0805-22UF,16V,20%,X6S,CA    I47 @S9S_MB_2U_LIB.S9S_MB_2U(SCH_1):PAGE257
PC613_P0_2    2      B Q_CAP_C0402-1UF,16V,10%,X6S,CHA    I51 @S9S_MB_2U_LIB.S9S_MB_2U(SCH_1):PAGE257
PC1670    2      B Q_CAP_C0805-22UF,16V,20%,X6S,CA    I84 @S9S_MB_2U_LIB.S9S_MB_2U(SCH_1):PAGE257
PR1298    2      B Q_RES_0402LF-8.87K,1%,1/16W,EMA    I15 @S9S_MB_2U_LIB.S9S_MB_2U(SCH_1):PAGE258
PC1351    1      A Q_CAP_0402-0.1UF,25V,10%,X7R,CA    I25 @S9S_MB_2U_LIB.S9S_MB_2U(SCH_1):PAGE258
PC1174_P0_4    2      B Q_CAP_0402-3300PF,50V,10%,X7R,A    I31 @S9S_MB_2U_LIB.S9S_MB_2U(SCH_1):PAGE258
PC1185_P0_3    2      B Q_CAP_C0805-22UF,4V,20%,X6S,CHA    I72 @S9S_MB_2U_LIB.S9S_MB_2U(SCH_1):PAGE258
PC1674    2      B Q_CAP_C0805-22UF,16V,20%,X6S,CA    I76 @S9S_MB_2U_LIB.S9S_MB_2U(SCH_1):PAGE258
PU44_P0_2    2   AGND ISL99390FRZTR5935-ISL99390FRZ-A    I12 @S9S_MB_2U_LIB.S9S_MB_2U(SCH_1):PAGE261
PU44_P0_2    5  PGND1 ISL99390FRZTR5935-ISL99390FRZ-A    I12 @S9S_MB_2U_LIB.S9S_MB_2U(SCH_1):PAGE261
PU44_P0_2 7_9-20_24  PGND2 ISL99390FRZTR5935-ISL99390FRZ-A    I12 @S9S_MB_2U_LIB.S9S_MB_2U(SCH_1):PAGE261
PU44_P0_2   40  PGND3 ISL99390FRZTR5935-ISL99390FRZ-A    I12 @S9S_MB_2U_LIB.S9S_MB_2U(SCH_1):PAGE261
PC1347    1      A Q_CAP_0402-0.1UF,25V,10%,X7R,CA    I25 @S9S_MB_2U_LIB.S9S_MB_2U(SCH_1):PAGE261
PC190_P0_2    2      B Q_CAP_0402-3300PF,50V,10%,X7R,A    I32 @S9S_MB_2U_LIB.S9S_MB_2U(SCH_1):PAGE261
PC192_P0_2    2      B Q_CAP_C0402-1UF,16V,10%,X6S,CHA    I35 @S9S_MB_2U_LIB.S9S_MB_2U(SCH_1):PAGE261
PC196_P0_2    2      B Q_CAP_C0805-22UF,16V,20%,X6S,CA    I36 @S9S_MB_2U_LIB.S9S_MB_2U(SCH_1):PAGE261
PC198_P0_2    2      B Q_CAP_C0805-22UF,16V,20%,X6S,CA    I37 @S9S_MB_2U_LIB.S9S_MB_2U(SCH_1):PAGE261
PC203_P0_2    2      B Q_CAP_C0805-22UF,4V,20%,X6S,CHA    I40 @S9S_MB_2U_LIB.S9S_MB_2U(SCH_1):PAGE261
PC189_P0_1    2      B Q_CAP_0402-3300PF,50V,10%,X7R,A    I45 @S9S_MB_2U_LIB.S9S_MB_2U(SCH_1):PAGE261
PC191_P0_1    2      B Q_CAP_C0402-1UF,16V,10%,X6S,CHA    I48 @S9S_MB_2U_LIB.S9S_MB_2U(SCH_1):PAGE261
PC195_P0_1    2      B Q_CAP_C0805-22UF,16V,20%,X6S,CA    I49 @S9S_MB_2U_LIB.S9S_MB_2U(SCH_1):PAGE261
PC197_P0_1    2      B Q_CAP_C0805-22UF,16V,20%,X6S,CA    I50 @S9S_MB_2U_LIB.S9S_MB_2U(SCH_1):PAGE261
PC202_P0_1    2      B Q_CAP_C0805-22UF,4V,20%,X6S,CHA    I56 @S9S_MB_2U_LIB.S9S_MB_2U(SCH_1):PAGE261
PC1574    2      B Q_CAPP_THLF-560UF,2.5V,20%,OSCA    I66 @S9S_MB_2U_LIB.S9S_MB_2U(SCH_1):PAGE261
PC1576    2      B Q_CAPP_THLF-560UF,2.5V,20%,OSCA    I67 @S9S_MB_2U_LIB.S9S_MB_2U(SCH_1):PAGE261
PC1573    2      B Q_CAPP_SMLF-330UF,2V,35%,SPCAPA    I68 @S9S_MB_2U_LIB.S9S_MB_2U(SCH_1):PAGE261
 PC207    2      B Q_CAPP_THLF-270UF,16V,20%,OSCOA    I74 @S9S_MB_2U_LIB.S9S_MB_2U(SCH_1):PAGE261
 PC175    2      B Q_CAP_C0402-2.2UF,10V,10%,X6S,A    I12 @S9S_MB_2U_LIB.S9S_MB_2U(SCH_1):PAGE262
PC2180    2      B Q_CAPP_THLF-560UF,2.5V,20%,OSCA    I33 @S9S_MB_2U_LIB.S9S_MB_2U(SCH_1):PAGE262
  C626    2      B Q_CAP_0402-1000PF,50V,5%,EMPTYA    I47 @S9S_MB_2U_LIB.S9S_MB_2U(SCH_1):PAGE264
 PC628    2      B Q_CAP_0402-0.1UF,25V,10%,X7R,CA    I50 @S9S_MB_2U_LIB.S9S_MB_2U(SCH_1):PAGE264
  PU35   20    EN1 ISL69260IRAZT-ISL69260IRAZ-T,SA    I53 @S9S_MB_2U_LIB.S9S_MB_2U(SCH_1):PAGE264
  PU35   31  RGND1 ISL69260IRAZT-ISL69260IRAZ-T,SA    I53 @S9S_MB_2U_LIB.S9S_MB_2U(SCH_1):PAGE264
  PU35   TH TH_GND ISL69260IRAZT-ISL69260IRAZ-T,SA    I53 @S9S_MB_2U_LIB.S9S_MB_2U(SCH_1):PAGE264
  PU35   32  VSEN1 ISL69260IRAZT-ISL69260IRAZ-T,SA    I53 @S9S_MB_2U_LIB.S9S_MB_2U(SCH_1):PAGE264
PR4236    2      B Q_RES_0402LF-0,5%,1/16W,CHIP,CA    I61 @S9S_MB_2U_LIB.S9S_MB_2U(SCH_1):PAGE264
PR4235    2      B Q_RES_0402LF-0,5%,1/16W,CHIP,CA    I62 @S9S_MB_2U_LIB.S9S_MB_2U(SCH_1):PAGE264
PR2718    2      B Q_RES_0402LF-8.87K,1%,1/16W,EMA     I3 @S9S_MB_2U_LIB.S9S_MB_2U(SCH_1):PAGE265
  PU36    2   AGND ISL99390FRZTR5935-ISL99390FRZ-A     I8 @S9S_MB_2U_LIB.S9S_MB_2U(SCH_1):PAGE265
  PU36    5  PGND1 ISL99390FRZTR5935-ISL99390FRZ-A     I8 @S9S_MB_2U_LIB.S9S_MB_2U(SCH_1):PAGE265
  PU36 7_9-20_24  PGND2 ISL99390FRZTR5935-ISL99390FRZ-A     I8 @S9S_MB_2U_LIB.S9S_MB_2U(SCH_1):PAGE265
  PU36   40  PGND3 ISL99390FRZTR5935-ISL99390FRZ-A     I8 @S9S_MB_2U_LIB.S9S_MB_2U(SCH_1):PAGE265
 PC633    2      B Q_CAP_C0402-2.2UF,10V,10%,X6S,A    I11 @S9S_MB_2U_LIB.S9S_MB_2U(SCH_1):PAGE265
 PC634    2      B Q_CAP_0402-3300PF,50V,10%,X7R,A    I18 @S9S_MB_2U_LIB.S9S_MB_2U(SCH_1):PAGE265
 PC635    2      B Q_CAP_C0402-1UF,16V,10%,X6S,CHA    I20 @S9S_MB_2U_LIB.S9S_MB_2U(SCH_1):PAGE265
 PC637    2      B Q_CAP_C0805-22UF,16V,20%,X6S,CA    I21 @S9S_MB_2U_LIB.S9S_MB_2U(SCH_1):PAGE265
 PC638    2      B Q_CAP_C0805-22UF,16V,20%,X6S,CA    I23 @S9S_MB_2U_LIB.S9S_MB_2U(SCH_1):PAGE265
 PC641    2      B Q_CAP_C0805-22UF,4V,20%,X6S,CHA    I25 @S9S_MB_2U_LIB.S9S_MB_2U(SCH_1):PAGE265
PC1910    2      B Q_CAPP_SMLF-330UF,2V,35%,SPCAPA    I26 @S9S_MB_2U_LIB.S9S_MB_2U(SCH_1):PAGE265
 PC642    2      B Q_CAP_C0805-22UF,4V,20%,X6S,CHA    I28 @S9S_MB_2U_LIB.S9S_MB_2U(SCH_1):PAGE265
   PC1    2      B Q_CAP_C0805-22UF,4V,20%,X6S,CHA    I29 @S9S_MB_2U_LIB.S9S_MB_2U(SCH_1):PAGE265
PC1645    2      B Q_CAPP_THLF-560UF,2.5V,20%,OSCA    I34 @S9S_MB_2U_LIB.S9S_MB_2U(SCH_1):PAGE265
PR4237    2      B Q_RES_0402LF-499,1%,1/16W,CHIPA    I37 @S9S_MB_2U_LIB.S9S_MB_2U(SCH_1):PAGE265
PC2643    2      B Q_CAP_C0402-1UF,25V,10%,X6S,CHA     I4 @S9S_MB_2U_LIB.S9S_MB_2U(SCH_1):PAGE267
 C1301    2      B Q_CAP_0402-1000PF,50V,5%,X7R,TA    I30 @S9S_MB_2U_LIB.S9S_MB_2U(SCH_1):PAGE267
   PR1    1      A Q_RES_0402LF-0,5%,1/16W,CHIP,CA    I19 @S9S_MB_2U_LIB.S9S_MB_2U(SCH_1):PAGE268
   PR1    2      B Q_RES_0402LF-0,5%,1/16W,CHIP,CA    I19 @S9S_MB_2U_LIB.S9S_MB_2U(SCH_1):PAGE268
 C2859    2      B Q_CAP_0402-1000PF,50V,5%,EMPTYA    I68 @S9S_MB_2U_LIB.S9S_MB_2U(SCH_1):PAGE270
 PR637    2      B Q_RES_0402LF-10K,1%,1/16W,EMPTA    I74 @S9S_MB_2U_LIB.S9S_MB_2U(SCH_1):PAGE270
PC1194    2      B Q_CAP_C0402-1UF,16V,10%,X6S,CHA   I121 @S9S_MB_2U_LIB.S9S_MB_2U(SCH_1):PAGE270
 PR325    2      B Q_RES_0402LF-8.87K,1%,1/16W,EMA     I3 @S9S_MB_2U_LIB.S9S_MB_2U(SCH_1):PAGE271
PC1338    1      A Q_CAP_0402-0.1UF,25V,10%,X7R,CA     I6 @S9S_MB_2U_LIB.S9S_MB_2U(SCH_1):PAGE271
 PC556    2      B Q_CAP_C0402-2.2UF,10V,10%,X6S,A    I11 @S9S_MB_2U_LIB.S9S_MB_2U(SCH_1):PAGE271
PC568_P1_2    2      B Q_CAP_C0805-22UF,16V,20%,X6S,CA    I24 @S9S_MB_2U_LIB.S9S_MB_2U(SCH_1):PAGE271
PC563_P1_1    2      B Q_CAP_C0402-1UF,16V,10%,X6S,CHA    I47 @S9S_MB_2U_LIB.S9S_MB_2U(SCH_1):PAGE271
PC567_P1_1    2      B Q_CAP_C0805-22UF,16V,20%,X6S,CA    I48 @S9S_MB_2U_LIB.S9S_MB_2U(SCH_1):PAGE271
PC569_P1_1    2      B Q_CAP_C0805-22UF,16V,20%,X6S,CA    I50 @S9S_MB_2U_LIB.S9S_MB_2U(SCH_1):PAGE271
PC575_P1_2    2      B Q_CAP_C0805-22UF,4V,20%,X6S,CHA    I57 @S9S_MB_2U_LIB.S9S_MB_2U(SCH_1):PAGE271
PC577_P1_2    2      B Q_CAP_C0805-22UF,4V,20%,X6S,CHA    I58 @S9S_MB_2U_LIB.S9S_MB_2U(SCH_1):PAGE271
PR4240    2      B Q_RES_0402LF-499,1%,1/16W,CHIPA    I59 @S9S_MB_2U_LIB.S9S_MB_2U(SCH_1):PAGE271
 PC580    2      B Q_CAPP_THLF-560UF,2.5V,20%,OSCA    I63 @S9S_MB_2U_LIB.S9S_MB_2U(SCH_1):PAGE271
 PC589    2      B Q_CAPP_THLF-560UF,2.5V,20%,OSCA    I72 @S9S_MB_2U_LIB.S9S_MB_2U(SCH_1):PAGE271
PC574_P1_1    2      B Q_CAP_C0402-1UF,16V,10%,X6S,CHA    I85 @S9S_MB_2U_LIB.S9S_MB_2U(SCH_1):PAGE271
 PR297    2      B Q_RES_0402LF-8.87K,1%,1/16W,EMA     I3 @S9S_MB_2U_LIB.S9S_MB_2U(SCH_1):PAGE272
PC1358    1      A Q_CAP_0402-0.1UF,25V,10%,X7R,CA     I6 @S9S_MB_2U_LIB.S9S_MB_2U(SCH_1):PAGE272
PU27_P1_4    2   AGND ISL99390FRZTR5935-ISL99390FRZ-A    I10 @S9S_MB_2U_LIB.S9S_MB_2U(SCH_1):PAGE272
PU27_P1_4    5  PGND1 ISL99390FRZTR5935-ISL99390FRZ-A    I10 @S9S_MB_2U_LIB.S9S_MB_2U(SCH_1):PAGE272
PU27_P1_4 7_9-20_24  PGND2 ISL99390FRZTR5935-ISL99390FRZ-A    I10 @S9S_MB_2U_LIB.S9S_MB_2U(SCH_1):PAGE272
PU27_P1_4   40  PGND3 ISL99390FRZTR5935-ISL99390FRZ-A    I10 @S9S_MB_2U_LIB.S9S_MB_2U(SCH_1):PAGE272
 PR298    2      B Q_RES_0402LF-8.87K,1%,1/16W,EMA    I15 @S9S_MB_2U_LIB.S9S_MB_2U(SCH_1):PAGE272
PC525_P1_4    2      B Q_CAP_C0402-2.2UF,10V,10%,X6S,A    I19 @S9S_MB_2U_LIB.S9S_MB_2U(SCH_1):PAGE272
 PC524    2      B Q_CAP_C0402-2.2UF,10V,10%,X6S,A    I24 @S9S_MB_2U_LIB.S9S_MB_2U(SCH_1):PAGE272
PC526_P1_3    2      B Q_CAP_C0402-2.2UF,10V,10%,X6S,A    I29 @S9S_MB_2U_LIB.S9S_MB_2U(SCH_1):PAGE272
PC527_P1_4    2      B Q_CAP_0402-3300PF,50V,10%,X7R,A    I33 @S9S_MB_2U_LIB.S9S_MB_2U(SCH_1):PAGE272
PC534_P1_3    2      B Q_CAP_C0805-22UF,16V,20%,X6S,CA    I50 @S9S_MB_2U_LIB.S9S_MB_2U(SCH_1):PAGE272
PC538_P1_3    2      B Q_CAP_C0805-22UF,16V,20%,X6S,CA    I55 @S9S_MB_2U_LIB.S9S_MB_2U(SCH_1):PAGE272
PC541_P1_4    2      B Q_CAP_C0805-22UF,4V,20%,X6S,CHA    I58 @S9S_MB_2U_LIB.S9S_MB_2U(SCH_1):PAGE272
PC543_P1_4    2      B Q_CAP_C0805-22UF,4V,20%,X6S,CHA    I59 @S9S_MB_2U_LIB.S9S_MB_2U(SCH_1):PAGE272
PC542_P1_3    2      B Q_CAP_C0805-22UF,4V,20%,X6S,CHA    I63 @S9S_MB_2U_LIB.S9S_MB_2U(SCH_1):PAGE272
PC544_P1_3    2      B Q_CAP_C0805-22UF,4V,20%,X6S,CHA    I64 @S9S_MB_2U_LIB.S9S_MB_2U(SCH_1):PAGE272
PU28_P1_3    2   AGND ISL99390FRZTR5935-ISL99390FRZ-A    I66 @S9S_MB_2U_LIB.S9S_MB_2U(SCH_1):PAGE272
PU28_P1_3    5  PGND1 ISL99390FRZTR5935-ISL99390FRZ-A    I66 @S9S_MB_2U_LIB.S9S_MB_2U(SCH_1):PAGE272
PU28_P1_3 7_9-20_24  PGND2 ISL99390FRZTR5935-ISL99390FRZ-A    I66 @S9S_MB_2U_LIB.S9S_MB_2U(SCH_1):PAGE272
PU28_P1_3   40  PGND3 ISL99390FRZTR5935-ISL99390FRZ-A    I66 @S9S_MB_2U_LIB.S9S_MB_2U(SCH_1):PAGE272
 PR292    2      B Q_RES_0402LF-8.87K,1%,1/16W,EMA     I7 @S9S_MB_2U_LIB.S9S_MB_2U(SCH_1):PAGE273
PC1360    1      A Q_CAP_0402-0.1UF,25V,10%,X7R,CA    I15 @S9S_MB_2U_LIB.S9S_MB_2U(SCH_1):PAGE273
PU25_P1_6    2   AGND ISL99390FRZTR5935-ISL99390FRZ-A    I16 @S9S_MB_2U_LIB.S9S_MB_2U(SCH_1):PAGE273
PU25_P1_6    5  PGND1 ISL99390FRZTR5935-ISL99390FRZ-A    I16 @S9S_MB_2U_LIB.S9S_MB_2U(SCH_1):PAGE273
PU25_P1_6 7_9-20_24  PGND2 ISL99390FRZTR5935-ISL99390FRZ-A    I16 @S9S_MB_2U_LIB.S9S_MB_2U(SCH_1):PAGE273
PU25_P1_6   40  PGND3 ISL99390FRZTR5935-ISL99390FRZ-A    I16 @S9S_MB_2U_LIB.S9S_MB_2U(SCH_1):PAGE273
 PC501    2      B Q_CAP_C0402-2.2UF,10V,10%,X6S,A    I17 @S9S_MB_2U_LIB.S9S_MB_2U(SCH_1):PAGE273
PC511_P1_6    2      B Q_CAP_C0805-22UF,16V,20%,X6S,CA    I33 @S9S_MB_2U_LIB.S9S_MB_2U(SCH_1):PAGE273
PC515_P1_6    2      B Q_CAP_C0805-22UF,16V,20%,X6S,CA    I35 @S9S_MB_2U_LIB.S9S_MB_2U(SCH_1):PAGE273
PC508_P1_5    2      B Q_CAP_C0402-1UF,16V,10%,X6S,CHA    I46 @S9S_MB_2U_LIB.S9S_MB_2U(SCH_1):PAGE273
PC514_P1_5    2      B Q_CAP_C0805-22UF,16V,20%,X6S,CA    I51 @S9S_MB_2U_LIB.S9S_MB_2U(SCH_1):PAGE273
PC516_P1_5    2      B Q_CAP_C0805-22UF,16V,20%,X6S,CA    I52 @S9S_MB_2U_LIB.S9S_MB_2U(SCH_1):PAGE273
PC521_P1_6    2      B Q_CAP_C0805-22UF,4V,20%,X6S,CHA    I57 @S9S_MB_2U_LIB.S9S_MB_2U(SCH_1):PAGE273
PC520_P1_5    2      B Q_CAP_C0805-22UF,4V,20%,X6S,CHA    I64 @S9S_MB_2U_LIB.S9S_MB_2U(SCH_1):PAGE273
PC522_P1_5    2      B Q_CAP_C0805-22UF,4V,20%,X6S,CHA    I65 @S9S_MB_2U_LIB.S9S_MB_2U(SCH_1):PAGE273
 PR285    2      B Q_RES_0402LF-8.87K,1%,1/16W,EMA     I3 @S9S_MB_2U_LIB.S9S_MB_2U(SCH_1):PAGE274
PC1362    1      A Q_CAP_0402-0.1UF,25V,10%,X7R,CA     I7 @S9S_MB_2U_LIB.S9S_MB_2U(SCH_1):PAGE274
PU23_P1_8    2   AGND ISL99390FRZTR5935-ISL99390FRZ-A    I11 @S9S_MB_2U_LIB.S9S_MB_2U(SCH_1):PAGE274
PU23_P1_8    5  PGND1 ISL99390FRZTR5935-ISL99390FRZ-A    I11 @S9S_MB_2U_LIB.S9S_MB_2U(SCH_1):PAGE274
PU23_P1_8 7_9-20_24  PGND2 ISL99390FRZTR5935-ISL99390FRZ-A    I11 @S9S_MB_2U_LIB.S9S_MB_2U(SCH_1):PAGE274
PU23_P1_8   40  PGND3 ISL99390FRZTR5935-ISL99390FRZ-A    I11 @S9S_MB_2U_LIB.S9S_MB_2U(SCH_1):PAGE274
 PR286    2      B Q_RES_0402LF-8.87K,1%,1/16W,EMA    I15 @S9S_MB_2U_LIB.S9S_MB_2U(SCH_1):PAGE274
PU24_P1_7    2   AGND ISL99390FRZTR5935-ISL99390FRZ-A    I20 @S9S_MB_2U_LIB.S9S_MB_2U(SCH_1):PAGE274
PU24_P1_7    5  PGND1 ISL99390FRZTR5935-ISL99390FRZ-A    I20 @S9S_MB_2U_LIB.S9S_MB_2U(SCH_1):PAGE274
PU24_P1_7 7_9-20_24  PGND2 ISL99390FRZTR5935-ISL99390FRZ-A    I20 @S9S_MB_2U_LIB.S9S_MB_2U(SCH_1):PAGE274
PU24_P1_7   40  PGND3 ISL99390FRZTR5935-ISL99390FRZ-A    I20 @S9S_MB_2U_LIB.S9S_MB_2U(SCH_1):PAGE274
 PL106    2      2 Q_INDUCTOR_SMLF-120NH/69A,IND,A    I23 @S9S_MB_2U_LIB.S9S_MB_2U(SCH_1):PAGE274
PC483_P1_8    2      B Q_CAP_0402-3300PF,50V,10%,X7R,A    I24 @S9S_MB_2U_LIB.S9S_MB_2U(SCH_1):PAGE274
PC485_P1_8    2      B Q_CAP_C0402-1UF,16V,10%,X6S,CHA    I27 @S9S_MB_2U_LIB.S9S_MB_2U(SCH_1):PAGE274
  PL25    3      3 Q_INDUCTOR4P_14-150NH,SMLF,INDA    I58 @S9S_MB_2U_LIB.S9S_MB_2U(SCH_1):PAGE274
PC492_P1_7    2      B Q_CAP_C0805-22UF,16V,20%,X6S,CA    I61 @S9S_MB_2U_LIB.S9S_MB_2U(SCH_1):PAGE274
PC494_P1_7    2      B Q_CAP_C0805-22UF,16V,20%,X6S,CA    I62 @S9S_MB_2U_LIB.S9S_MB_2U(SCH_1):PAGE274
PC496_P1_7    2      B Q_CAP_C0402-1UF,16V,10%,X6S,CHA    I64 @S9S_MB_2U_LIB.S9S_MB_2U(SCH_1):PAGE274
PC498_P1_7    2      B Q_CAP_C0805-22UF,4V,20%,X6S,CHA    I65 @S9S_MB_2U_LIB.S9S_MB_2U(SCH_1):PAGE274
PC500_P1_7    2      B Q_CAP_C0805-22UF,4V,20%,X6S,CHA    I66 @S9S_MB_2U_LIB.S9S_MB_2U(SCH_1):PAGE274
PC482_P1_7    2      B Q_CAP_C0402-2.2UF,10V,10%,X6S,A    I69 @S9S_MB_2U_LIB.S9S_MB_2U(SCH_1):PAGE274
PC1367    1      A Q_CAP_0402-0.1UF,25V,10%,X7R,CA    I29 @S9S_MB_2U_LIB.S9S_MB_2U(SCH_1):PAGE275
PC404_P1_2    2      B Q_CAP_C0805-22UF,16V,20%,X6S,CA    I40 @S9S_MB_2U_LIB.S9S_MB_2U(SCH_1):PAGE275
PC399_P1_1    2      B Q_CAP_C0402-1UF,16V,10%,X6S,CHA    I51 @S9S_MB_2U_LIB.S9S_MB_2U(SCH_1):PAGE275
PC403_P1_1    2      B Q_CAP_C0805-22UF,16V,20%,X6S,CA    I52 @S9S_MB_2U_LIB.S9S_MB_2U(SCH_1):PAGE275
PC411_P1_2    2      B Q_CAP_C0805-22UF,4V,20%,X6S,CHA    I62 @S9S_MB_2U_LIB.S9S_MB_2U(SCH_1):PAGE275
PC1678    2      B Q_CAP_C0805-22UF,16V,20%,X6S,CA    I83 @S9S_MB_2U_LIB.S9S_MB_2U(SCH_1):PAGE275
PU78_P1_4    2   AGND ISL99390FRZTR5935-ISL99390FRZ-A    I15 @S9S_MB_2U_LIB.S9S_MB_2U(SCH_1):PAGE276
PU78_P1_4    5  PGND1 ISL99390FRZTR5935-ISL99390FRZ-A    I15 @S9S_MB_2U_LIB.S9S_MB_2U(SCH_1):PAGE276
PU78_P1_4 7_9-20_24  PGND2 ISL99390FRZTR5935-ISL99390FRZ-A    I15 @S9S_MB_2U_LIB.S9S_MB_2U(SCH_1):PAGE276
PU78_P1_4   40  PGND3 ISL99390FRZTR5935-ISL99390FRZ-A    I15 @S9S_MB_2U_LIB.S9S_MB_2U(SCH_1):PAGE276
PC1191    2      B Q_CAP_C0402-2.2UF,10V,10%,X6S,A    I27 @S9S_MB_2U_LIB.S9S_MB_2U(SCH_1):PAGE276
PC1202_P1_4    2      B Q_CAP_C0805-22UF,16V,20%,X6S,CA    I37 @S9S_MB_2U_LIB.S9S_MB_2U(SCH_1):PAGE276
PC1195_P1_3    2      B Q_CAP_C0402-1UF,16V,10%,X6S,CHA    I39 @S9S_MB_2U_LIB.S9S_MB_2U(SCH_1):PAGE276
PC1201_P1_3    2      B Q_CAP_C0805-22UF,16V,20%,X6S,CA    I42 @S9S_MB_2U_LIB.S9S_MB_2U(SCH_1):PAGE276
PC1206_P1_3    2      B Q_CAP_C0805-22UF,4V,20%,X6S,CHA    I66 @S9S_MB_2U_LIB.S9S_MB_2U(SCH_1):PAGE276
PC1684    2      B Q_CAP_C0805-22UF,16V,20%,X6S,CA    I80 @S9S_MB_2U_LIB.S9S_MB_2U(SCH_1):PAGE276
 PC475    2      B Q_CAP_0402-470PF,50V,10%,X7R,TA    I66 @S9S_MB_2U_LIB.S9S_MB_2U(SCH_1):PAGE278
PR1726    2      B Q_RES_0402LF-8.87K,1%,1/16W,EMA    I16 @S9S_MB_2U_LIB.S9S_MB_2U(SCH_1):PAGE279
PU51_P1_2    2   AGND ISL99390FRZTR5935-ISL99390FRZ-A    I29 @S9S_MB_2U_LIB.S9S_MB_2U(SCH_1):PAGE279
PU51_P1_2    5  PGND1 ISL99390FRZTR5935-ISL99390FRZ-A    I29 @S9S_MB_2U_LIB.S9S_MB_2U(SCH_1):PAGE279
PU51_P1_2 7_9-20_24  PGND2 ISL99390FRZTR5935-ISL99390FRZ-A    I29 @S9S_MB_2U_LIB.S9S_MB_2U(SCH_1):PAGE279
PU51_P1_2   40  PGND3 ISL99390FRZTR5935-ISL99390FRZ-A    I29 @S9S_MB_2U_LIB.S9S_MB_2U(SCH_1):PAGE279
PC456_P1_2    2      B Q_CAP_C0805-22UF,4V,20%,X6S,CHA    I32 @S9S_MB_2U_LIB.S9S_MB_2U(SCH_1):PAGE279
PC445_P1_2    2      B Q_CAP_C0402-1UF,16V,10%,X6S,CHA    I37 @S9S_MB_2U_LIB.S9S_MB_2U(SCH_1):PAGE279
PC451_P1_2    2      B Q_CAP_C0805-22UF,16V,20%,X6S,CA    I45 @S9S_MB_2U_LIB.S9S_MB_2U(SCH_1):PAGE279
PC450_P1_1    2      B Q_CAP_C0805-22UF,16V,20%,X6S,CA    I53 @S9S_MB_2U_LIB.S9S_MB_2U(SCH_1):PAGE279
PC1595    2      B Q_CAPP_THLF-560UF,2.5V,20%,OSCA    I60 @S9S_MB_2U_LIB.S9S_MB_2U(SCH_1):PAGE279
PC1588    2      B Q_CAPP_SMLF-330UF,2V,35%,SPCAPA    I61 @S9S_MB_2U_LIB.S9S_MB_2U(SCH_1):PAGE279
PC455_P1_1    2      B Q_CAP_C0805-22UF,4V,20%,X6S,CHA    I63 @S9S_MB_2U_LIB.S9S_MB_2U(SCH_1):PAGE279
 PC461    2      B Q_CAPP_THLF-270UF,16V,20%,OSCOA    I70 @S9S_MB_2U_LIB.S9S_MB_2U(SCH_1):PAGE279
 PC430    2      B Q_CAP_C0402-1UF,16V,10%,X6S,CHA    I26 @S9S_MB_2U_LIB.S9S_MB_2U(SCH_1):PAGE280
 PC433    2      B Q_CAP_C0805-22UF,16V,20%,X6S,CA    I28 @S9S_MB_2U_LIB.S9S_MB_2U(SCH_1):PAGE280
 PC434    2      B Q_CAP_C0402-100NF,50V,10%,X7R,A    I29 @S9S_MB_2U_LIB.S9S_MB_2U(SCH_1):PAGE280
 PR218    2      B Q_RES_0402LF-1K,1%,1/16W,EMPTYA    I48 @S9S_MB_2U_LIB.S9S_MB_2U(SCH_1):PAGE282
 PC390    2      B Q_CAP_0402-0.1UF,25V,10%,X7R,CA    I50 @S9S_MB_2U_LIB.S9S_MB_2U(SCH_1):PAGE282
  PU18   20    EN1 ISL69260IRAZT-ISL69260IRAZ-T,SA    I53 @S9S_MB_2U_LIB.S9S_MB_2U(SCH_1):PAGE282
  PU18   31  RGND1 ISL69260IRAZT-ISL69260IRAZ-T,SA    I53 @S9S_MB_2U_LIB.S9S_MB_2U(SCH_1):PAGE282
  PU18   TH TH_GND ISL69260IRAZT-ISL69260IRAZ-T,SA    I53 @S9S_MB_2U_LIB.S9S_MB_2U(SCH_1):PAGE282
  PU18   32  VSEN1 ISL69260IRAZT-ISL69260IRAZ-T,SA    I53 @S9S_MB_2U_LIB.S9S_MB_2U(SCH_1):PAGE282
PR1315    2      B Q_RES_0402LF-0,5%,1/16W,CHIP,CA    I60 @S9S_MB_2U_LIB.S9S_MB_2U(SCH_1):PAGE282
PR4256    2      B Q_RES_0402LF-0,5%,1/16W,CHIP,CA    I63 @S9S_MB_2U_LIB.S9S_MB_2U(SCH_1):PAGE282
 PC375    2      B Q_CAP_C0402-1UF,16V,10%,X6S,CHA    I22 @S9S_MB_2U_LIB.S9S_MB_2U(SCH_1):PAGE283
PC1262    2      B Q_CAP_C0402-1UF,16V,10%,X6S,CHA    I17 @S9S_MB_2U_LIB.S9S_MB_2U(SCH_1):PAGE285
 C1308    2      B Q_CAP_0402-1000PF,50V,5%,EMPTYA     I6 @S9S_MB_2U_LIB.S9S_MB_2U(SCH_1):PAGE286
  PR51    2      B Q_RES_0402LF-12.4K,0.1%,1/16W,A    I26 @S9S_MB_2U_LIB.S9S_MB_2U(SCH_1):PAGE286
 C2358    2      B Q_CAP_0402-0.1UF,25V,10%,X7R,CA   I100 @S9S_MB_2U_LIB.S9S_MB_2U(SCH_1):PAGE159
 C1273    2      B Q_CAP_C0805-47UF,4V,20%,X6S,CHA   I151 @S9S_MB_2U_LIB.S9S_MB_2U(SCH_1):PAGE181
 C1244    2      B Q_CAP_C0805-47UF,4V,20%,X6S,CHA   I152 @S9S_MB_2U_LIB.S9S_MB_2U(SCH_1):PAGE181
 C1246    2      B Q_CAP_C0805-47UF,4V,20%,X6S,CHA   I153 @S9S_MB_2U_LIB.S9S_MB_2U(SCH_1):PAGE181
 C1247    2      B Q_CAP_C0805-47UF,4V,20%,X6S,CHA   I154 @S9S_MB_2U_LIB.S9S_MB_2U(SCH_1):PAGE181
 C1248    2      B Q_CAP_C0805-47UF,4V,20%,X6S,CHA   I155 @S9S_MB_2U_LIB.S9S_MB_2U(SCH_1):PAGE181
 C1249    2      B Q_CAP_C0805-47UF,4V,20%,X6S,CHA   I156 @S9S_MB_2U_LIB.S9S_MB_2U(SCH_1):PAGE181
 C1258    2      B Q_CAP_C0805-47UF,4V,20%,X6S,CHA   I157 @S9S_MB_2U_LIB.S9S_MB_2U(SCH_1):PAGE181
 C1259    2      B Q_CAP_C0805-47UF,4V,20%,X6S,CHA   I158 @S9S_MB_2U_LIB.S9S_MB_2U(SCH_1):PAGE181
 C1272    2      B Q_CAP_C0805-47UF,4V,20%,X6S,CHA   I159 @S9S_MB_2U_LIB.S9S_MB_2U(SCH_1):PAGE181
   J90   G1     G1 SCONN56_123276793-SCONN56_1-23A   I318 @S9S_MB_2U_LIB.S9S_MB_2U(SCH_1):PAGE297
   J90   G2     G2 SCONN56_123276793-SCONN56_1-23A   I318 @S9S_MB_2U_LIB.S9S_MB_2U(SCH_1):PAGE297
   J90   A1 GND_A1 SCONN56_123276793-SCONN56_1-23A   I318 @S9S_MB_2U_LIB.S9S_MB_2U(SCH_1):PAGE297
   J90   A2 GND_A2 SCONN56_123276793-SCONN56_1-23A   I318 @S9S_MB_2U_LIB.S9S_MB_2U(SCH_1):PAGE297
   J90   A3 GND_A3 SCONN56_123276793-SCONN56_1-23A   I318 @S9S_MB_2U_LIB.S9S_MB_2U(SCH_1):PAGE297
   J90   A4 GND_A4 SCONN56_123276793-SCONN56_1-23A   I318 @S9S_MB_2U_LIB.S9S_MB_2U(SCH_1):PAGE297
   J90   A5 GND_A5 SCONN56_123276793-SCONN56_1-23A   I318 @S9S_MB_2U_LIB.S9S_MB_2U(SCH_1):PAGE297
   J90   A6 GND_A6 SCONN56_123276793-SCONN56_1-23A   I318 @S9S_MB_2U_LIB.S9S_MB_2U(SCH_1):PAGE297
   J90  A13 GND_A13 SCONN56_123276793-SCONN56_1-23A   I318 @S9S_MB_2U_LIB.S9S_MB_2U(SCH_1):PAGE297
   J90  A16 GND_A16 SCONN56_123276793-SCONN56_1-23A   I318 @S9S_MB_2U_LIB.S9S_MB_2U(SCH_1):PAGE297
   J90  A19 GND_A19 SCONN56_123276793-SCONN56_1-23A   I318 @S9S_MB_2U_LIB.S9S_MB_2U(SCH_1):PAGE297
   J90  A22 GND_A22 SCONN56_123276793-SCONN56_1-23A   I318 @S9S_MB_2U_LIB.S9S_MB_2U(SCH_1):PAGE297
   J90  A25 GND_A25 SCONN56_123276793-SCONN56_1-23A   I318 @S9S_MB_2U_LIB.S9S_MB_2U(SCH_1):PAGE297
   J90  A28 GND_A28 SCONN56_123276793-SCONN56_1-23A   I318 @S9S_MB_2U_LIB.S9S_MB_2U(SCH_1):PAGE297
   J90  B13 GND_B13 SCONN56_123276793-SCONN56_1-23A   I318 @S9S_MB_2U_LIB.S9S_MB_2U(SCH_1):PAGE297
   J90  B16 GND_B16 SCONN56_123276793-SCONN56_1-23A   I318 @S9S_MB_2U_LIB.S9S_MB_2U(SCH_1):PAGE297
   J90  B19 GND_B19 SCONN56_123276793-SCONN56_1-23A   I318 @S9S_MB_2U_LIB.S9S_MB_2U(SCH_1):PAGE297
   J90  B22 GND_B22 SCONN56_123276793-SCONN56_1-23A   I318 @S9S_MB_2U_LIB.S9S_MB_2U(SCH_1):PAGE297
   J90  B25 GND_B25 SCONN56_123276793-SCONN56_1-23A   I318 @S9S_MB_2U_LIB.S9S_MB_2U(SCH_1):PAGE297
   J90  B28 GND_B28 SCONN56_123276793-SCONN56_1-23A   I318 @S9S_MB_2U_LIB.S9S_MB_2U(SCH_1):PAGE297
  U248    3    GND 74LVC1G32GW_SMLF-74LVC1G32GW,IA   I158 @S9S_MB_2U_LIB.S9S_MB_2U(SCH_1):PAGE201
 R4095    2      B Q_RES_0402LF-10K,1%,1/16W,CHIPA   I284 @S9S_MB_2U_LIB.S9S_MB_2U(SCH_1):PAGE175
 R4096    2      B Q_RES_0402LF-10K,1%,1/16W,CHIPA   I285 @S9S_MB_2U_LIB.S9S_MB_2U(SCH_1):PAGE175
 R4097    2      B Q_RES_0402LF-10K,1%,1/16W,CHIPA   I286 @S9S_MB_2U_LIB.S9S_MB_2U(SCH_1):PAGE175
 R4098    2      B Q_RES_0402LF-10K,1%,1/16W,CHIPA   I287 @S9S_MB_2U_LIB.S9S_MB_2U(SCH_1):PAGE175
 R4099    2      B Q_RES_0402LF-10K,1%,1/16W,CHIPA   I288 @S9S_MB_2U_LIB.S9S_MB_2U(SCH_1):PAGE175
 R4105    2      B Q_RES_0402LF-10K,1%,1/16W,CHIPA   I183 @S9S_MB_2U_LIB.S9S_MB_2U(SCH_1):PAGE176
 R4106    2      B Q_RES_0402LF-10K,1%,1/16W,CHIPA   I184 @S9S_MB_2U_LIB.S9S_MB_2U(SCH_1):PAGE176
 R4104    2      B Q_RES_0402LF-10K,1%,1/16W,CHIPA   I185 @S9S_MB_2U_LIB.S9S_MB_2U(SCH_1):PAGE176
 R4103    2      B Q_RES_0402LF-10K,1%,1/16W,CHIPA   I186 @S9S_MB_2U_LIB.S9S_MB_2U(SCH_1):PAGE176
 R4109    2      B Q_RES_0402LF-10K,1%,1/16W,CHIPA   I195 @S9S_MB_2U_LIB.S9S_MB_2U(SCH_1):PAGE176
 R4108    2      B Q_RES_0402LF-10K,1%,1/16W,CHIPA   I196 @S9S_MB_2U_LIB.S9S_MB_2U(SCH_1):PAGE176
 R4107    2      B Q_RES_0402LF-10K,1%,1/16W,CHIPA   I197 @S9S_MB_2U_LIB.S9S_MB_2U(SCH_1):PAGE176
 R4115    2      B Q_RES_0402LF-10K,1%,1/16W,CHIPA   I201 @S9S_MB_2U_LIB.S9S_MB_2U(SCH_1):PAGE176
 R4110    2      B Q_RES_0402LF-10K,1%,1/16W,CHIPA   I202 @S9S_MB_2U_LIB.S9S_MB_2U(SCH_1):PAGE176
 R4112    2      B Q_RES_0402LF-10K,1%,1/16W,CHIPA   I203 @S9S_MB_2U_LIB.S9S_MB_2U(SCH_1):PAGE176
 R4111    2      B Q_RES_0402LF-10K,1%,1/16W,CHIPA   I204 @S9S_MB_2U_LIB.S9S_MB_2U(SCH_1):PAGE176
 R4114    2      B Q_RES_0402LF-10K,1%,1/16W,CHIPA   I205 @S9S_MB_2U_LIB.S9S_MB_2U(SCH_1):PAGE176
 R4113    2      B Q_RES_0402LF-10K,1%,1/16W,CHIPA   I206 @S9S_MB_2U_LIB.S9S_MB_2U(SCH_1):PAGE176
 R4116    2      B Q_RES_0402LF-10K,1%,1/16W,CHIPA   I207 @S9S_MB_2U_LIB.S9S_MB_2U(SCH_1):PAGE176
 R4117    2      B Q_RES_0402LF-10K,1%,1/16W,CHIPA   I209 @S9S_MB_2U_LIB.S9S_MB_2U(SCH_1):PAGE176
 R4102    2      B Q_RES_0402LF-10K,1%,1/16W,CHIPA   I298 @S9S_MB_2U_LIB.S9S_MB_2U(SCH_1):PAGE175
 R4101    2      B Q_RES_0402LF-10K,1%,1/16W,CHIPA   I299 @S9S_MB_2U_LIB.S9S_MB_2U(SCH_1):PAGE175
 R4100    2      B Q_RES_0402LF-10K,1%,1/16W,CHIPA   I300 @S9S_MB_2U_LIB.S9S_MB_2U(SCH_1):PAGE175
 C2264    2      B Q_CAP_0402-1000PF,50V,5%,EMPTYA     I2 @S9S_MB_2U_LIB.S9S_MB_2U(SCH_1):PAGE143
  Q128    4     S2 MOSFET_NCH_DUAL-PJT138K,SMLF,IA     I6 @S9S_MB_2U_LIB.S9S_MB_2U(SCH_1):PAGE143
  Q128    1     S1 MOSFET_NCH_DUAL-PJT138K,SMLF,IA    I11 @S9S_MB_2U_LIB.S9S_MB_2U(SCH_1):PAGE143
 R4120    2      B Q_RES_0402LF-100K,1%,1/16W,EMPA    I14 @S9S_MB_2U_LIB.S9S_MB_2U(SCH_1):PAGE143
  Q131    4     S2 MOSFET_NCH_DUAL-PJT138K,SMLF,IA    I19 @S9S_MB_2U_LIB.S9S_MB_2U(SCH_1):PAGE143
 C2266    2      B Q_CAP_0402-1000PF,50V,5%,EMPTYA    I23 @S9S_MB_2U_LIB.S9S_MB_2U(SCH_1):PAGE143
  Q131    1     S1 MOSFET_NCH_DUAL-PJT138K,SMLF,IA    I29 @S9S_MB_2U_LIB.S9S_MB_2U(SCH_1):PAGE143
 R4124    2      B Q_RES_0402LF-100K,1%,1/16W,EMPA    I32 @S9S_MB_2U_LIB.S9S_MB_2U(SCH_1):PAGE143
  Q132    4     S2 MOSFET_NCH_DUAL-PJT138K,SMLF,IA    I35 @S9S_MB_2U_LIB.S9S_MB_2U(SCH_1):PAGE143
 C2265    2      B Q_CAP_0402-1000PF,50V,5%,EMPTYA    I40 @S9S_MB_2U_LIB.S9S_MB_2U(SCH_1):PAGE143
  Q132    1     S1 MOSFET_NCH_DUAL-PJT138K,SMLF,IA    I44 @S9S_MB_2U_LIB.S9S_MB_2U(SCH_1):PAGE143
 R4122    2      B Q_RES_0402LF-100K,1%,1/16W,EMPA    I49 @S9S_MB_2U_LIB.S9S_MB_2U(SCH_1):PAGE143
 C2267    2      B Q_CAP_0402-1000PF,50V,5%,EMPTYA    I55 @S9S_MB_2U_LIB.S9S_MB_2U(SCH_1):PAGE143
 C2269    2      B Q_CAP_0402-1000PF,50V,5%,EMPTYA    I57 @S9S_MB_2U_LIB.S9S_MB_2U(SCH_1):PAGE143
 C2268    2      B Q_CAP_0402-1000PF,50V,5%,EMPTYA    I66 @S9S_MB_2U_LIB.S9S_MB_2U(SCH_1):PAGE143
  Q130    4     S2 MOSFET_NCH_DUAL-PJT138K,SMLF,IA    I70 @S9S_MB_2U_LIB.S9S_MB_2U(SCH_1):PAGE143
  Q133    4     S2 MOSFET_NCH_DUAL-PJT138K,SMLF,IA    I71 @S9S_MB_2U_LIB.S9S_MB_2U(SCH_1):PAGE143
  Q130    1     S1 MOSFET_NCH_DUAL-PJT138K,SMLF,IA    I74 @S9S_MB_2U_LIB.S9S_MB_2U(SCH_1):PAGE143
  Q129    4     S2 MOSFET_NCH_DUAL-PJT138K,SMLF,IA    I77 @S9S_MB_2U_LIB.S9S_MB_2U(SCH_1):PAGE143
  Q133    1     S1 MOSFET_NCH_DUAL-PJT138K,SMLF,IA    I78 @S9S_MB_2U_LIB.S9S_MB_2U(SCH_1):PAGE143
  Q129    1     S1 MOSFET_NCH_DUAL-PJT138K,SMLF,IA    I83 @S9S_MB_2U_LIB.S9S_MB_2U(SCH_1):PAGE143
 R4132    2      B Q_RES_0402LF-100K,1%,1/16W,EMPA    I86 @S9S_MB_2U_LIB.S9S_MB_2U(SCH_1):PAGE143
 R4136    2      B Q_RES_0402LF-100K,1%,1/16W,EMPA    I91 @S9S_MB_2U_LIB.S9S_MB_2U(SCH_1):PAGE143
 R4134    2      B Q_RES_0402LF-100K,1%,1/16W,EMPA    I96 @S9S_MB_2U_LIB.S9S_MB_2U(SCH_1):PAGE143
  Q134    1     S1 MOSFET_NCH_DUAL-PJT138K,SMLF,IA    I99 @S9S_MB_2U_LIB.S9S_MB_2U(SCH_1):PAGE143
 C2270    2      B Q_CAP_0402-1000PF,50V,5%,EMPTYA   I105 @S9S_MB_2U_LIB.S9S_MB_2U(SCH_1):PAGE143
  Q134    4     S2 MOSFET_NCH_DUAL-PJT138K,SMLF,IA   I107 @S9S_MB_2U_LIB.S9S_MB_2U(SCH_1):PAGE143
 R4154    2      B Q_RES_0402LF-100K,1%,1/16W,EMPA   I113 @S9S_MB_2U_LIB.S9S_MB_2U(SCH_1):PAGE143
 R4161    2      B Q_RES_0402LF-100K,1%,1/16W,EMPA     I2 @S9S_MB_2U_LIB.S9S_MB_2U(SCH_1):PAGE139
 R4163    2      B Q_RES_0402LF-100K,1%,1/16W,EMPA     I8 @S9S_MB_2U_LIB.S9S_MB_2U(SCH_1):PAGE139
 R4159    2      B Q_RES_0402LF-100K,1%,1/16W,EMPA    I13 @S9S_MB_2U_LIB.S9S_MB_2U(SCH_1):PAGE139
  Q136    1     S1 MOSFET_NCH_DUAL-PJT138K,SMLF,IA    I17 @S9S_MB_2U_LIB.S9S_MB_2U(SCH_1):PAGE139
  Q137    1     S1 MOSFET_NCH_DUAL-PJT138K,SMLF,IA    I21 @S9S_MB_2U_LIB.S9S_MB_2U(SCH_1):PAGE139
  Q136    4     S2 MOSFET_NCH_DUAL-PJT138K,SMLF,IA    I22 @S9S_MB_2U_LIB.S9S_MB_2U(SCH_1):PAGE139
  Q135    1     S1 MOSFET_NCH_DUAL-PJT138K,SMLF,IA    I25 @S9S_MB_2U_LIB.S9S_MB_2U(SCH_1):PAGE139
  Q137    4     S2 MOSFET_NCH_DUAL-PJT138K,SMLF,IA    I28 @S9S_MB_2U_LIB.S9S_MB_2U(SCH_1):PAGE139
  Q135    4     S2 MOSFET_NCH_DUAL-PJT138K,SMLF,IA    I29 @S9S_MB_2U_LIB.S9S_MB_2U(SCH_1):PAGE139
 C2272    2      B Q_CAP_0402-1000PF,50V,5%,EMPTYA    I33 @S9S_MB_2U_LIB.S9S_MB_2U(SCH_1):PAGE139
 C2273    2      B Q_CAP_0402-1000PF,50V,5%,EMPTYA    I42 @S9S_MB_2U_LIB.S9S_MB_2U(SCH_1):PAGE139
 C2271    2      B Q_CAP_0402-1000PF,50V,5%,EMPTYA    I44 @S9S_MB_2U_LIB.S9S_MB_2U(SCH_1):PAGE139
  U307    S SOURCE MOSFET_N_SMLF-BSS138K,BSS138K,A    I15 @S9S_MB_2U_LIB.S9S_MB_2U(SCH_1):PAGE243
    Y2    2     G1 Q_XTAL_4P_13BI_24GND-25MHZ,SMLB   I391 @S9S_MB_2U_LIB.S9S_MB_2U(SCH_1):PAGE197
    Y2    4     G2 Q_XTAL_4P_13BI_24GND-25MHZ,SMLB   I391 @S9S_MB_2U_LIB.S9S_MB_2U(SCH_1):PAGE197
    Y3    2     G1 Q_XTAL_4P_13BI_24GND-25MHZ,SMLB   I159 @S9S_MB_2U_LIB.S9S_MB_2U(SCH_1):PAGE201
    Y3    4     G2 Q_XTAL_4P_13BI_24GND-25MHZ,SMLB   I159 @S9S_MB_2U_LIB.S9S_MB_2U(SCH_1):PAGE201
 R4199    2      B Q_RES_0402LF-1K,1%,1/16W,CHIP,A    I81 @S9S_MB_2U_LIB.S9S_MB_2U(SCH_1):PAGE161
 R4207    2      B Q_RES_0402LF-1K,1%,1/16W,CHIP,A    I85 @S9S_MB_2U_LIB.S9S_MB_2U(SCH_1):PAGE161
 R4191    2      B Q_RES_0402LF-1K,1%,1/16W,CHIP,A    I89 @S9S_MB_2U_LIB.S9S_MB_2U(SCH_1):PAGE161
 R4205    2      B Q_RES_0402LF-1K,1%,1/16W,CHIP,A    I96 @S9S_MB_2U_LIB.S9S_MB_2U(SCH_1):PAGE161
 R4197    2      B Q_RES_0402LF-1K,1%,1/16W,CHIP,A    I98 @S9S_MB_2U_LIB.S9S_MB_2U(SCH_1):PAGE161
 R4189    2      B Q_RES_0402LF-1K,1%,1/16W,CHIP,A   I102 @S9S_MB_2U_LIB.S9S_MB_2U(SCH_1):PAGE161
 C2276    2      B Q_CAP_0402-0.1UF,25V,10%,X7R,CA   I104 @S9S_MB_2U_LIB.S9S_MB_2U(SCH_1):PAGE161
 C2275    2      B Q_CAP_0402-0.1UF,25V,10%,X7R,CA   I119 @S9S_MB_2U_LIB.S9S_MB_2U(SCH_1):PAGE161
 R4187    2      B Q_RES_0402LF-1K,1%,1/16W,CHIP,A   I121 @S9S_MB_2U_LIB.S9S_MB_2U(SCH_1):PAGE161
 R4195    2      B Q_RES_0402LF-1K,1%,1/16W,CHIP,A   I125 @S9S_MB_2U_LIB.S9S_MB_2U(SCH_1):PAGE161
 R4203    2      B Q_RES_0402LF-1K,1%,1/16W,CHIP,A   I127 @S9S_MB_2U_LIB.S9S_MB_2U(SCH_1):PAGE161
 C2274    2      B Q_CAP_0402-0.1UF,25V,10%,X7R,CA   I139 @S9S_MB_2U_LIB.S9S_MB_2U(SCH_1):PAGE161
 R4185    2      B Q_RES_0402LF-1K,1%,1/16W,CHIP,A   I141 @S9S_MB_2U_LIB.S9S_MB_2U(SCH_1):PAGE161
 R4193    2      B Q_RES_0402LF-1K,1%,1/16W,CHIP,A   I145 @S9S_MB_2U_LIB.S9S_MB_2U(SCH_1):PAGE161
 R4201    2      B Q_RES_0402LF-1K,1%,1/16W,CHIP,A   I147 @S9S_MB_2U_LIB.S9S_MB_2U(SCH_1):PAGE161
PR3337    2      B Q_RES_0402LF-0,5%,1/16W,CHIP,CA    I10 @S9S_MB_2U_LIB.S9S_MB_2U(SCH_1):PAGE244
  PR89    2      B Q_RES_0402LF-16.9K,1%,1/16W,CHA    I16 @S9S_MB_2U_LIB.S9S_MB_2U(SCH_1):PAGE244
 PR158    2      B Q_RES_0402LF-0,5%,1/16W,CHIP,CA    I51 @S9S_MB_2U_LIB.S9S_MB_2U(SCH_1):PAGE252
  PU14   TH TH_GND RAA229126GNPHA0-RAA229126GNP#HA    I63 @S9S_MB_2U_LIB.S9S_MB_2U(SCH_1):PAGE252
 PR150    2      B Q_RES_0402LF-8.87K,1%,1/16W,EMA     I2 @S9S_MB_2U_LIB.S9S_MB_2U(SCH_1):PAGE253
PC296_P0_2    2      B Q_CAP_0402-3300PF,50V,10%,X7R,A    I19 @S9S_MB_2U_LIB.S9S_MB_2U(SCH_1):PAGE253
PC1356    1      A Q_CAP_0402-0.1UF,25V,10%,X7R,CA    I34 @S9S_MB_2U_LIB.S9S_MB_2U(SCH_1):PAGE253
PC303_P0_1    2      B Q_CAP_C0805-22UF,16V,20%,X6S,CA    I49 @S9S_MB_2U_LIB.S9S_MB_2U(SCH_1):PAGE253
PR4219    2      B Q_RES_0402LF-499,1%,1/16W,CHIPA    I59 @S9S_MB_2U_LIB.S9S_MB_2U(SCH_1):PAGE253
PC1920    2      B Q_CAPP_SMLF-330UF,2.5V,+10/-35A    I63 @S9S_MB_2U_LIB.S9S_MB_2U(SCH_1):PAGE253
 PC326    2      B Q_CAPP_SMLF-330UF,2.5V,+10/-35A    I66 @S9S_MB_2U_LIB.S9S_MB_2U(SCH_1):PAGE253
 PC322    2      B Q_CAPP_THLF-560UF,2.5V,20%,OSCA    I67 @S9S_MB_2U_LIB.S9S_MB_2U(SCH_1):PAGE253
PC307_P0_1    2      B Q_CAP_C0805-22UF,16V,20%,X6S,CA    I75 @S9S_MB_2U_LIB.S9S_MB_2U(SCH_1):PAGE253
 PR354    2      B Q_RES_0402LF-8.87K,1%,1/16W,EMA     I8 @S9S_MB_2U_LIB.S9S_MB_2U(SCH_1):PAGE257
PU70_P0_2    2   AGND ISL99390FRZTR5935-ISL99390FRZ-A    I16 @S9S_MB_2U_LIB.S9S_MB_2U(SCH_1):PAGE257
PU70_P0_2    5  PGND1 ISL99390FRZTR5935-ISL99390FRZ-A    I16 @S9S_MB_2U_LIB.S9S_MB_2U(SCH_1):PAGE257
PU70_P0_2 7_9-20_24  PGND2 ISL99390FRZTR5935-ISL99390FRZ-A    I16 @S9S_MB_2U_LIB.S9S_MB_2U(SCH_1):PAGE257
PU70_P0_2   40  PGND3 ISL99390FRZTR5935-ISL99390FRZ-A    I16 @S9S_MB_2U_LIB.S9S_MB_2U(SCH_1):PAGE257
PC615_P0_1    2      B Q_CAP_C0805-22UF,4V,20%,X6S,CHA    I77 @S9S_MB_2U_LIB.S9S_MB_2U(SCH_1):PAGE257
 PC221    2      B Q_CAP_0402-0.1UF,25V,10%,X7R,CA    I63 @S9S_MB_2U_LIB.S9S_MB_2U(SCH_1):PAGE260
PC2947    2      B Q_CAP_C0402-2.2UF,10V,10%,X6S,A    I29 @S9S_MB_2U_LIB.S9S_MB_2U(SCH_1):PAGE261
PC205_P0_2    2      B Q_CAP_C0805-22UF,4V,20%,X6S,CHA    I41 @S9S_MB_2U_LIB.S9S_MB_2U(SCH_1):PAGE261
PC1655    2      B Q_CAP_C0402-100NF,50V,10%,X7R,A    I60 @S9S_MB_2U_LIB.S9S_MB_2U(SCH_1):PAGE261
PC1575    2      B Q_CAPP_SMLF-330UF,2V,35%,SPCAPA    I69 @S9S_MB_2U_LIB.S9S_MB_2U(SCH_1):PAGE261
 PC208    2      B Q_CAPP_THLF-270UF,16V,20%,OSCOA    I75 @S9S_MB_2U_LIB.S9S_MB_2U(SCH_1):PAGE261
PU43_P0_1    2   AGND ISL99390FRZTR5935-ISL99390FRZ-A    I79 @S9S_MB_2U_LIB.S9S_MB_2U(SCH_1):PAGE261
PU43_P0_1    5  PGND1 ISL99390FRZTR5935-ISL99390FRZ-A    I79 @S9S_MB_2U_LIB.S9S_MB_2U(SCH_1):PAGE261
PU43_P0_1 7_9-20_24  PGND2 ISL99390FRZTR5935-ISL99390FRZ-A    I79 @S9S_MB_2U_LIB.S9S_MB_2U(SCH_1):PAGE261
PU43_P0_1   40  PGND3 ISL99390FRZTR5935-ISL99390FRZ-A    I79 @S9S_MB_2U_LIB.S9S_MB_2U(SCH_1):PAGE261
 PC179    2      B Q_CAP_C0805-22UF,16V,20%,X6S,CA    I26 @S9S_MB_2U_LIB.S9S_MB_2U(SCH_1):PAGE262
 PC186    2      B Q_CAP_C0805-22UF,4V,20%,X6S,CHA    I32 @S9S_MB_2U_LIB.S9S_MB_2U(SCH_1):PAGE262
PC1900    2      B Q_CAPP_SMLF-330UF,2.5V,+10/-35B    I34 @S9S_MB_2U_LIB.S9S_MB_2U(SCH_1):PAGE262
PR4229    2      B Q_RES_0402LF-499,1%,1/16W,CHIPA    I36 @S9S_MB_2U_LIB.S9S_MB_2U(SCH_1):PAGE262
 PR591    2      B Q_RES_0402LF-100,1%,1/16W,CHIPA    I30 @S9S_MB_2U_LIB.S9S_MB_2U(SCH_1):PAGE264
 PR634    2      B Q_RES_0402LF-10K,1%,1/16W,EMPTA    I57 @S9S_MB_2U_LIB.S9S_MB_2U(SCH_1):PAGE264
PR1311    2      B Q_RES_0402LF-0,5%,1/16W,CHIP,CA    I59 @S9S_MB_2U_LIB.S9S_MB_2U(SCH_1):PAGE264
PC2948    2      B Q_CAP_C0402-2.2UF,10V,10%,X6S,A    I14 @S9S_MB_2U_LIB.S9S_MB_2U(SCH_1):PAGE265
 PC639    2      B Q_CAP_C0402-100NF,50V,10%,X7R,A    I24 @S9S_MB_2U_LIB.S9S_MB_2U(SCH_1):PAGE265
PC1644    2      B Q_CAPP_THLF-560UF,2.5V,20%,OSCA    I27 @S9S_MB_2U_LIB.S9S_MB_2U(SCH_1):PAGE265
PC1258    2      B Q_CAPP_THLF-560UF,6.3V,20%,OSCA    I49 @S9S_MB_2U_LIB.S9S_MB_2U(SCH_1):PAGE267
 PR560    2      B Q_RES_0402LF-100,1%,1/16W,CHIPA    I12 @S9S_MB_2U_LIB.S9S_MB_2U(SCH_1):PAGE270
 PC547    2      B Q_CAP_0402-0.1UF,25V,10%,EMPTYA    I28 @S9S_MB_2U_LIB.S9S_MB_2U(SCH_1):PAGE270
 PR313    2      B Q_RES_0402LF-1K,1%,1/16W,EMPTYA    I29 @S9S_MB_2U_LIB.S9S_MB_2U(SCH_1):PAGE270
 PC548    2      B Q_CAP_0402-0.1UF,25V,10%,X7R,CA    I31 @S9S_MB_2U_LIB.S9S_MB_2U(SCH_1):PAGE270
 C2446    2      B Q_CAP_0402-1000PF,50V,5%,X7R,TA    I34 @S9S_MB_2U_LIB.S9S_MB_2U(SCH_1):PAGE270
 C2447    2      B Q_CAP_0402-1000PF,50V,5%,EMPTYA    I35 @S9S_MB_2U_LIB.S9S_MB_2U(SCH_1):PAGE270
 PC552    2      B Q_CAP_C0402-100NF,50V,10%,EMPTA   I120 @S9S_MB_2U_LIB.S9S_MB_2U(SCH_1):PAGE270
 PC396    2      B Q_CAP_C0402-2.2UF,10V,10%,X6S,A    I11 @S9S_MB_2U_LIB.S9S_MB_2U(SCH_1):PAGE275
PC405_P1_1    2      B Q_CAP_C0805-22UF,16V,20%,X6S,CA    I56 @S9S_MB_2U_LIB.S9S_MB_2U(SCH_1):PAGE275
PC408_P1_2    2      B Q_CAP_C0402-1UF,16V,10%,X6S,CHA    I61 @S9S_MB_2U_LIB.S9S_MB_2U(SCH_1):PAGE275
PR4241    2      B Q_RES_0402LF-499,1%,1/16W,CHIPA    I64 @S9S_MB_2U_LIB.S9S_MB_2U(SCH_1):PAGE275
 PC418    2      B Q_CAPP_SMLF-330UF,2.5V,+10/-35B    I70 @S9S_MB_2U_LIB.S9S_MB_2U(SCH_1):PAGE275
PC2172    2      B Q_CAPP_SMLF-330UF,2.5V,+10/-35B    I72 @S9S_MB_2U_LIB.S9S_MB_2U(SCH_1):PAGE275
PC1677    2      B Q_CAP_C0805-22UF,16V,20%,X6S,CA    I80 @S9S_MB_2U_LIB.S9S_MB_2U(SCH_1):PAGE275
 C2453    2      B Q_CAP_0402-1000PF,50V,5%,EMPTYA    I32 @S9S_MB_2U_LIB.S9S_MB_2U(SCH_1):PAGE278
 C2452    2      B Q_CAP_0402-1000PF,50V,5%,X7R,TA    I33 @S9S_MB_2U_LIB.S9S_MB_2U(SCH_1):PAGE278
 C2454    2      B Q_CAP_0402-1000PF,50V,5%,EMPTYA    I45 @S9S_MB_2U_LIB.S9S_MB_2U(SCH_1):PAGE282
 PR705    2      B Q_RES_0402LF-10K,1%,1/16W,EMPTA    I81 @S9S_MB_2U_LIB.S9S_MB_2U(SCH_1):PAGE282
PC558_P1_2    2      B Q_CAP_C0402-2.2UF,10V,10%,X6S,A    I15 @S9S_MB_2U_LIB.S9S_MB_2U(SCH_1):PAGE271
PC560_P1_2    2      B Q_CAP_0402-3300PF,50V,10%,X7R,A    I19 @S9S_MB_2U_LIB.S9S_MB_2U(SCH_1):PAGE271
PC562_P1_2    2      B Q_CAP_C0402-1UF,16V,10%,X6S,CHA    I21 @S9S_MB_2U_LIB.S9S_MB_2U(SCH_1):PAGE271
PC559_P1_1    2      B Q_CAP_C0402-2.2UF,10V,10%,X6S,A    I39 @S9S_MB_2U_LIB.S9S_MB_2U(SCH_1):PAGE271
PU31_P1_1    2   AGND ISL99390FRZTR5935-ISL99390FRZ-A    I40 @S9S_MB_2U_LIB.S9S_MB_2U(SCH_1):PAGE271
PU31_P1_1    5  PGND1 ISL99390FRZTR5935-ISL99390FRZ-A    I40 @S9S_MB_2U_LIB.S9S_MB_2U(SCH_1):PAGE271
PU31_P1_1 7_9-20_24  PGND2 ISL99390FRZTR5935-ISL99390FRZ-A    I40 @S9S_MB_2U_LIB.S9S_MB_2U(SCH_1):PAGE271
PU31_P1_1   40  PGND3 ISL99390FRZTR5935-ISL99390FRZ-A    I40 @S9S_MB_2U_LIB.S9S_MB_2U(SCH_1):PAGE271
  PC83    2      B Q_CAPP_THLF-560UF,2.5V,20%,OSCA    I56 @S9S_MB_2U_LIB.S9S_MB_2U(SCH_1):PAGE271
 PC189    2      B Q_CAPP_SMLF-330UF,2.5V,+10/-35A    I62 @S9S_MB_2U_LIB.S9S_MB_2U(SCH_1):PAGE271
 PC582    2      B Q_CAPP_THLF-270UF,16V,20%,OSCOA    I87 @S9S_MB_2U_LIB.S9S_MB_2U(SCH_1):PAGE271
PC576_P1_1    2      B Q_CAP_C0805-22UF,4V,20%,X6S,CHA    I88 @S9S_MB_2U_LIB.S9S_MB_2U(SCH_1):PAGE271
PC578_P1_1    2      B Q_CAP_C0805-22UF,4V,20%,X6S,CHA    I91 @S9S_MB_2U_LIB.S9S_MB_2U(SCH_1):PAGE271
PC2346    2      B Q_CAPP_THLF-270UF,16V,20%,OSCOA    I96 @S9S_MB_2U_LIB.S9S_MB_2U(SCH_1):PAGE271
 PC441    2      B Q_CAP_C0402-2.2UF,10V,10%,X6S,A    I10 @S9S_MB_2U_LIB.S9S_MB_2U(SCH_1):PAGE279
 PC440    2      B Q_CAP_C0402-2.2UF,10V,10%,X6S,A    I24 @S9S_MB_2U_LIB.S9S_MB_2U(SCH_1):PAGE279
PC442_P1_1    2      B Q_CAP_0402-3300PF,50V,10%,X7R,A    I40 @S9S_MB_2U_LIB.S9S_MB_2U(SCH_1):PAGE279
PC1366    1      A Q_CAP_0402-0.1UF,25V,10%,X7R,CA     I9 @S9S_MB_2U_LIB.S9S_MB_2U(SCH_1):PAGE280
PC2199    2      B Q_CAPP_THLF-560UF,2.5V,20%,OSCA    I32 @S9S_MB_2U_LIB.S9S_MB_2U(SCH_1):PAGE280
 PC373    2      B Q_CAP_C0402-2.2UF,10V,10%,X6S,A    I15 @S9S_MB_2U_LIB.S9S_MB_2U(SCH_1):PAGE283
 PC382    2      B Q_CAP_C0805-22UF,4V,20%,X6S,CHA    I29 @S9S_MB_2U_LIB.S9S_MB_2U(SCH_1):PAGE283
  PJ67    2      2 Q_SHORT_SM-EMPTY,SHORT6    I44 @S9S_MB_2U_LIB.S9S_MB_2U(SCH_1):PAGE285
PC1282    2      B Q_CAP_C0402-1UF,16V,10%,X6S,CHA    I16 @S9S_MB_2U_LIB.S9S_MB_2U(SCH_1):PAGE286
PC1218    2      B Q_CAP_C0805-22UF,16V,20%,X6S,CA    I29 @S9S_MB_2U_LIB.S9S_MB_2U(SCH_1):PAGE248
  PJ63    2      2 Q_SHORT_SM-EMPTY,SHORT6    I42 @S9S_MB_2U_LIB.S9S_MB_2U(SCH_1):PAGE248
  U308    2    GND 74LVC2G07DW7-74LVC2G07DW-7,SMLA    I37 @S9S_MB_2U_LIB.S9S_MB_2U(SCH_1):PAGE230
 C2283    2      B Q_CAP_0402-0.1UF,25V,10%,X7R,CA    I40 @S9S_MB_2U_LIB.S9S_MB_2U(SCH_1):PAGE230
 R4265    2      B Q_RES_0402LF-4.7K,5%,1/16W,EMPA    I43 @S9S_MB_2U_LIB.S9S_MB_2U(SCH_1):PAGE230
  R293    2      B Q_RES_0402LF-240,1%,1/16W,EMPTA   I211 @S9S_MB_2U_LIB.S9S_MB_2U(SCH_1):PAGE119
 R4263    2      B Q_RES_0402LF-240,1%,1/16W,EMPTA   I216 @S9S_MB_2U_LIB.S9S_MB_2U(SCH_1):PAGE119
 R4261    2      B Q_RES_0402LF-240,1%,1/16W,EMPTA   I220 @S9S_MB_2U_LIB.S9S_MB_2U(SCH_1):PAGE119
  R289    2      B Q_RES_0402LF-240,1%,1/16W,EMPTA   I225 @S9S_MB_2U_LIB.S9S_MB_2U(SCH_1):PAGE119
  U270    4    GND LM75BD-LM75BD,SMLF,IC,AL0075BDA   I164 @S9S_MB_2U_LIB.S9S_MB_2U(SCH_1):PAGE161
  U271    4    GND LM75BD-LM75BD,SMLF,IC,AL0075BDA   I165 @S9S_MB_2U_LIB.S9S_MB_2U(SCH_1):PAGE161
  U272    4    GND LM75BD-LM75BD,SMLF,IC,AL0075BDA   I166 @S9S_MB_2U_LIB.S9S_MB_2U(SCH_1):PAGE161
  U273    4    GND LM75BD-LM75BD,SMLF,IC,AL0075BDA   I167 @S9S_MB_2U_LIB.S9S_MB_2U(SCH_1):PAGE161
   H44    1      1 HOLE_TH-EMPTY,SP_HOLE1199   I216 @S9S_MB_2U_LIB.S9S_MB_2U(SCH_1):PAGE289
   H45    1      1 HOLE_TH-EMPTY,SP_HOLE1199   I217 @S9S_MB_2U_LIB.S9S_MB_2U(SCH_1):PAGE289
   H47    1      1 HOLE_TH-EMPTY,SP_HOLE1199   I218 @S9S_MB_2U_LIB.S9S_MB_2U(SCH_1):PAGE289
   H49    1      1 HOLE_TH-EMPTY,SP_HOLE1199   I219 @S9S_MB_2U_LIB.S9S_MB_2U(SCH_1):PAGE289
 R4274    2      B Q_RES_0402LF-1K,1%,1/16W,EMPTYA    I11 @S9S_MB_2U_LIB.S9S_MB_2U(SCH_1):PAGE162
 R4280    2      B Q_RES_0402LF-1K,1%,1/16W,EMPTYA    I17 @S9S_MB_2U_LIB.S9S_MB_2U(SCH_1):PAGE162
 R4637    2      B Q_RES_0402LF-200K,1%,1/16W,CHIA    I24 @S9S_MB_2U_LIB.S9S_MB_2U(SCH_1):PAGE162
 R4292    2      B Q_RES_0402LF-4.7K,1%,1/16W,EMPA    I63 @S9S_MB_2U_LIB.S9S_MB_2U(SCH_1):PAGE162
 R4290    2      B Q_RES_0402LF-4.7K,1%,1/16W,EMPA    I68 @S9S_MB_2U_LIB.S9S_MB_2U(SCH_1):PAGE162
  R148    2      B Q_RES_0402LF-10K,1%,1/16W,EMPTA    I49 @S9S_MB_2U_LIB.S9S_MB_2U(SCH_1):PAGE185
  R147    2      B Q_RES_0402LF-10K,1%,1/16W,CHIPA    I50 @S9S_MB_2U_LIB.S9S_MB_2U(SCH_1):PAGE185
 R4039    2      B Q_RES_0402LF-1K,1%,1/16W,CHIP,A   I129 @S9S_MB_2U_LIB.S9S_MB_2U(SCH_1):PAGE322
 R4040    2      B Q_RES_0402LF-1K,1%,1/16W,CHIP,A   I131 @S9S_MB_2U_LIB.S9S_MB_2U(SCH_1):PAGE322
PR1746    2      B Q_RES_0402LF-8.87K,1%,1/16W,EMA     I3 @S9S_MB_2U_LIB.S9S_MB_2U(SCH_1):PAGE283
  PU17    2   AGND ISL99390FRZTR5935-ISL99390FRZ-A    I10 @S9S_MB_2U_LIB.S9S_MB_2U(SCH_1):PAGE283
  PU17    5  PGND1 ISL99390FRZTR5935-ISL99390FRZ-A    I10 @S9S_MB_2U_LIB.S9S_MB_2U(SCH_1):PAGE283
  PU17 7_9-20_24  PGND2 ISL99390FRZTR5935-ISL99390FRZ-A    I10 @S9S_MB_2U_LIB.S9S_MB_2U(SCH_1):PAGE283
  PU17   40  PGND3 ISL99390FRZTR5935-ISL99390FRZ-A    I10 @S9S_MB_2U_LIB.S9S_MB_2U(SCH_1):PAGE283
   PC2    2      B Q_CAP_C0805-22UF,4V,20%,X6S,CHA    I30 @S9S_MB_2U_LIB.S9S_MB_2U(SCH_1):PAGE283
 PC385    2      B Q_CAPP_THLF-560UF,2.5V,20%,OSCA    I32 @S9S_MB_2U_LIB.S9S_MB_2U(SCH_1):PAGE283
 C1296    2      B Q_CAP_0402-1000PF,50V,5%,X7R,TA    I31 @S9S_MB_2U_LIB.S9S_MB_2U(SCH_1):PAGE268
  PC28    2      B Q_CAP_0402-3300PF,50V,10%,X7R,A    I23 @S9S_MB_2U_LIB.S9S_MB_2U(SCH_1):PAGE286
PC1287    2      B Q_CAP_C0805-22UF,4V,20%,X6S,CHA    I44 @S9S_MB_2U_LIB.S9S_MB_2U(SCH_1):PAGE286
PC2201    2      B Q_CAP_0402-0.068UF,16V,10%,EMPA    I30 @S9S_MB_2U_LIB.S9S_MB_2U(SCH_1):PAGE323
PC2203    2      B Q_CAP_0402-100PF,50V,5%,EMPTY,A    I32 @S9S_MB_2U_LIB.S9S_MB_2U(SCH_1):PAGE323
PR3844    2      B Q_RES_0402LF-71.5K,1%,1/16W,EMA    I43 @S9S_MB_2U_LIB.S9S_MB_2U(SCH_1):PAGE236
PC2161    2      B Q_CAP_0402-0.068UF,16V,10%,EMPA    I49 @S9S_MB_2U_LIB.S9S_MB_2U(SCH_1):PAGE236
 PU205    3    GND MP5016GQHLZ-MP5016GQH-L-Z,SMLFA    I50 @S9S_MB_2U_LIB.S9S_MB_2U(SCH_1):PAGE236
PC2159    2      B Q_CAP_C0402-1UF,25V,10%,EMPTY,A    I55 @S9S_MB_2U_LIB.S9S_MB_2U(SCH_1):PAGE236
PR3855    2      B Q_RES_0402LF-71.5K,1%,1/16W,EMA    I43 @S9S_MB_2U_LIB.S9S_MB_2U(SCH_1):PAGE237
PC2169    2      B Q_CAP_C0402-1UF,25V,10%,EMPTY,A    I48 @S9S_MB_2U_LIB.S9S_MB_2U(SCH_1):PAGE237
PC1322    2      B Q_CAP_0402-100PF,50V,5%,EMPTY,A    I54 @S9S_MB_2U_LIB.S9S_MB_2U(SCH_1):PAGE237
 R4019    2      B Q_RES_0402LF-1K,1%,1/16W,CHIP,A    I98 @S9S_MB_2U_LIB.S9S_MB_2U(SCH_1):PAGE321
 R4041    2      B Q_RES_0402LF-1K,1%,1/16W,CHIP,A   I181 @S9S_MB_2U_LIB.S9S_MB_2U(SCH_1):PAGE322
 R4391    2      B Q_RES_0402LF-150,1%,1/16W,CHIPA   I190 @S9S_MB_2U_LIB.S9S_MB_2U(SCH_1):PAGE322
  H128    1      1 HOLE_TH-EMPTY,HOLE596   I232 @S9S_MB_2U_LIB.S9S_MB_2U(SCH_1):PAGE289
 C2321    2      B Q_CAP_0402-0.1UF,25V,10%,EMPTYA     I2 @S9S_MB_2U_LIB.S9S_MB_2U(SCH_1):PAGE194
 R4465    2      B Q_RES_0402LF-3.9K,5%,1/16W,EMPA     I4 @S9S_MB_2U_LIB.S9S_MB_2U(SCH_1):PAGE194
 R4449    2      B Q_RES_0402LF-10K,1%,1/16W,EMPTA     I8 @S9S_MB_2U_LIB.S9S_MB_2U(SCH_1):PAGE194
 C2317    2      B Q_CAP_C0402-1UF,25V,10%,EMPTY,A    I15 @S9S_MB_2U_LIB.S9S_MB_2U(SCH_1):PAGE194
  U312   10    GND TUSB211IRWBR-TUSB211IRWBR,SMLFA    I20 @S9S_MB_2U_LIB.S9S_MB_2U(SCH_1):PAGE194
 R4453    1      A Q_RES_0402LF-47K,0.1%,1/16W,EMA    I26 @S9S_MB_2U_LIB.S9S_MB_2U(SCH_1):PAGE194
 R4463    2      B Q_RES_0402LF-680,1%,1/16W,EMPTA    I37 @S9S_MB_2U_LIB.S9S_MB_2U(SCH_1):PAGE194
 R4464    2      B Q_RES_0402LF-100K,1%,1/16W,EMPA    I38 @S9S_MB_2U_LIB.S9S_MB_2U(SCH_1):PAGE194
  U313   TH     TH GL852GOHY60-GL852G-OHY60,SMLF,B    I40 @S9S_MB_2U_LIB.S9S_MB_2U(SCH_1):PAGE194
 C2313    2      B Q_CAP_C0402-10UF,6.3V,20%,EMPTA    I43 @S9S_MB_2U_LIB.S9S_MB_2U(SCH_1):PAGE194
 C2314    2      B Q_CAP_0402-0.1UF,25V,10%,EMPTYA    I45 @S9S_MB_2U_LIB.S9S_MB_2U(SCH_1):PAGE194
 C2315    2      B Q_CAP_0402-0.1UF,25V,10%,EMPTYA    I46 @S9S_MB_2U_LIB.S9S_MB_2U(SCH_1):PAGE194
 C2316    2      B Q_CAP_C0402-1UF,25V,10%,EMPTY,A    I47 @S9S_MB_2U_LIB.S9S_MB_2U(SCH_1):PAGE194
 C2318    2      B Q_CAP_0402-0.1UF,25V,10%,EMPTYA    I49 @S9S_MB_2U_LIB.S9S_MB_2U(SCH_1):PAGE194
 C2319    2      B Q_CAP_0402-0.1UF,25V,10%,EMPTYA    I51 @S9S_MB_2U_LIB.S9S_MB_2U(SCH_1):PAGE194
 C2320    2      B Q_CAP_0402-0.1UF,25V,10%,EMPTYA    I52 @S9S_MB_2U_LIB.S9S_MB_2U(SCH_1):PAGE194
 C2322    2      B Q_CAP_C0402-1UF,25V,10%,EMPTY,A    I53 @S9S_MB_2U_LIB.S9S_MB_2U(SCH_1):PAGE194
 C2325    2      B Q_CAP_0402-0.1UF,25V,10%,EMPTYA    I55 @S9S_MB_2U_LIB.S9S_MB_2U(SCH_1):PAGE194
 C2323    2      B Q_CAP_C0402-1UF,25V,10%,EMPTY,A    I56 @S9S_MB_2U_LIB.S9S_MB_2U(SCH_1):PAGE194
 C2324    2      B Q_CAP_0402-0.1UF,25V,10%,EMPTYA    I58 @S9S_MB_2U_LIB.S9S_MB_2U(SCH_1):PAGE194
 R4466    2      B Q_RES_0402LF-0,5%,1/16W,EMPTY,A    I75 @S9S_MB_2U_LIB.S9S_MB_2U(SCH_1):PAGE194
 C2326    2      B Q_CAP_C0402-12PF,50V,5%,EMPTY,A    I81 @S9S_MB_2U_LIB.S9S_MB_2U(SCH_1):PAGE194
    Y9    2     G1 Q_XTAL_4P_13BI_24GND-12MHZ,SMLB    I83 @S9S_MB_2U_LIB.S9S_MB_2U(SCH_1):PAGE194
    Y9    4     G2 Q_XTAL_4P_13BI_24GND-12MHZ,SMLB    I83 @S9S_MB_2U_LIB.S9S_MB_2U(SCH_1):PAGE194
 C2327    2      B Q_CAP_C0402-12PF,50V,5%,EMPTY,A    I85 @S9S_MB_2U_LIB.S9S_MB_2U(SCH_1):PAGE194
 R3907    2      B Q_RES_0402LF-33K,1%,1/16W,CHIPA     I4 @S9S_MB_2U_LIB.S9S_MB_2U(SCH_1):PAGE303
  U290    S      S MOSFET_NCH_GDS_ESD_PROTECTED-2A     I5 @S9S_MB_2U_LIB.S9S_MB_2U(SCH_1):PAGE303
 R4420    2      B Q_RES_0402LF-49.9,1%,1/16W,EMPA   I202 @S9S_MB_2U_LIB.S9S_MB_2U(SCH_1):PAGE155
 R4419    2      B Q_RES_0402LF-49.9,1%,1/16W,EMPA   I203 @S9S_MB_2U_LIB.S9S_MB_2U(SCH_1):PAGE155
  R422    2      B Q_RES_0402LF-10K,1%,1/16W,CHIPA   I215 @S9S_MB_2U_LIB.S9S_MB_2U(SCH_1):PAGE150
 R3175    2      B Q_RES_0402LF-10K,1%,1/16W,CHIPA   I334 @S9S_MB_2U_LIB.S9S_MB_2U(SCH_1):PAGE146
  U314   33 EPAD_GND 9ZXL0451EKILFT-9ZXL0451EKILFT,A     I1 @S9S_MB_2U_LIB.S9S_MB_2U(SCH_1):PAGE200
 C2328    2      B Q_CAP_C0603-10UF,6.3V,20%,X6S,A    I17 @S9S_MB_2U_LIB.S9S_MB_2U(SCH_1):PAGE200
 R4490    2      B Q_RES_0402LF-4.75K,1%,1/16W,EMA    I31 @S9S_MB_2U_LIB.S9S_MB_2U(SCH_1):PAGE200
 R4492    2      B Q_RES_0402LF-10K,1%,1/16W,CHIPA    I49 @S9S_MB_2U_LIB.S9S_MB_2U(SCH_1):PAGE200
 C2329    2      B Q_CAP_0402-0.1UF,25V,10%,X7R,CA    I54 @S9S_MB_2U_LIB.S9S_MB_2U(SCH_1):PAGE200
 C2330    2      B Q_CAP_0402-0.1UF,25V,10%,X7R,CA    I55 @S9S_MB_2U_LIB.S9S_MB_2U(SCH_1):PAGE200
 C2333    2      B Q_CAP_0402-0.1UF,25V,10%,X7R,CA    I56 @S9S_MB_2U_LIB.S9S_MB_2U(SCH_1):PAGE200
 C2336    2      B Q_CAP_0402-0.1UF,25V,10%,X7R,CA    I57 @S9S_MB_2U_LIB.S9S_MB_2U(SCH_1):PAGE200
 C2334    2      B Q_CAP_0402-0.1UF,25V,10%,X7R,CA    I58 @S9S_MB_2U_LIB.S9S_MB_2U(SCH_1):PAGE200
 C2335    2      B Q_CAP_0402-0.1UF,25V,10%,X7R,CA    I59 @S9S_MB_2U_LIB.S9S_MB_2U(SCH_1):PAGE200
 R4482    2      B Q_RES_0402LF-49.9,1%,1/16W,EMPA   I208 @S9S_MB_2U_LIB.S9S_MB_2U(SCH_1):PAGE155
 R4486    2      B Q_RES_0402LF-49.9,1%,1/16W,EMPA    I90 @S9S_MB_2U_LIB.S9S_MB_2U(SCH_1):PAGE194
 R4483    2      B Q_RES_0402LF-49.9,1%,1/16W,EMPA   I206 @S9S_MB_2U_LIB.S9S_MB_2U(SCH_1):PAGE155
 R4487    2      B Q_RES_0402LF-49.9,1%,1/16W,EMPA    I88 @S9S_MB_2U_LIB.S9S_MB_2U(SCH_1):PAGE194
 C2339    2      B Q_CAP_0402-0.1UF,25V,10%,X7R,CA    I71 @S9S_MB_2U_LIB.S9S_MB_2U(SCH_1):PAGE200
 C2337    2      B Q_CAP_0402-0.1UF,25V,10%,X7R,CA     I5 @S9S_MB_2U_LIB.S9S_MB_2U(SCH_1):PAGE225
 C2338    2      B Q_CAP_0402-0.1UF,25V,10%,X7R,CA     I8 @S9S_MB_2U_LIB.S9S_MB_2U(SCH_1):PAGE225
  U315    4    GND PCA9617ADP-PCA9617ADP,SMLF,IC,A    I17 @S9S_MB_2U_LIB.S9S_MB_2U(SCH_1):PAGE225
PC1181_P0_3    2      B Q_CAP_C0805-22UF,16V,20%,X6S,CA    I48 @S9S_MB_2U_LIB.S9S_MB_2U(SCH_1):PAGE258
PC1654    2      B Q_CAP_C0402-100NF,50V,10%,X7R,A    I57 @S9S_MB_2U_LIB.S9S_MB_2U(SCH_1):PAGE258
PC1186_P0_4    2      B Q_CAP_C0805-22UF,4V,20%,X6S,CHA    I60 @S9S_MB_2U_LIB.S9S_MB_2U(SCH_1):PAGE258
PC1673    2      B Q_CAP_C0805-22UF,16V,20%,X6S,CA    I75 @S9S_MB_2U_LIB.S9S_MB_2U(SCH_1):PAGE258
PC1189    2      B Q_CAPP_THLF-270UF,16V,20%,OSCOA    I80 @S9S_MB_2U_LIB.S9S_MB_2U(SCH_1):PAGE258
PU71_P0_3    2   AGND ISL99390FRZTR5935-ISL99390FRZ-A    I82 @S9S_MB_2U_LIB.S9S_MB_2U(SCH_1):PAGE258
PU71_P0_3    5  PGND1 ISL99390FRZTR5935-ISL99390FRZ-A    I82 @S9S_MB_2U_LIB.S9S_MB_2U(SCH_1):PAGE258
PU71_P0_3 7_9-20_24  PGND2 ISL99390FRZTR5935-ISL99390FRZ-A    I82 @S9S_MB_2U_LIB.S9S_MB_2U(SCH_1):PAGE258
PU71_P0_3   40  PGND3 ISL99390FRZTR5935-ISL99390FRZ-A    I82 @S9S_MB_2U_LIB.S9S_MB_2U(SCH_1):PAGE258
 C3275    2      B Q_CAP_0402-1000PF,50V,5%,X7R,TA    I23 @S9S_MB_2U_LIB.S9S_MB_2U(SCH_1):PAGE260
PR4224    2      B Q_RES_0402LF-0,5%,1/16W,CHIP,CA    I84 @S9S_MB_2U_LIB.S9S_MB_2U(SCH_1):PAGE260
PR4223    2      B Q_RES_0402LF-0,5%,1/16W,CHIP,CA    I85 @S9S_MB_2U_LIB.S9S_MB_2U(SCH_1):PAGE260
PR4222    2      B Q_RES_0402LF-0,5%,1/16W,CHIP,CA    I86 @S9S_MB_2U_LIB.S9S_MB_2U(SCH_1):PAGE260
 PC224    2      B Q_CAP_C0402-10UF,6.3V,20%,X6S,B    I92 @S9S_MB_2U_LIB.S9S_MB_2U(SCH_1):PAGE260
PR4234    2      B Q_RES_0402LF-0,5%,1/16W,CHIP,CA    I66 @S9S_MB_2U_LIB.S9S_MB_2U(SCH_1):PAGE264
PR4233    2      B Q_RES_0402LF-0,5%,1/16W,CHIP,CA    I67 @S9S_MB_2U_LIB.S9S_MB_2U(SCH_1):PAGE264
PR4232    2      B Q_RES_0402LF-0,5%,1/16W,CHIP,CA    I68 @S9S_MB_2U_LIB.S9S_MB_2U(SCH_1):PAGE264
PR4238    2      B Q_RES_0402LF-0,5%,1/16W,EMPTY,A    I81 @S9S_MB_2U_LIB.S9S_MB_2U(SCH_1):PAGE270
 C2449    2      B Q_CAP_C0402-100NF,50V,10%,X7R,A   I104 @S9S_MB_2U_LIB.S9S_MB_2U(SCH_1):PAGE270
 PC555    2      B Q_CAP_C0402-1UF,16V,10%,X6S,CHA   I122 @S9S_MB_2U_LIB.S9S_MB_2U(SCH_1):PAGE270
 C3268    2      B Q_CAP_0402-1000PF,50V,5%,X7R,TA    I58 @S9S_MB_2U_LIB.S9S_MB_2U(SCH_1):PAGE252
 PR166    2      B Q_RES_0402LF-1K,1%,1/16W,EMPTYA    I60 @S9S_MB_2U_LIB.S9S_MB_2U(SCH_1):PAGE252
 PC330    2      B Q_CAP_0402-0.1UF,25V,10%,X7R,CA    I61 @S9S_MB_2U_LIB.S9S_MB_2U(SCH_1):PAGE252
 PC335    2      B Q_CAP_C0402-10UF,6.3V,20%,X6S,B    I86 @S9S_MB_2U_LIB.S9S_MB_2U(SCH_1):PAGE252
PC1369    1      A Q_CAP_0402-0.1UF,25V,10%,X7R,CA    I23 @S9S_MB_2U_LIB.S9S_MB_2U(SCH_1):PAGE276
PU77_P1_3    2   AGND ISL99390FRZTR5935-ISL99390FRZ-A    I24 @S9S_MB_2U_LIB.S9S_MB_2U(SCH_1):PAGE276
PU77_P1_3    5  PGND1 ISL99390FRZTR5935-ISL99390FRZ-A    I24 @S9S_MB_2U_LIB.S9S_MB_2U(SCH_1):PAGE276
PU77_P1_3 7_9-20_24  PGND2 ISL99390FRZTR5935-ISL99390FRZ-A    I24 @S9S_MB_2U_LIB.S9S_MB_2U(SCH_1):PAGE276
PU77_P1_3   40  PGND3 ISL99390FRZTR5935-ISL99390FRZ-A    I24 @S9S_MB_2U_LIB.S9S_MB_2U(SCH_1):PAGE276
PC1244_P1_3    2      B Q_CAP_C0402-2.2UF,10V,10%,X6S,A    I31 @S9S_MB_2U_LIB.S9S_MB_2U(SCH_1):PAGE276
PC1196_P1_4    2      B Q_CAP_C0402-1UF,16V,10%,X6S,CHA    I35 @S9S_MB_2U_LIB.S9S_MB_2U(SCH_1):PAGE276
PC1209_P1_4    2      B Q_CAP_C0805-22UF,4V,20%,X6S,CHA    I50 @S9S_MB_2U_LIB.S9S_MB_2U(SCH_1):PAGE276
PC727_P1_4    2      B Q_CAP_C0805-22UF,16V,20%,X6S,CA    I52 @S9S_MB_2U_LIB.S9S_MB_2U(SCH_1):PAGE276
PC1204    2      B Q_CAPP_THLF-560UF,2.5V,20%,OSCA    I70 @S9S_MB_2U_LIB.S9S_MB_2U(SCH_1):PAGE276
PC1205    2      B Q_CAPP_SMLF-330UF,2.5V,+10/-35B    I72 @S9S_MB_2U_LIB.S9S_MB_2U(SCH_1):PAGE276
 PC467    2      B Q_CAP_0402-0.1UF,25V,10%,EMPTYA    I28 @S9S_MB_2U_LIB.S9S_MB_2U(SCH_1):PAGE278
PC1292    2      B Q_CAP_0402-470PF,50V,10%,X7R,TA    I69 @S9S_MB_2U_LIB.S9S_MB_2U(SCH_1):PAGE278
PR4246    2      B Q_RES_0402LF-0,5%,1/16W,CHIP,CA    I78 @S9S_MB_2U_LIB.S9S_MB_2U(SCH_1):PAGE278
PR4245    2      B Q_RES_0402LF-0,5%,1/16W,CHIP,CA    I79 @S9S_MB_2U_LIB.S9S_MB_2U(SCH_1):PAGE278
PR4244    2      B Q_RES_0402LF-0,5%,1/16W,CHIP,CA    I80 @S9S_MB_2U_LIB.S9S_MB_2U(SCH_1):PAGE278
PR4243    2      B Q_RES_0402LF-0,5%,1/16W,CHIP,CA    I81 @S9S_MB_2U_LIB.S9S_MB_2U(SCH_1):PAGE278
 PC476    2      B Q_CAP_C0402-100NF,50V,10%,EMPTA    I93 @S9S_MB_2U_LIB.S9S_MB_2U(SCH_1):PAGE278
 PC478    2      B Q_CAP_C0402-1UF,16V,10%,X6S,CHA    I97 @S9S_MB_2U_LIB.S9S_MB_2U(SCH_1):PAGE278
 PC386    2      B Q_CAP_0402-0.1UF,25V,10%,X7R,CA    I13 @S9S_MB_2U_LIB.S9S_MB_2U(SCH_1):PAGE282
 C1337    2      B Q_CAP_0402-0.1UF,25V,10%,X7R,CA    I28 @S9S_MB_2U_LIB.S9S_MB_2U(SCH_1):PAGE282
 PC393    2      B Q_CAP_0402-470PF,50V,10%,X7R,TA    I57 @S9S_MB_2U_LIB.S9S_MB_2U(SCH_1):PAGE282
 PC392    2      B Q_CAP_C0402-10UF,6.3V,20%,X6S,B    I68 @S9S_MB_2U_LIB.S9S_MB_2U(SCH_1):PAGE282
 PC391    2      B Q_CAP_C0402-100NF,50V,10%,EMPTA    I69 @S9S_MB_2U_LIB.S9S_MB_2U(SCH_1):PAGE282
PR4251    2      B Q_RES_0402LF-0,5%,1/16W,CHIP,CA    I70 @S9S_MB_2U_LIB.S9S_MB_2U(SCH_1):PAGE282
PC1289    2      B Q_CAP_C0402-1UF,16V,10%,X6S,CHA    I74 @S9S_MB_2U_LIB.S9S_MB_2U(SCH_1):PAGE282
 R4514    2      B Q_RES_0402LF-4.7K,1%,1/16W,EMPA   I161 @S9S_MB_2U_LIB.S9S_MB_2U(SCH_1):PAGE201
 C2340    2      B Q_CAP_0402-1000PF,50V,5%,EMPTYA    I52 @S9S_MB_2U_LIB.S9S_MB_2U(SCH_1):PAGE139
  Q148    4     S2 MOSFET_NCH_DUAL-PJT138K,SMLF,IA    I55 @S9S_MB_2U_LIB.S9S_MB_2U(SCH_1):PAGE139
  Q148    1     S1 MOSFET_NCH_DUAL-PJT138K,SMLF,IA    I61 @S9S_MB_2U_LIB.S9S_MB_2U(SCH_1):PAGE139
 R4544    2      B Q_RES_0402LF-100K,1%,1/16W,EMPA    I62 @S9S_MB_2U_LIB.S9S_MB_2U(SCH_1):PAGE139
 R4552    2      B Q_RES_0402LF-100K,1%,1/16W,CHIA    I50 @S9S_MB_2U_LIB.S9S_MB_2U(SCH_1):PAGE230
  Q145    1     S1 MOSFET_NCH_DUAL-PJT138K,SMLF,IA    I53 @S9S_MB_2U_LIB.S9S_MB_2U(SCH_1):PAGE230
  Q145    4     S2 MOSFET_NCH_DUAL-PJT138K,SMLF,IA    I58 @S9S_MB_2U_LIB.S9S_MB_2U(SCH_1):PAGE230
 C2342    2      B Q_CAP_0402-1000PF,50V,5%,EMPTYA    I62 @S9S_MB_2U_LIB.S9S_MB_2U(SCH_1):PAGE230
PC2188    2      B Q_CAP_C0402-1UF,25V,10%,X6S,CHA    I51 @S9S_MB_2U_LIB.S9S_MB_2U(SCH_1):PAGE303
  Q123    4     S2 MOSFET_NCH_DUAL-PJT138K,SMLF,EA    I17 @S9S_MB_2U_LIB.S9S_MB_2U(SCH_1):PAGE153
 R4069    2      B Q_RES_0402LF-4.7K,5%,1/16W,CHIA    I20 @S9S_MB_2U_LIB.S9S_MB_2U(SCH_1):PAGE153
  U212    2    GND 74LVC2G07DW7-74LVC2G07DW-7,SMLA    I23 @S9S_MB_2U_LIB.S9S_MB_2U(SCH_1):PAGE153
  U211    2    GND 74LVC2G07DW7-74LVC2G07DW-7,SMLA    I26 @S9S_MB_2U_LIB.S9S_MB_2U(SCH_1):PAGE153
  C593    2      B Q_CAP_0402-0.1UF,25V,10%,X7R,CA    I27 @S9S_MB_2U_LIB.S9S_MB_2U(SCH_1):PAGE153
 PD101    A      A DIODE_TVS-SMF14A,SMLF,IC,BCSMFA    I38 @S9S_MB_2U_LIB.S9S_MB_2U(SCH_1):PAGE153
PR3791    2      B Q_RES_0402LF-15K,1%,1/16W,CHIPA    I58 @S9S_MB_2U_LIB.S9S_MB_2U(SCH_1):PAGE153
PC2086    2      B Q_CAP_C0402-1UF,25V,10%,X6S,CHA    I71 @S9S_MB_2U_LIB.S9S_MB_2U(SCH_1):PAGE153
PC2093    1      A Q_CAP_C0402-1UF,25V,10%,X6S,CHA    I72 @S9S_MB_2U_LIB.S9S_MB_2U(SCH_1):PAGE153
PR5481    2      B Q_RES_0402LF-4.53K,1%,1/16W,CHA   I102 @S9S_MB_2U_LIB.S9S_MB_2U(SCH_1):PAGE153
 PD103    A      A SCHOTTKY_AC-B340A-13-F,SMLF,ICA   I104 @S9S_MB_2U_LIB.S9S_MB_2U(SCH_1):PAGE153
PR3846    1      A Q_RES_0402LF-1.33K,1%,1/16W,EMA    I45 @S9S_MB_2U_LIB.S9S_MB_2U(SCH_1):PAGE236
PC2163    2      B Q_CAP_C0805-10UF,16V,10%,EMPTYB    I54 @S9S_MB_2U_LIB.S9S_MB_2U(SCH_1):PAGE236
  Q118    4     S2 MOSFET_NCH_DUAL-PJT138K,SMLF,EA    I16 @S9S_MB_2U_LIB.S9S_MB_2U(SCH_1):PAGE131
   U59    2    GND 74LVC2G07DW7-74LVC2G07DW-7,SMLA    I19 @S9S_MB_2U_LIB.S9S_MB_2U(SCH_1):PAGE131
   U58    2    GND 74LVC2G07DW7-74LVC2G07DW-7,SMLA    I25 @S9S_MB_2U_LIB.S9S_MB_2U(SCH_1):PAGE131
  Q119    4     S2 MOSFET_NCH_DUAL-PJT138K,SMLF,IA    I42 @S9S_MB_2U_LIB.S9S_MB_2U(SCH_1):PAGE131
PC2140    2      B Q_CAP_C0402-1UF,25V,10%,X6S,CHA    I52 @S9S_MB_2U_LIB.S9S_MB_2U(SCH_1):PAGE131
 PU201   A7   CDLY MAX15090BEWIT-MAX15090BEWI+T,SA    I63 @S9S_MB_2U_LIB.S9S_MB_2U(SCH_1):PAGE131
 PU201   B7    EN# MAX15090BEWIT-MAX15090BEWI+T,SA    I63 @S9S_MB_2U_LIB.S9S_MB_2U(SCH_1):PAGE131
 PU201   B2 GND_B2 MAX15090BEWIT-MAX15090BEWI+T,SA    I63 @S9S_MB_2U_LIB.S9S_MB_2U(SCH_1):PAGE131
 PU201   C1 GND_C1 MAX15090BEWIT-MAX15090BEWI+T,SA    I63 @S9S_MB_2U_LIB.S9S_MB_2U(SCH_1):PAGE131
 PU201   C2 GND_C2 MAX15090BEWIT-MAX15090BEWI+T,SA    I63 @S9S_MB_2U_LIB.S9S_MB_2U(SCH_1):PAGE131
PR3822    2      B Q_RES_0402LF-5.36K,1%,1/16W,CHA    I89 @S9S_MB_2U_LIB.S9S_MB_2U(SCH_1):PAGE131
 PU200   A7   CDLY MAX15090BEWIT-MAX15090BEWI+T,SB    I90 @S9S_MB_2U_LIB.S9S_MB_2U(SCH_1):PAGE131
 PU200   B7    EN# MAX15090BEWIT-MAX15090BEWI+T,SB    I90 @S9S_MB_2U_LIB.S9S_MB_2U(SCH_1):PAGE131
 PU200   B2 GND_B2 MAX15090BEWIT-MAX15090BEWI+T,SB    I90 @S9S_MB_2U_LIB.S9S_MB_2U(SCH_1):PAGE131
 PU200   C1 GND_C1 MAX15090BEWIT-MAX15090BEWI+T,SB    I90 @S9S_MB_2U_LIB.S9S_MB_2U(SCH_1):PAGE131
 PU200   C2 GND_C2 MAX15090BEWIT-MAX15090BEWI+T,SB    I90 @S9S_MB_2U_LIB.S9S_MB_2U(SCH_1):PAGE131
 PD108    A      A SCHOTTKY_AC-B340A-13-F,SMLF,ICA    I93 @S9S_MB_2U_LIB.S9S_MB_2U(SCH_1):PAGE131
PC2151    2      B Q_CAP_C0402-6800PF,50V,10%,X7RA    I96 @S9S_MB_2U_LIB.S9S_MB_2U(SCH_1):PAGE131
PC2141    2      B Q_CAP_C0805-22UF,16V,20%,X6S,CC   I100 @S9S_MB_2U_LIB.S9S_MB_2U(SCH_1):PAGE131
PC2143    2      B Q_CAP_C0805-10UF,16V,10%,X6S,CC   I102 @S9S_MB_2U_LIB.S9S_MB_2U(SCH_1):PAGE131
 PD109    A      A SCHOTTKY_AC-B340A-13-F,SMLF,ICA   I107 @S9S_MB_2U_LIB.S9S_MB_2U(SCH_1):PAGE131
PC2137    2      B Q_CAP_0402-0.1UF,25V,10%,X7R,CA   I109 @S9S_MB_2U_LIB.S9S_MB_2U(SCH_1):PAGE131
PC2168    2      B Q_CAP_C0402-39PF,50V,5%,EMPTY,A    I35 @S9S_MB_2U_LIB.S9S_MB_2U(SCH_1):PAGE237
PR3856    1      A Q_RES_0402LF-1.33K,1%,1/16W,EMA    I46 @S9S_MB_2U_LIB.S9S_MB_2U(SCH_1):PAGE237
PC1321    2      B Q_CAP_0402-0.068UF,16V,10%,EMPA    I50 @S9S_MB_2U_LIB.S9S_MB_2U(SCH_1):PAGE237
 PU207    3    GND MP5016GQHLZ-MP5016GQH-L-Z,SMLFA    I51 @S9S_MB_2U_LIB.S9S_MB_2U(SCH_1):PAGE237
PC2173    2      B Q_CAP_C0805-10UF,16V,10%,EMPTYB    I56 @S9S_MB_2U_LIB.S9S_MB_2U(SCH_1):PAGE237
PR3962    2      B Q_RES_0402LF-15K,1%,1/16W,EMPTA    I28 @S9S_MB_2U_LIB.S9S_MB_2U(SCH_1):PAGE324
PC2207    2      B Q_CAP_C0402-1UF,25V,10%,X6S,CHA    I31 @S9S_MB_2U_LIB.S9S_MB_2U(SCH_1):PAGE324
PC2210    2      B Q_CAP_C0402-1UF,25V,10%,X6S,CHA    I37 @S9S_MB_2U_LIB.S9S_MB_2U(SCH_1):PAGE324
PR3971    2      B Q_RES_0402LF-9.76K,1%,1/16W,CHA    I41 @S9S_MB_2U_LIB.S9S_MB_2U(SCH_1):PAGE324
PC2217    2      B Q_CAP_0402-0.1UF,25V,10%,X7R,CA    I75 @S9S_MB_2U_LIB.S9S_MB_2U(SCH_1):PAGE324
PC2219    2      B Q_CAP_C0805-10UF,16V,10%,X6S,CC    I78 @S9S_MB_2U_LIB.S9S_MB_2U(SCH_1):PAGE324
 PU293    3    GND MP5016GQHLZ-MP5016GQH-L-Z,SMLFA    I31 @S9S_MB_2U_LIB.S9S_MB_2U(SCH_1):PAGE323
PC2196    2      B Q_CAP_0402-0.22UF,16V,10%,X7R,A    I37 @S9S_MB_2U_LIB.S9S_MB_2U(SCH_1):PAGE323
PR3944    2      B Q_RES_0402LF-46.4K,1%,1/16W,CHA    I40 @S9S_MB_2U_LIB.S9S_MB_2U(SCH_1):PAGE323
PC2341    2      B Q_CAP_C0402-560PF,50V,10%,X7R,A    I42 @S9S_MB_2U_LIB.S9S_MB_2U(SCH_1):PAGE323
PC2281    2      B Q_CAP_C0402-0.047UF,25V,10%,X7A    I47 @S9S_MB_2U_LIB.S9S_MB_2U(SCH_1):PAGE323
 PU292    3   ENTM RS31312R-RS31312R,SMLF,IC,AL03A    I49 @S9S_MB_2U_LIB.S9S_MB_2U(SCH_1):PAGE323
 PU292    7    GND RS31312R-RS31312R,SMLF,IC,AL03A    I49 @S9S_MB_2U_LIB.S9S_MB_2U(SCH_1):PAGE323
 PU292    2 LOADEN RS31312R-RS31312R,SMLF,IC,AL03A    I49 @S9S_MB_2U_LIB.S9S_MB_2U(SCH_1):PAGE323
PC2198    2      B Q_CAP_C0402-1UF,25V,10%,X6S,CHA    I51 @S9S_MB_2U_LIB.S9S_MB_2U(SCH_1):PAGE323
PC2202    2      B Q_CAP_C0402-100NF,50V,10%,X7R,A    I56 @S9S_MB_2U_LIB.S9S_MB_2U(SCH_1):PAGE323
PC2229    2      B Q_CAP_0402-0.22UF,16V,10%,X7R,A     I8 @S9S_MB_2U_LIB.S9S_MB_2U(SCH_1):PAGE229
PR3999    2      B Q_RES_0402LF-24.3K,1%,1/16W,CHA    I11 @S9S_MB_2U_LIB.S9S_MB_2U(SCH_1):PAGE229
 PD115    A      A DIODE_TVS-SMF14A,SMLF,IC,BCSMFA    I29 @S9S_MB_2U_LIB.S9S_MB_2U(SCH_1):PAGE229
PC2230    2      B Q_CAP_C0402-1UF,25V,10%,X6S,CHA    I31 @S9S_MB_2U_LIB.S9S_MB_2U(SCH_1):PAGE229
PC2232    2      B Q_CAP_C0402-0.047UF,25V,10%,X7A    I33 @S9S_MB_2U_LIB.S9S_MB_2U(SCH_1):PAGE229
PC2239    2      B Q_CAP_C0603-2.2UF,16V,20%,X7R,A    I53 @S9S_MB_2U_LIB.S9S_MB_2U(SCH_1):PAGE229
PC2234    1      A Q_CAP_C0402-1UF,25V,10%,EMPTY,A    I66 @S9S_MB_2U_LIB.S9S_MB_2U(SCH_1):PAGE229
PC2233    2      B Q_CAP_C0402-1UF,25V,10%,EMPTY,A    I68 @S9S_MB_2U_LIB.S9S_MB_2U(SCH_1):PAGE229
PC1898    2      B Q_CAP_C0805-22UF,16V,20%,X6S,CA    I12 @S9S_MB_2U_LIB.S9S_MB_2U(SCH_1):PAGE244
PC1226    2      B Q_CAP_C0805-47UF,4V,20%,X6S,CHA    I45 @S9S_MB_2U_LIB.S9S_MB_2U(SCH_1):PAGE248
PR1336    2      B Q_RES_0402LF-9.76K,1%,1/16W,CHA    I15 @S9S_MB_2U_LIB.S9S_MB_2U(SCH_1):PAGE267
  PJ65    2      2 Q_SHORT_SM-EMPTY,SHORT6    I33 @S9S_MB_2U_LIB.S9S_MB_2U(SCH_1):PAGE267
 R1445    2      B Q_RES_0402LF-2K,1%,1/16W,CHIP,A    I11 @S9S_MB_2U_LIB.S9S_MB_2U(SCH_1):PAGE268
  PC27    2      B Q_CAP_0402-3300PF,50V,10%,X7R,A    I25 @S9S_MB_2U_LIB.S9S_MB_2U(SCH_1):PAGE268
PC1278    2      B Q_CAP_C0805-22UF,4V,20%,X6S,CHA    I42 @S9S_MB_2U_LIB.S9S_MB_2U(SCH_1):PAGE268
 C2445    2      B Q_CAP_0402-1000PF,50V,5%,EMPTYA    I11 @S9S_MB_2U_LIB.S9S_MB_2U(SCH_1):PAGE285
 R2374    2      B Q_RES_0402LF-2K,1%,1/16W,CHIP,A    I13 @S9S_MB_2U_LIB.S9S_MB_2U(SCH_1):PAGE285
  PU80    2   AGND RS53318LR-RS53318LR,SMLF,IC,ALA    I25 @S9S_MB_2U_LIB.S9S_MB_2U(SCH_1):PAGE285
  PU80 11_18   PGND RS53318LR-RS53318LR,SMLF,IC,ALA    I25 @S9S_MB_2U_LIB.S9S_MB_2U(SCH_1):PAGE285
PC1280    2      B Q_CAP_C0805-22UF,16V,20%,X6S,CA     I9 @S9S_MB_2U_LIB.S9S_MB_2U(SCH_1):PAGE286
  PU82    7   AGND RS53317LR-RS53317LR,SMLF,IC,ALA    I20 @S9S_MB_2U_LIB.S9S_MB_2U(SCH_1):PAGE286
  PU82    1  PGND1 RS53317LR-RS53317LR,SMLF,IC,ALA    I20 @S9S_MB_2U_LIB.S9S_MB_2U(SCH_1):PAGE286
  PU82   14  PGND2 RS53317LR-RS53317LR,SMLF,IC,ALA    I20 @S9S_MB_2U_LIB.S9S_MB_2U(SCH_1):PAGE286
PC1285    2      B Q_CAP_C0805-22UF,4V,20%,X6S,CHA    I36 @S9S_MB_2U_LIB.S9S_MB_2U(SCH_1):PAGE286
PC2340    2      B Q_CAP_C0402-560PF,50V,10%,X7R,A     I7 @S9S_MB_2U_LIB.S9S_MB_2U(SCH_1):PAGE229
PC2238    2      B Q_CAP_0402-0.1UF,25V,10%,X7R,CA    I83 @S9S_MB_2U_LIB.S9S_MB_2U(SCH_1):PAGE229
  U316    3     A1 74LVC2G17GW-74LVC2G17GW,SMLF,IA    I86 @S9S_MB_2U_LIB.S9S_MB_2U(SCH_1):PAGE139
  U316    2    GND 74LVC2G17GW-74LVC2G17GW,SMLF,IA    I86 @S9S_MB_2U_LIB.S9S_MB_2U(SCH_1):PAGE139
 R4548    2      B Q_RES_0402LF-100K,1%,1/16W,CHIA    I87 @S9S_MB_2U_LIB.S9S_MB_2U(SCH_1):PAGE139
 C2341    2      B Q_CAP_0402-0.1UF,25V,10%,X7R,CA    I93 @S9S_MB_2U_LIB.S9S_MB_2U(SCH_1):PAGE139
 R4555    2      B Q_RES_0402LF-4.7K,5%,1/16W,EMPA    I99 @S9S_MB_2U_LIB.S9S_MB_2U(SCH_1):PAGE139
 R2927    2      B Q_RES_0402LF-100K,1%,1/16W,CHIA   I203 @S9S_MB_2U_LIB.S9S_MB_2U(SCH_1):PAGE140
   U39   12    GND TCA9548APWR-TCA9548APWR,SMLF,IA   I103 @S9S_MB_2U_LIB.S9S_MB_2U(SCH_1):PAGE221
 C2056    2      B Q_CAP_0402-0.1UF,25V,10%,X7R,CA   I106 @S9S_MB_2U_LIB.S9S_MB_2U(SCH_1):PAGE221
 C2343    2      B Q_CAP_0402-1000PF,50V,5%,EMPTYA   I118 @S9S_MB_2U_LIB.S9S_MB_2U(SCH_1):PAGE143
  Q146    4     S2 MOSFET_NCH_DUAL-PJT138K,SMLF,IA   I121 @S9S_MB_2U_LIB.S9S_MB_2U(SCH_1):PAGE143
  Q146    1     S1 MOSFET_NCH_DUAL-PJT138K,SMLF,IA   I126 @S9S_MB_2U_LIB.S9S_MB_2U(SCH_1):PAGE143
 R4559    2      B Q_RES_0402LF-100K,1%,1/16W,CHIA   I129 @S9S_MB_2U_LIB.S9S_MB_2U(SCH_1):PAGE143
 R4564    2      B Q_RES_0402LF-10K,1%,1/16W,CHIPA   I239 @S9S_MB_2U_LIB.S9S_MB_2U(SCH_1):PAGE176
 R4565    2      B Q_RES_0402LF-10K,1%,1/16W,CHIPA   I240 @S9S_MB_2U_LIB.S9S_MB_2U(SCH_1):PAGE176
 R4568    2      B Q_RES_0402LF-4.7K,1%,1/16W,CHIA   I346 @S9S_MB_2U_LIB.S9S_MB_2U(SCH_1):PAGE239
 C2344    2      B Q_CAP_0402-0.1UF,25V,10%,X7R,CA    I87 @S9S_MB_2U_LIB.S9S_MB_2U(SCH_1):PAGE152
 C2345    2      B Q_CAP_0402-0.1UF,25V,10%,X7R,CA    I81 @S9S_MB_2U_LIB.S9S_MB_2U(SCH_1):PAGE156
 R4581    2      B Q_RES_0402LF-1K,1%,1/16W,CHIP,A     I1 @S9S_MB_2U_LIB.S9S_MB_2U(SCH_1):PAGE184
 R4583    2      B Q_RES_0402LF-1K,1%,1/16W,CHIP,A    I18 @S9S_MB_2U_LIB.S9S_MB_2U(SCH_1):PAGE184
 R4585    2      B Q_RES_0402LF-1K,1%,1/16W,CHIP,A    I20 @S9S_MB_2U_LIB.S9S_MB_2U(SCH_1):PAGE184
 R2243    2      B Q_RES_0402LF-1K,1%,1/16W,CHIP,A    I30 @S9S_MB_2U_LIB.S9S_MB_2U(SCH_1):PAGE184
 R4588    2      B Q_RES_0402LF-1K,1%,1/16W,EMPTYA    I58 @S9S_MB_2U_LIB.S9S_MB_2U(SCH_1):PAGE184
 R4590    2      B Q_RES_0402LF-1K,1%,1/16W,EMPTYA    I59 @S9S_MB_2U_LIB.S9S_MB_2U(SCH_1):PAGE184
    D6    C      C Q_LED_SMLF-LED_YELLOW,LTST-C19A   I279 @S9S_MB_2U_LIB.S9S_MB_2U(SCH_1):PAGE207
  U209   12    VSS PCA9555APW-PCA9555APW,SMLF,IC,A   I206 @S9S_MB_2U_LIB.S9S_MB_2U(SCH_1):PAGE154
   U51   12    VSS PCA9555APW-PCA9555APW,SMLF,IC,A    I66 @S9S_MB_2U_LIB.S9S_MB_2U(SCH_1):PAGE132
  Q144    4     S2 MOSFET_NCH_DUAL-PJT138K,SMLF,IA    I21 @S9S_MB_2U_LIB.S9S_MB_2U(SCH_1):PAGE213
  Q144    1     S1 MOSFET_NCH_DUAL-PJT138K,SMLF,IA    I27 @S9S_MB_2U_LIB.S9S_MB_2U(SCH_1):PAGE213
 C1243    2      B Q_CAP_C0805-47UF,6.3V,20%,X6S,A   I162 @S9S_MB_2U_LIB.S9S_MB_2U(SCH_1):PAGE181
 C1245    2      B Q_CAP_C0805-47UF,6.3V,20%,X6S,A   I163 @S9S_MB_2U_LIB.S9S_MB_2U(SCH_1):PAGE181
   U16    3    GND 74LVC1G66GV-74LVC1G66GV,SMLF,IA   I115 @S9S_MB_2U_LIB.S9S_MB_2U(SCH_1):PAGE135
 R1495    2      B Q_RES_0402LF-10K,1%,1/16W,CHIPA   I190 @S9S_MB_2U_LIB.S9S_MB_2U(SCH_1):PAGE312
  U322    3    GND 74LVC1G08W57-74LVC1G08W5-7,SMLA   I221 @S9S_MB_2U_LIB.S9S_MB_2U(SCH_1):PAGE154
 C2346    2      B Q_CAP_0402-0.1UF,25V,10%,X7R,CA   I223 @S9S_MB_2U_LIB.S9S_MB_2U(SCH_1):PAGE154
   U52    1    GND APX80929SAG7-APX809-29SAG-7,SMA   I228 @S9S_MB_2U_LIB.S9S_MB_2U(SCH_1):PAGE154
  C580    2      B Q_CAP_0402-0.1UF,25V,10%,X7R,CA   I229 @S9S_MB_2U_LIB.S9S_MB_2U(SCH_1):PAGE154
  U216    1    GND APX80929SAG7-APX809-29SAG-7,SMA    I85 @S9S_MB_2U_LIB.S9S_MB_2U(SCH_1):PAGE132
 C1819    2      B Q_CAP_0402-0.1UF,25V,10%,X7R,CA    I87 @S9S_MB_2U_LIB.S9S_MB_2U(SCH_1):PAGE132
 C2347    2      B Q_CAP_0402-0.1UF,25V,10%,X7R,CA    I90 @S9S_MB_2U_LIB.S9S_MB_2U(SCH_1):PAGE132
  U323    3    GND 74LVC1G08W57-74LVC1G08W5-7,SMLA    I92 @S9S_MB_2U_LIB.S9S_MB_2U(SCH_1):PAGE132
PC1368    1      A Q_CAP_0402-0.1UF,25V,10%,X7R,CA     I8 @S9S_MB_2U_LIB.S9S_MB_2U(SCH_1):PAGE275
PC1243_P1_2    2      B Q_CAP_C0402-2.2UF,10V,10%,X6S,A    I16 @S9S_MB_2U_LIB.S9S_MB_2U(SCH_1):PAGE275
 PR225    2      B Q_RES_0402LF-8.87K,1%,1/16W,EMA    I20 @S9S_MB_2U_LIB.S9S_MB_2U(SCH_1):PAGE275
PC1242_P1_1    2      B Q_CAP_C0402-2.2UF,10V,10%,X6S,A    I31 @S9S_MB_2U_LIB.S9S_MB_2U(SCH_1):PAGE275
PC406_P1_2    2      B Q_CAP_C0805-22UF,16V,20%,X6S,CA    I42 @S9S_MB_2U_LIB.S9S_MB_2U(SCH_1):PAGE275
PC724_P1_1    2      B Q_CAP_C0805-22UF,16V,20%,X6S,CA    I58 @S9S_MB_2U_LIB.S9S_MB_2U(SCH_1):PAGE275
 PC414    2      B Q_CAPP_THLF-560UF,2.5V,20%,OSCA    I66 @S9S_MB_2U_LIB.S9S_MB_2U(SCH_1):PAGE275
 PC415    2      B Q_CAPP_THLF-560UF,2.5V,20%,OSCA    I67 @S9S_MB_2U_LIB.S9S_MB_2U(SCH_1):PAGE275
PC410_P1_1    2      B Q_CAP_C0805-22UF,4V,20%,X6S,CHA    I74 @S9S_MB_2U_LIB.S9S_MB_2U(SCH_1):PAGE275
PC412_P1_1    2      B Q_CAP_C0805-22UF,4V,20%,X6S,CHA    I75 @S9S_MB_2U_LIB.S9S_MB_2U(SCH_1):PAGE275
PC1657    2      B Q_CAP_C0402-100NF,50V,10%,X7R,A    I77 @S9S_MB_2U_LIB.S9S_MB_2U(SCH_1):PAGE275
PC1680    2      B Q_CAP_C0805-22UF,16V,20%,X6S,CA    I85 @S9S_MB_2U_LIB.S9S_MB_2U(SCH_1):PAGE275
 PC417    2      B Q_CAPP_THLF-270UF,16V,20%,OSCOA    I87 @S9S_MB_2U_LIB.S9S_MB_2U(SCH_1):PAGE275
PU75_P1_1    2   AGND ISL99390FRZTR5935-ISL99390FRZ-A    I89 @S9S_MB_2U_LIB.S9S_MB_2U(SCH_1):PAGE275
PU75_P1_1    5  PGND1 ISL99390FRZTR5935-ISL99390FRZ-A    I89 @S9S_MB_2U_LIB.S9S_MB_2U(SCH_1):PAGE275
PU75_P1_1 7_9-20_24  PGND2 ISL99390FRZTR5935-ISL99390FRZ-A    I89 @S9S_MB_2U_LIB.S9S_MB_2U(SCH_1):PAGE275
PU75_P1_1   40  PGND3 ISL99390FRZTR5935-ISL99390FRZ-A    I89 @S9S_MB_2U_LIB.S9S_MB_2U(SCH_1):PAGE275
PC1350    1      A Q_CAP_0402-0.1UF,25V,10%,X7R,CA    I15 @S9S_MB_2U_LIB.S9S_MB_2U(SCH_1):PAGE257
 PC601    2      B Q_CAP_C0402-2.2UF,10V,10%,X6S,A    I18 @S9S_MB_2U_LIB.S9S_MB_2U(SCH_1):PAGE257
PC1212_P0_2    2      B Q_CAP_C0402-2.2UF,10V,10%,X6S,A    I21 @S9S_MB_2U_LIB.S9S_MB_2U(SCH_1):PAGE257
PC609_P0_2    2      B Q_CAP_C0805-22UF,16V,20%,X6S,CA    I31 @S9S_MB_2U_LIB.S9S_MB_2U(SCH_1):PAGE257
PC616_P0_2    2      B Q_CAP_C0805-22UF,4V,20%,X6S,CHA    I52 @S9S_MB_2U_LIB.S9S_MB_2U(SCH_1):PAGE257
 PC619    2      B Q_CAPP_THLF-560UF,2.5V,20%,OSCA    I57 @S9S_MB_2U_LIB.S9S_MB_2U(SCH_1):PAGE257
 PC620    2      B Q_CAPP_THLF-560UF,2.5V,20%,OSCA    I58 @S9S_MB_2U_LIB.S9S_MB_2U(SCH_1):PAGE257
PC1669    2      B Q_CAP_C0805-22UF,16V,20%,X6S,CA    I83 @S9S_MB_2U_LIB.S9S_MB_2U(SCH_1):PAGE257
PC1671    2      B Q_CAP_C0805-22UF,16V,20%,X6S,CA    I85 @S9S_MB_2U_LIB.S9S_MB_2U(SCH_1):PAGE257
PR3947    1      A Q_RES_0402LF-2.8K,1%,1/16W,EMPA     I6 @S9S_MB_2U_LIB.S9S_MB_2U(SCH_1):PAGE323
PR1728    2      B Q_RES_0402LF-8.87K,1%,1/16W,EMA     I1 @S9S_MB_2U_LIB.S9S_MB_2U(SCH_1):PAGE280
 PC428    2      B Q_CAP_C0402-2.2UF,10V,10%,X6S,A    I11 @S9S_MB_2U_LIB.S9S_MB_2U(SCH_1):PAGE280
PR1709    2      B Q_RES_0402LF-8.87K,1%,1/16W,EMA     I2 @S9S_MB_2U_LIB.S9S_MB_2U(SCH_1):PAGE262
PC1348    1      A Q_CAP_0402-0.1UF,25V,10%,X7R,CA    I10 @S9S_MB_2U_LIB.S9S_MB_2U(SCH_1):PAGE262
  PU42 6_7-13_15-29   GND1 RAA2213404GNPHB0-RAA2213404GNPA    I14 @S9S_MB_2U_LIB.S9S_MB_2U(SCH_1):PAGE262
  PU42   23   GND2 RAA2213404GNPHB0-RAA2213404GNPA    I14 @S9S_MB_2U_LIB.S9S_MB_2U(SCH_1):PAGE262
  PU42   26   GND3 RAA2213404GNPHB0-RAA2213404GNPA    I14 @S9S_MB_2U_LIB.S9S_MB_2U(SCH_1):PAGE262
PC1642    2      B Q_CAP_C0402-1UF,25V,10%,X6S,CHA     I4 @S9S_MB_2U_LIB.S9S_MB_2U(SCH_1):PAGE249
PC1234    2      B Q_CAP_C0402-100NF,50V,10%,X7R,A    I21 @S9S_MB_2U_LIB.S9S_MB_2U(SCH_1):PAGE249
PC1237    2      B Q_CAP_C0805-22UF,4V,20%,X6S,CHA    I29 @S9S_MB_2U_LIB.S9S_MB_2U(SCH_1):PAGE249
 C2287    2      B Q_CAP_C0402-0.01UF,50V,10%,X7RA    I36 @S9S_MB_2U_LIB.S9S_MB_2U(SCH_1):PAGE249
PC1238    2      B Q_CAP_C0805-22UF,4V,20%,X6S,CHA    I37 @S9S_MB_2U_LIB.S9S_MB_2U(SCH_1):PAGE249
PC1239    2      B Q_CAP_C0805-22UF,4V,20%,X6S,CHA    I38 @S9S_MB_2U_LIB.S9S_MB_2U(SCH_1):PAGE249
 PR214    2      B Q_RES_0402LF-1K,1%,1/16W,EMPTYA    I11 @S9S_MB_2U_LIB.S9S_MB_2U(SCH_1):PAGE282
 PR558    2      B Q_RES_0402LF-100,1%,1/16W,CHIPA    I15 @S9S_MB_2U_LIB.S9S_MB_2U(SCH_1):PAGE282
 C1336    2      B Q_CAP_C0402-10UF,6.3V,20%,X6S,B    I24 @S9S_MB_2U_LIB.S9S_MB_2U(SCH_1):PAGE282
PR4257    2      B Q_RES_0402LF-0,5%,1/16W,CHIP,CA    I59 @S9S_MB_2U_LIB.S9S_MB_2U(SCH_1):PAGE282
PR4255    2      B Q_RES_0402LF-0,5%,1/16W,CHIP,CA    I62 @S9S_MB_2U_LIB.S9S_MB_2U(SCH_1):PAGE282
PR4252    2      B Q_RES_0402LF-0,5%,1/16W,CHIP,CA    I64 @S9S_MB_2U_LIB.S9S_MB_2U(SCH_1):PAGE282
PR4253    2      B Q_RES_0402LF-0,5%,1/16W,CHIP,CA    I65 @S9S_MB_2U_LIB.S9S_MB_2U(SCH_1):PAGE282
PR4254    2      B Q_RES_0402LF-0,5%,1/16W,CHIP,CA    I66 @S9S_MB_2U_LIB.S9S_MB_2U(SCH_1):PAGE282
 PC394    2      B Q_CAP_C0402-1UF,16V,10%,X6S,CHA    I77 @S9S_MB_2U_LIB.S9S_MB_2U(SCH_1):PAGE282
 PC378    2      B Q_CAP_C0805-22UF,16V,20%,X6S,CA    I24 @S9S_MB_2U_LIB.S9S_MB_2U(SCH_1):PAGE283
PC1940    2      B Q_CAPP_SMLF-330UF,2V,35%,SPCAPA    I25 @S9S_MB_2U_LIB.S9S_MB_2U(SCH_1):PAGE283
 PC384    2      B Q_CAPP_THLF-560UF,2.5V,20%,OSCA    I26 @S9S_MB_2U_LIB.S9S_MB_2U(SCH_1):PAGE283
PR4258    2      B Q_RES_0402LF-499,1%,1/16W,CHIPA    I35 @S9S_MB_2U_LIB.S9S_MB_2U(SCH_1):PAGE283
 PR276    2      B Q_RES_0402LF-1K,1%,1/16W,EMPTYA    I35 @S9S_MB_2U_LIB.S9S_MB_2U(SCH_1):PAGE278
 PC474    2      B Q_CAP_0402-0.1UF,25V,10%,X7R,CA    I36 @S9S_MB_2U_LIB.S9S_MB_2U(SCH_1):PAGE278
  PU22   TH TH_GND ISL69260IRAZT-ISL69260IRAZ-T,SA    I38 @S9S_MB_2U_LIB.S9S_MB_2U(SCH_1):PAGE278
 PR567    2      B Q_RES_0402LF-100,1%,1/16W,CHIPA    I41 @S9S_MB_2U_LIB.S9S_MB_2U(SCH_1):PAGE278
 PR566    2      B Q_RES_0402LF-100,1%,1/16W,CHIPA    I46 @S9S_MB_2U_LIB.S9S_MB_2U(SCH_1):PAGE278
 C2451    2      B Q_CAP_0402-1000PF,50V,5%,X7R,TA    I63 @S9S_MB_2U_LIB.S9S_MB_2U(SCH_1):PAGE278
 PR665    2      B Q_RES_0402LF-10K,1%,1/16W,EMPTA    I67 @S9S_MB_2U_LIB.S9S_MB_2U(SCH_1):PAGE278
 PR667    2      B Q_RES_0402LF-10K,1%,1/16W,EMPTA    I75 @S9S_MB_2U_LIB.S9S_MB_2U(SCH_1):PAGE278
PR4242    2      B Q_RES_0402LF-0,5%,1/16W,CHIP,CA    I89 @S9S_MB_2U_LIB.S9S_MB_2U(SCH_1):PAGE278
 PC477    2      B Q_CAP_C0402-10UF,6.3V,20%,X6S,B    I92 @S9S_MB_2U_LIB.S9S_MB_2U(SCH_1):PAGE278
PC1193    2      B Q_CAP_C0402-1UF,16V,10%,X6S,CHA    I96 @S9S_MB_2U_LIB.S9S_MB_2U(SCH_1):PAGE278
 C2450    2      B Q_CAP_0402-1000PF,50V,5%,EMPTYA   I106 @S9S_MB_2U_LIB.S9S_MB_2U(SCH_1):PAGE278
PU12_P0_2    2   AGND ISL99390FRZTR5935-ISL99390FRZ-A     I6 @S9S_MB_2U_LIB.S9S_MB_2U(SCH_1):PAGE253
PU12_P0_2    5  PGND1 ISL99390FRZTR5935-ISL99390FRZ-A     I6 @S9S_MB_2U_LIB.S9S_MB_2U(SCH_1):PAGE253
PU12_P0_2 7_9-20_24  PGND2 ISL99390FRZTR5935-ISL99390FRZ-A     I6 @S9S_MB_2U_LIB.S9S_MB_2U(SCH_1):PAGE253
PU12_P0_2   40  PGND3 ISL99390FRZTR5935-ISL99390FRZ-A     I6 @S9S_MB_2U_LIB.S9S_MB_2U(SCH_1):PAGE253
 PC292    2      B Q_CAP_C0402-2.2UF,10V,10%,X6S,A     I9 @S9S_MB_2U_LIB.S9S_MB_2U(SCH_1):PAGE253
PC294_P0_2    2      B Q_CAP_C0402-2.2UF,10V,10%,X6S,A    I15 @S9S_MB_2U_LIB.S9S_MB_2U(SCH_1):PAGE253
PC302_P0_2    2      B Q_CAP_C0805-22UF,16V,20%,X6S,CA    I23 @S9S_MB_2U_LIB.S9S_MB_2U(SCH_1):PAGE253
 PR151    2      B Q_RES_0402LF-8.87K,1%,1/16W,EMA    I29 @S9S_MB_2U_LIB.S9S_MB_2U(SCH_1):PAGE253
PC297_P0_1    2      B Q_CAP_0402-3300PF,50V,10%,X7R,A    I44 @S9S_MB_2U_LIB.S9S_MB_2U(SCH_1):PAGE253
PC299_P0_1    2      B Q_CAP_C0402-1UF,16V,10%,X6S,CHA    I47 @S9S_MB_2U_LIB.S9S_MB_2U(SCH_1):PAGE253
PC311_P0_2    2      B Q_CAP_C0805-22UF,4V,20%,X6S,CHA    I57 @S9S_MB_2U_LIB.S9S_MB_2U(SCH_1):PAGE253
PC313_P0_2    2      B Q_CAP_C0805-22UF,4V,20%,X6S,CHA    I58 @S9S_MB_2U_LIB.S9S_MB_2U(SCH_1):PAGE253
PC2336    2      B Q_CAPP_SMLF-330UF,2.5V,+10/-35A    I60 @S9S_MB_2U_LIB.S9S_MB_2U(SCH_1):PAGE253
PC1652    2      B Q_CAP_C0402-100NF,50V,10%,X7R,A    I80 @S9S_MB_2U_LIB.S9S_MB_2U(SCH_1):PAGE253
PC308_P0_1    2      B Q_CAP_C0402-100NF,50V,10%,X7R,A    I83 @S9S_MB_2U_LIB.S9S_MB_2U(SCH_1):PAGE253
PC312_P0_1    2      B Q_CAP_C0805-22UF,4V,20%,X6S,CHA    I85 @S9S_MB_2U_LIB.S9S_MB_2U(SCH_1):PAGE253
 PC321    2      B Q_CAPP_THLF-270UF,16V,20%,OSCOA    I93 @S9S_MB_2U_LIB.S9S_MB_2U(SCH_1):PAGE253
 PC324    2      B Q_CAPP_THLF-270UF,16V,20%,OSCOA    I94 @S9S_MB_2U_LIB.S9S_MB_2U(SCH_1):PAGE253
PU69_P0_1    2   AGND ISL99390FRZTR5935-ISL99390FRZ-A    I25 @S9S_MB_2U_LIB.S9S_MB_2U(SCH_1):PAGE257
PU69_P0_1    5  PGND1 ISL99390FRZTR5935-ISL99390FRZ-A    I25 @S9S_MB_2U_LIB.S9S_MB_2U(SCH_1):PAGE257
PU69_P0_1 7_9-20_24  PGND2 ISL99390FRZTR5935-ISL99390FRZ-A    I25 @S9S_MB_2U_LIB.S9S_MB_2U(SCH_1):PAGE257
PU69_P0_1   40  PGND3 ISL99390FRZTR5935-ISL99390FRZ-A    I25 @S9S_MB_2U_LIB.S9S_MB_2U(SCH_1):PAGE257
PC605_P0_2    2      B Q_CAP_C0402-1UF,16V,10%,X6S,CHA    I28 @S9S_MB_2U_LIB.S9S_MB_2U(SCH_1):PAGE257
PC611_P0_2    2      B Q_CAP_C0805-22UF,16V,20%,X6S,CA    I32 @S9S_MB_2U_LIB.S9S_MB_2U(SCH_1):PAGE257
PC1349    1      A Q_CAP_0402-0.1UF,25V,10%,X7R,CA    I35 @S9S_MB_2U_LIB.S9S_MB_2U(SCH_1):PAGE257
 PC600    2      B Q_CAP_C0402-2.2UF,10V,10%,X6S,A    I37 @S9S_MB_2U_LIB.S9S_MB_2U(SCH_1):PAGE257
PC1211_P0_1    2      B Q_CAP_C0402-2.2UF,10V,10%,X6S,A    I42 @S9S_MB_2U_LIB.S9S_MB_2U(SCH_1):PAGE257
PC721_P0_2    2      B Q_CAP_C0805-22UF,16V,20%,X6S,CA    I55 @S9S_MB_2U_LIB.S9S_MB_2U(SCH_1):PAGE257
PR4265    2      B Q_RES_0402LF-499,1%,1/16W,CHIPA    I60 @S9S_MB_2U_LIB.S9S_MB_2U(SCH_1):PAGE257
 PC623    2      B Q_CAPP_SMLF-330UF,2.5V,+10/-35B    I63 @S9S_MB_2U_LIB.S9S_MB_2U(SCH_1):PAGE257
PC2645    2      B Q_CAPP_SMLF-330UF,2.5V,+10/-35B    I67 @S9S_MB_2U_LIB.S9S_MB_2U(SCH_1):PAGE257
PC720_P0_1    2      B Q_CAP_C0805-22UF,16V,20%,X6S,CA    I73 @S9S_MB_2U_LIB.S9S_MB_2U(SCH_1):PAGE257
PC612_P0_1    2      B Q_CAP_C0402-100NF,50V,10%,X7R,A    I75 @S9S_MB_2U_LIB.S9S_MB_2U(SCH_1):PAGE257
PC1653    2      B Q_CAP_C0402-100NF,50V,10%,X7R,A    I78 @S9S_MB_2U_LIB.S9S_MB_2U(SCH_1):PAGE257
PC617_P0_1    2      B Q_CAP_C0805-22UF,4V,20%,X6S,CHA    I81 @S9S_MB_2U_LIB.S9S_MB_2U(SCH_1):PAGE257
PC1672    2      B Q_CAP_C0805-22UF,16V,20%,X6S,CA    I86 @S9S_MB_2U_LIB.S9S_MB_2U(SCH_1):PAGE257
 PC622    2      B Q_CAPP_THLF-270UF,16V,20%,OSCOA    I88 @S9S_MB_2U_LIB.S9S_MB_2U(SCH_1):PAGE257
PR1297    2      B Q_RES_0402LF-8.87K,1%,1/16W,EMA     I3 @S9S_MB_2U_LIB.S9S_MB_2U(SCH_1):PAGE258
PC1352    1      A Q_CAP_0402-0.1UF,25V,10%,X7R,CA     I9 @S9S_MB_2U_LIB.S9S_MB_2U(SCH_1):PAGE258
PU72_P0_4    2   AGND ISL99390FRZTR5935-ISL99390FRZ-A    I10 @S9S_MB_2U_LIB.S9S_MB_2U(SCH_1):PAGE258
PU72_P0_4    5  PGND1 ISL99390FRZTR5935-ISL99390FRZ-A    I10 @S9S_MB_2U_LIB.S9S_MB_2U(SCH_1):PAGE258
PU72_P0_4 7_9-20_24  PGND2 ISL99390FRZTR5935-ISL99390FRZ-A    I10 @S9S_MB_2U_LIB.S9S_MB_2U(SCH_1):PAGE258
PU72_P0_4   40  PGND3 ISL99390FRZTR5935-ISL99390FRZ-A    I10 @S9S_MB_2U_LIB.S9S_MB_2U(SCH_1):PAGE258
PC1172    2      B Q_CAP_C0402-2.2UF,10V,10%,X6S,A    I13 @S9S_MB_2U_LIB.S9S_MB_2U(SCH_1):PAGE258
PC1214_P0_4    2      B Q_CAP_C0402-2.2UF,10V,10%,X6S,A    I18 @S9S_MB_2U_LIB.S9S_MB_2U(SCH_1):PAGE258
PC1213_P0_3    2      B Q_CAP_C0402-2.2UF,10V,10%,X6S,A    I28 @S9S_MB_2U_LIB.S9S_MB_2U(SCH_1):PAGE258
PC1176_P0_4    2      B Q_CAP_C0402-1UF,16V,10%,X6S,CHA    I34 @S9S_MB_2U_LIB.S9S_MB_2U(SCH_1):PAGE258
PC1180_P0_4    2      B Q_CAP_C0805-22UF,16V,20%,X6S,CA    I35 @S9S_MB_2U_LIB.S9S_MB_2U(SCH_1):PAGE258
PC1179_P0_3    2      B Q_CAP_C0805-22UF,16V,20%,X6S,CA    I47 @S9S_MB_2U_LIB.S9S_MB_2U(SCH_1):PAGE258
PC722_P0_3    2      B Q_CAP_C0805-22UF,16V,20%,X6S,CA    I53 @S9S_MB_2U_LIB.S9S_MB_2U(SCH_1):PAGE258
PC1183    2      B Q_CAPP_THLF-560UF,2.5V,20%,OSCA    I64 @S9S_MB_2U_LIB.S9S_MB_2U(SCH_1):PAGE258
PC1185    2      B Q_CAPP_THLF-560UF,2.5V,20%,OSCA    I65 @S9S_MB_2U_LIB.S9S_MB_2U(SCH_1):PAGE258
PC1187    2      B Q_CAPP_SMLF-330UF,2.5V,+10/-35B    I69 @S9S_MB_2U_LIB.S9S_MB_2U(SCH_1):PAGE258
PC2170    2      B Q_CAPP_SMLF-330UF,2.5V,+10/-35B    I70 @S9S_MB_2U_LIB.S9S_MB_2U(SCH_1):PAGE258
PC1187_P0_3    2      B Q_CAP_C0805-22UF,4V,20%,X6S,CHA    I73 @S9S_MB_2U_LIB.S9S_MB_2U(SCH_1):PAGE258
PC1676    2      B Q_CAP_C0805-22UF,16V,20%,X6S,CA    I79 @S9S_MB_2U_LIB.S9S_MB_2U(SCH_1):PAGE258
PR1707    2      B Q_RES_0402LF-8.87K,1%,1/16W,EMA     I2 @S9S_MB_2U_LIB.S9S_MB_2U(SCH_1):PAGE261
PR1708    2      B Q_RES_0402LF-8.87K,1%,1/16W,EMA     I5 @S9S_MB_2U_LIB.S9S_MB_2U(SCH_1):PAGE261
PC1346    1      A Q_CAP_0402-0.1UF,25V,10%,X7R,CA    I11 @S9S_MB_2U_LIB.S9S_MB_2U(SCH_1):PAGE261
 PC188    2      B Q_CAP_C0402-2.2UF,10V,10%,X6S,A    I13 @S9S_MB_2U_LIB.S9S_MB_2U(SCH_1):PAGE261
PC2946    2      B Q_CAP_C0402-2.2UF,10V,10%,X6S,A    I16 @S9S_MB_2U_LIB.S9S_MB_2U(SCH_1):PAGE261
 PC187    2      B Q_CAP_C0402-2.2UF,10V,10%,X6S,A    I24 @S9S_MB_2U_LIB.S9S_MB_2U(SCH_1):PAGE261
PC199_P0_1    2      B Q_CAP_C0402-100NF,50V,10%,X7R,A    I54 @S9S_MB_2U_LIB.S9S_MB_2U(SCH_1):PAGE261
PC204_P0_1    2      B Q_CAP_C0805-22UF,4V,20%,X6S,CHA    I57 @S9S_MB_2U_LIB.S9S_MB_2U(SCH_1):PAGE261
PR4226    2      B Q_RES_0402LF-499,1%,1/16W,CHIPA    I63 @S9S_MB_2U_LIB.S9S_MB_2U(SCH_1):PAGE261
PC1579    2      B Q_CAPP_THLF-560UF,2.5V,20%,OSCA    I70 @S9S_MB_2U_LIB.S9S_MB_2U(SCH_1):PAGE261
PC1354    1      A Q_CAP_0402-0.1UF,25V,10%,X7R,CA     I7 @S9S_MB_2U_LIB.S9S_MB_2U(SCH_1):PAGE265
PU30_P1_2    2   AGND ISL99390FRZTR5935-ISL99390FRZ-A     I7 @S9S_MB_2U_LIB.S9S_MB_2U(SCH_1):PAGE271
PU30_P1_2    5  PGND1 ISL99390FRZTR5935-ISL99390FRZ-A     I7 @S9S_MB_2U_LIB.S9S_MB_2U(SCH_1):PAGE271
PU30_P1_2 7_9-20_24  PGND2 ISL99390FRZTR5935-ISL99390FRZ-A     I7 @S9S_MB_2U_LIB.S9S_MB_2U(SCH_1):PAGE271
PU30_P1_2   40  PGND3 ISL99390FRZTR5935-ISL99390FRZ-A     I7 @S9S_MB_2U_LIB.S9S_MB_2U(SCH_1):PAGE271
PC1339    1      A Q_CAP_0402-0.1UF,25V,10%,X7R,CA    I34 @S9S_MB_2U_LIB.S9S_MB_2U(SCH_1):PAGE271
 PC557    2      B Q_CAP_C0402-2.2UF,10V,10%,X6S,A    I36 @S9S_MB_2U_LIB.S9S_MB_2U(SCH_1):PAGE271
PC561_P1_1    2      B Q_CAP_0402-3300PF,50V,10%,X7R,A    I44 @S9S_MB_2U_LIB.S9S_MB_2U(SCH_1):PAGE271
PC570_P1_2    2      B Q_CAP_C0805-22UF,16V,20%,X6S,CA    I53 @S9S_MB_2U_LIB.S9S_MB_2U(SCH_1):PAGE271
 PC583    2      B Q_CAPP_THLF-560UF,2.5V,20%,OSCA    I64 @S9S_MB_2U_LIB.S9S_MB_2U(SCH_1):PAGE271
 PC590    2      B Q_CAPP_SMLF-330UF,2.5V,+10/-35A    I68 @S9S_MB_2U_LIB.S9S_MB_2U(SCH_1):PAGE271
PC571_P1_1    2      B Q_CAP_C0805-22UF,16V,20%,X6S,CA    I76 @S9S_MB_2U_LIB.S9S_MB_2U(SCH_1):PAGE271
 PC579    2      B Q_CAPP_THLF-270UF,16V,20%,OSCOA    I86 @S9S_MB_2U_LIB.S9S_MB_2U(SCH_1):PAGE271
 PC585    2      B Q_CAPP_THLF-270UF,16V,20%,OSCOA    I92 @S9S_MB_2U_LIB.S9S_MB_2U(SCH_1):PAGE271
 PC588    2      B Q_CAPP_THLF-270UF,16V,20%,OSCOA    I94 @S9S_MB_2U_LIB.S9S_MB_2U(SCH_1):PAGE271
PR1305    2      B Q_RES_0402LF-8.87K,1%,1/16W,EMA     I5 @S9S_MB_2U_LIB.S9S_MB_2U(SCH_1):PAGE276
PC1192    2      B Q_CAP_C0402-2.2UF,10V,10%,X6S,A    I12 @S9S_MB_2U_LIB.S9S_MB_2U(SCH_1):PAGE276
PC1370    1      A Q_CAP_0402-0.1UF,25V,10%,X7R,CA    I13 @S9S_MB_2U_LIB.S9S_MB_2U(SCH_1):PAGE276
PC1245_P1_4    2      B Q_CAP_C0402-2.2UF,10V,10%,X6S,A    I20 @S9S_MB_2U_LIB.S9S_MB_2U(SCH_1):PAGE276
PC1203_P1_4    2      B Q_CAP_C0402-100NF,50V,10%,X7R,A    I47 @S9S_MB_2U_LIB.S9S_MB_2U(SCH_1):PAGE276
PC1207_P1_4    2      B Q_CAP_C0805-22UF,4V,20%,X6S,CHA    I48 @S9S_MB_2U_LIB.S9S_MB_2U(SCH_1):PAGE276
PC726_P1_3    2      B Q_CAP_C0805-22UF,16V,20%,X6S,CA    I60 @S9S_MB_2U_LIB.S9S_MB_2U(SCH_1):PAGE276
PC1658    2      B Q_CAP_C0402-100NF,50V,10%,X7R,A    I62 @S9S_MB_2U_LIB.S9S_MB_2U(SCH_1):PAGE276
PC2171    2      B Q_CAPP_SMLF-330UF,2.5V,+10/-35B    I73 @S9S_MB_2U_LIB.S9S_MB_2U(SCH_1):PAGE276
PC1681    2      B Q_CAP_C0805-22UF,16V,20%,X6S,CA    I75 @S9S_MB_2U_LIB.S9S_MB_2U(SCH_1):PAGE276
PC1683    2      B Q_CAP_C0805-22UF,16V,20%,X6S,CA    I78 @S9S_MB_2U_LIB.S9S_MB_2U(SCH_1):PAGE276
PC1210    2      B Q_CAPP_THLF-270UF,16V,20%,OSCOA    I81 @S9S_MB_2U_LIB.S9S_MB_2U(SCH_1):PAGE276
PR1727    2      B Q_RES_0402LF-8.87K,1%,1/16W,EMA     I3 @S9S_MB_2U_LIB.S9S_MB_2U(SCH_1):PAGE279
PC1365    1      A Q_CAP_0402-0.1UF,25V,10%,X7R,CA     I6 @S9S_MB_2U_LIB.S9S_MB_2U(SCH_1):PAGE279
PC2949    2      B Q_CAP_C0402-2.2UF,10V,10%,X6S,A    I13 @S9S_MB_2U_LIB.S9S_MB_2U(SCH_1):PAGE279
PC1364    1      A Q_CAP_0402-0.1UF,25V,10%,X7R,CA    I20 @S9S_MB_2U_LIB.S9S_MB_2U(SCH_1):PAGE279
PC2950    2      B Q_CAP_C0402-2.2UF,10V,10%,X6S,A    I26 @S9S_MB_2U_LIB.S9S_MB_2U(SCH_1):PAGE279
PC452_P1_1    2      B Q_CAP_C0402-100NF,50V,10%,X7R,A    I55 @S9S_MB_2U_LIB.S9S_MB_2U(SCH_1):PAGE279
PC457_P1_1    2      B Q_CAP_C0805-22UF,4V,20%,X6S,CHA    I65 @S9S_MB_2U_LIB.S9S_MB_2U(SCH_1):PAGE279
PC1596    2      B Q_CAPP_THLF-560UF,2.5V,20%,OSCA    I71 @S9S_MB_2U_LIB.S9S_MB_2U(SCH_1):PAGE279
PR4249    2      B Q_RES_0402LF-0,5%,1/16W,EMPTY,A    I18 @S9S_MB_2U_LIB.S9S_MB_2U(SCH_1):PAGE280
PC1930    2      B Q_CAPP_SMLF-330UF,2.5V,+10/-35B    I33 @S9S_MB_2U_LIB.S9S_MB_2U(SCH_1):PAGE280
PR4250    2      B Q_RES_0402LF-499,1%,1/16W,CHIPA    I37 @S9S_MB_2U_LIB.S9S_MB_2U(SCH_1):PAGE280
 PR369    2      B Q_RES_0402LF-1K,1%,1/16W,EMPTYA     I7 @S9S_MB_2U_LIB.S9S_MB_2U(SCH_1):PAGE264
 PC624    2      B Q_CAP_0402-0.1UF,25V,10%,X7R,CA     I9 @S9S_MB_2U_LIB.S9S_MB_2U(SCH_1):PAGE264
 C2443    2      B Q_CAP_C0402-10UF,6.3V,20%,X6S,B    I18 @S9S_MB_2U_LIB.S9S_MB_2U(SCH_1):PAGE264
 C2444    2      B Q_CAP_0402-0.1UF,25V,10%,X7R,CA    I19 @S9S_MB_2U_LIB.S9S_MB_2U(SCH_1):PAGE264
 PC631    2      B Q_CAP_0402-470PF,50V,10%,X7R,TA    I56 @S9S_MB_2U_LIB.S9S_MB_2U(SCH_1):PAGE264
PR4231    2      B Q_RES_0402LF-0,5%,1/16W,CHIP,CA    I69 @S9S_MB_2U_LIB.S9S_MB_2U(SCH_1):PAGE264
 PC630    2      B Q_CAP_C0402-10UF,6.3V,20%,X6S,B    I70 @S9S_MB_2U_LIB.S9S_MB_2U(SCH_1):PAGE264
PC1196    2      B Q_CAP_C0402-1UF,16V,10%,X6S,CHA    I71 @S9S_MB_2U_LIB.S9S_MB_2U(SCH_1):PAGE264
 PC632    2      B Q_CAP_C0402-1UF,16V,10%,X6S,CHA    I73 @S9S_MB_2U_LIB.S9S_MB_2U(SCH_1):PAGE264
PR4230    2      B Q_RES_0402LF-0,5%,1/16W,CHIP,CA    I74 @S9S_MB_2U_LIB.S9S_MB_2U(SCH_1):PAGE264
 PR171    2      B Q_RES_0402LF-0,5%,1/16W,CHIP,CA     I8 @S9S_MB_2U_LIB.S9S_MB_2U(SCH_1):PAGE252
 PR527    2      B Q_RES_0402LF-100,1%,1/16W,CHIPA    I26 @S9S_MB_2U_LIB.S9S_MB_2U(SCH_1):PAGE252
  PJP1    2      2 CONN3_210HP1030BR1-CONN3_210-HB    I32 @S9S_MB_2U_LIB.S9S_MB_2U(SCH_1):PAGE252
 PC329    2      B Q_CAP_0402-0.1UF,25V,10%,EMPTYA    I53 @S9S_MB_2U_LIB.S9S_MB_2U(SCH_1):PAGE252
 C3269    2      B Q_CAP_0402-1000PF,50V,5%,EMPTYA    I57 @S9S_MB_2U_LIB.S9S_MB_2U(SCH_1):PAGE252
 PC336    2      B Q_CAP_0402-470PF,50V,10%,X7R,TA    I70 @S9S_MB_2U_LIB.S9S_MB_2U(SCH_1):PAGE252
 PR400    2      B Q_RES_0402LF-10K,1%,1/16W,EMPTA    I72 @S9S_MB_2U_LIB.S9S_MB_2U(SCH_1):PAGE252
PR4218    2      B Q_RES_0402LF-0,5%,1/16W,EMPTY,A    I73 @S9S_MB_2U_LIB.S9S_MB_2U(SCH_1):PAGE252
 C3267    2      B Q_CAP_0402-1000PF,50V,5%,X7R,TA    I82 @S9S_MB_2U_LIB.S9S_MB_2U(SCH_1):PAGE252
 C3266    2      B Q_CAP_0402-1000PF,50V,5%,EMPTYA    I84 @S9S_MB_2U_LIB.S9S_MB_2U(SCH_1):PAGE252
PC1173    2      B Q_CAP_C0402-1UF,16V,10%,X6S,CHA    I87 @S9S_MB_2U_LIB.S9S_MB_2U(SCH_1):PAGE252
 PC334    2      B Q_CAP_0402-0.1UF,25V,10%,EMPTYA    I88 @S9S_MB_2U_LIB.S9S_MB_2U(SCH_1):PAGE252
 PC337    2      B Q_CAP_C0402-1UF,16V,10%,X6S,CHA    I89 @S9S_MB_2U_LIB.S9S_MB_2U(SCH_1):PAGE252
 PC100    2      B Q_CAP_0402-470PF,50V,10%,X7R,TA   I116 @S9S_MB_2U_LIB.S9S_MB_2U(SCH_1):PAGE252
 PR451    2      B Q_RES_0402LF-10K,1%,1/16W,EMPTA   I121 @S9S_MB_2U_LIB.S9S_MB_2U(SCH_1):PAGE252
 C3270    2      B Q_CAP_C0603-10UF,4V,20%,EMPTY,A   I127 @S9S_MB_2U_LIB.S9S_MB_2U(SCH_1):PAGE252
 C3271    2      B Q_CAP_C0402-100NF,50V,10%,X7R,A   I128 @S9S_MB_2U_LIB.S9S_MB_2U(SCH_1):PAGE252
 PR318    2      B Q_RES_0402LF-5.23K,1%,1/16W,CHA     I6 @S9S_MB_2U_LIB.S9S_MB_2U(SCH_1):PAGE270
 PR305    2      B Q_RES_0402LF-0,5%,1/16W,CHIP,CA    I27 @S9S_MB_2U_LIB.S9S_MB_2U(SCH_1):PAGE270
  PU29   TH TH_GND RAA229126GNPHA0-RAA229126GNP#HA    I33 @S9S_MB_2U_LIB.S9S_MB_2U(SCH_1):PAGE270
 PR574    2      B Q_RES_0402LF-100,1%,1/16W,CHIPA    I45 @S9S_MB_2U_LIB.S9S_MB_2U(SCH_1):PAGE270
 PC554    2      B Q_CAP_0402-470PF,50V,10%,X7R,TA    I72 @S9S_MB_2U_LIB.S9S_MB_2U(SCH_1):PAGE270
PR4239    2      B Q_RES_0402LF-0,5%,1/16W,EMPTY,A    I80 @S9S_MB_2U_LIB.S9S_MB_2U(SCH_1):PAGE270
 PC101    2      B Q_CAP_0402-470PF,50V,10%,X7R,TA    I92 @S9S_MB_2U_LIB.S9S_MB_2U(SCH_1):PAGE270
 PR453    2      B Q_RES_0402LF-10K,1%,1/16W,EMPTA    I94 @S9S_MB_2U_LIB.S9S_MB_2U(SCH_1):PAGE270
 C2448    2      B Q_CAP_C0603-10UF,4V,20%,EMPTY,A   I103 @S9S_MB_2U_LIB.S9S_MB_2U(SCH_1):PAGE270
 PC553    2      B Q_CAP_C0402-10UF,6.3V,20%,X6S,B   I119 @S9S_MB_2U_LIB.S9S_MB_2U(SCH_1):PAGE270
PR4220    2      B Q_RES_0402LF-0,5%,1/16W,CHIP,CA    I19 @S9S_MB_2U_LIB.S9S_MB_2U(SCH_1):PAGE260
 PC214    2      B Q_CAP_0402-0.1UF,25V,10%,EMPTYA    I20 @S9S_MB_2U_LIB.S9S_MB_2U(SCH_1):PAGE260
 PR123    2      B Q_RES_0402LF-1K,1%,1/16W,EMPTYA    I21 @S9S_MB_2U_LIB.S9S_MB_2U(SCH_1):PAGE260
 C3276    2      B Q_CAP_0402-1000PF,50V,5%,EMPTYA    I22 @S9S_MB_2U_LIB.S9S_MB_2U(SCH_1):PAGE260
 PR520    2      B Q_RES_0402LF-100,1%,1/16W,CHIPA    I38 @S9S_MB_2U_LIB.S9S_MB_2U(SCH_1):PAGE260
 PR519    2      B Q_RES_0402LF-100,1%,1/16W,CHIPA    I42 @S9S_MB_2U_LIB.S9S_MB_2U(SCH_1):PAGE260
 PC222    2      B Q_CAP_0402-470PF,50V,10%,X7R,TA    I69 @S9S_MB_2U_LIB.S9S_MB_2U(SCH_1):PAGE260
 PR435    2      B Q_RES_0402LF-10K,1%,1/16W,EMPTA    I71 @S9S_MB_2U_LIB.S9S_MB_2U(SCH_1):PAGE260
PC1271    2      B Q_CAP_0402-470PF,50V,10%,X7R,TA    I73 @S9S_MB_2U_LIB.S9S_MB_2U(SCH_1):PAGE260
PR4225    2      B Q_RES_0402LF-0,5%,1/16W,CHIP,CA    I76 @S9S_MB_2U_LIB.S9S_MB_2U(SCH_1):PAGE260
PR4221    2      B Q_RES_0402LF-0,5%,1/16W,CHIP,CA    I87 @S9S_MB_2U_LIB.S9S_MB_2U(SCH_1):PAGE260
PC1372    2      B Q_CAP_C0402-1UF,16V,10%,X6S,CHA    I95 @S9S_MB_2U_LIB.S9S_MB_2U(SCH_1):PAGE260
 PC223    2      B Q_CAP_C0402-100NF,50V,10%,EMPTA    I98 @S9S_MB_2U_LIB.S9S_MB_2U(SCH_1):PAGE260
 PC225    2      B Q_CAP_C0402-1UF,16V,10%,X6S,CHA    I99 @S9S_MB_2U_LIB.S9S_MB_2U(SCH_1):PAGE260
 PR436    2      B Q_RES_0402LF-10K,1%,1/16W,EMPTA   I106 @S9S_MB_2U_LIB.S9S_MB_2U(SCH_1):PAGE260
  U324    S      S MOSFET_NCH_GDS_ESD_PROTECTED-2A    I67 @S9S_MB_2U_LIB.S9S_MB_2U(SCH_1):PAGE246
 R4622    2      B Q_RES_0402LF-2K,1%,1/16W,CHIP,A    I66 @S9S_MB_2U_LIB.S9S_MB_2U(SCH_1):PAGE208
 PR358    1      A Q_RES_0402LF-3.57K,1%,1/16W,CHA    I95 @S9S_MB_2U_LIB.S9S_MB_2U(SCH_1):PAGE264
 PR259    2      B Q_RES_0402LF-8.45K,1%,1/16W,CHA   I110 @S9S_MB_2U_LIB.S9S_MB_2U(SCH_1):PAGE278
 PR106    2      B Q_RES_0402LF-681,1%,1/16W,CHIPA   I109 @S9S_MB_2U_LIB.S9S_MB_2U(SCH_1):PAGE260
 PR203    1      A Q_RES_0402LF-24.3K,1%,1/16W,CHA    I95 @S9S_MB_2U_LIB.S9S_MB_2U(SCH_1):PAGE282
  U321    3    GND 74LVC1G66GV-74LVC1G66GV,SMLF,IA    I92 @S9S_MB_2U_LIB.S9S_MB_2U(SCH_1):PAGE156
  U320    3    GND 74LVC1G66GV-74LVC1G66GV,SMLF,IA    I92 @S9S_MB_2U_LIB.S9S_MB_2U(SCH_1):PAGE152
 C1226    2      B Q_CAP_C0402-0.22UF,25V,10%,X7RA    I68 @S9S_MB_2U_LIB.S9S_MB_2U(SCH_1):PAGE246
   Q37    1     S1 MOSFET_NCH_DUAL-PJT138K,SMLF,IA    I69 @S9S_MB_2U_LIB.S9S_MB_2U(SCH_1):PAGE246
   Q15    1     S1 MOSFET_NCH_DUAL-PJT138K,SMLF,IA   I104 @S9S_MB_2U_LIB.S9S_MB_2U(SCH_1):PAGE223
   Q16    1     S1 MOSFET_NCH_DUAL-PJT138K,SMLF,IA   I106 @S9S_MB_2U_LIB.S9S_MB_2U(SCH_1):PAGE223
   Q37    4     S2 MOSFET_NCH_DUAL-PJT138K,SMLF,IA    I76 @S9S_MB_2U_LIB.S9S_MB_2U(SCH_1):PAGE246
   Q15    4     S2 MOSFET_NCH_DUAL-PJT138K,SMLF,IA   I108 @S9S_MB_2U_LIB.S9S_MB_2U(SCH_1):PAGE223
   Q16    4     S2 MOSFET_NCH_DUAL-PJT138K,SMLF,IA   I109 @S9S_MB_2U_LIB.S9S_MB_2U(SCH_1):PAGE223
   Q95    1     S1 MOSFET_NCH_DUAL-PJT138K,SMLF,IA   I342 @S9S_MB_2U_LIB.S9S_MB_2U(SCH_1):PAGE182
PR1327    2      B Q_RES_0402LF-8.45K,1%,1/16W,CHA     I6 @S9S_MB_2U_LIB.S9S_MB_2U(SCH_1):PAGE248
  PU73    2   AGND RS53319LR-RS53319LR,SMLF,IC,ALA    I11 @S9S_MB_2U_LIB.S9S_MB_2U(SCH_1):PAGE248
  PU73 11_18   PGND RS53319LR-RS53319LR,SMLF,IC,ALA    I11 @S9S_MB_2U_LIB.S9S_MB_2U(SCH_1):PAGE248
PC1650    2      B Q_CAP_C0402-100NF,50V,10%,X7R,A    I18 @S9S_MB_2U_LIB.S9S_MB_2U(SCH_1):PAGE248
PC1217    2      B Q_CAP_C0805-22UF,16V,20%,X6S,CA    I28 @S9S_MB_2U_LIB.S9S_MB_2U(SCH_1):PAGE248
PC1229    2      B Q_CAPP_SMLF-330UF,2V,35%,SPCAPA    I47 @S9S_MB_2U_LIB.S9S_MB_2U(SCH_1):PAGE248
 PC831    2      B Q_CAP_C0805-22UF,16V,20%,X6S,CA     I7 @S9S_MB_2U_LIB.S9S_MB_2U(SCH_1):PAGE267
PC2001    2      B Q_CAP_0402-0.022UF,16V,10%,X7RA    I23 @S9S_MB_2U_LIB.S9S_MB_2U(SCH_1):PAGE267
PC1256    2      B Q_CAP_C0805-22UF,4V,20%,X6S,CHA    I43 @S9S_MB_2U_LIB.S9S_MB_2U(SCH_1):PAGE267
PC1420    2      B Q_CAP_0402-0.01UF,25V,10%,X7R,A    I39 @S9S_MB_2U_LIB.S9S_MB_2U(SCH_1):PAGE268
PR1339    2      B Q_RES_0402LF-9.76K,1%,1/16W,CHA    I10 @S9S_MB_2U_LIB.S9S_MB_2U(SCH_1):PAGE285
PC1261    2      B Q_CAP_C0805-22UF,16V,20%,X6S,CA    I16 @S9S_MB_2U_LIB.S9S_MB_2U(SCH_1):PAGE285
PC1269    2      B Q_CAP_C0805-22UF,4V,20%,X6S,CHA    I41 @S9S_MB_2U_LIB.S9S_MB_2U(SCH_1):PAGE285
 C2036    2      B Q_CAP_C0402-8.2PF,50V,0.1P,NP0A   I393 @S9S_MB_2U_LIB.S9S_MB_2U(SCH_1):PAGE197
 C2037    2      B Q_CAP_C0402-8.2PF,50V,0.1P,NP0A   I394 @S9S_MB_2U_LIB.S9S_MB_2U(SCH_1):PAGE197
 C2363    2      B Q_CAP_0402-0.1UF,25V,10%,EMPTYA    I15 @S9S_MB_2U_LIB.S9S_MB_2U(SCH_1):PAGE240
 R4688    1      A Q_RES_0402LF-4.7K,1%,1/16W,EMPA    I18 @S9S_MB_2U_LIB.S9S_MB_2U(SCH_1):PAGE240
 R4687    1      A Q_RES_0402LF-4.7K,1%,1/16W,EMPA    I19 @S9S_MB_2U_LIB.S9S_MB_2U(SCH_1):PAGE240
  U102    1   GND0 INA183A1IDBVR-INA183A1IDBVR,SMA    I29 @S9S_MB_2U_LIB.S9S_MB_2U(SCH_1):PAGE240
  U102    2   GND1 INA183A1IDBVR-INA183A1IDBVR,SMA    I29 @S9S_MB_2U_LIB.S9S_MB_2U(SCH_1):PAGE240
 C2364    2      B Q_CAP_0402-0.1UF,25V,10%,EMPTYA    I33 @S9S_MB_2U_LIB.S9S_MB_2U(SCH_1):PAGE240
 R2585    2      B Q_RES_0402LF-31.6K,1%,1/16W,CHA     I7 @S9S_MB_2U_LIB.S9S_MB_2U(SCH_1):PAGE303
  PD15    A      A ZENER_AC-5.0SMDJ14A,SMLF,IC,BCA    I51 @S9S_MB_2U_LIB.S9S_MB_2U(SCH_1):PAGE328
  PD16    A      A ZENER_AC-5.0SMDJ14A,SMLF,IC,BCA    I53 @S9S_MB_2U_LIB.S9S_MB_2U(SCH_1):PAGE328
  PD17    1 ANODE_1 SS15P3SM386A-SS15P3S-M3/86A,SMA    I72 @S9S_MB_2U_LIB.S9S_MB_2U(SCH_1):PAGE328
  PD17    2 ANODE_2 SS15P3SM386A-SS15P3S-M3/86A,SMA    I72 @S9S_MB_2U_LIB.S9S_MB_2U(SCH_1):PAGE328
 C2458    2      B Q_CAP_0402-0.1UF,25V,10%,EMPTYA     I8 @S9S_MB_2U_LIB.S9S_MB_2U(SCH_1):PAGE327
  U345    5    GND NCT7718W-NCT7718W,SMLF,EMPTY,AA    I10 @S9S_MB_2U_LIB.S9S_MB_2U(SCH_1):PAGE327
  PJ42   11     11 SCONN21_9193031121LF-SCONN21_9A    I34 @S9S_MB_2U_LIB.S9S_MB_2U(SCH_1):PAGE327
  PJ42   21     21 SCONN21_9193031121LF-SCONN21_9A    I34 @S9S_MB_2U_LIB.S9S_MB_2U(SCH_1):PAGE327
  PJ42   G1     G1 SCONN21_9193031121LF-SCONN21_9A    I34 @S9S_MB_2U_LIB.S9S_MB_2U(SCH_1):PAGE327
  PJ42   G2     G2 SCONN21_9193031121LF-SCONN21_9A    I34 @S9S_MB_2U_LIB.S9S_MB_2U(SCH_1):PAGE327
PC1789    2      B Q_CAP_0402-0.1UF,25V,10%,EMPTYA    I38 @S9S_MB_2U_LIB.S9S_MB_2U(SCH_1):PAGE327
 R2238    2      B Q_RES_0402LF-4.99K,1%,1/16W,EMA     I2 @S9S_MB_2U_LIB.S9S_MB_2U(SCH_1):PAGE326
  U205    2    GND TPS3700DDCR-TPS3700DDCR,SMLF,EA     I5 @S9S_MB_2U_LIB.S9S_MB_2U(SCH_1):PAGE326
 R4668    2      B Q_RES_0402LF-10K,1%,1/16W,EMPTA    I13 @S9S_MB_2U_LIB.S9S_MB_2U(SCH_1):PAGE326
 R2222    2      B Q_RES_0402LF-1K,1%,1/16W,CHIP,A    I17 @S9S_MB_2U_LIB.S9S_MB_2U(SCH_1):PAGE326
 R4670    2      B Q_RES_0402LF-10K,1%,1/16W,EMPTA    I24 @S9S_MB_2U_LIB.S9S_MB_2U(SCH_1):PAGE326
  U369    2    GND TPS3700DDCR-TPS3700DDCR,SMLF,EA    I30 @S9S_MB_2U_LIB.S9S_MB_2U(SCH_1):PAGE326
  U325    S SOURCE MOSFET_N_SMLF-BSS138K,BSS138K,A    I38 @S9S_MB_2U_LIB.S9S_MB_2U(SCH_1):PAGE326
 R4673    2      B Q_RES_0402LF-0,5%,1/16W,EMPTY,A    I44 @S9S_MB_2U_LIB.S9S_MB_2U(SCH_1):PAGE326
  U329    S      S MOSFET_NCH_GDS_ESD_PROTECTED-2B    I46 @S9S_MB_2U_LIB.S9S_MB_2U(SCH_1):PAGE326
 R3268    2      B Q_RES_0402LF-68K,1%,1/16W,EMPTA     I2 @S9S_MB_2U_LIB.S9S_MB_2U(SCH_1):PAGE136
 R3272    2      B Q_RES_0402LF-1K,1%,1/16W,EMPTYA     I4 @S9S_MB_2U_LIB.S9S_MB_2U(SCH_1):PAGE136
 R3274    2      B Q_RES_0402LF-68K,1%,1/16W,EMPTA     I6 @S9S_MB_2U_LIB.S9S_MB_2U(SCH_1):PAGE136
 R3278    2      B Q_RES_0402LF-1K,1%,1/16W,CHIP,A     I8 @S9S_MB_2U_LIB.S9S_MB_2U(SCH_1):PAGE136
 R3267    2      B Q_RES_0402LF-68K,1%,1/16W,EMPTA    I12 @S9S_MB_2U_LIB.S9S_MB_2U(SCH_1):PAGE136
 R3270    2      B Q_RES_0402LF-1K,1%,1/16W,EMPTYA    I14 @S9S_MB_2U_LIB.S9S_MB_2U(SCH_1):PAGE136
 R3273    2      B Q_RES_0402LF-68K,1%,1/16W,EMPTA    I18 @S9S_MB_2U_LIB.S9S_MB_2U(SCH_1):PAGE136
 R3276    2      B Q_RES_0402LF-1K,1%,1/16W,EMPTYA    I20 @S9S_MB_2U_LIB.S9S_MB_2U(SCH_1):PAGE136
 R3282    2      B Q_RES_0402LF-68K,1%,1/16W,EMPTA    I27 @S9S_MB_2U_LIB.S9S_MB_2U(SCH_1):PAGE136
 C1863    2      B Q_CAP_0402-0.1UF,25V,10%,X7R,CA    I49 @S9S_MB_2U_LIB.S9S_MB_2U(SCH_1):PAGE136
  U237    4   GND1 PI3EQX12902AZLEX-PI3EQX12902AZA    I50 @S9S_MB_2U_LIB.S9S_MB_2U(SCH_1):PAGE136
  U237    6   GND2 PI3EQX12902AZLEX-PI3EQX12902AZA    I50 @S9S_MB_2U_LIB.S9S_MB_2U(SCH_1):PAGE136
  U237    7   GND3 PI3EQX12902AZLEX-PI3EQX12902AZA    I50 @S9S_MB_2U_LIB.S9S_MB_2U(SCH_1):PAGE136
  U237   13   GND4 PI3EQX12902AZLEX-PI3EQX12902AZA    I50 @S9S_MB_2U_LIB.S9S_MB_2U(SCH_1):PAGE136
  U237   19   GND5 PI3EQX12902AZLEX-PI3EQX12902AZA    I50 @S9S_MB_2U_LIB.S9S_MB_2U(SCH_1):PAGE136
  U237   22   GND6 PI3EQX12902AZLEX-PI3EQX12902AZA    I50 @S9S_MB_2U_LIB.S9S_MB_2U(SCH_1):PAGE136
  U237   28   GND7 PI3EQX12902AZLEX-PI3EQX12902AZA    I50 @S9S_MB_2U_LIB.S9S_MB_2U(SCH_1):PAGE136
  U237   TH GND_TH PI3EQX12902AZLEX-PI3EQX12902AZA    I50 @S9S_MB_2U_LIB.S9S_MB_2U(SCH_1):PAGE136
 C1864    2      B Q_CAP_0402-0.1UF,25V,10%,X7R,CA    I51 @S9S_MB_2U_LIB.S9S_MB_2U(SCH_1):PAGE136
 C1865    2      B Q_CAP_0402-0.1UF,25V,10%,X7R,CA    I52 @S9S_MB_2U_LIB.S9S_MB_2U(SCH_1):PAGE136
 C1866    2      B Q_CAP_0402-0.1UF,25V,10%,X7R,CA    I53 @S9S_MB_2U_LIB.S9S_MB_2U(SCH_1):PAGE136
 R3284    2      B Q_RES_0402LF-1K,1%,1/16W,CHIP,A    I56 @S9S_MB_2U_LIB.S9S_MB_2U(SCH_1):PAGE136
 R3285    2      B Q_RES_0402LF-68K,1%,1/16W,EMPTA    I61 @S9S_MB_2U_LIB.S9S_MB_2U(SCH_1):PAGE136
 R3287    2      B Q_RES_0402LF-1K,1%,1/16W,EMPTYA    I63 @S9S_MB_2U_LIB.S9S_MB_2U(SCH_1):PAGE136
 R3288    2      B Q_RES_0402LF-68K,1%,1/16W,EMPTA    I66 @S9S_MB_2U_LIB.S9S_MB_2U(SCH_1):PAGE136
 R3291    2      B Q_RES_0402LF-4.7K,1%,1/16W,EMPA    I82 @S9S_MB_2U_LIB.S9S_MB_2U(SCH_1):PAGE136
 R3265    2      B Q_RES_0402LF-4.7K,1%,1/16W,EMPA    I84 @S9S_MB_2U_LIB.S9S_MB_2U(SCH_1):PAGE136
 R4694    2      B Q_RES_0402LF-1K,1%,1/16W,CHIP,A    I10 @S9S_MB_2U_LIB.S9S_MB_2U(SCH_1):PAGE159
 R3362    2      B Q_RES_0402LF-1K,1%,1/16W,CHIP,A    I53 @S9S_MB_2U_LIB.S9S_MB_2U(SCH_1):PAGE159
 R3381    2      B Q_RES_0402LF-1K,1%,1/16W,EMPTYA    I61 @S9S_MB_2U_LIB.S9S_MB_2U(SCH_1):PAGE159
 R4657    2      B Q_RES_0402LF-1K,1%,1/16W,EMPTYA    I65 @S9S_MB_2U_LIB.S9S_MB_2U(SCH_1):PAGE159
 R4650    2      B Q_RES_0402LF-1K,1%,1/16W,EMPTYA    I71 @S9S_MB_2U_LIB.S9S_MB_2U(SCH_1):PAGE159
 R4658    2      B Q_RES_0402LF-1K,1%,1/16W,EMPTYA    I80 @S9S_MB_2U_LIB.S9S_MB_2U(SCH_1):PAGE159
 C2355    2      B Q_CAP_C0402-1UF,25V,10%,X6S,CHA    I96 @S9S_MB_2U_LIB.S9S_MB_2U(SCH_1):PAGE159
 C2356    2      B Q_CAP_C0805-10UF,16V,10%,X6S,CA    I98 @S9S_MB_2U_LIB.S9S_MB_2U(SCH_1):PAGE159
 C2357    2      B Q_CAP_0402-0.1UF,25V,10%,X7R,CA    I99 @S9S_MB_2U_LIB.S9S_MB_2U(SCH_1):PAGE159
   Q50    1     S1 MOSFET_NCH_DUAL-PJT138K,SMLF,IA    I43 @S9S_MB_2U_LIB.S9S_MB_2U(SCH_1):PAGE314
  U224    3    GND 74LVC1G126SE7-74LVC1G126SE-7,SA     I7 @S9S_MB_2U_LIB.S9S_MB_2U(SCH_1):PAGE151
 C1840    2      B Q_CAP_0402-0.1UF,25V,10%,X7R,CA     I8 @S9S_MB_2U_LIB.S9S_MB_2U(SCH_1):PAGE151
 R3232    2      B Q_RES_0402LF-100K,1%,1/16W,CHIA    I13 @S9S_MB_2U_LIB.S9S_MB_2U(SCH_1):PAGE151
   U66    3    GND 74LVC1G126SE7-74LVC1G126SE-7,SA    I15 @S9S_MB_2U_LIB.S9S_MB_2U(SCH_1):PAGE151
 R1289    2      B Q_RES_0402LF-100K,1%,1/16W,CHIA    I21 @S9S_MB_2U_LIB.S9S_MB_2U(SCH_1):PAGE151
  C639    2      B Q_CAP_0402-0.1UF,25V,10%,X7R,CA    I22 @S9S_MB_2U_LIB.S9S_MB_2U(SCH_1):PAGE151
   U68    7    GND 74CBTLV3126PW-74CBTLV3126PW,SMA    I30 @S9S_MB_2U_LIB.S9S_MB_2U(SCH_1):PAGE151
  C641    2      B Q_CAP_0402-0.1UF,25V,10%,X7R,CA    I32 @S9S_MB_2U_LIB.S9S_MB_2U(SCH_1):PAGE151
   U67    7    GND 74CBTLV3126PW-74CBTLV3126PW,SMA    I39 @S9S_MB_2U_LIB.S9S_MB_2U(SCH_1):PAGE151
  C640    2      B Q_CAP_0402-0.1UF,25V,10%,X7R,CA    I40 @S9S_MB_2U_LIB.S9S_MB_2U(SCH_1):PAGE151
 R1896    2      B Q_RES_0402LF-100,1%,1/16W,CHIPA    I43 @S9S_MB_2U_LIB.S9S_MB_2U(SCH_1):PAGE151
 R1897    2      B Q_RES_0402LF-100,1%,1/16W,CHIPA    I50 @S9S_MB_2U_LIB.S9S_MB_2U(SCH_1):PAGE151
 R1898    2      B Q_RES_0402LF-100,1%,1/16W,CHIPA    I52 @S9S_MB_2U_LIB.S9S_MB_2U(SCH_1):PAGE151
 R1356    2      B Q_RES_0402LF-1K,1%,1/16W,CHIP,A    I53 @S9S_MB_2U_LIB.S9S_MB_2U(SCH_1):PAGE151
 R1355    2      B Q_RES_0402LF-100K,1%,1/16W,CHIA    I54 @S9S_MB_2U_LIB.S9S_MB_2U(SCH_1):PAGE151
 R1354    2      B Q_RES_0402LF-100K,1%,1/16W,CHIA    I55 @S9S_MB_2U_LIB.S9S_MB_2U(SCH_1):PAGE151
 R1352    2      B Q_RES_0402LF-100K,1%,1/16W,CHIA    I71 @S9S_MB_2U_LIB.S9S_MB_2U(SCH_1):PAGE151
 R1351    2      B Q_RES_0402LF-100K,1%,1/16W,CHIA    I72 @S9S_MB_2U_LIB.S9S_MB_2U(SCH_1):PAGE151
 R1350    2      B Q_RES_0402LF-100K,1%,1/16W,CHIA    I73 @S9S_MB_2U_LIB.S9S_MB_2U(SCH_1):PAGE151
 R3442    2      B Q_RES_0402LF-0,5%,1/16W,CHIP,CA     I6 @S9S_MB_2U_LIB.S9S_MB_2U(SCH_1):PAGE147
 R3441    2      B Q_RES_0402LF-0,5%,1/16W,CHIP,CA     I7 @S9S_MB_2U_LIB.S9S_MB_2U(SCH_1):PAGE147
 C1209    2      B Q_CAP_0402-100PF,50V,5%,NPO,CHA     I3 @S9S_MB_2U_LIB.S9S_MB_2U(SCH_1):PAGE209
 C1211    2      B Q_CAP_0402-100PF,50V,5%,NPO,CHA     I4 @S9S_MB_2U_LIB.S9S_MB_2U(SCH_1):PAGE209
  R736    2      B Q_RES_0402LF-1K,1%,1/16W,EMPTYA    I11 @S9S_MB_2U_LIB.S9S_MB_2U(SCH_1):PAGE209
 R1494    2      B Q_RES_0402LF-1K,1%,1/16W,EMPTYA    I21 @S9S_MB_2U_LIB.S9S_MB_2U(SCH_1):PAGE209
 R1312    2      B Q_RES_0402LF-10K,1%,1/16W,EMPTA    I22 @S9S_MB_2U_LIB.S9S_MB_2U(SCH_1):PAGE209
 R1308    2      B Q_RES_0402LF-10K,1%,1/16W,EMPTA    I23 @S9S_MB_2U_LIB.S9S_MB_2U(SCH_1):PAGE209
 R1742    2      B Q_RES_0402LF-10K,1%,1/16W,EMPTA    I24 @S9S_MB_2U_LIB.S9S_MB_2U(SCH_1):PAGE209
 C1797    2      B Q_CAP_0402-0.1UF,25V,10%,X7R,CA     I3 @S9S_MB_2U_LIB.S9S_MB_2U(SCH_1):PAGE303
JP4003    3      3 CONN3_210HP1030BR1-CONN3_210-HB    I12 @S9S_MB_2U_LIB.S9S_MB_2U(SCH_1):PAGE303
PR3002    1      A Q_RES_0402LF-0,5%,1/16W,CHIP,CA    I54 @S9S_MB_2U_LIB.S9S_MB_2U(SCH_1):PAGE303
 R4674    2      B Q_RES_0402LF-10K,1%,1/16W,CHIPA    I46 @S9S_MB_2U_LIB.S9S_MB_2U(SCH_1):PAGE209
 C2359    2      B Q_CAP_C0402-0.22UF,25V,10%,X7RA    I94 @S9S_MB_2U_LIB.S9S_MB_2U(SCH_1):PAGE246
  Q236    4     S2 MOSFET_NCH_DUAL-PJT138K,SMLF,IA    I98 @S9S_MB_2U_LIB.S9S_MB_2U(SCH_1):PAGE246
  Q236    1     S1 MOSFET_NCH_DUAL-PJT138K,SMLF,IA    I99 @S9S_MB_2U_LIB.S9S_MB_2U(SCH_1):PAGE246
  U330    1    GND APX80929SAG7-APX809-29SAG-7,SMA   I105 @S9S_MB_2U_LIB.S9S_MB_2U(SCH_1):PAGE246
 C2360    2      B Q_CAP_0402-0.1UF,25V,10%,X7R,CA   I107 @S9S_MB_2U_LIB.S9S_MB_2U(SCH_1):PAGE246
 R4681    2      B Q_RES_0402LF-100K,1%,1/16W,CHIA   I109 @S9S_MB_2U_LIB.S9S_MB_2U(SCH_1):PAGE246
 R4682    2      B Q_RES_0402LF-100K,1%,1/16W,CHIA   I112 @S9S_MB_2U_LIB.S9S_MB_2U(SCH_1):PAGE246
  H113    2   GND2 GND_HOLE_TH-EMPTY,TMP-QGND_HOLA   I247 @S9S_MB_2U_LIB.S9S_MB_2U(SCH_1):PAGE289
  H113    3   GND3 GND_HOLE_TH-EMPTY,TMP-QGND_HOLA   I247 @S9S_MB_2U_LIB.S9S_MB_2U(SCH_1):PAGE289
  H113    4   GND4 GND_HOLE_TH-EMPTY,TMP-QGND_HOLA   I247 @S9S_MB_2U_LIB.S9S_MB_2U(SCH_1):PAGE289
  H113    5   GND5 GND_HOLE_TH-EMPTY,TMP-QGND_HOLA   I247 @S9S_MB_2U_LIB.S9S_MB_2U(SCH_1):PAGE289
  H113    6   GND6 GND_HOLE_TH-EMPTY,TMP-QGND_HOLA   I247 @S9S_MB_2U_LIB.S9S_MB_2U(SCH_1):PAGE289
  H113    7   GND7 GND_HOLE_TH-EMPTY,TMP-QGND_HOLA   I247 @S9S_MB_2U_LIB.S9S_MB_2U(SCH_1):PAGE289
  H113    8   GND8 GND_HOLE_TH-EMPTY,TMP-QGND_HOLA   I247 @S9S_MB_2U_LIB.S9S_MB_2U(SCH_1):PAGE289
  H113    9   GND9 GND_HOLE_TH-EMPTY,TMP-QGND_HOLA   I247 @S9S_MB_2U_LIB.S9S_MB_2U(SCH_1):PAGE289
  H114    2   GND2 GND_HOLE_TH-EMPTY,TMP-QGND_HOLA   I248 @S9S_MB_2U_LIB.S9S_MB_2U(SCH_1):PAGE289
  H114    3   GND3 GND_HOLE_TH-EMPTY,TMP-QGND_HOLA   I248 @S9S_MB_2U_LIB.S9S_MB_2U(SCH_1):PAGE289
  H114    4   GND4 GND_HOLE_TH-EMPTY,TMP-QGND_HOLA   I248 @S9S_MB_2U_LIB.S9S_MB_2U(SCH_1):PAGE289
  H114    5   GND5 GND_HOLE_TH-EMPTY,TMP-QGND_HOLA   I248 @S9S_MB_2U_LIB.S9S_MB_2U(SCH_1):PAGE289
  H114    6   GND6 GND_HOLE_TH-EMPTY,TMP-QGND_HOLA   I248 @S9S_MB_2U_LIB.S9S_MB_2U(SCH_1):PAGE289
  H114    7   GND7 GND_HOLE_TH-EMPTY,TMP-QGND_HOLA   I248 @S9S_MB_2U_LIB.S9S_MB_2U(SCH_1):PAGE289
  H114    8   GND8 GND_HOLE_TH-EMPTY,TMP-QGND_HOLA   I248 @S9S_MB_2U_LIB.S9S_MB_2U(SCH_1):PAGE289
  H114    9   GND9 GND_HOLE_TH-EMPTY,TMP-QGND_HOLA   I248 @S9S_MB_2U_LIB.S9S_MB_2U(SCH_1):PAGE289
 C1307    2      B Q_CAP_0402-1000PF,50V,5%,EMPTYA     I4 @S9S_MB_2U_LIB.S9S_MB_2U(SCH_1):PAGE268
PC1273    2      B Q_CAP_C0805-22UF,16V,20%,X6S,CA    I15 @S9S_MB_2U_LIB.S9S_MB_2U(SCH_1):PAGE268
PC1274    2      B Q_CAP_C0402-1UF,16V,10%,X6S,CHA    I23 @S9S_MB_2U_LIB.S9S_MB_2U(SCH_1):PAGE268
  PR50    2      B Q_RES_0402LF-12.4K,0.1%,1/16W,A    I28 @S9S_MB_2U_LIB.S9S_MB_2U(SCH_1):PAGE268
PC1279    2      B Q_CAP_C0805-22UF,4V,20%,X6S,CHA    I43 @S9S_MB_2U_LIB.S9S_MB_2U(SCH_1):PAGE268
   PR2    1      A Q_RES_0402LF-0,5%,1/16W,CHIP,CA    I22 @S9S_MB_2U_LIB.S9S_MB_2U(SCH_1):PAGE286
   PR2    2      B Q_RES_0402LF-0,5%,1/16W,CHIP,CA    I22 @S9S_MB_2U_LIB.S9S_MB_2U(SCH_1):PAGE286
PC1286    2      B Q_CAP_C0805-22UF,4V,20%,X6S,CHA    I38 @S9S_MB_2U_LIB.S9S_MB_2U(SCH_1):PAGE286
PC2361    2      B Q_CAP_0402-0.1UF,25V,10%,EMPTYA   I136 @S9S_MB_2U_LIB.S9S_MB_2U(SCH_1):PAGE252
PC2362    2      B Q_CAP_0402-0.1UF,25V,10%,EMPTYA   I110 @S9S_MB_2U_LIB.S9S_MB_2U(SCH_1):PAGE260
PC2365    2      B Q_CAP_0402-0.1UF,25V,10%,EMPTYA    I96 @S9S_MB_2U_LIB.S9S_MB_2U(SCH_1):PAGE264
PC2366    2      B Q_CAP_0402-0.1UF,25V,10%,EMPTYA   I128 @S9S_MB_2U_LIB.S9S_MB_2U(SCH_1):PAGE270
PC2367    2      B Q_CAP_0402-0.1UF,25V,10%,EMPTYA   I111 @S9S_MB_2U_LIB.S9S_MB_2U(SCH_1):PAGE278
PC2368    2      B Q_CAP_0402-0.1UF,25V,10%,EMPTYA    I96 @S9S_MB_2U_LIB.S9S_MB_2U(SCH_1):PAGE282
 R4276    2      B Q_RES_0402LF-68K,1%,1/16W,CHIPA     I2 @S9S_MB_2U_LIB.S9S_MB_2U(SCH_1):PAGE162
 R4282    2      B Q_RES_0402LF-68K,1%,1/16W,CHIPA     I6 @S9S_MB_2U_LIB.S9S_MB_2U(SCH_1):PAGE162
 R4636    2      B Q_RES_0402LF-200K,1%,1/16W,CHIA    I23 @S9S_MB_2U_LIB.S9S_MB_2U(SCH_1):PAGE162
 C2284    2      B Q_CAP_C0805-22UF,16V,20%,X6S,CB    I37 @S9S_MB_2U_LIB.S9S_MB_2U(SCH_1):PAGE162
 R4285    2      B Q_RES_0402LF-1K,1%,1/16W,EMPTYA    I40 @S9S_MB_2U_LIB.S9S_MB_2U(SCH_1):PAGE162
  U309    8  GND_1 PI3EQX1002EZREX-PI3EQX1002EZREA    I43 @S9S_MB_2U_LIB.S9S_MB_2U(SCH_1):PAGE162
  U309    9  GND_2 PI3EQX1002EZREX-PI3EQX1002EZREA    I43 @S9S_MB_2U_LIB.S9S_MB_2U(SCH_1):PAGE162
  U309   10  GND_3 PI3EQX1002EZREX-PI3EQX1002EZREA    I43 @S9S_MB_2U_LIB.S9S_MB_2U(SCH_1):PAGE162
  U309   20  GND_4 PI3EQX1002EZREX-PI3EQX1002EZREA    I43 @S9S_MB_2U_LIB.S9S_MB_2U(SCH_1):PAGE162
  U309   21  GND_5 PI3EQX1002EZREX-PI3EQX1002EZREA    I43 @S9S_MB_2U_LIB.S9S_MB_2U(SCH_1):PAGE162
  U309   22  GND_6 PI3EQX1002EZREX-PI3EQX1002EZREA    I43 @S9S_MB_2U_LIB.S9S_MB_2U(SCH_1):PAGE162
  U309   TH TH_GND PI3EQX1002EZREX-PI3EQX1002EZREA    I43 @S9S_MB_2U_LIB.S9S_MB_2U(SCH_1):PAGE162
 C2285    2      B Q_CAP_0402-0.1UF,25V,10%,X7R,CA    I44 @S9S_MB_2U_LIB.S9S_MB_2U(SCH_1):PAGE162
 C2286    2      B Q_CAP_0402-0.1UF,25V,10%,X7R,CA    I45 @S9S_MB_2U_LIB.S9S_MB_2U(SCH_1):PAGE162
 R4288    2      B Q_RES_0402LF-1K,1%,1/16W,EMPTYA    I48 @S9S_MB_2U_LIB.S9S_MB_2U(SCH_1):PAGE162
 C2255    2      B Q_CAP_C0402-8.2PF,50V,0.1P,NP0A   I165 @S9S_MB_2U_LIB.S9S_MB_2U(SCH_1):PAGE201
 C2256    2      B Q_CAP_C0402-8.2PF,50V,0.1P,NP0A   I166 @S9S_MB_2U_LIB.S9S_MB_2U(SCH_1):PAGE201
  H129    1      1 HOLE_TH-EMPTY,HOLE1195   I249 @S9S_MB_2U_LIB.S9S_MB_2U(SCH_1):PAGE289
 C2029    2      B Q_CAP_0402-18PF,50V,5%,C0G,CH0A   I210 @S9S_MB_2U_LIB.S9S_MB_2U(SCH_1):PAGE155
 C2030    2      B Q_CAP_0402-18PF,50V,5%,C0G,CH0A   I211 @S9S_MB_2U_LIB.S9S_MB_2U(SCH_1):PAGE155
  D143    C      C Q_LED_SMLF-LED_BLUE,LTST-C281TA    I49 @S9S_MB_2U_LIB.S9S_MB_2U(SCH_1):PAGE241
  D142    C      C Q_LED_SMLF-LED_BLUE,LTST-C281TA    I58 @S9S_MB_2U_LIB.S9S_MB_2U(SCH_1):PAGE241
  Q150    1     S1 MOSFET_NCH_DUAL-PJT138K,SMLF,IA    I69 @S9S_MB_2U_LIB.S9S_MB_2U(SCH_1):PAGE241
  Q150    4     S2 MOSFET_NCH_DUAL-PJT138K,SMLF,IA    I72 @S9S_MB_2U_LIB.S9S_MB_2U(SCH_1):PAGE241
   Q34    S      S MOSFET_NCH_GDS_ESD_PROTECTED-2A   I123 @S9S_MB_2U_LIB.S9S_MB_2U(SCH_1):PAGE177
   Q35    S      S MOSFET_NCH_GDS_ESD_PROTECTED-2A   I124 @S9S_MB_2U_LIB.S9S_MB_2U(SCH_1):PAGE177
 R4712    2      B Q_RES_0402LF-100K,1%,1/16W,CHIA   I125 @S9S_MB_2U_LIB.S9S_MB_2U(SCH_1):PAGE177
 R4713    2      B Q_RES_0402LF-100K,1%,1/16W,CHIA   I127 @S9S_MB_2U_LIB.S9S_MB_2U(SCH_1):PAGE177
 C2370    2      B Q_CAP_0402-0.1UF,25V,10%,EMPTYA    I35 @S9S_MB_2U_LIB.S9S_MB_2U(SCH_1):PAGE213
  U332    3     2A 74LVC2G07DW7-74LVC2G07DW-7,SMLB    I37 @S9S_MB_2U_LIB.S9S_MB_2U(SCH_1):PAGE213
  U332    2    GND 74LVC2G07DW7-74LVC2G07DW-7,SMLB    I37 @S9S_MB_2U_LIB.S9S_MB_2U(SCH_1):PAGE213
 C2369    2      B Q_CAP_C0402-1UF,25V,10%,EMPTY,A    I42 @S9S_MB_2U_LIB.S9S_MB_2U(SCH_1):PAGE213
 C2372    2      B Q_CAP_0402-1000PF,50V,5%,EMPTYA    I15 @S9S_MB_2U_LIB.S9S_MB_2U(SCH_1):PAGE147
  Q151    4     S2 MOSFET_NCH_DUAL-PJT138K,SMLF,IA    I20 @S9S_MB_2U_LIB.S9S_MB_2U(SCH_1):PAGE147
 C2373    2      B Q_CAP_0402-1000PF,50V,5%,EMPTYA    I22 @S9S_MB_2U_LIB.S9S_MB_2U(SCH_1):PAGE147
  Q152    4     S2 MOSFET_NCH_DUAL-PJT138K,SMLF,IA    I26 @S9S_MB_2U_LIB.S9S_MB_2U(SCH_1):PAGE147
  Q151    1     S1 MOSFET_NCH_DUAL-PJT138K,SMLF,IA    I31 @S9S_MB_2U_LIB.S9S_MB_2U(SCH_1):PAGE147
 R4724    2      B Q_RES_0402LF-100K,1%,1/16W,EMPA    I34 @S9S_MB_2U_LIB.S9S_MB_2U(SCH_1):PAGE147
  Q152    1     S1 MOSFET_NCH_DUAL-PJT138K,SMLF,IA    I38 @S9S_MB_2U_LIB.S9S_MB_2U(SCH_1):PAGE147
 R4731    2      B Q_RES_0402LF-100K,1%,1/16W,EMPA    I42 @S9S_MB_2U_LIB.S9S_MB_2U(SCH_1):PAGE147
 C2374    2      B Q_CAP_0402-1000PF,50V,5%,EMPTYA    I47 @S9S_MB_2U_LIB.S9S_MB_2U(SCH_1):PAGE147
  Q153    4     S2 MOSFET_NCH_DUAL-PJT138K,SMLF,IA    I51 @S9S_MB_2U_LIB.S9S_MB_2U(SCH_1):PAGE147
  Q153    1     S1 MOSFET_NCH_DUAL-PJT138K,SMLF,IA    I55 @S9S_MB_2U_LIB.S9S_MB_2U(SCH_1):PAGE147
 R4738    2      B Q_RES_0402LF-100K,1%,1/16W,EMPA    I60 @S9S_MB_2U_LIB.S9S_MB_2U(SCH_1):PAGE147
 C2376    2      B Q_CAP_0402-0.1UF,25V,10%,X7R,CA   I241 @S9S_MB_2U_LIB.S9S_MB_2U(SCH_1):PAGE154
  U334    3    GND 74LVC1G08W57-74LVC1G08W5-7,SMLA   I243 @S9S_MB_2U_LIB.S9S_MB_2U(SCH_1):PAGE154
PC2142    2      B Q_CAP_C0805-10UF,16V,10%,X6S,CB   I113 @S9S_MB_2U_LIB.S9S_MB_2U(SCH_1):PAGE131
  U335    3    GND 74LVC1G08W57-74LVC1G08W5-7,SMLA   I108 @S9S_MB_2U_LIB.S9S_MB_2U(SCH_1):PAGE132
 C2377    2      B Q_CAP_0402-0.1UF,25V,10%,X7R,CA   I110 @S9S_MB_2U_LIB.S9S_MB_2U(SCH_1):PAGE132
 C2378    2      B Q_CAP_0402-0.1UF,25V,10%,X7R,CA   I327 @S9S_MB_2U_LIB.S9S_MB_2U(SCH_1):PAGE297
  U336    1    GND APX80929SAG7-APX809-29SAG-7,SMA   I329 @S9S_MB_2U_LIB.S9S_MB_2U(SCH_1):PAGE297
 C2379    2      B Q_CAP_C0402-100NF,50V,10%,EMPTA     I1 @S9S_MB_2U_LIB.S9S_MB_2U(SCH_1):PAGE329
 R4775    2      B Q_RES_0402LF-5.11K,1%,1/16W,EMA     I2 @S9S_MB_2U_LIB.S9S_MB_2U(SCH_1):PAGE329
  U337    2     2- LM4040AIM3X25NOPB-LM4040AIM3X-A     I3 @S9S_MB_2U_LIB.S9S_MB_2U(SCH_1):PAGE329
 C2383    2      B Q_CAP_C0402-100NF,50V,10%,EMPTA    I11 @S9S_MB_2U_LIB.S9S_MB_2U(SCH_1):PAGE329
  U339    2    GND AP331AWG7-AP331AWG-7,SMLF,EMPTA    I12 @S9S_MB_2U_LIB.S9S_MB_2U(SCH_1):PAGE329
 C2381    2      B Q_CAP_C0402-100NF,50V,10%,EMPTA    I14 @S9S_MB_2U_LIB.S9S_MB_2U(SCH_1):PAGE329
  U340    2    GND AP331AWG7-AP331AWG-7,SMLF,EMPTA    I23 @S9S_MB_2U_LIB.S9S_MB_2U(SCH_1):PAGE329
 C2384    2      B Q_CAP_C0402-100NF,50V,10%,EMPTA    I29 @S9S_MB_2U_LIB.S9S_MB_2U(SCH_1):PAGE329
 C2382    2      B Q_CAP_C0402-100NF,50V,10%,EMPTA    I33 @S9S_MB_2U_LIB.S9S_MB_2U(SCH_1):PAGE329
 C2380    2      B Q_CAP_C0402-100NF,50V,10%,EMPTA    I35 @S9S_MB_2U_LIB.S9S_MB_2U(SCH_1):PAGE329
 R4777    2      B Q_RES_0402LF-5.11K,1%,1/16W,EMA    I39 @S9S_MB_2U_LIB.S9S_MB_2U(SCH_1):PAGE329
  U338    2     2- LM4040AIM3X25NOPB-LM4040AIM3X-A    I43 @S9S_MB_2U_LIB.S9S_MB_2U(SCH_1):PAGE329
  U342    2    GND AP331AWG7-AP331AWG-7,SMLF,EMPTA    I45 @S9S_MB_2U_LIB.S9S_MB_2U(SCH_1):PAGE329
 C2387    2      B Q_CAP_C0402-100NF,50V,10%,EMPTA    I51 @S9S_MB_2U_LIB.S9S_MB_2U(SCH_1):PAGE329
 C2386    2      B Q_CAP_C0402-100NF,50V,10%,EMPTA    I55 @S9S_MB_2U_LIB.S9S_MB_2U(SCH_1):PAGE329
 C2385    2      B Q_CAP_C0402-100NF,50V,10%,EMPTA    I57 @S9S_MB_2U_LIB.S9S_MB_2U(SCH_1):PAGE329
  U341    2     2- LM4040AIM3X25NOPB-LM4040AIM3X-A    I63 @S9S_MB_2U_LIB.S9S_MB_2U(SCH_1):PAGE329
 R4791    2      B Q_RES_0402LF-2K,1%,1/16W,EMPTYA    I68 @S9S_MB_2U_LIB.S9S_MB_2U(SCH_1):PAGE329
  U343    2     2- LM4040AIM3X25NOPB-LM4040AIM3X-A    I56 @S9S_MB_2U_LIB.S9S_MB_2U(SCH_1):PAGE326
 C2388    2      B Q_CAP_C0402-100NF,50V,10%,EMPTA    I64 @S9S_MB_2U_LIB.S9S_MB_2U(SCH_1):PAGE326
  U344    2    GND AP331AWG7-AP331AWG-7,SMLF,EMPTA    I66 @S9S_MB_2U_LIB.S9S_MB_2U(SCH_1):PAGE326
 C2390    2      B Q_CAP_C0402-100NF,50V,10%,EMPTA    I71 @S9S_MB_2U_LIB.S9S_MB_2U(SCH_1):PAGE326
 C2389    2      B Q_CAP_C0402-100NF,50V,10%,EMPTA    I76 @S9S_MB_2U_LIB.S9S_MB_2U(SCH_1):PAGE326
 R4796    2      B Q_RES_0402LF-10K,1%,1/16W,EMPTA    I77 @S9S_MB_2U_LIB.S9S_MB_2U(SCH_1):PAGE326
  Q154    4     S2 MOSFET_NCH_DUAL-PJT138K,SMLF,IA    I62 @S9S_MB_2U_LIB.S9S_MB_2U(SCH_1):PAGE147
 C2391    2      B Q_CAP_0402-1000PF,50V,5%,EMPTYA    I66 @S9S_MB_2U_LIB.S9S_MB_2U(SCH_1):PAGE147
  Q154    1     S1 MOSFET_NCH_DUAL-PJT138K,SMLF,IA    I71 @S9S_MB_2U_LIB.S9S_MB_2U(SCH_1):PAGE147
 R4799    2      B Q_RES_0402LF-100K,1%,1/16W,EMPA    I76 @S9S_MB_2U_LIB.S9S_MB_2U(SCH_1):PAGE147
 C1562    2      B Q_CAP_C0402-1UF,25V,10%,EMPTY,A    I89 @S9S_MB_2U_LIB.S9S_MB_2U(SCH_1):PAGE326
 C1561    2      B Q_CAP_C0402-1UF,25V,10%,X6S,CHA    I90 @S9S_MB_2U_LIB.S9S_MB_2U(SCH_1):PAGE326
 C4562    2      B Q_CAP_C0402-1UF,25V,10%,EMPTY,A    I91 @S9S_MB_2U_LIB.S9S_MB_2U(SCH_1):PAGE326
 C2393    2      B Q_CAP_0402-0.1UF,25V,10%,EMPTYA    I92 @S9S_MB_2U_LIB.S9S_MB_2U(SCH_1):PAGE326
 C2394    2      B Q_CAP_0402-0.1UF,25V,10%,X7R,CA    I93 @S9S_MB_2U_LIB.S9S_MB_2U(SCH_1):PAGE326
 C2392    2      B Q_CAP_0402-0.1UF,25V,10%,EMPTYA    I95 @S9S_MB_2U_LIB.S9S_MB_2U(SCH_1):PAGE326
 R2227    2      B Q_RES_0402LF-1K,1%,1/16W,CHIP,A   I101 @S9S_MB_2U_LIB.S9S_MB_2U(SCH_1):PAGE326
  U206    2    GND LT6700CS61TRPBF-LT6700CS6-1#TRA   I102 @S9S_MB_2U_LIB.S9S_MB_2U(SCH_1):PAGE326
  JP10    3      3 CONN3_210HP1030BR1-CONN3_210-HB    I51 @S9S_MB_2U_LIB.S9S_MB_2U(SCH_1):PAGE327
  Q123    1     S1 MOSFET_NCH_DUAL-PJT138K,SMLF,EA     I9 @S9S_MB_2U_LIB.S9S_MB_2U(SCH_1):PAGE153
  Q124    1     S1 MOSFET_NCH_DUAL-PJT138K,SMLF,IA    I21 @S9S_MB_2U_LIB.S9S_MB_2U(SCH_1):PAGE153
  C592    2      B Q_CAP_0402-0.1UF,25V,10%,X7R,CA    I30 @S9S_MB_2U_LIB.S9S_MB_2U(SCH_1):PAGE153
PR3788    2      B Q_RES_0402LF-15K,1%,1/16W,EMPTA    I33 @S9S_MB_2U_LIB.S9S_MB_2U(SCH_1):PAGE153
  Q124    4     S2 MOSFET_NCH_DUAL-PJT138K,SMLF,IA    I36 @S9S_MB_2U_LIB.S9S_MB_2U(SCH_1):PAGE153
PC2079    2      B Q_CAP_C0402-1UF,25V,10%,X6S,CHA    I44 @S9S_MB_2U_LIB.S9S_MB_2U(SCH_1):PAGE153
 PU203   A7   CDLY MAX15090BEWIT-MAX15090BEWI+T,SA    I51 @S9S_MB_2U_LIB.S9S_MB_2U(SCH_1):PAGE153
 PU203   B7    EN# MAX15090BEWIT-MAX15090BEWI+T,SA    I51 @S9S_MB_2U_LIB.S9S_MB_2U(SCH_1):PAGE153
 PU203   B2 GND_B2 MAX15090BEWIT-MAX15090BEWI+T,SA    I51 @S9S_MB_2U_LIB.S9S_MB_2U(SCH_1):PAGE153
 PU203   C1 GND_C1 MAX15090BEWIT-MAX15090BEWI+T,SA    I51 @S9S_MB_2U_LIB.S9S_MB_2U(SCH_1):PAGE153
 PU203   C2 GND_C2 MAX15090BEWIT-MAX15090BEWI+T,SA    I51 @S9S_MB_2U_LIB.S9S_MB_2U(SCH_1):PAGE153
PR3780    2      B Q_RES_0402LF-5.36K,1%,1/16W,CHA    I60 @S9S_MB_2U_LIB.S9S_MB_2U(SCH_1):PAGE153
 PU202   A7   CDLY MAX15090BEWIT-MAX15090BEWI+T,SB    I61 @S9S_MB_2U_LIB.S9S_MB_2U(SCH_1):PAGE153
 PU202   B7    EN# MAX15090BEWIT-MAX15090BEWI+T,SB    I61 @S9S_MB_2U_LIB.S9S_MB_2U(SCH_1):PAGE153
 PU202   B2 GND_B2 MAX15090BEWIT-MAX15090BEWI+T,SB    I61 @S9S_MB_2U_LIB.S9S_MB_2U(SCH_1):PAGE153
 PU202   C1 GND_C1 MAX15090BEWIT-MAX15090BEWI+T,SB    I61 @S9S_MB_2U_LIB.S9S_MB_2U(SCH_1):PAGE153
 PU202   C2 GND_C2 MAX15090BEWIT-MAX15090BEWI+T,SB    I61 @S9S_MB_2U_LIB.S9S_MB_2U(SCH_1):PAGE153
PC5328    2      B Q_CAP_C0402-1UF,25V,10%,X6S,CHA    I66 @S9S_MB_2U_LIB.S9S_MB_2U(SCH_1):PAGE153
PC4056    2      B Q_CAP_C0402-3900PF,50V,10%,EMPA    I83 @S9S_MB_2U_LIB.S9S_MB_2U(SCH_1):PAGE153
 PD102    A      A SCHOTTKY_AC-B340A-13-F,SMLF,ICA    I86 @S9S_MB_2U_LIB.S9S_MB_2U(SCH_1):PAGE153
PC2080    2      B Q_CAP_C0805-22UF,16V,20%,X6S,CC    I94 @S9S_MB_2U_LIB.S9S_MB_2U(SCH_1):PAGE153
PC2091    2      B Q_CAP_0402-0.1UF,25V,10%,X7R,CA   I111 @S9S_MB_2U_LIB.S9S_MB_2U(SCH_1):PAGE153
PC2081    2      B Q_CAP_C0805-10UF,16V,10%,X6S,CB   I113 @S9S_MB_2U_LIB.S9S_MB_2U(SCH_1):PAGE153
PC2153    2      B Q_CAP_0402-0.22UF,16V,10%,X7R,A    I60 @S9S_MB_2U_LIB.S9S_MB_2U(SCH_1):PAGE236
PR3835    2      B Q_RES_0402LF-14.3K,1%,1/16W,CHA    I62 @S9S_MB_2U_LIB.S9S_MB_2U(SCH_1):PAGE236
PC2155    2      B Q_CAP_C0402-0.047UF,25V,10%,X7A    I63 @S9S_MB_2U_LIB.S9S_MB_2U(SCH_1):PAGE236
PC2154    2      B Q_CAP_C0402-1UF,25V,10%,X6S,CHA    I68 @S9S_MB_2U_LIB.S9S_MB_2U(SCH_1):PAGE236
 PU204    3   ENTM RS31312R-RS31312R,SMLF,IC,AL03A    I70 @S9S_MB_2U_LIB.S9S_MB_2U(SCH_1):PAGE236
 PU204    7    GND RS31312R-RS31312R,SMLF,IC,AL03A    I70 @S9S_MB_2U_LIB.S9S_MB_2U(SCH_1):PAGE236
 PU204    2 LOADEN RS31312R-RS31312R,SMLF,IC,AL03A    I70 @S9S_MB_2U_LIB.S9S_MB_2U(SCH_1):PAGE236
PR3837    2      B Q_RES_0402LF-17.4K,1%,1/16W,CHA    I72 @S9S_MB_2U_LIB.S9S_MB_2U(SCH_1):PAGE236
PC2156    2      B Q_CAP_C0402-100NF,50V,10%,X7R,A    I74 @S9S_MB_2U_LIB.S9S_MB_2U(SCH_1):PAGE236
PR3842    2      B Q_RES_0402LF-10K,1%,1/16W,CHIPA    I83 @S9S_MB_2U_LIB.S9S_MB_2U(SCH_1):PAGE236
PC2158    2      B Q_CAP_C0603-2.2UF,16V,20%,X7R,A    I88 @S9S_MB_2U_LIB.S9S_MB_2U(SCH_1):PAGE236
PC2160    2      B Q_CAP_0402-0.1UF,25V,10%,X7R,CA    I91 @S9S_MB_2U_LIB.S9S_MB_2U(SCH_1):PAGE236
  Q118    1     S1 MOSFET_NCH_DUAL-PJT138K,SMLF,EA     I7 @S9S_MB_2U_LIB.S9S_MB_2U(SCH_1):PAGE131
 C1810    2      B Q_CAP_0402-0.1UF,25V,10%,X7R,CA    I21 @S9S_MB_2U_LIB.S9S_MB_2U(SCH_1):PAGE131
PR3828    2      B Q_RES_0402LF-15K,1%,1/16W,EMPTA    I29 @S9S_MB_2U_LIB.S9S_MB_2U(SCH_1):PAGE131
 R4066    2      B Q_RES_0402LF-4.7K,5%,1/16W,CHIA    I37 @S9S_MB_2U_LIB.S9S_MB_2U(SCH_1):PAGE131
 PD107    A      A DIODE_TVS-SMF14A,SMLF,IC,BCSMFA    I44 @S9S_MB_2U_LIB.S9S_MB_2U(SCH_1):PAGE131
PC2139    2      B Q_CAP_C0402-1UF,25V,10%,X6S,CHA    I46 @S9S_MB_2U_LIB.S9S_MB_2U(SCH_1):PAGE131
PC2098    2      B Q_CAP_C0402-1UF,25V,10%,EMPTY,A    I61 @S9S_MB_2U_LIB.S9S_MB_2U(SCH_1):PAGE131
PC2146    1      A Q_CAP_C0402-1UF,25V,10%,EMPTY,A    I62 @S9S_MB_2U_LIB.S9S_MB_2U(SCH_1):PAGE131
PR3823    2      B Q_RES_0402LF-845,1%,1/16W,EMPTA    I72 @S9S_MB_2U_LIB.S9S_MB_2U(SCH_1):PAGE131
PC2150    2      B Q_CAP_C0402-3900PF,50V,10%,EMPA    I76 @S9S_MB_2U_LIB.S9S_MB_2U(SCH_1):PAGE131
 PC190    2      B Q_CAP_C0402-1UF,25V,10%,X6S,CHA    I91 @S9S_MB_2U_LIB.S9S_MB_2U(SCH_1):PAGE131
PR3824    2      B Q_RES_0402LF-4.53K,1%,1/16W,CHA    I95 @S9S_MB_2U_LIB.S9S_MB_2U(SCH_1):PAGE131
PC2152    2      B Q_CAP_0402-0.1UF,25V,10%,X7R,CA    I98 @S9S_MB_2U_LIB.S9S_MB_2U(SCH_1):PAGE131
PR3847    2      B Q_RES_0402LF-14.3K,1%,1/16W,CHA    I61 @S9S_MB_2U_LIB.S9S_MB_2U(SCH_1):PAGE237
PC2164    2      B Q_CAP_0402-0.22UF,16V,10%,X7R,A    I62 @S9S_MB_2U_LIB.S9S_MB_2U(SCH_1):PAGE237
PC2166    2      B Q_CAP_C0402-0.047UF,25V,10%,X7A    I65 @S9S_MB_2U_LIB.S9S_MB_2U(SCH_1):PAGE237
PC2165    2      B Q_CAP_C0402-1UF,25V,10%,X6S,CHA    I68 @S9S_MB_2U_LIB.S9S_MB_2U(SCH_1):PAGE237
 PU206    3   ENTM RS31312R-RS31312R,SMLF,IC,AL03A    I70 @S9S_MB_2U_LIB.S9S_MB_2U(SCH_1):PAGE237
 PU206    7    GND RS31312R-RS31312R,SMLF,IC,AL03A    I70 @S9S_MB_2U_LIB.S9S_MB_2U(SCH_1):PAGE237
 PU206    2 LOADEN RS31312R-RS31312R,SMLF,IC,AL03A    I70 @S9S_MB_2U_LIB.S9S_MB_2U(SCH_1):PAGE237
PR3849    2      B Q_RES_0402LF-17.4K,1%,1/16W,CHA    I72 @S9S_MB_2U_LIB.S9S_MB_2U(SCH_1):PAGE237
PC2167    2      B Q_CAP_0402-100PF,50V,5%,X7R,CHA    I73 @S9S_MB_2U_LIB.S9S_MB_2U(SCH_1):PAGE237
PR3854    2      B Q_RES_0402LF-10K,1%,1/16W,CHIPA    I83 @S9S_MB_2U_LIB.S9S_MB_2U(SCH_1):PAGE237
PC2174    2      B Q_CAP_0402-0.1UF,25V,10%,X7R,CA    I91 @S9S_MB_2U_LIB.S9S_MB_2U(SCH_1):PAGE237
PC1320    2      B Q_CAP_C0603-2.2UF,16V,20%,X7R,A    I95 @S9S_MB_2U_LIB.S9S_MB_2U(SCH_1):PAGE237
PR3949    2      B Q_RES_0402LF-56K,1%,1/16W,CHIPA    I53 @S9S_MB_2U_LIB.S9S_MB_2U(SCH_1):PAGE323
PR3954    2      B Q_RES_0402LF-10K,1%,1/16W,CHIPA    I58 @S9S_MB_2U_LIB.S9S_MB_2U(SCH_1):PAGE323
PC2205    2      B Q_CAP_C0603-2.2UF,16V,20%,X7R,A    I69 @S9S_MB_2U_LIB.S9S_MB_2U(SCH_1):PAGE323
PC2206    2      B Q_CAP_0402-0.1UF,25V,10%,X7R,CA    I73 @S9S_MB_2U_LIB.S9S_MB_2U(SCH_1):PAGE323
  Q126    1     S1 MOSFET_NCH_DUAL-PJT138K,SMLF,IA     I3 @S9S_MB_2U_LIB.S9S_MB_2U(SCH_1):PAGE324
  Q127    1     S1 MOSFET_NCH_DUAL-PJT138K,SMLF,EA    I10 @S9S_MB_2U_LIB.S9S_MB_2U(SCH_1):PAGE324
  Q127    4     S2 MOSFET_NCH_DUAL-PJT138K,SMLF,EA    I24 @S9S_MB_2U_LIB.S9S_MB_2U(SCH_1):PAGE324
 PU295   A7   CDLY MAX15090BEWIT-MAX15090BEWI+T,SB    I35 @S9S_MB_2U_LIB.S9S_MB_2U(SCH_1):PAGE324
 PU295   B7    EN# MAX15090BEWIT-MAX15090BEWI+T,SB    I35 @S9S_MB_2U_LIB.S9S_MB_2U(SCH_1):PAGE324
 PU295   B2 GND_B2 MAX15090BEWIT-MAX15090BEWI+T,SB    I35 @S9S_MB_2U_LIB.S9S_MB_2U(SCH_1):PAGE324
 PU295   C1 GND_C1 MAX15090BEWIT-MAX15090BEWI+T,SB    I35 @S9S_MB_2U_LIB.S9S_MB_2U(SCH_1):PAGE324
 PU295   C2 GND_C2 MAX15090BEWIT-MAX15090BEWI+T,SB    I35 @S9S_MB_2U_LIB.S9S_MB_2U(SCH_1):PAGE324
PC2212    1      A Q_CAP_C0402-1UF,25V,10%,X6S,CHA    I38 @S9S_MB_2U_LIB.S9S_MB_2U(SCH_1):PAGE324
PC2218    2      B Q_CAP_0402-0.1UF,25V,10%,X7R,CA    I52 @S9S_MB_2U_LIB.S9S_MB_2U(SCH_1):PAGE324
PC2220    2      B Q_CAP_C0805-10UF,16V,10%,X6S,CB    I53 @S9S_MB_2U_LIB.S9S_MB_2U(SCH_1):PAGE324
PC2211    1      A Q_CAP_C0402-1UF,25V,10%,EMPTY,A    I57 @S9S_MB_2U_LIB.S9S_MB_2U(SCH_1):PAGE324
PR3968    2      B Q_RES_0402LF-9.31K,1%,1/16W,EMA    I59 @S9S_MB_2U_LIB.S9S_MB_2U(SCH_1):PAGE324
PR3970    2      B Q_RES_0402LF-2.67K,1%,1/16W,EMA    I64 @S9S_MB_2U_LIB.S9S_MB_2U(SCH_1):PAGE324
PC2280    2      B Q_CAP_C0805-10UF,16V,10%,X6S,CC    I79 @S9S_MB_2U_LIB.S9S_MB_2U(SCH_1):PAGE324
 PD114    A      A DIODE_TVS-SMF14A,SMLF,IC,BCSMFA    I84 @S9S_MB_2U_LIB.S9S_MB_2U(SCH_1):PAGE324
 C2541    2      B Q_CAP_C0402-0.22UF,25V,10%,X7RA    I73 @S9S_MB_2U_LIB.S9S_MB_2U(SCH_1):PAGE245
 R3118    2      B Q_RES_0402LF-86.6K,1%,1/16W,EMA    I76 @S9S_MB_2U_LIB.S9S_MB_2U(SCH_1):PAGE245
 PR832    2      B Q_RES_0402LF-0,5%,1/16W,CHIP,CA    I84 @S9S_MB_2U_LIB.S9S_MB_2U(SCH_1):PAGE245
 PC581    2      B Q_CAP_C0603-4.7UF,16V,10%,X6S,A    I86 @S9S_MB_2U_LIB.S9S_MB_2U(SCH_1):PAGE245
 PR833    2      B Q_RES_0402LF-1.5K,1%,1/16W,EMPA    I89 @S9S_MB_2U_LIB.S9S_MB_2U(SCH_1):PAGE245
 PR834    2      B Q_RES_0402LF-21.5K,1%,1/16W,CHA    I91 @S9S_MB_2U_LIB.S9S_MB_2U(SCH_1):PAGE245
 PC591    2      B Q_CAP_C0603-2.2UF,16V,10%,X6S,A    I93 @S9S_MB_2U_LIB.S9S_MB_2U(SCH_1):PAGE245
   PU9   32   AGND IR3889MTRPBF-IR3889MTRPBF,SMLFA    I95 @S9S_MB_2U_LIB.S9S_MB_2U(SCH_1):PAGE245
   PU9 7_10-19   PGND IR3889MTRPBF-IR3889MTRPBF,SMLFA    I95 @S9S_MB_2U_LIB.S9S_MB_2U(SCH_1):PAGE245
   PU9   31  VSENM IR3889MTRPBF-IR3889MTRPBF,SMLFA    I95 @S9S_MB_2U_LIB.S9S_MB_2U(SCH_1):PAGE245
PC1649    2      B Q_CAP_C0402-100NF,50V,10%,X7R,A    I97 @S9S_MB_2U_LIB.S9S_MB_2U(SCH_1):PAGE245
PC2260    2      B Q_CAP_C0805-22UF,16V,20%,X6S,CA   I100 @S9S_MB_2U_LIB.S9S_MB_2U(SCH_1):PAGE245
PC2261    2      B Q_CAP_C0805-22UF,16V,20%,X6S,CA   I101 @S9S_MB_2U_LIB.S9S_MB_2U(SCH_1):PAGE245
   PC3    2      B Q_CAPP_THLF-270UF,16V,20%,OSCOA   I103 @S9S_MB_2U_LIB.S9S_MB_2U(SCH_1):PAGE245
 PC566    2      B Q_CAPP_THLF-270UF,16V,20%,OSCOA   I104 @S9S_MB_2U_LIB.S9S_MB_2U(SCH_1):PAGE245
PC2262    2      B Q_CAP_C0805-22UF,16V,20%,X6S,CA   I105 @S9S_MB_2U_LIB.S9S_MB_2U(SCH_1):PAGE245
 PC567    2      B Q_CAP_C0805-22UF,16V,20%,X6S,CA   I106 @S9S_MB_2U_LIB.S9S_MB_2U(SCH_1):PAGE245
PC2263    2      B Q_CAP_C0805-22UF,16V,20%,X6S,CA   I107 @S9S_MB_2U_LIB.S9S_MB_2U(SCH_1):PAGE245
PC2342    2      B Q_CAP_C0805-22UF,16V,20%,X6S,CA   I108 @S9S_MB_2U_LIB.S9S_MB_2U(SCH_1):PAGE245
 PC570    2      B Q_CAP_C0805-22UF,16V,20%,X6S,CA   I109 @S9S_MB_2U_LIB.S9S_MB_2U(SCH_1):PAGE245
 PC571    2      B Q_CAP_C0805-22UF,16V,20%,X6S,CA   I110 @S9S_MB_2U_LIB.S9S_MB_2U(SCH_1):PAGE245
PC2343    2      B Q_CAP_C0805-22UF,16V,20%,X6S,CA   I111 @S9S_MB_2U_LIB.S9S_MB_2U(SCH_1):PAGE245
PC2344    2      B Q_CAP_C0805-22UF,16V,20%,X6S,CA   I112 @S9S_MB_2U_LIB.S9S_MB_2U(SCH_1):PAGE245
 PC576    2      B Q_CAP_C0805-22UF,16V,20%,X6S,CA   I113 @S9S_MB_2U_LIB.S9S_MB_2U(SCH_1):PAGE245
  PC71    2      B Q_CAP_C0805-22UF,16V,20%,X6S,CA   I114 @S9S_MB_2U_LIB.S9S_MB_2U(SCH_1):PAGE245
 PC577    2      B Q_CAP_0402-0.1UF,25V,10%,X7R,CA   I115 @S9S_MB_2U_LIB.S9S_MB_2U(SCH_1):PAGE245
   PC8    2      B Q_CAP_C0603-4.7UF,16V,10%,X6S,A   I118 @S9S_MB_2U_LIB.S9S_MB_2U(SCH_1):PAGE245
 PR830    2      B Q_RES_0402LF-15K,0.1%,1/16W,CHA   I125 @S9S_MB_2U_LIB.S9S_MB_2U(SCH_1):PAGE245
PC1866    2      B Q_CAPP_THLF-560UF,6.3V,20%,OSCA   I131 @S9S_MB_2U_LIB.S9S_MB_2U(SCH_1):PAGE245
PC1867    2      B Q_CAPP_THLF-560UF,6.3V,20%,OSCA   I132 @S9S_MB_2U_LIB.S9S_MB_2U(SCH_1):PAGE245
PC1868    2      B Q_CAP_C0805-22UF,10V,20%,X6S,CA   I133 @S9S_MB_2U_LIB.S9S_MB_2U(SCH_1):PAGE245
PC1599    2      B Q_CAP_C0805-22UF,10V,20%,X6S,CA   I134 @S9S_MB_2U_LIB.S9S_MB_2U(SCH_1):PAGE245
PC1600    2      B Q_CAP_C0805-22UF,10V,20%,X6S,CA   I136 @S9S_MB_2U_LIB.S9S_MB_2U(SCH_1):PAGE245
PC1869    2      B Q_CAP_0402-0.1UF,25V,10%,X7R,CA   I137 @S9S_MB_2U_LIB.S9S_MB_2U(SCH_1):PAGE245
   Q39    S      S MOSFET_NCH_GDS_ESD_PROTECTED-2A     I9 @S9S_MB_2U_LIB.S9S_MB_2U(SCH_1):PAGE229
  Q125    4     S2 MOSFET_NCH_DUAL-PJT138K,SMLF,EA    I26 @S9S_MB_2U_LIB.S9S_MB_2U(SCH_1):PAGE229
PC2241    2      B Q_CAP_0402-0.1UF,25V,10%,X7R,CA    I57 @S9S_MB_2U_LIB.S9S_MB_2U(SCH_1):PAGE229
PR4002    2      B Q_RES_0402LF-15K,1%,1/16W,EMPTA    I61 @S9S_MB_2U_LIB.S9S_MB_2U(SCH_1):PAGE229
 PU300   A7   CDLY MAX15090BEWIT-MAX15090BEWI+T,SA    I69 @S9S_MB_2U_LIB.S9S_MB_2U(SCH_1):PAGE229
 PU300   B7    EN# MAX15090BEWIT-MAX15090BEWI+T,SA    I69 @S9S_MB_2U_LIB.S9S_MB_2U(SCH_1):PAGE229
 PU300   B2 GND_B2 MAX15090BEWIT-MAX15090BEWI+T,SA    I69 @S9S_MB_2U_LIB.S9S_MB_2U(SCH_1):PAGE229
 PU300   C1 GND_C1 MAX15090BEWIT-MAX15090BEWI+T,SA    I69 @S9S_MB_2U_LIB.S9S_MB_2U(SCH_1):PAGE229
 PU300   C2 GND_C2 MAX15090BEWIT-MAX15090BEWI+T,SA    I69 @S9S_MB_2U_LIB.S9S_MB_2U(SCH_1):PAGE229
PC2237    2      B Q_CAP_C0402-3900PF,50V,10%,EMPA    I75 @S9S_MB_2U_LIB.S9S_MB_2U(SCH_1):PAGE229
 PD116    A      A SCHOTTKY_AC-B340A-13-F,SMLF,ICA    I82 @S9S_MB_2U_LIB.S9S_MB_2U(SCH_1):PAGE229
PC2240    2      B Q_CAP_C0805-10UF,16V,10%,X6S,CC    I84 @S9S_MB_2U_LIB.S9S_MB_2U(SCH_1):PAGE229
PC2242    2      B Q_CAP_C0805-22UF,16V,20%,X6S,CC    I88 @S9S_MB_2U_LIB.S9S_MB_2U(SCH_1):PAGE229
 PU299    3   ENTM RS31312R-RS31312R,SMLF,IC,AL03A    I90 @S9S_MB_2U_LIB.S9S_MB_2U(SCH_1):PAGE229
 PU299    7    GND RS31312R-RS31312R,SMLF,IC,AL03A    I90 @S9S_MB_2U_LIB.S9S_MB_2U(SCH_1):PAGE229
 PU299    2 LOADEN RS31312R-RS31312R,SMLF,IC,AL03A    I90 @S9S_MB_2U_LIB.S9S_MB_2U(SCH_1):PAGE229
PC1648    2      B Q_CAP_C0402-100NF,50V,10%,X7R,A     I2 @S9S_MB_2U_LIB.S9S_MB_2U(SCH_1):PAGE244
PC1849    2      B Q_CAP_C0805-22UF,16V,20%,X6S,CA     I7 @S9S_MB_2U_LIB.S9S_MB_2U(SCH_1):PAGE244
PC1848    2      B Q_CAP_C0402-1UF,25V,10%,X6S,CHA     I8 @S9S_MB_2U_LIB.S9S_MB_2U(SCH_1):PAGE244
PC1850    2      B Q_CAP_C0805-22UF,16V,20%,X6S,CA    I11 @S9S_MB_2U_LIB.S9S_MB_2U(SCH_1):PAGE244
PC1846    2      B Q_CAP_C0402-1UF,16V,10%,X6S,CHA    I14 @S9S_MB_2U_LIB.S9S_MB_2U(SCH_1):PAGE244
 PU181    2   AGND RS53318LR-RS53318LR,SMLF,IC,ALA    I20 @S9S_MB_2U_LIB.S9S_MB_2U(SCH_1):PAGE244
 PU181 11_18   PGND RS53318LR-RS53318LR,SMLF,IC,ALA    I20 @S9S_MB_2U_LIB.S9S_MB_2U(SCH_1):PAGE244
 PU181    6    RTN RS53318LR-RS53318LR,SMLF,IC,ALA    I20 @S9S_MB_2U_LIB.S9S_MB_2U(SCH_1):PAGE244
PC1853    2      B Q_CAP_0402-0.1UF,25V,10%,X7R,CA    I21 @S9S_MB_2U_LIB.S9S_MB_2U(SCH_1):PAGE244
PC1845    2      B Q_CAPP_SMLF-220UF,6.3V,20%,ALUA    I32 @S9S_MB_2U_LIB.S9S_MB_2U(SCH_1):PAGE244
PC1855    2      B Q_CAP_C0805-22UF,10V,20%,X6S,CA    I33 @S9S_MB_2U_LIB.S9S_MB_2U(SCH_1):PAGE244
PC1852    2      B Q_CAP_0402-0.1UF,25V,10%,X7R,CA    I36 @S9S_MB_2U_LIB.S9S_MB_2U(SCH_1):PAGE244
PR1850    1      A Q_RES_0402LF-1K,1%,1/16W,EMPTYA    I11 @S9S_MB_2U_LIB.S9S_MB_2U(SCH_1):PAGE249
PC1232    2      B Q_CAP_C0805-10UF,16V,10%,X6S,CB    I19 @S9S_MB_2U_LIB.S9S_MB_2U(SCH_1):PAGE249
PC1233    2      B Q_CAP_C0805-10UF,16V,10%,X6S,CB    I20 @S9S_MB_2U_LIB.S9S_MB_2U(SCH_1):PAGE249
PC1241    2      B Q_CAP_C0805-22UF,4V,20%,X6S,CHA    I41 @S9S_MB_2U_LIB.S9S_MB_2U(SCH_1):PAGE249
PR1653    2      B Q_RES_0402LF-470,1%,1/16W,CHIPA    I42 @S9S_MB_2U_LIB.S9S_MB_2U(SCH_1):PAGE249
PC1247    2      B Q_CAP_C0805-22UF,16V,20%,X6S,CA    I10 @S9S_MB_2U_LIB.S9S_MB_2U(SCH_1):PAGE267
 R2332    2      B Q_RES_0402LF-2K,1%,1/16W,CHIP,A    I14 @S9S_MB_2U_LIB.S9S_MB_2U(SCH_1):PAGE267
  PU79    2   AGND RS53318LR-RS53318LR,SMLF,IC,ALA    I19 @S9S_MB_2U_LIB.S9S_MB_2U(SCH_1):PAGE267
  PU79 11_18   PGND RS53318LR-RS53318LR,SMLF,IC,ALA    I19 @S9S_MB_2U_LIB.S9S_MB_2U(SCH_1):PAGE267
PC1257    2      B Q_CAP_C0805-22UF,4V,20%,X6S,CHA    I44 @S9S_MB_2U_LIB.S9S_MB_2U(SCH_1):PAGE267
 PC113    2      B Q_CAP_C0402-1UF,25V,10%,X6S,CHA     I2 @S9S_MB_2U_LIB.S9S_MB_2U(SCH_1):PAGE248
 PR338    2      B Q_RES_0402LF-0,5%,1/16W,CHIP,CA    I10 @S9S_MB_2U_LIB.S9S_MB_2U(SCH_1):PAGE248
PC2000    2      B Q_CAP_0402-0.022UF,16V,10%,X7RA    I14 @S9S_MB_2U_LIB.S9S_MB_2U(SCH_1):PAGE248
PC1216    2      B Q_CAP_C0805-22UF,16V,20%,X6S,CA    I25 @S9S_MB_2U_LIB.S9S_MB_2U(SCH_1):PAGE248
PC1224    2      B Q_CAP_0402-0.1UF,25V,10%,X7R,CA    I38 @S9S_MB_2U_LIB.S9S_MB_2U(SCH_1):PAGE248
 PC117    2      B Q_CAPP_SMLF-330UF,2V,35%,SPCAPA    I40 @S9S_MB_2U_LIB.S9S_MB_2U(SCH_1):PAGE248
PC1230    2      B Q_CAPP_THLF-560UF,2.5V,20%,OSCA    I48 @S9S_MB_2U_LIB.S9S_MB_2U(SCH_1):PAGE248
PC2221    2      B Q_CAP_C0402-1UF,25V,10%,X6S,CHA     I7 @S9S_MB_2U_LIB.S9S_MB_2U(SCH_1):PAGE268
PR1301    2      B Q_RES_0402LF-60.4K,1%,1/16W,CHA     I9 @S9S_MB_2U_LIB.S9S_MB_2U(SCH_1):PAGE268
PC1272    2      B Q_CAP_C0805-22UF,16V,20%,X6S,CA    I13 @S9S_MB_2U_LIB.S9S_MB_2U(SCH_1):PAGE268
PR1303    2      B Q_RES_0402LF-22.6K,1%,1/16W,CHA    I21 @S9S_MB_2U_LIB.S9S_MB_2U(SCH_1):PAGE268
  PU81    7   AGND RS53317LR-RS53317LR,SMLF,IC,ALA    I22 @S9S_MB_2U_LIB.S9S_MB_2U(SCH_1):PAGE268
  PU81    1  PGND1 RS53317LR-RS53317LR,SMLF,IC,ALA    I22 @S9S_MB_2U_LIB.S9S_MB_2U(SCH_1):PAGE268
  PU81   14  PGND2 RS53317LR-RS53317LR,SMLF,IC,ALA    I22 @S9S_MB_2U_LIB.S9S_MB_2U(SCH_1):PAGE268
PC1276    2      B Q_CAP_C0402-100NF,50V,10%,X7R,A    I37 @S9S_MB_2U_LIB.S9S_MB_2U(SCH_1):PAGE268
PC1277    2      B Q_CAP_C0805-22UF,4V,20%,X6S,CHA    I38 @S9S_MB_2U_LIB.S9S_MB_2U(SCH_1):PAGE268
PC1206    2      B Q_CAP_C0805-22UF,4V,20%,X6S,CHA    I47 @S9S_MB_2U_LIB.S9S_MB_2U(SCH_1):PAGE268
 PC644    2      B Q_CAP_C0402-1UF,25V,10%,X6S,CHA     I1 @S9S_MB_2U_LIB.S9S_MB_2U(SCH_1):PAGE285
PC1259    2      B Q_CAP_C0805-22UF,16V,20%,X6S,CA     I8 @S9S_MB_2U_LIB.S9S_MB_2U(SCH_1):PAGE285
PC2002    2      B Q_CAP_0402-0.022UF,16V,10%,X7RA    I23 @S9S_MB_2U_LIB.S9S_MB_2U(SCH_1):PAGE285
PC1267    2      B Q_CAP_0402-0.1UF,25V,10%,X7R,CA    I39 @S9S_MB_2U_LIB.S9S_MB_2U(SCH_1):PAGE285
PC1268    2      B Q_CAP_C0805-22UF,4V,20%,X6S,CHA    I40 @S9S_MB_2U_LIB.S9S_MB_2U(SCH_1):PAGE285
PC1270    2      B Q_CAP_C0805-22UF,4V,20%,X6S,CHA    I47 @S9S_MB_2U_LIB.S9S_MB_2U(SCH_1):PAGE285
PC1771    2      B Q_CAPP_THLF-560UF,6.3V,20%,OSCA    I49 @S9S_MB_2U_LIB.S9S_MB_2U(SCH_1):PAGE285
 R2385    2      B Q_RES_0402LF-2K,1%,1/16W,CHIP,A     I7 @S9S_MB_2U_LIB.S9S_MB_2U(SCH_1):PAGE286
PC2222    2      B Q_CAP_C0402-1UF,25V,10%,X6S,CHA    I10 @S9S_MB_2U_LIB.S9S_MB_2U(SCH_1):PAGE286
PR2220    2      B Q_RES_0402LF-60.4K,1%,1/16W,CHA    I12 @S9S_MB_2U_LIB.S9S_MB_2U(SCH_1):PAGE286
PC1281    2      B Q_CAP_C0805-22UF,16V,20%,X6S,CA    I14 @S9S_MB_2U_LIB.S9S_MB_2U(SCH_1):PAGE286
PR2222    2      B Q_RES_0402LF-34.8K,1%,1/16W,CHA    I19 @S9S_MB_2U_LIB.S9S_MB_2U(SCH_1):PAGE286
PC1284    2      B Q_CAP_C0402-100NF,50V,10%,X7R,A    I28 @S9S_MB_2U_LIB.S9S_MB_2U(SCH_1):PAGE286
 C1297    2      B Q_CAP_0402-1000PF,50V,5%,X7R,TA    I37 @S9S_MB_2U_LIB.S9S_MB_2U(SCH_1):PAGE286
PC2277    2      B Q_CAP_0402-0.01UF,25V,10%,X7R,A    I40 @S9S_MB_2U_LIB.S9S_MB_2U(SCH_1):PAGE286
PC1207    2      B Q_CAP_C0805-22UF,4V,20%,X6S,CHA    I45 @S9S_MB_2U_LIB.S9S_MB_2U(SCH_1):PAGE286
 R1692    2      B Q_RES_0402LF-100K,1%,1/16W,CHIA     I3 @S9S_MB_2U_LIB.S9S_MB_2U(SCH_1):PAGE232
 C1318    2      B Q_CAP_C0402-1UF,25V,10%,EMPTY,A     I7 @S9S_MB_2U_LIB.S9S_MB_2U(SCH_1):PAGE232
 C1317    2      B Q_CAP_0402-0.1UF,25V,10%,X7R,CA     I9 @S9S_MB_2U_LIB.S9S_MB_2U(SCH_1):PAGE232
   U95    3    GND 74LVC1G07SE7-74LVC1G07SE-7,SMLA    I11 @S9S_MB_2U_LIB.S9S_MB_2U(SCH_1):PAGE232
   Q52    S      S MOSFET_NCH_GDS_ESD_PROTECTED-2A    I14 @S9S_MB_2U_LIB.S9S_MB_2U(SCH_1):PAGE232
 R1689    2      B Q_RES_0402LF-6.19K,1%,1/16W,CHA    I16 @S9S_MB_2U_LIB.S9S_MB_2U(SCH_1):PAGE232
 C1315    2      B Q_CAP_C0402-1UF,25V,10%,X6S,CHA    I24 @S9S_MB_2U_LIB.S9S_MB_2U(SCH_1):PAGE232
  U117    2    GND TPS3895ADRYR-TPS3895ADRYR,SMLFA    I26 @S9S_MB_2U_LIB.S9S_MB_2U(SCH_1):PAGE232
   U94    2    GND ADM1086AKSZREEL7-ADM1086AKSZ-RA    I27 @S9S_MB_2U_LIB.S9S_MB_2U(SCH_1):PAGE232
 R4808    2      B Q_RES_0402LF-100K,1%,1/16W,EMPA    I31 @S9S_MB_2U_LIB.S9S_MB_2U(SCH_1):PAGE232
   Q53    S      S MOSFET_NCH_GDS_ESD_PROTECTED-2A    I39 @S9S_MB_2U_LIB.S9S_MB_2U(SCH_1):PAGE232
  R678    2      B Q_RES_0402LF-1K,1%,1/16W,CHIP,A    I13 @S9S_MB_2U_LIB.S9S_MB_2U(SCH_1):PAGE217
   U15    8    GND QS3VH257QG8_SMLF-QS3VH257QG8,IA    I19 @S9S_MB_2U_LIB.S9S_MB_2U(SCH_1):PAGE217
  C538    2      B Q_CAP_0402-0.1UF,25V,10%,X7R,CA    I24 @S9S_MB_2U_LIB.S9S_MB_2U(SCH_1):PAGE217
  R318    2      B Q_RES_0402LF-10K,1%,1/16W,CHIPA    I42 @S9S_MB_2U_LIB.S9S_MB_2U(SCH_1):PAGE217
 R4592    2      B Q_RES_0402LF-1K,1%,1/16W,CHIP,A     I4 @S9S_MB_2U_LIB.S9S_MB_2U(SCH_1):PAGE184
 R2235    2      B Q_RES_0402LF-1K,1%,1/16W,CHIP,A     I9 @S9S_MB_2U_LIB.S9S_MB_2U(SCH_1):PAGE184
 R2977    2      B Q_RES_0402LF-1K,1%,1/16W,CHIP,A    I11 @S9S_MB_2U_LIB.S9S_MB_2U(SCH_1):PAGE184
 R4598    2      B Q_RES_0402LF-1K,1%,1/16W,CHIP,A    I16 @S9S_MB_2U_LIB.S9S_MB_2U(SCH_1):PAGE184
 R2980    2      B Q_RES_0402LF-1K,1%,1/16W,CHIP,A    I26 @S9S_MB_2U_LIB.S9S_MB_2U(SCH_1):PAGE184
 R2241    2      B Q_RES_0402LF-1K,1%,1/16W,CHIP,A    I28 @S9S_MB_2U_LIB.S9S_MB_2U(SCH_1):PAGE184
 R4596    2      B Q_RES_0402LF-1K,1%,1/16W,EMPTYA    I61 @S9S_MB_2U_LIB.S9S_MB_2U(SCH_1):PAGE184
  Q139    1     E1 BC847BPN-BC847BPN,SMLF,IC,BA00A    I21 @S9S_MB_2U_LIB.S9S_MB_2U(SCH_1):PAGE121
  Q138    1     E1 BC847BPN-BC847BPN,SMLF,IC,BA00A    I31 @S9S_MB_2U_LIB.S9S_MB_2U(SCH_1):PAGE121
  Q142    1     E1 BC847BPN-BC847BPN,SMLF,IC,BA00A    I17 @S9S_MB_2U_LIB.S9S_MB_2U(SCH_1):PAGE122
  Q143    1     E1 BC847BPN-BC847BPN,SMLF,IC,BA00A    I22 @S9S_MB_2U_LIB.S9S_MB_2U(SCH_1):PAGE122
  Q140    1     E1 BC847BPN-BC847BPN,SMLF,IC,BA00A    I16 @S9S_MB_2U_LIB.S9S_MB_2U(SCH_1):PAGE123
  Q141    1     E1 BC847BPN-BC847BPN,SMLF,IC,BA00A    I18 @S9S_MB_2U_LIB.S9S_MB_2U(SCH_1):PAGE123
 R4769    2      B Q_RES_0402LF-100K,1%,1/16W,CHIA     I3 @S9S_MB_2U_LIB.S9S_MB_2U(SCH_1):PAGE233
   J45   B3     B3 CONN60_101062636003K02LF-CONN6A    I12 @S9S_MB_2U_LIB.S9S_MB_2U(SCH_1):PAGE233
   J45 P1_1   P1_1 CONN60_101062636003K02LF-CONN6A    I12 @S9S_MB_2U_LIB.S9S_MB_2U(SCH_1):PAGE233
   J45 P1_2   P1_2 CONN60_101062636003K02LF-CONN6A    I12 @S9S_MB_2U_LIB.S9S_MB_2U(SCH_1):PAGE233
   J45 P1_3   P1_3 CONN60_101062636003K02LF-CONN6A    I12 @S9S_MB_2U_LIB.S9S_MB_2U(SCH_1):PAGE233
   J45 P1_4   P1_4 CONN60_101062636003K02LF-CONN6A    I12 @S9S_MB_2U_LIB.S9S_MB_2U(SCH_1):PAGE233
   J45 P1_5   P1_5 CONN60_101062636003K02LF-CONN6A    I12 @S9S_MB_2U_LIB.S9S_MB_2U(SCH_1):PAGE233
   J45 P1_6   P1_6 CONN60_101062636003K02LF-CONN6A    I12 @S9S_MB_2U_LIB.S9S_MB_2U(SCH_1):PAGE233
   J45 P1_7   P1_7 CONN60_101062636003K02LF-CONN6A    I12 @S9S_MB_2U_LIB.S9S_MB_2U(SCH_1):PAGE233
   J45 P1_8   P1_8 CONN60_101062636003K02LF-CONN6A    I12 @S9S_MB_2U_LIB.S9S_MB_2U(SCH_1):PAGE233
   J45 P2_1   P2_1 CONN60_101062636003K02LF-CONN6A    I12 @S9S_MB_2U_LIB.S9S_MB_2U(SCH_1):PAGE233
   J45 P2_2   P2_2 CONN60_101062636003K02LF-CONN6A    I12 @S9S_MB_2U_LIB.S9S_MB_2U(SCH_1):PAGE233
   J45 P2_3   P2_3 CONN60_101062636003K02LF-CONN6A    I12 @S9S_MB_2U_LIB.S9S_MB_2U(SCH_1):PAGE233
   J45 P2_4   P2_4 CONN60_101062636003K02LF-CONN6A    I12 @S9S_MB_2U_LIB.S9S_MB_2U(SCH_1):PAGE233
   J45 P2_5   P2_5 CONN60_101062636003K02LF-CONN6A    I12 @S9S_MB_2U_LIB.S9S_MB_2U(SCH_1):PAGE233
   J45 P2_6   P2_6 CONN60_101062636003K02LF-CONN6A    I12 @S9S_MB_2U_LIB.S9S_MB_2U(SCH_1):PAGE233
   J45 P2_7   P2_7 CONN60_101062636003K02LF-CONN6A    I12 @S9S_MB_2U_LIB.S9S_MB_2U(SCH_1):PAGE233
   J45 P2_8   P2_8 CONN60_101062636003K02LF-CONN6A    I12 @S9S_MB_2U_LIB.S9S_MB_2U(SCH_1):PAGE233
   J45 P3_1   P3_1 CONN60_101062636003K02LF-CONN6A    I12 @S9S_MB_2U_LIB.S9S_MB_2U(SCH_1):PAGE233
   J45 P3_2   P3_2 CONN60_101062636003K02LF-CONN6A    I12 @S9S_MB_2U_LIB.S9S_MB_2U(SCH_1):PAGE233
   J45 P3_3   P3_3 CONN60_101062636003K02LF-CONN6A    I12 @S9S_MB_2U_LIB.S9S_MB_2U(SCH_1):PAGE233
   J45 P3_4   P3_4 CONN60_101062636003K02LF-CONN6A    I12 @S9S_MB_2U_LIB.S9S_MB_2U(SCH_1):PAGE233
   J45 P3_5   P3_5 CONN60_101062636003K02LF-CONN6A    I12 @S9S_MB_2U_LIB.S9S_MB_2U(SCH_1):PAGE233
   J45 P3_6   P3_6 CONN60_101062636003K02LF-CONN6A    I12 @S9S_MB_2U_LIB.S9S_MB_2U(SCH_1):PAGE233
   J45 P3_7   P3_7 CONN60_101062636003K02LF-CONN6A    I12 @S9S_MB_2U_LIB.S9S_MB_2U(SCH_1):PAGE233
   J45 P3_8   P3_8 CONN60_101062636003K02LF-CONN6A    I12 @S9S_MB_2U_LIB.S9S_MB_2U(SCH_1):PAGE233
  U192    4    GND LTC4307CMS8-LTC4307CMS8,SMLF,IA    I16 @S9S_MB_2U_LIB.S9S_MB_2U(SCH_1):PAGE233
 C1751    2      B Q_CAP_0402-0.1UF,25V,10%,X7R,CA    I19 @S9S_MB_2U_LIB.S9S_MB_2U(SCH_1):PAGE233
 C2371    2      B Q_CAP_0402-0.1UF,25V,10%,EMPTYA    I51 @S9S_MB_2U_LIB.S9S_MB_2U(SCH_1):PAGE233
 C2297    2      B Q_CAP_0402-0.1UF,25V,10%,EMPTYA    I52 @S9S_MB_2U_LIB.S9S_MB_2U(SCH_1):PAGE233
 C2296    2      B Q_CAP_0402-0.1UF,25V,10%,EMPTYA    I53 @S9S_MB_2U_LIB.S9S_MB_2U(SCH_1):PAGE233
 C2295    2      B Q_CAP_0402-0.1UF,25V,10%,EMPTYA    I54 @S9S_MB_2U_LIB.S9S_MB_2U(SCH_1):PAGE233
 C2294    2      B Q_CAP_0402-0.1UF,25V,10%,EMPTYA    I55 @S9S_MB_2U_LIB.S9S_MB_2U(SCH_1):PAGE233
 C2293    2      B Q_CAP_0402-0.1UF,25V,10%,EMPTYA    I57 @S9S_MB_2U_LIB.S9S_MB_2U(SCH_1):PAGE233
  R661    2      B Q_RES_0402LF-1K,1%,1/16W,CHIP,A     I4 @S9S_MB_2U_LIB.S9S_MB_2U(SCH_1):PAGE218
   U14    8    GND QS3VH257QG8_SMLF-QS3VH257QG8,IA    I12 @S9S_MB_2U_LIB.S9S_MB_2U(SCH_1):PAGE218
  C537    2      B Q_CAP_0402-0.1UF,25V,10%,X7R,CA    I25 @S9S_MB_2U_LIB.S9S_MB_2U(SCH_1):PAGE218
  U200    4    GND LTC4307CMS8-LTC4307CMS8,SMLF,IA    I11 @S9S_MB_2U_LIB.S9S_MB_2U(SCH_1):PAGE222
 C1796    2      B Q_CAP_0402-0.1UF,25V,10%,X7R,CA    I20 @S9S_MB_2U_LIB.S9S_MB_2U(SCH_1):PAGE222
  U176    4    GND LTC4307CMS8-LTC4307CMS8,SMLF,EA    I31 @S9S_MB_2U_LIB.S9S_MB_2U(SCH_1):PAGE222
 R4603    2      B Q_RES_0402LF-10K,1%,1/16W,CHIPA    I48 @S9S_MB_2U_LIB.S9S_MB_2U(SCH_1):PAGE222
  U175    4    GND LTC4307CMS8-LTC4307CMS8,SMLF,IA    I50 @S9S_MB_2U_LIB.S9S_MB_2U(SCH_1):PAGE222
 C1707    2      B Q_CAP_0402-0.1UF,25V,10%,X7R,CA    I58 @S9S_MB_2U_LIB.S9S_MB_2U(SCH_1):PAGE222
  U194    4    GND LTC4307CMS8-LTC4307CMS8,SMLF,IA    I63 @S9S_MB_2U_LIB.S9S_MB_2U(SCH_1):PAGE222
  R587    2      B Q_RES_0402LF-1K,1%,1/16W,CHIP,A     I8 @S9S_MB_2U_LIB.S9S_MB_2U(SCH_1):PAGE219
   U36   12    GND TCA9548APWR-TCA9548APWR,SMLF,IA    I45 @S9S_MB_2U_LIB.S9S_MB_2U(SCH_1):PAGE219
  C174    2      B Q_CAP_0402-0.1UF,25V,10%,X7R,CA    I47 @S9S_MB_2U_LIB.S9S_MB_2U(SCH_1):PAGE219
 C1302    2      B Q_CAP_C0402-22UF,4V,20%,X6S,CHA    I82 @S9S_MB_2U_LIB.S9S_MB_2U(SCH_1):PAGE227
 R4635    2      B Q_RES_0402LF-10K,1%,1/16W,CHIPA     I3 @S9S_MB_2U_LIB.S9S_MB_2U(SCH_1):PAGE235
  JP16    3      3 CONN3_210HP1030BR1-CONN3_210-HB    I13 @S9S_MB_2U_LIB.S9S_MB_2U(SCH_1):PAGE235
  U327    7    GND 74CBTLV3126PW-74CBTLV3126PW,SMA    I19 @S9S_MB_2U_LIB.S9S_MB_2U(SCH_1):PAGE235
 C2348    2      B Q_CAP_0402-0.1UF,25V,10%,X7R,CA    I23 @S9S_MB_2U_LIB.S9S_MB_2U(SCH_1):PAGE235
  U331   10    GND INA230AIRGTR-INA230AIRGTR,SMLFA    I39 @S9S_MB_2U_LIB.S9S_MB_2U(SCH_1):PAGE240
  U331   TH     TH INA230AIRGTR-INA230AIRGTR,SMLFA    I39 @S9S_MB_2U_LIB.S9S_MB_2U(SCH_1):PAGE240
 R2973    2      B Q_RES_0402LF-1K,1%,1/16W,EMPTYA    I69 @S9S_MB_2U_LIB.S9S_MB_2U(SCH_1):PAGE184
 R2975    2      B Q_RES_0402LF-1K,1%,1/16W,EMPTYA    I70 @S9S_MB_2U_LIB.S9S_MB_2U(SCH_1):PAGE184
 R2978    2      B Q_RES_0402LF-1K,1%,1/16W,EMPTYA    I74 @S9S_MB_2U_LIB.S9S_MB_2U(SCH_1):PAGE184
 R4809    2      B Q_RES_0402LF-0,5%,1/16W,CHIP,CA     I2 @S9S_MB_2U_LIB.S9S_MB_2U(SCH_1):PAGE227
 R1801    2      B Q_RES_0402LF-0,5%,1/16W,CHIP,CA   I172 @S9S_MB_2U_LIB.S9S_MB_2U(SCH_1):PAGE227
   J41  OB4 DATA_IN SCONN168_ME1016810202011-SCONNA   I173 @S9S_MB_2U_LIB.S9S_MB_2U(SCH_1):PAGE227
   J41   G1     G1 SCONN168_ME1016810202011-SCONNA   I173 @S9S_MB_2U_LIB.S9S_MB_2U(SCH_1):PAGE227
   J41   G2     G2 SCONN168_ME1016810202011-SCONNA   I173 @S9S_MB_2U_LIB.S9S_MB_2U(SCH_1):PAGE227
   J41   G3     G3 SCONN168_ME1016810202011-SCONNA   I173 @S9S_MB_2U_LIB.S9S_MB_2U(SCH_1):PAGE227
   J41   G4     G4 SCONN168_ME1016810202011-SCONNA   I173 @S9S_MB_2U_LIB.S9S_MB_2U(SCH_1):PAGE227
   J41   G5     G5 SCONN168_ME1016810202011-SCONNA   I173 @S9S_MB_2U_LIB.S9S_MB_2U(SCH_1):PAGE227
   J41  A13 GND_A13 SCONN168_ME1016810202011-SCONNA   I173 @S9S_MB_2U_LIB.S9S_MB_2U(SCH_1):PAGE227
   J41  A16 GND_A16 SCONN168_ME1016810202011-SCONNA   I173 @S9S_MB_2U_LIB.S9S_MB_2U(SCH_1):PAGE227
   J41  A19 GND_A19 SCONN168_ME1016810202011-SCONNA   I173 @S9S_MB_2U_LIB.S9S_MB_2U(SCH_1):PAGE227
   J41  A22 GND_A22 SCONN168_ME1016810202011-SCONNA   I173 @S9S_MB_2U_LIB.S9S_MB_2U(SCH_1):PAGE227
   J41  A58 GND_A58 SCONN168_ME1016810202011-SCONNA   I173 @S9S_MB_2U_LIB.S9S_MB_2U(SCH_1):PAGE227
   J41  A61 GND_A61 SCONN168_ME1016810202011-SCONNA   I173 @S9S_MB_2U_LIB.S9S_MB_2U(SCH_1):PAGE227
   J41  A64 GND_A64 SCONN168_ME1016810202011-SCONNA   I173 @S9S_MB_2U_LIB.S9S_MB_2U(SCH_1):PAGE227
   J41  A67 GND_A67 SCONN168_ME1016810202011-SCONNA   I173 @S9S_MB_2U_LIB.S9S_MB_2U(SCH_1):PAGE227
   J41  B38 GND_B38 SCONN168_ME1016810202011-SCONNA   I173 @S9S_MB_2U_LIB.S9S_MB_2U(SCH_1):PAGE227
   J41  B49 GND_B49 SCONN168_ME1016810202011-SCONNA   I173 @S9S_MB_2U_LIB.S9S_MB_2U(SCH_1):PAGE227
   J41  B52 GND_B52 SCONN168_ME1016810202011-SCONNA   I173 @S9S_MB_2U_LIB.S9S_MB_2U(SCH_1):PAGE227
   J41  B55 GND_B55 SCONN168_ME1016810202011-SCONNA   I173 @S9S_MB_2U_LIB.S9S_MB_2U(SCH_1):PAGE227
   J41  B58 GND_B58 SCONN168_ME1016810202011-SCONNA   I173 @S9S_MB_2U_LIB.S9S_MB_2U(SCH_1):PAGE227
   J41  B61 GND_B61 SCONN168_ME1016810202011-SCONNA   I173 @S9S_MB_2U_LIB.S9S_MB_2U(SCH_1):PAGE227
   J41  B64 GND_B64 SCONN168_ME1016810202011-SCONNA   I173 @S9S_MB_2U_LIB.S9S_MB_2U(SCH_1):PAGE227
   J41  B67 GND_B67 SCONN168_ME1016810202011-SCONNA   I173 @S9S_MB_2U_LIB.S9S_MB_2U(SCH_1):PAGE227
   J41 OA13 GND_OA13 SCONN168_ME1016810202011-SCONNA   I173 @S9S_MB_2U_LIB.S9S_MB_2U(SCH_1):PAGE227
   J41 OB10 GND_OB10 SCONN168_ME1016810202011-SCONNA   I173 @S9S_MB_2U_LIB.S9S_MB_2U(SCH_1):PAGE227
   J41  A33  PERN5 SCONN168_ME1016810202011-SCONNA   I173 @S9S_MB_2U_LIB.S9S_MB_2U(SCH_1):PAGE227
   J41  B10 PERST0# SCONN168_ME1016810202011-SCONNA   I173 @S9S_MB_2U_LIB.S9S_MB_2U(SCH_1):PAGE227
   J41  B17  PETN0 SCONN168_ME1016810202011-SCONNA   I173 @S9S_MB_2U_LIB.S9S_MB_2U(SCH_1):PAGE227
   J41  B26  PETN3 SCONN168_ME1016810202011-SCONNA   I173 @S9S_MB_2U_LIB.S9S_MB_2U(SCH_1):PAGE227
   J41  B33  PETN5 SCONN168_ME1016810202011-SCONNA   I173 @S9S_MB_2U_LIB.S9S_MB_2U(SCH_1):PAGE227
   J41  A42 PRSNTB1# SCONN168_ME1016810202011-SCONNA   I173 @S9S_MB_2U_LIB.S9S_MB_2U(SCH_1):PAGE227
   J41  B70 PRSNTB3# SCONN168_ME1016810202011-SCONNA   I173 @S9S_MB_2U_LIB.S9S_MB_2U(SCH_1):PAGE227
   J41  A70 PWRBRK0# SCONN168_ME1016810202011-SCONNA   I173 @S9S_MB_2U_LIB.S9S_MB_2U(SCH_1):PAGE227
   J41  OA4 RBT_ARB_IN SCONN168_ME1016810202011-SCONNA   I173 @S9S_MB_2U_LIB.S9S_MB_2U(SCH_1):PAGE227
   J41  OB7 SLOT_ID0 SCONN168_ME1016810202011-SCONNA   I173 @S9S_MB_2U_LIB.S9S_MB_2U(SCH_1):PAGE227
   J41  OA3  WAKE# SCONN168_ME1016810202011-SCONNA   I173 @S9S_MB_2U_LIB.S9S_MB_2U(SCH_1):PAGE227
  U247   10 GND_10 9FGL0251DKILFT-9FGL0251DKILFT,A   I167 @S9S_MB_2U_LIB.S9S_MB_2U(SCH_1):PAGE201
  U247   21 GND_21 9FGL0251DKILFT-9FGL0251DKILFT,A   I167 @S9S_MB_2U_LIB.S9S_MB_2U(SCH_1):PAGE201
  U247   15   GNDA 9FGL0251DKILFT-9FGL0251DKILFT,A   I167 @S9S_MB_2U_LIB.S9S_MB_2U(SCH_1):PAGE201
  U247    6 GNDDIG 9FGL0251DKILFT-9FGL0251DKILFT,A   I167 @S9S_MB_2U_LIB.S9S_MB_2U(SCH_1):PAGE201
  U247    5 GNDREF 9FGL0251DKILFT-9FGL0251DKILFT,A   I167 @S9S_MB_2U_LIB.S9S_MB_2U(SCH_1):PAGE201
  U247   24 GNDXTAL 9FGL0251DKILFT-9FGL0251DKILFT,A   I167 @S9S_MB_2U_LIB.S9S_MB_2U(SCH_1):PAGE201
  U247   25 TH_GND 9FGL0251DKILFT-9FGL0251DKILFT,A   I167 @S9S_MB_2U_LIB.S9S_MB_2U(SCH_1):PAGE201

GPU_3V3IO_RSVD0_FFU @S9S_MB_2U_LIB.S9S_MB_2U(SCH_1):GPU_3V3IO_RSVD0_FFU
  J109   N4     N4 CONN112_10137002101LF-CONN112_A    I53 @S9S_MB_2U_LIB.S9S_MB_2U(SCH_1):PAGE319
  Q128    2     G1 MOSFET_NCH_DUAL-PJT138K,SMLF,IA    I11 @S9S_MB_2U_LIB.S9S_MB_2U(SCH_1):PAGE143
 R4119    2      B Q_RES_0402LF-54.9K,1%,1/16W,EMA    I13 @S9S_MB_2U_LIB.S9S_MB_2U(SCH_1):PAGE143
 R4120    1      A Q_RES_0402LF-100K,1%,1/16W,EMPA    I14 @S9S_MB_2U_LIB.S9S_MB_2U(SCH_1):PAGE143
 R4575    1      A Q_RES_0402LF-0,5%,1/16W,EMPTY,A   I142 @S9S_MB_2U_LIB.S9S_MB_2U(SCH_1):PAGE143

GPU_3V3IO_RSVD0_FFU_ISO @S9S_MB_2U_LIB.S9S_MB_2U(SCH_1):GPU_3V3IO_RSVD0_FFU_ISO
 C2264    1      A Q_CAP_0402-1000PF,50V,5%,EMPTYA     I2 @S9S_MB_2U_LIB.S9S_MB_2U(SCH_1):PAGE143
 R4128    2      B Q_RES_0402LF-4.7K,5%,1/16W,CHIA     I5 @S9S_MB_2U_LIB.S9S_MB_2U(SCH_1):PAGE143
  Q128    3     D2 MOSFET_NCH_DUAL-PJT138K,SMLF,IA     I6 @S9S_MB_2U_LIB.S9S_MB_2U(SCH_1):PAGE143
 R4143    1      A Q_RES_0402LF-33.2,1%,1/16W,CHIA    I89 @S9S_MB_2U_LIB.S9S_MB_2U(SCH_1):PAGE312
 R4575    2      B Q_RES_0402LF-0,5%,1/16W,EMPTY,A   I142 @S9S_MB_2U_LIB.S9S_MB_2U(SCH_1):PAGE143

GPU_3V3IO_RSVD0_FFU_ISO_R @S9S_MB_2U_LIB.S9S_MB_2U(SCH_1):GPU_3V3IO_RSVD0_FFU_ISO_R
  U249  T11  PB22C LCMXO3LF9400C5BG484C-LCMXO3LF-A     I1 @S9S_MB_2U_LIB.S9S_MB_2U(SCH_1):PAGE312
 R4143    2      B Q_RES_0402LF-33.2,1%,1/16W,CHIA    I89 @S9S_MB_2U_LIB.S9S_MB_2U(SCH_1):PAGE312

GPU_3V3IO_RSVD0_FFU_N @S9S_MB_2U_LIB.S9S_MB_2U(SCH_1):GPU_3V3IO_RSVD0_FFU_N
  Q128    5     G2 MOSFET_NCH_DUAL-PJT138K,SMLF,IA     I6 @S9S_MB_2U_LIB.S9S_MB_2U(SCH_1):PAGE143
 R4125    2      B Q_RES_0402LF-4.7K,5%,1/16W,CHIA     I9 @S9S_MB_2U_LIB.S9S_MB_2U(SCH_1):PAGE143
  Q128    6     D1 MOSFET_NCH_DUAL-PJT138K,SMLF,IA    I11 @S9S_MB_2U_LIB.S9S_MB_2U(SCH_1):PAGE143

GPU_3V3IO_RSVD1 @S9S_MB_2U_LIB.S9S_MB_2U(SCH_1):GPU_3V3IO_RSVD1
  J105   A7     A7 CONN112_10137002101LF-CONN112_A    I68 @S9S_MB_2U_LIB.S9S_MB_2U(SCH_1):PAGE142
 R4159    1      A Q_RES_0402LF-100K,1%,1/16W,EMPA    I13 @S9S_MB_2U_LIB.S9S_MB_2U(SCH_1):PAGE139
 R4158    2      B Q_RES_0402LF-54.9K,1%,1/16W,EMA    I14 @S9S_MB_2U_LIB.S9S_MB_2U(SCH_1):PAGE139
  Q135    2     G1 MOSFET_NCH_DUAL-PJT138K,SMLF,IA    I25 @S9S_MB_2U_LIB.S9S_MB_2U(SCH_1):PAGE139
 R4569    1      A Q_RES_0402LF-0,5%,1/16W,EMPTY,A   I107 @S9S_MB_2U_LIB.S9S_MB_2U(SCH_1):PAGE139

GPU_3V3IO_RSVD1_FFU @S9S_MB_2U_LIB.S9S_MB_2U(SCH_1):GPU_3V3IO_RSVD1_FFU
  J109   N6     N6 CONN112_10137002101LF-CONN112_A    I76 @S9S_MB_2U_LIB.S9S_MB_2U(SCH_1):PAGE319
  Q131    2     G1 MOSFET_NCH_DUAL-PJT138K,SMLF,IA    I29 @S9S_MB_2U_LIB.S9S_MB_2U(SCH_1):PAGE143
 R4123    2      B Q_RES_0402LF-54.9K,1%,1/16W,EMA    I31 @S9S_MB_2U_LIB.S9S_MB_2U(SCH_1):PAGE143
 R4124    1      A Q_RES_0402LF-100K,1%,1/16W,EMPA    I32 @S9S_MB_2U_LIB.S9S_MB_2U(SCH_1):PAGE143
 R4572    1      A Q_RES_0402LF-0,5%,1/16W,EMPTY,A   I141 @S9S_MB_2U_LIB.S9S_MB_2U(SCH_1):PAGE143

GPU_3V3IO_RSVD1_FFU_ISO @S9S_MB_2U_LIB.S9S_MB_2U(SCH_1):GPU_3V3IO_RSVD1_FFU_ISO
  Q131    3     D2 MOSFET_NCH_DUAL-PJT138K,SMLF,IA    I19 @S9S_MB_2U_LIB.S9S_MB_2U(SCH_1):PAGE143
 R4130    2      B Q_RES_0402LF-4.7K,5%,1/16W,CHIA    I21 @S9S_MB_2U_LIB.S9S_MB_2U(SCH_1):PAGE143
 C2266    1      A Q_CAP_0402-1000PF,50V,5%,EMPTYA    I23 @S9S_MB_2U_LIB.S9S_MB_2U(SCH_1):PAGE143
 R4144    1      A Q_RES_0402LF-33.2,1%,1/16W,CHIA    I93 @S9S_MB_2U_LIB.S9S_MB_2U(SCH_1):PAGE312
 R4572    2      B Q_RES_0402LF-0,5%,1/16W,EMPTY,A   I141 @S9S_MB_2U_LIB.S9S_MB_2U(SCH_1):PAGE143

GPU_3V3IO_RSVD1_FFU_ISO_R @S9S_MB_2U_LIB.S9S_MB_2U(SCH_1):GPU_3V3IO_RSVD1_FFU_ISO_R
  U249  U11  PB22D LCMXO3LF9400C5BG484C-LCMXO3LF-A     I1 @S9S_MB_2U_LIB.S9S_MB_2U(SCH_1):PAGE312
 R4144    2      B Q_RES_0402LF-33.2,1%,1/16W,CHIA    I93 @S9S_MB_2U_LIB.S9S_MB_2U(SCH_1):PAGE312

GPU_3V3IO_RSVD1_FFU_N @S9S_MB_2U_LIB.S9S_MB_2U(SCH_1):GPU_3V3IO_RSVD1_FFU_N
  Q131    5     G2 MOSFET_NCH_DUAL-PJT138K,SMLF,IA    I19 @S9S_MB_2U_LIB.S9S_MB_2U(SCH_1):PAGE143
 R4127    2      B Q_RES_0402LF-4.7K,5%,1/16W,CHIA    I27 @S9S_MB_2U_LIB.S9S_MB_2U(SCH_1):PAGE143
  Q131    6     D1 MOSFET_NCH_DUAL-PJT138K,SMLF,IA    I29 @S9S_MB_2U_LIB.S9S_MB_2U(SCH_1):PAGE143

GPU_3V3IO_RSVD1_ISO @S9S_MB_2U_LIB.S9S_MB_2U(SCH_1):GPU_3V3IO_RSVD1_ISO
  Q135    3     D2 MOSFET_NCH_DUAL-PJT138K,SMLF,IA    I29 @S9S_MB_2U_LIB.S9S_MB_2U(SCH_1):PAGE139
 C2271    1      A Q_CAP_0402-1000PF,50V,5%,EMPTYA    I44 @S9S_MB_2U_LIB.S9S_MB_2U(SCH_1):PAGE139
 R4167    2      B Q_RES_0402LF-4.7K,5%,1/16W,CHIA    I47 @S9S_MB_2U_LIB.S9S_MB_2U(SCH_1):PAGE139
 R4170    1      A Q_RES_0402LF-33.2,1%,1/16W,CHIA   I120 @S9S_MB_2U_LIB.S9S_MB_2U(SCH_1):PAGE312
 R4569    2      B Q_RES_0402LF-0,5%,1/16W,EMPTY,A   I107 @S9S_MB_2U_LIB.S9S_MB_2U(SCH_1):PAGE139

GPU_3V3IO_RSVD1_ISO_R @S9S_MB_2U_LIB.S9S_MB_2U(SCH_1):GPU_3V3IO_RSVD1_ISO_R
  U249  T12  PB27B LCMXO3LF9400C5BG484C-LCMXO3LF-A     I1 @S9S_MB_2U_LIB.S9S_MB_2U(SCH_1):PAGE312
 R4170    2      B Q_RES_0402LF-33.2,1%,1/16W,CHIA   I120 @S9S_MB_2U_LIB.S9S_MB_2U(SCH_1):PAGE312

GPU_3V3IO_RSVD1_N @S9S_MB_2U_LIB.S9S_MB_2U(SCH_1):GPU_3V3IO_RSVD1_N
  Q135    6     D1 MOSFET_NCH_DUAL-PJT138K,SMLF,IA    I25 @S9S_MB_2U_LIB.S9S_MB_2U(SCH_1):PAGE139
 R4164    2      B Q_RES_0402LF-4.7K,5%,1/16W,CHIA    I27 @S9S_MB_2U_LIB.S9S_MB_2U(SCH_1):PAGE139
  Q135    5     G2 MOSFET_NCH_DUAL-PJT138K,SMLF,IA    I29 @S9S_MB_2U_LIB.S9S_MB_2U(SCH_1):PAGE139

GPU_3V3IO_RSVD3 @S9S_MB_2U_LIB.S9S_MB_2U(SCH_1):GPU_3V3IO_RSVD3
  J105   A5     A5 CONN112_10137002101LF-CONN112_A    I68 @S9S_MB_2U_LIB.S9S_MB_2U(SCH_1):PAGE142
 R4163    1      A Q_RES_0402LF-100K,1%,1/16W,EMPA     I8 @S9S_MB_2U_LIB.S9S_MB_2U(SCH_1):PAGE139
 R4162    2      B Q_RES_0402LF-54.9K,1%,1/16W,EMA     I9 @S9S_MB_2U_LIB.S9S_MB_2U(SCH_1):PAGE139
  Q137    2     G1 MOSFET_NCH_DUAL-PJT138K,SMLF,IA    I21 @S9S_MB_2U_LIB.S9S_MB_2U(SCH_1):PAGE139
 R4570    1      A Q_RES_0402LF-0,5%,1/16W,EMPTY,A   I109 @S9S_MB_2U_LIB.S9S_MB_2U(SCH_1):PAGE139

GPU_3V3IO_RSVD3_FFU @S9S_MB_2U_LIB.S9S_MB_2U(SCH_1):GPU_3V3IO_RSVD3_FFU
  J108   A1     A1 CONN112_10137002101LF-CONN112_A    I57 @S9S_MB_2U_LIB.S9S_MB_2U(SCH_1):PAGE320
  Q130    2     G1 MOSFET_NCH_DUAL-PJT138K,SMLF,IA    I74 @S9S_MB_2U_LIB.S9S_MB_2U(SCH_1):PAGE143
 R4131    2      B Q_RES_0402LF-54.9K,1%,1/16W,EMA    I85 @S9S_MB_2U_LIB.S9S_MB_2U(SCH_1):PAGE143
 R4132    1      A Q_RES_0402LF-100K,1%,1/16W,EMPA    I86 @S9S_MB_2U_LIB.S9S_MB_2U(SCH_1):PAGE143
 R4577    1      A Q_RES_0402LF-0,5%,1/16W,EMPTY,A   I137 @S9S_MB_2U_LIB.S9S_MB_2U(SCH_1):PAGE143

GPU_3V3IO_RSVD3_FFU_ISO @S9S_MB_2U_LIB.S9S_MB_2U(SCH_1):GPU_3V3IO_RSVD3_FFU_ISO
 R4140    2      B Q_RES_0402LF-4.7K,5%,1/16W,CHIA    I52 @S9S_MB_2U_LIB.S9S_MB_2U(SCH_1):PAGE143
 C2267    1      A Q_CAP_0402-1000PF,50V,5%,EMPTYA    I55 @S9S_MB_2U_LIB.S9S_MB_2U(SCH_1):PAGE143
  Q130    3     D2 MOSFET_NCH_DUAL-PJT138K,SMLF,IA    I70 @S9S_MB_2U_LIB.S9S_MB_2U(SCH_1):PAGE143
 R4146    1      A Q_RES_0402LF-33.2,1%,1/16W,CHIA    I98 @S9S_MB_2U_LIB.S9S_MB_2U(SCH_1):PAGE312
 R4577    2      B Q_RES_0402LF-0,5%,1/16W,EMPTY,A   I137 @S9S_MB_2U_LIB.S9S_MB_2U(SCH_1):PAGE143

GPU_3V3IO_RSVD3_FFU_ISO_R @S9S_MB_2U_LIB.S9S_MB_2U(SCH_1):GPU_3V3IO_RSVD3_FFU_ISO_R
  U249 AB11  PB24B LCMXO3LF9400C5BG484C-LCMXO3LF-A     I1 @S9S_MB_2U_LIB.S9S_MB_2U(SCH_1):PAGE312
 R4146    2      B Q_RES_0402LF-33.2,1%,1/16W,CHIA    I98 @S9S_MB_2U_LIB.S9S_MB_2U(SCH_1):PAGE312

GPU_3V3IO_RSVD3_FFU_N @S9S_MB_2U_LIB.S9S_MB_2U(SCH_1):GPU_3V3IO_RSVD3_FFU_N
  Q130    5     G2 MOSFET_NCH_DUAL-PJT138K,SMLF,IA    I70 @S9S_MB_2U_LIB.S9S_MB_2U(SCH_1):PAGE143
 R4137    2      B Q_RES_0402LF-4.7K,5%,1/16W,CHIA    I72 @S9S_MB_2U_LIB.S9S_MB_2U(SCH_1):PAGE143
  Q130    6     D1 MOSFET_NCH_DUAL-PJT138K,SMLF,IA    I74 @S9S_MB_2U_LIB.S9S_MB_2U(SCH_1):PAGE143

GPU_3V3IO_RSVD3_ISO @S9S_MB_2U_LIB.S9S_MB_2U(SCH_1):GPU_3V3IO_RSVD3_ISO
  Q137    3     D2 MOSFET_NCH_DUAL-PJT138K,SMLF,IA    I28 @S9S_MB_2U_LIB.S9S_MB_2U(SCH_1):PAGE139
 R4169    2      B Q_RES_0402LF-4.7K,5%,1/16W,CHIA    I39 @S9S_MB_2U_LIB.S9S_MB_2U(SCH_1):PAGE139
 C2273    1      A Q_CAP_0402-1000PF,50V,5%,EMPTYA    I42 @S9S_MB_2U_LIB.S9S_MB_2U(SCH_1):PAGE139
 R4171    1      A Q_RES_0402LF-33.2,1%,1/16W,CHIA   I121 @S9S_MB_2U_LIB.S9S_MB_2U(SCH_1):PAGE312
 R4570    2      B Q_RES_0402LF-0,5%,1/16W,EMPTY,A   I109 @S9S_MB_2U_LIB.S9S_MB_2U(SCH_1):PAGE139

GPU_3V3IO_RSVD3_ISO_R @S9S_MB_2U_LIB.S9S_MB_2U(SCH_1):GPU_3V3IO_RSVD3_ISO_R
  U249  U12  PB27C LCMXO3LF9400C5BG484C-LCMXO3LF-A     I1 @S9S_MB_2U_LIB.S9S_MB_2U(SCH_1):PAGE312
 R4171    2      B Q_RES_0402LF-33.2,1%,1/16W,CHIA   I121 @S9S_MB_2U_LIB.S9S_MB_2U(SCH_1):PAGE312

GPU_3V3IO_RSVD3_N @S9S_MB_2U_LIB.S9S_MB_2U(SCH_1):GPU_3V3IO_RSVD3_N
  Q137    6     D1 MOSFET_NCH_DUAL-PJT138K,SMLF,IA    I21 @S9S_MB_2U_LIB.S9S_MB_2U(SCH_1):PAGE139
 R4166    2      B Q_RES_0402LF-4.7K,5%,1/16W,CHIA    I23 @S9S_MB_2U_LIB.S9S_MB_2U(SCH_1):PAGE139
  Q137    5     G2 MOSFET_NCH_DUAL-PJT138K,SMLF,IA    I28 @S9S_MB_2U_LIB.S9S_MB_2U(SCH_1):PAGE139

GPU_3V3IO_RSVD4 @S9S_MB_2U_LIB.S9S_MB_2U(SCH_1):GPU_3V3IO_RSVD4
  J105   A1     A1 CONN112_10137002101LF-CONN112_A    I65 @S9S_MB_2U_LIB.S9S_MB_2U(SCH_1):PAGE142
 R4161    1      A Q_RES_0402LF-100K,1%,1/16W,EMPA     I2 @S9S_MB_2U_LIB.S9S_MB_2U(SCH_1):PAGE139
 R4160    2      B Q_RES_0402LF-54.9K,1%,1/16W,EMA     I4 @S9S_MB_2U_LIB.S9S_MB_2U(SCH_1):PAGE139
  Q136    2     G1 MOSFET_NCH_DUAL-PJT138K,SMLF,IA    I17 @S9S_MB_2U_LIB.S9S_MB_2U(SCH_1):PAGE139
 R4571    1      A Q_RES_0402LF-0,5%,1/16W,EMPTY,A   I108 @S9S_MB_2U_LIB.S9S_MB_2U(SCH_1):PAGE139

GPU_3V3IO_RSVD4_ISO @S9S_MB_2U_LIB.S9S_MB_2U(SCH_1):GPU_3V3IO_RSVD4_ISO
  Q136    3     D2 MOSFET_NCH_DUAL-PJT138K,SMLF,IA    I22 @S9S_MB_2U_LIB.S9S_MB_2U(SCH_1):PAGE139
 C2272    1      A Q_CAP_0402-1000PF,50V,5%,EMPTYA    I33 @S9S_MB_2U_LIB.S9S_MB_2U(SCH_1):PAGE139
 R4168    2      B Q_RES_0402LF-4.7K,5%,1/16W,CHIA    I35 @S9S_MB_2U_LIB.S9S_MB_2U(SCH_1):PAGE139
 R4172    1      A Q_RES_0402LF-33.2,1%,1/16W,CHIA   I122 @S9S_MB_2U_LIB.S9S_MB_2U(SCH_1):PAGE312
 R4571    2      B Q_RES_0402LF-0,5%,1/16W,EMPTY,A   I108 @S9S_MB_2U_LIB.S9S_MB_2U(SCH_1):PAGE139

GPU_3V3IO_RSVD4_ISO_R @S9S_MB_2U_LIB.S9S_MB_2U(SCH_1):GPU_3V3IO_RSVD4_ISO_R
  U249  V12  PB27D LCMXO3LF9400C5BG484C-LCMXO3LF-A     I1 @S9S_MB_2U_LIB.S9S_MB_2U(SCH_1):PAGE312
 R4172    2      B Q_RES_0402LF-33.2,1%,1/16W,CHIA   I122 @S9S_MB_2U_LIB.S9S_MB_2U(SCH_1):PAGE312

GPU_3V3IO_RSVD4_N @S9S_MB_2U_LIB.S9S_MB_2U(SCH_1):GPU_3V3IO_RSVD4_N
  Q136    6     D1 MOSFET_NCH_DUAL-PJT138K,SMLF,IA    I17 @S9S_MB_2U_LIB.S9S_MB_2U(SCH_1):PAGE139
 R4165    2      B Q_RES_0402LF-4.7K,5%,1/16W,CHIA    I18 @S9S_MB_2U_LIB.S9S_MB_2U(SCH_1):PAGE139
  Q136    5     G2 MOSFET_NCH_DUAL-PJT138K,SMLF,IA    I22 @S9S_MB_2U_LIB.S9S_MB_2U(SCH_1):PAGE139

GPU_3V3IO_RSVD5_FFU @S9S_MB_2U_LIB.S9S_MB_2U(SCH_1):GPU_3V3IO_RSVD5_FFU
  J108   A5     A5 CONN112_10137002101LF-CONN112_A    I76 @S9S_MB_2U_LIB.S9S_MB_2U(SCH_1):PAGE320
  Q129    2     G1 MOSFET_NCH_DUAL-PJT138K,SMLF,IA    I83 @S9S_MB_2U_LIB.S9S_MB_2U(SCH_1):PAGE143
 R4133    2      B Q_RES_0402LF-54.9K,1%,1/16W,EMA    I95 @S9S_MB_2U_LIB.S9S_MB_2U(SCH_1):PAGE143
 R4134    1      A Q_RES_0402LF-100K,1%,1/16W,EMPA    I96 @S9S_MB_2U_LIB.S9S_MB_2U(SCH_1):PAGE143
 R4576    1      A Q_RES_0402LF-0,5%,1/16W,EMPTY,A   I139 @S9S_MB_2U_LIB.S9S_MB_2U(SCH_1):PAGE143

GPU_3V3IO_RSVD5_FFU_ISO @S9S_MB_2U_LIB.S9S_MB_2U(SCH_1):GPU_3V3IO_RSVD5_FFU_ISO
 R4141    2      B Q_RES_0402LF-4.7K,5%,1/16W,CHIA    I64 @S9S_MB_2U_LIB.S9S_MB_2U(SCH_1):PAGE143
 C2268    1      A Q_CAP_0402-1000PF,50V,5%,EMPTYA    I66 @S9S_MB_2U_LIB.S9S_MB_2U(SCH_1):PAGE143
  Q129    3     D2 MOSFET_NCH_DUAL-PJT138K,SMLF,IA    I77 @S9S_MB_2U_LIB.S9S_MB_2U(SCH_1):PAGE143
 R4148    1      A Q_RES_0402LF-33.2,1%,1/16W,CHIA   I103 @S9S_MB_2U_LIB.S9S_MB_2U(SCH_1):PAGE312
 R4576    2      B Q_RES_0402LF-0,5%,1/16W,EMPTY,A   I139 @S9S_MB_2U_LIB.S9S_MB_2U(SCH_1):PAGE143

GPU_3V3IO_RSVD5_FFU_ISO_R @S9S_MB_2U_LIB.S9S_MB_2U(SCH_1):GPU_3V3IO_RSVD5_FFU_ISO_R
  U249  Y11  PB24D LCMXO3LF9400C5BG484C-LCMXO3LF-A     I1 @S9S_MB_2U_LIB.S9S_MB_2U(SCH_1):PAGE312
 R4148    2      B Q_RES_0402LF-33.2,1%,1/16W,CHIA   I103 @S9S_MB_2U_LIB.S9S_MB_2U(SCH_1):PAGE312

GPU_3V3IO_RSVD5_FFU_N @S9S_MB_2U_LIB.S9S_MB_2U(SCH_1):GPU_3V3IO_RSVD5_FFU_N
  Q129    5     G2 MOSFET_NCH_DUAL-PJT138K,SMLF,IA    I77 @S9S_MB_2U_LIB.S9S_MB_2U(SCH_1):PAGE143
 R4138    2      B Q_RES_0402LF-4.7K,5%,1/16W,CHIA    I81 @S9S_MB_2U_LIB.S9S_MB_2U(SCH_1):PAGE143
  Q129    6     D1 MOSFET_NCH_DUAL-PJT138K,SMLF,IA    I83 @S9S_MB_2U_LIB.S9S_MB_2U(SCH_1):PAGE143

GPU_BASE_HMC_READY @S9S_MB_2U_LIB.S9S_MB_2U(SCH_1):GPU_BASE_HMC_READY
  J110   A5     A5 CONN112_10137002101LF-CONN112_A    I16 @S9S_MB_2U_LIB.S9S_MB_2U(SCH_1):PAGE318
  Q102    2     G1 MOSFET_NCH_DUAL-PJT138K,SMLF,IA    I40 @S9S_MB_2U_LIB.S9S_MB_2U(SCH_1):PAGE299
 R3429    2      B Q_RES_0402LF-100K,1%,1/16W,EMPA   I130 @S9S_MB_2U_LIB.S9S_MB_2U(SCH_1):PAGE299
 R3463    1      A Q_RES_0402LF-54.9K,1%,1/16W,CHA   I131 @S9S_MB_2U_LIB.S9S_MB_2U(SCH_1):PAGE299

GPU_BASE_HMC_READY_ISO @S9S_MB_2U_LIB.S9S_MB_2U(SCH_1):GPU_BASE_HMC_READY_ISO
  Q102    3     D2 MOSFET_NCH_DUAL-PJT138K,SMLF,IA    I48 @S9S_MB_2U_LIB.S9S_MB_2U(SCH_1):PAGE299
 R3438    2      B Q_RES_0402LF-4.7K,5%,1/16W,CHIA    I55 @S9S_MB_2U_LIB.S9S_MB_2U(SCH_1):PAGE299
 C1973    1      A Q_CAP_0402-1000PF,50V,5%,EMPTYA    I71 @S9S_MB_2U_LIB.S9S_MB_2U(SCH_1):PAGE299
 R3480    1      A Q_RES_0402LF-33.2,1%,1/16W,CHIA    I21 @S9S_MB_2U_LIB.S9S_MB_2U(SCH_1):PAGE314

GPU_BASE_HMC_READY_ISO_R @S9S_MB_2U_LIB.S9S_MB_2U(SCH_1):GPU_BASE_HMC_READY_ISO_R
 R3480    2      B Q_RES_0402LF-33.2,1%,1/16W,CHIA    I21 @S9S_MB_2U_LIB.S9S_MB_2U(SCH_1):PAGE314
  U249  F10  PT22A LCMXO3LF9400C5BG484C-LCMXO3LF-A   I188 @S9S_MB_2U_LIB.S9S_MB_2U(SCH_1):PAGE314

GPU_BASE_HMC_READY_N @S9S_MB_2U_LIB.S9S_MB_2U(SCH_1):GPU_BASE_HMC_READY_N
  Q102    6     D1 MOSFET_NCH_DUAL-PJT138K,SMLF,IA    I40 @S9S_MB_2U_LIB.S9S_MB_2U(SCH_1):PAGE299
  Q102    5     G2 MOSFET_NCH_DUAL-PJT138K,SMLF,IA    I48 @S9S_MB_2U_LIB.S9S_MB_2U(SCH_1):PAGE299
 R3433    2      B Q_RES_0402LF-4.7K,5%,1/16W,CHIA    I49 @S9S_MB_2U_LIB.S9S_MB_2U(SCH_1):PAGE299

GPU_BASE_ID0 @S9S_MB_2U_LIB.S9S_MB_2U(SCH_1):GPU_BASE_ID0
  J111   A3     A3 CONN112_10137002101LF-CONN112_A    I75 @S9S_MB_2U_LIB.S9S_MB_2U(SCH_1):PAGE148
 R3440    1      A Q_RES_0402LF-0,5%,1/16W,EMPTY,A     I8 @S9S_MB_2U_LIB.S9S_MB_2U(SCH_1):PAGE147
 R3516    1      A Q_RES_0402LF-0,5%,1/16W,CHIP,CA   I127 @S9S_MB_2U_LIB.S9S_MB_2U(SCH_1):PAGE214

GPU_BASE_ID0_R @S9S_MB_2U_LIB.S9S_MB_2U(SCH_1):GPU_BASE_ID0_R
  U181   15  IO1_2 PCA9539RPW-PCA9539RPW,SMLF,IC,A    I66 @S9S_MB_2U_LIB.S9S_MB_2U(SCH_1):PAGE214
 R3516    2      B Q_RES_0402LF-0,5%,1/16W,CHIP,CA   I127 @S9S_MB_2U_LIB.S9S_MB_2U(SCH_1):PAGE214

GPU_BASE_ID1 @S9S_MB_2U_LIB.S9S_MB_2U(SCH_1):GPU_BASE_ID1
  J111   N8     N8 CONN112_10137002101LF-CONN112_A    I74 @S9S_MB_2U_LIB.S9S_MB_2U(SCH_1):PAGE148
 R3499    1      A Q_RES_0402LF-0,5%,1/16W,CHIP,CA   I118 @S9S_MB_2U_LIB.S9S_MB_2U(SCH_1):PAGE214
 R3441    1      A Q_RES_0402LF-0,5%,1/16W,CHIP,CA     I7 @S9S_MB_2U_LIB.S9S_MB_2U(SCH_1):PAGE147

GPU_BASE_ID1_R @S9S_MB_2U_LIB.S9S_MB_2U(SCH_1):GPU_BASE_ID1_R
  U181   16  IO1_3 PCA9539RPW-PCA9539RPW,SMLF,IC,A    I66 @S9S_MB_2U_LIB.S9S_MB_2U(SCH_1):PAGE214
 R3499    2      B Q_RES_0402LF-0,5%,1/16W,CHIP,CA   I118 @S9S_MB_2U_LIB.S9S_MB_2U(SCH_1):PAGE214

GPU_BASE_STBY_EN @S9S_MB_2U_LIB.S9S_MB_2U(SCH_1):GPU_BASE_STBY_EN
  U253    3     A1 74LVC2G17GW-74LVC2G17GW,SMLF,IA    I26 @S9S_MB_2U_LIB.S9S_MB_2U(SCH_1):PAGE160
 R3452    1      A Q_RES_0402LF-100K,1%,1/16W,CHIA    I95 @S9S_MB_2U_LIB.S9S_MB_2U(SCH_1):PAGE160
 R3451    2      B Q_RES_0402LF-4.7K,5%,1/16W,EMPA   I127 @S9S_MB_2U_LIB.S9S_MB_2U(SCH_1):PAGE160
 R3479    1      A Q_RES_0402LF-33.2,1%,1/16W,CHIA    I24 @S9S_MB_2U_LIB.S9S_MB_2U(SCH_1):PAGE314

GPU_BASE_STBY_EN_BUF @S9S_MB_2U_LIB.S9S_MB_2U(SCH_1):GPU_BASE_STBY_EN_BUF
  J110   A7     A7 CONN112_10137002101LF-CONN112_A    I16 @S9S_MB_2U_LIB.S9S_MB_2U(SCH_1):PAGE318
 R3392    2      B Q_RES_0402LF-49.9,1%,1/16W,CHIA   I202 @S9S_MB_2U_LIB.S9S_MB_2U(SCH_1):PAGE160

GPU_BASE_STBY_EN_BUF_R @S9S_MB_2U_LIB.S9S_MB_2U(SCH_1):GPU_BASE_STBY_EN_BUF_R
  U253    4     B1 74LVC2G17GW-74LVC2G17GW,SMLF,IA    I26 @S9S_MB_2U_LIB.S9S_MB_2U(SCH_1):PAGE160
 R3457    1      A Q_RES_0402LF-10K,1%,1/16W,CHIPA   I123 @S9S_MB_2U_LIB.S9S_MB_2U(SCH_1):PAGE160
 R3456    2      B Q_RES_0402LF-100K,1%,1/16W,EMPA   I124 @S9S_MB_2U_LIB.S9S_MB_2U(SCH_1):PAGE160
 R3392    1      A Q_RES_0402LF-49.9,1%,1/16W,CHIA   I202 @S9S_MB_2U_LIB.S9S_MB_2U(SCH_1):PAGE160

GPU_BASE_STBY_EN_R @S9S_MB_2U_LIB.S9S_MB_2U(SCH_1):GPU_BASE_STBY_EN_R
 R3479    2      B Q_RES_0402LF-33.2,1%,1/16W,CHIA    I24 @S9S_MB_2U_LIB.S9S_MB_2U(SCH_1):PAGE314
  U249   G9  PT21D LCMXO3LF9400C5BG484C-LCMXO3LF-A   I188 @S9S_MB_2U_LIB.S9S_MB_2U(SCH_1):PAGE314

GPU_FPGA_BOOT_EN @S9S_MB_2U_LIB.S9S_MB_2U(SCH_1):GPU_FPGA_BOOT_EN
  U253    1     A0 74LVC2G17GW-74LVC2G17GW,SMLF,IA    I26 @S9S_MB_2U_LIB.S9S_MB_2U(SCH_1):PAGE160
 R3448    2      B Q_RES_0402LF-4.7K,5%,1/16W,EMPA   I168 @S9S_MB_2U_LIB.S9S_MB_2U(SCH_1):PAGE160
 R3449    1      A Q_RES_0402LF-100K,1%,1/16W,CHIA   I170 @S9S_MB_2U_LIB.S9S_MB_2U(SCH_1):PAGE160
 R3482    1      A Q_RES_0402LF-33.2,1%,1/16W,CHIA    I19 @S9S_MB_2U_LIB.S9S_MB_2U(SCH_1):PAGE314

GPU_FPGA_BOOT_EN_BUF @S9S_MB_2U_LIB.S9S_MB_2U(SCH_1):GPU_FPGA_BOOT_EN_BUF
  J110   N2     N2 CONN112_10137002101LF-CONN112_A    I54 @S9S_MB_2U_LIB.S9S_MB_2U(SCH_1):PAGE318
 R3390    2      B Q_RES_0402LF-49.9,1%,1/16W,CHIA   I201 @S9S_MB_2U_LIB.S9S_MB_2U(SCH_1):PAGE160

GPU_FPGA_BOOT_EN_BUF_R @S9S_MB_2U_LIB.S9S_MB_2U(SCH_1):GPU_FPGA_BOOT_EN_BUF_R
  U253    6     B0 74LVC2G17GW-74LVC2G17GW,SMLF,IA    I26 @S9S_MB_2U_LIB.S9S_MB_2U(SCH_1):PAGE160
 R3453    2      B Q_RES_0402LF-100K,1%,1/16W,EMPA   I164 @S9S_MB_2U_LIB.S9S_MB_2U(SCH_1):PAGE160
 R3454    1      A Q_RES_0402LF-1K,1%,1/16W,CHIP,A   I165 @S9S_MB_2U_LIB.S9S_MB_2U(SCH_1):PAGE160
 R3390    1      A Q_RES_0402LF-49.9,1%,1/16W,CHIA   I201 @S9S_MB_2U_LIB.S9S_MB_2U(SCH_1):PAGE160

GPU_FPGA_BOOT_EN_R @S9S_MB_2U_LIB.S9S_MB_2U(SCH_1):GPU_FPGA_BOOT_EN_R
 R3482    2      B Q_RES_0402LF-33.2,1%,1/16W,CHIA    I19 @S9S_MB_2U_LIB.S9S_MB_2U(SCH_1):PAGE314
  U249  G11  PT23C LCMXO3LF9400C5BG484C-LCMXO3LF-A   I188 @S9S_MB_2U_LIB.S9S_MB_2U(SCH_1):PAGE314

GPU_FPGA_EROT_FATALERR @S9S_MB_2U_LIB.S9S_MB_2U(SCH_1):GPU_FPGA_EROT_FATALERR
  Q108    5     G2 MOSFET_NCH_DUAL-PJT138K,SMLF,IA   I168 @S9S_MB_2U_LIB.S9S_MB_2U(SCH_1):PAGE299
  Q108    6     D1 MOSFET_NCH_DUAL-PJT138K,SMLF,IA   I169 @S9S_MB_2U_LIB.S9S_MB_2U(SCH_1):PAGE299
 R3503    2      B Q_RES_0402LF-4.7K,5%,1/16W,CHIA   I177 @S9S_MB_2U_LIB.S9S_MB_2U(SCH_1):PAGE299

GPU_FPGA_EROT_FATALERR_ISO_N @S9S_MB_2U_LIB.S9S_MB_2U(SCH_1):GPU_FPGA_EROT_FATALERR_ISO_N
  Q108    3     D2 MOSFET_NCH_DUAL-PJT138K,SMLF,IA   I168 @S9S_MB_2U_LIB.S9S_MB_2U(SCH_1):PAGE299
 C1988    1      A Q_CAP_0402-1000PF,50V,5%,EMPTYA   I171 @S9S_MB_2U_LIB.S9S_MB_2U(SCH_1):PAGE299
 R3504    2      B Q_RES_0402LF-4.7K,5%,1/16W,CHIA   I174 @S9S_MB_2U_LIB.S9S_MB_2U(SCH_1):PAGE299
 R3505    1      A Q_RES_0402LF-33.2,1%,1/16W,CHIA    I16 @S9S_MB_2U_LIB.S9S_MB_2U(SCH_1):PAGE314

GPU_FPGA_EROT_FATALERR_ISO_R_N @S9S_MB_2U_LIB.S9S_MB_2U(SCH_1):GPU_FPGA_EROT_FATALERR_ISO_R_N
 R3505    2      B Q_RES_0402LF-33.2,1%,1/16W,CHIA    I16 @S9S_MB_2U_LIB.S9S_MB_2U(SCH_1):PAGE314
  U249  D11  PT24D LCMXO3LF9400C5BG484C-LCMXO3LF-A   I188 @S9S_MB_2U_LIB.S9S_MB_2U(SCH_1):PAGE314

GPU_FPGA_EROT_FATALERR_N @S9S_MB_2U_LIB.S9S_MB_2U(SCH_1):GPU_FPGA_EROT_FATALERR_N
  J109   N2     N2 CONN112_10137002101LF-CONN112_A    I53 @S9S_MB_2U_LIB.S9S_MB_2U(SCH_1):PAGE319
  Q108    2     G1 MOSFET_NCH_DUAL-PJT138K,SMLF,IA   I169 @S9S_MB_2U_LIB.S9S_MB_2U(SCH_1):PAGE299
 R3502    1      A Q_RES_0402LF-100K,1%,1/16W,EMPA   I181 @S9S_MB_2U_LIB.S9S_MB_2U(SCH_1):PAGE299
 R3525    2      B Q_RES_0402LF-54.9K,1%,1/16W,CHA   I184 @S9S_MB_2U_LIB.S9S_MB_2U(SCH_1):PAGE299

GPU_FPGA_EROT_RECOV_BUF_N @S9S_MB_2U_LIB.S9S_MB_2U(SCH_1):GPU_FPGA_EROT_RECOV_BUF_N
  J110   A1     A1 CONN112_10137002101LF-CONN112_A    I54 @S9S_MB_2U_LIB.S9S_MB_2U(SCH_1):PAGE318
 R3497    2      B Q_RES_0402LF-33.2,1%,1/16W,CHIA    I53 @S9S_MB_2U_LIB.S9S_MB_2U(SCH_1):PAGE296

GPU_FPGA_EROT_RECOV_BUF_R_N @S9S_MB_2U_LIB.S9S_MB_2U(SCH_1):GPU_FPGA_EROT_RECOV_BUF_R_N
  U257    6     1Y 74LVC2G07DW7-74LVC2G07DW-7,SMLA    I50 @S9S_MB_2U_LIB.S9S_MB_2U(SCH_1):PAGE296
 R3497    1      A Q_RES_0402LF-33.2,1%,1/16W,CHIA    I53 @S9S_MB_2U_LIB.S9S_MB_2U(SCH_1):PAGE296
 R3494    2      B Q_RES_0402LF-54.9K,1%,1/16W,CHA    I55 @S9S_MB_2U_LIB.S9S_MB_2U(SCH_1):PAGE296
 R3495    1      A Q_RES_0402LF-100K,1%,1/16W,EMPA    I62 @S9S_MB_2U_LIB.S9S_MB_2U(SCH_1):PAGE296

GPU_FPGA_EROT_RECOV_N @S9S_MB_2U_LIB.S9S_MB_2U(SCH_1):GPU_FPGA_EROT_RECOV_N
  U257    1     1A 74LVC2G07DW7-74LVC2G07DW-7,SMLA    I50 @S9S_MB_2U_LIB.S9S_MB_2U(SCH_1):PAGE296
 R3490    2      B Q_RES_0402LF-4.7K,5%,1/16W,CHIA    I57 @S9S_MB_2U_LIB.S9S_MB_2U(SCH_1):PAGE296
 R3491    1      A Q_RES_0402LF-100K,1%,1/16W,EMPA    I70 @S9S_MB_2U_LIB.S9S_MB_2U(SCH_1):PAGE296
 R3483    1      A Q_RES_0402LF-33.2,1%,1/16W,CHIA    I20 @S9S_MB_2U_LIB.S9S_MB_2U(SCH_1):PAGE314

GPU_FPGA_EROT_RECOV_R_N @S9S_MB_2U_LIB.S9S_MB_2U(SCH_1):GPU_FPGA_EROT_RECOV_R_N
 R3483    2      B Q_RES_0402LF-33.2,1%,1/16W,CHIA    I20 @S9S_MB_2U_LIB.S9S_MB_2U(SCH_1):PAGE314
  U249  F11  PT23D LCMXO3LF9400C5BG484C-LCMXO3LF-A   I188 @S9S_MB_2U_LIB.S9S_MB_2U(SCH_1):PAGE314

GPU_FPGA_EROT_RST_BUF_N @S9S_MB_2U_LIB.S9S_MB_2U(SCH_1):GPU_FPGA_EROT_RST_BUF_N
  J110   N8     N8 CONN112_10137002101LF-CONN112_A    I16 @S9S_MB_2U_LIB.S9S_MB_2U(SCH_1):PAGE318
 R3496    2      B Q_RES_0402LF-33.2,1%,1/16W,CHIA    I45 @S9S_MB_2U_LIB.S9S_MB_2U(SCH_1):PAGE296

GPU_FPGA_EROT_RST_BUF_R_N @S9S_MB_2U_LIB.S9S_MB_2U(SCH_1):GPU_FPGA_EROT_RST_BUF_R_N
  U255    4     2Y 74LVC2G07DW7-74LVC2G07DW-7,SMLA    I16 @S9S_MB_2U_LIB.S9S_MB_2U(SCH_1):PAGE296
 R3496    1      A Q_RES_0402LF-33.2,1%,1/16W,CHIA    I45 @S9S_MB_2U_LIB.S9S_MB_2U(SCH_1):PAGE296
 R3492    2      B Q_RES_0402LF-54.9K,1%,1/16W,CHA    I47 @S9S_MB_2U_LIB.S9S_MB_2U(SCH_1):PAGE296
 R3493    1      A Q_RES_0402LF-100K,1%,1/16W,EMPA    I48 @S9S_MB_2U_LIB.S9S_MB_2U(SCH_1):PAGE296

GPU_FPGA_EROT_RST_N @S9S_MB_2U_LIB.S9S_MB_2U(SCH_1):GPU_FPGA_EROT_RST_N
  U255    3     2A 74LVC2G07DW7-74LVC2G07DW-7,SMLA    I16 @S9S_MB_2U_LIB.S9S_MB_2U(SCH_1):PAGE296
 R3488    2      B Q_RES_0402LF-4.7K,5%,1/16W,CHIA    I40 @S9S_MB_2U_LIB.S9S_MB_2U(SCH_1):PAGE296
 R3489    1      A Q_RES_0402LF-100K,1%,1/16W,EMPA    I42 @S9S_MB_2U_LIB.S9S_MB_2U(SCH_1):PAGE296
 R3478    1      A Q_RES_0402LF-33.2,1%,1/16W,CHIA    I23 @S9S_MB_2U_LIB.S9S_MB_2U(SCH_1):PAGE314

GPU_FPGA_EROT_RST_R_N @S9S_MB_2U_LIB.S9S_MB_2U(SCH_1):GPU_FPGA_EROT_RST_R_N
 R3478    2      B Q_RES_0402LF-33.2,1%,1/16W,CHIA    I23 @S9S_MB_2U_LIB.S9S_MB_2U(SCH_1):PAGE314
  U249   F9  PT21C LCMXO3LF9400C5BG484C-LCMXO3LF-A   I188 @S9S_MB_2U_LIB.S9S_MB_2U(SCH_1):PAGE314

GPU_FPGA_OVERT @S9S_MB_2U_LIB.S9S_MB_2U(SCH_1):GPU_FPGA_OVERT
  Q104    6     D1 MOSFET_NCH_DUAL-PJT138K,SMLF,IA    I21 @S9S_MB_2U_LIB.S9S_MB_2U(SCH_1):PAGE299
 R3435    2      B Q_RES_0402LF-4.7K,5%,1/16W,CHIA    I23 @S9S_MB_2U_LIB.S9S_MB_2U(SCH_1):PAGE299
  Q104    5     G2 MOSFET_NCH_DUAL-PJT138K,SMLF,IA    I26 @S9S_MB_2U_LIB.S9S_MB_2U(SCH_1):PAGE299

GPU_FPGA_OVERT_ISO_N @S9S_MB_2U_LIB.S9S_MB_2U(SCH_1):GPU_FPGA_OVERT_ISO_N
  Q104    3     D2 MOSFET_NCH_DUAL-PJT138K,SMLF,IA    I26 @S9S_MB_2U_LIB.S9S_MB_2U(SCH_1):PAGE299
 R3437    2      B Q_RES_0402LF-4.7K,5%,1/16W,CHIA    I27 @S9S_MB_2U_LIB.S9S_MB_2U(SCH_1):PAGE299
 C1976    1      A Q_CAP_0402-1000PF,50V,5%,EMPTYA    I30 @S9S_MB_2U_LIB.S9S_MB_2U(SCH_1):PAGE299
 R3484    1      A Q_RES_0402LF-33.2,1%,1/16W,CHIA    I17 @S9S_MB_2U_LIB.S9S_MB_2U(SCH_1):PAGE314

GPU_FPGA_OVERT_ISO_R_N @S9S_MB_2U_LIB.S9S_MB_2U(SCH_1):GPU_FPGA_OVERT_ISO_R_N
 R3484    2      B Q_RES_0402LF-33.2,1%,1/16W,CHIA    I17 @S9S_MB_2U_LIB.S9S_MB_2U(SCH_1):PAGE314
  U249  B11  PT24A LCMXO3LF9400C5BG484C-LCMXO3LF-A   I188 @S9S_MB_2U_LIB.S9S_MB_2U(SCH_1):PAGE314

GPU_FPGA_OVERT_N @S9S_MB_2U_LIB.S9S_MB_2U(SCH_1):GPU_FPGA_OVERT_N
  J108   A7     A7 CONN112_10137002101LF-CONN112_A    I76 @S9S_MB_2U_LIB.S9S_MB_2U(SCH_1):PAGE320
 R3430    1      A Q_RES_0402LF-100K,1%,1/16W,EMPA     I3 @S9S_MB_2U_LIB.S9S_MB_2U(SCH_1):PAGE299
  Q104    2     G1 MOSFET_NCH_DUAL-PJT138K,SMLF,IA    I21 @S9S_MB_2U_LIB.S9S_MB_2U(SCH_1):PAGE299
 R3464    2      B Q_RES_0402LF-54.9K,1%,1/16W,CHA   I134 @S9S_MB_2U_LIB.S9S_MB_2U(SCH_1):PAGE299

GPU_FPGA_READY @S9S_MB_2U_LIB.S9S_MB_2U(SCH_1):GPU_FPGA_READY
  J112   T2     T2 CONN160_10131762101LF-CONN160_A    I76 @S9S_MB_2U_LIB.S9S_MB_2U(SCH_1):PAGE149
   Q96    2     G1 MOSFET_NCH_DUAL-PJT138K,SMLF,IA   I154 @S9S_MB_2U_LIB.S9S_MB_2U(SCH_1):PAGE145
 R3318    2      B Q_RES_0402LF-100K,1%,1/16W,EMPA   I171 @S9S_MB_2U_LIB.S9S_MB_2U(SCH_1):PAGE145
 R3511    1      A Q_RES_0402LF-54.9K,1%,1/16W,CHA   I172 @S9S_MB_2U_LIB.S9S_MB_2U(SCH_1):PAGE145

GPU_FPGA_READY_ISO @S9S_MB_2U_LIB.S9S_MB_2U(SCH_1):GPU_FPGA_READY_ISO
   Q96    3     D2 MOSFET_NCH_DUAL-PJT138K,SMLF,IA   I159 @S9S_MB_2U_LIB.S9S_MB_2U(SCH_1):PAGE145
 C1881    1      A Q_CAP_0402-1000PF,50V,5%,EMPTYA   I156 @S9S_MB_2U_LIB.S9S_MB_2U(SCH_1):PAGE145
 R3321    2      B Q_RES_0402LF-4.7K,5%,1/16W,CHIA   I158 @S9S_MB_2U_LIB.S9S_MB_2U(SCH_1):PAGE145
 R3324    1      A Q_RES_0402LF-33.2,1%,1/16W,CHIA   I108 @S9S_MB_2U_LIB.S9S_MB_2U(SCH_1):PAGE314

GPU_FPGA_READY_ISO_R @S9S_MB_2U_LIB.S9S_MB_2U(SCH_1):GPU_FPGA_READY_ISO_R
 R3324    2      B Q_RES_0402LF-33.2,1%,1/16W,CHIA   I108 @S9S_MB_2U_LIB.S9S_MB_2U(SCH_1):PAGE314
  U249  A18  PT41A LCMXO3LF9400C5BG484C-LCMXO3LF-A   I188 @S9S_MB_2U_LIB.S9S_MB_2U(SCH_1):PAGE314

GPU_FPGA_READY_N @S9S_MB_2U_LIB.S9S_MB_2U(SCH_1):GPU_FPGA_READY_N
   Q96    5     G2 MOSFET_NCH_DUAL-PJT138K,SMLF,IA   I159 @S9S_MB_2U_LIB.S9S_MB_2U(SCH_1):PAGE145
   Q96    6     D1 MOSFET_NCH_DUAL-PJT138K,SMLF,IA   I154 @S9S_MB_2U_LIB.S9S_MB_2U(SCH_1):PAGE145
 R3320    2      B Q_RES_0402LF-4.7K,5%,1/16W,CHIA   I162 @S9S_MB_2U_LIB.S9S_MB_2U(SCH_1):PAGE145
 R3326    1      A Q_RES_0402LF-0,5%,1/16W,CHIP,CA    I84 @S9S_MB_2U_LIB.S9S_MB_2U(SCH_1):PAGE201

GPU_FPGA_READY_R_N @S9S_MB_2U_LIB.S9S_MB_2U(SCH_1):GPU_FPGA_READY_R_N
 R3326    2      B Q_RES_0402LF-0,5%,1/16W,CHIP,CA    I84 @S9S_MB_2U_LIB.S9S_MB_2U(SCH_1):PAGE201
  U248    1     I0 74LVC1G32GW_SMLF-74LVC1G32GW,IA   I158 @S9S_MB_2U_LIB.S9S_MB_2U(SCH_1):PAGE201

GPU_FPGA_RST_N @S9S_MB_2U_LIB.S9S_MB_2U(SCH_1):GPU_FPGA_RST_N
  U249  Y21  PR29B LCMXO3LF9400C5BG484C-LCMXO3LF-A     I1 @S9S_MB_2U_LIB.S9S_MB_2U(SCH_1):PAGE313
 R4608    1      A Q_RES_0402LF-33.2,1%,1/16W,CHIA   I190 @S9S_MB_2U_LIB.S9S_MB_2U(SCH_1):PAGE313

GPU_FPGA_RST_R1_BUF_N @S9S_MB_2U_LIB.S9S_MB_2U(SCH_1):GPU_FPGA_RST_R1_BUF_N
  U196    4     B1 74LVC2G17GW-74LVC2G17GW,SMLF,IA   I127 @S9S_MB_2U_LIB.S9S_MB_2U(SCH_1):PAGE140
 R3317    2      B Q_RES_0402LF-4.7K,5%,1/16W,EMPA   I190 @S9S_MB_2U_LIB.S9S_MB_2U(SCH_1):PAGE140
 R3509    1      A Q_RES_0402LF-10K,1%,1/16W,CHIPA   I191 @S9S_MB_2U_LIB.S9S_MB_2U(SCH_1):PAGE140
 R3315    1      A Q_RES_0402LF-49.9,1%,1/16W,CHIA   I205 @S9S_MB_2U_LIB.S9S_MB_2U(SCH_1):PAGE140

GPU_FPGA_RST_R_BUF_N @S9S_MB_2U_LIB.S9S_MB_2U(SCH_1):GPU_FPGA_RST_R_BUF_N
  J111   A7     A7 CONN112_10137002101LF-CONN112_A    I74 @S9S_MB_2U_LIB.S9S_MB_2U(SCH_1):PAGE148
 R3315    2      B Q_RES_0402LF-49.9,1%,1/16W,CHIA   I205 @S9S_MB_2U_LIB.S9S_MB_2U(SCH_1):PAGE140

GPU_FPGA_RST_R_N @S9S_MB_2U_LIB.S9S_MB_2U(SCH_1):GPU_FPGA_RST_R_N
  U196    3     A1 74LVC2G17GW-74LVC2G17GW,SMLF,IA   I127 @S9S_MB_2U_LIB.S9S_MB_2U(SCH_1):PAGE140
 R3507    1      A Q_RES_0402LF-10K,1%,1/16W,CHIPA   I192 @S9S_MB_2U_LIB.S9S_MB_2U(SCH_1):PAGE140
 R3506    2      B Q_RES_0402LF-4.7K,5%,1/16W,EMPA   I193 @S9S_MB_2U_LIB.S9S_MB_2U(SCH_1):PAGE140
 R4608    2      B Q_RES_0402LF-33.2,1%,1/16W,CHIA   I190 @S9S_MB_2U_LIB.S9S_MB_2U(SCH_1):PAGE313

GPU_FPGA_THERM_OVERT @S9S_MB_2U_LIB.S9S_MB_2U(SCH_1):GPU_FPGA_THERM_OVERT
  Q101    6     D1 MOSFET_NCH_DUAL-PJT138K,SMLF,IA    I52 @S9S_MB_2U_LIB.S9S_MB_2U(SCH_1):PAGE299
 R3432    2      B Q_RES_0402LF-4.7K,5%,1/16W,CHIA    I53 @S9S_MB_2U_LIB.S9S_MB_2U(SCH_1):PAGE299
  Q101    5     G2 MOSFET_NCH_DUAL-PJT138K,SMLF,IA    I57 @S9S_MB_2U_LIB.S9S_MB_2U(SCH_1):PAGE299

GPU_FPGA_THERM_OVERT_ISO_N @S9S_MB_2U_LIB.S9S_MB_2U(SCH_1):GPU_FPGA_THERM_OVERT_ISO_N
  Q101    3     D2 MOSFET_NCH_DUAL-PJT138K,SMLF,IA    I57 @S9S_MB_2U_LIB.S9S_MB_2U(SCH_1):PAGE299
 R3439    2      B Q_RES_0402LF-4.7K,5%,1/16W,CHIA    I59 @S9S_MB_2U_LIB.S9S_MB_2U(SCH_1):PAGE299
 C1974    1      A Q_CAP_0402-1000PF,50V,5%,EMPTYA    I74 @S9S_MB_2U_LIB.S9S_MB_2U(SCH_1):PAGE299
 R3476    1      A Q_RES_0402LF-33.2,1%,1/16W,CHIA    I25 @S9S_MB_2U_LIB.S9S_MB_2U(SCH_1):PAGE314

GPU_FPGA_THERM_OVERT_ISO_R_N @S9S_MB_2U_LIB.S9S_MB_2U(SCH_1):GPU_FPGA_THERM_OVERT_ISO_R_N
 R3476    2      B Q_RES_0402LF-33.2,1%,1/16W,CHIA    I25 @S9S_MB_2U_LIB.S9S_MB_2U(SCH_1):PAGE314
  U249   B9  PT21A LCMXO3LF9400C5BG484C-LCMXO3LF-A   I188 @S9S_MB_2U_LIB.S9S_MB_2U(SCH_1):PAGE314

GPU_FPGA_THERM_OVERT_N @S9S_MB_2U_LIB.S9S_MB_2U(SCH_1):GPU_FPGA_THERM_OVERT_N
  J112   T6     T6 CONN160_10131762101LF-CONN160_A    I75 @S9S_MB_2U_LIB.S9S_MB_2U(SCH_1):PAGE149
 R3428    1      A Q_RES_0402LF-100K,1%,1/16W,EMPA    I17 @S9S_MB_2U_LIB.S9S_MB_2U(SCH_1):PAGE299
  Q101    2     G1 MOSFET_NCH_DUAL-PJT138K,SMLF,IA    I52 @S9S_MB_2U_LIB.S9S_MB_2U(SCH_1):PAGE299
 R3498    2      B Q_RES_0402LF-54.9K,1%,1/16W,CHA   I167 @S9S_MB_2U_LIB.S9S_MB_2U(SCH_1):PAGE299

GPU_HMC_PRSNT @S9S_MB_2U_LIB.S9S_MB_2U(SCH_1):GPU_HMC_PRSNT
  Q103    6     D1 MOSFET_NCH_DUAL-PJT138K,SMLF,IA    I37 @S9S_MB_2U_LIB.S9S_MB_2U(SCH_1):PAGE299
 R3434    2      B Q_RES_0402LF-4.7K,5%,1/16W,CHIA    I39 @S9S_MB_2U_LIB.S9S_MB_2U(SCH_1):PAGE299
  Q103    5     G2 MOSFET_NCH_DUAL-PJT138K,SMLF,IA    I43 @S9S_MB_2U_LIB.S9S_MB_2U(SCH_1):PAGE299

GPU_HMC_PRSNT_ISO_N @S9S_MB_2U_LIB.S9S_MB_2U(SCH_1):GPU_HMC_PRSNT_ISO_N
  Q103    3     D2 MOSFET_NCH_DUAL-PJT138K,SMLF,IA    I43 @S9S_MB_2U_LIB.S9S_MB_2U(SCH_1):PAGE299
 R3436    2      B Q_RES_0402LF-4.7K,5%,1/16W,CHIA    I45 @S9S_MB_2U_LIB.S9S_MB_2U(SCH_1):PAGE299
 C1975    1      A Q_CAP_0402-1000PF,50V,5%,EMPTYA   I129 @S9S_MB_2U_LIB.S9S_MB_2U(SCH_1):PAGE299
 R3481    1      A Q_RES_0402LF-33.2,1%,1/16W,CHIA    I22 @S9S_MB_2U_LIB.S9S_MB_2U(SCH_1):PAGE314

GPU_HMC_PRSNT_ISO_R_N @S9S_MB_2U_LIB.S9S_MB_2U(SCH_1):GPU_HMC_PRSNT_ISO_R_N
 R3481    2      B Q_RES_0402LF-33.2,1%,1/16W,CHIA    I22 @S9S_MB_2U_LIB.S9S_MB_2U(SCH_1):PAGE314
  U249  E10  PT22B LCMXO3LF9400C5BG484C-LCMXO3LF-A   I188 @S9S_MB_2U_LIB.S9S_MB_2U(SCH_1):PAGE314

GPU_HMC_PRSNT_N @S9S_MB_2U_LIB.S9S_MB_2U(SCH_1):GPU_HMC_PRSNT_N
  J110   A3     A3 CONN112_10137002101LF-CONN112_A    I54 @S9S_MB_2U_LIB.S9S_MB_2U(SCH_1):PAGE318
  Q103    2     G1 MOSFET_NCH_DUAL-PJT138K,SMLF,IA    I37 @S9S_MB_2U_LIB.S9S_MB_2U(SCH_1):PAGE299
 R3465    2      B Q_RES_0402LF-10K,1%,1/16W,CHIPA   I132 @S9S_MB_2U_LIB.S9S_MB_2U(SCH_1):PAGE299
 R3431    1      A Q_RES_0402LF-100K,1%,1/16W,EMPA   I133 @S9S_MB_2U_LIB.S9S_MB_2U(SCH_1):PAGE299

GPU_NVS_PWR_BRAKE_N @S9S_MB_2U_LIB.S9S_MB_2U(SCH_1):GPU_NVS_PWR_BRAKE_N
  U255    1     1A 74LVC2G07DW7-74LVC2G07DW-7,SMLA    I16 @S9S_MB_2U_LIB.S9S_MB_2U(SCH_1):PAGE296
 R3459    2      B Q_RES_0402LF-4.7K,5%,1/16W,CHIA    I29 @S9S_MB_2U_LIB.S9S_MB_2U(SCH_1):PAGE296
 R3460    1      A Q_RES_0402LF-100K,1%,1/16W,EMPA    I31 @S9S_MB_2U_LIB.S9S_MB_2U(SCH_1):PAGE296
 R3477    1      A Q_RES_0402LF-33.2,1%,1/16W,CHIA    I26 @S9S_MB_2U_LIB.S9S_MB_2U(SCH_1):PAGE314

GPU_NVS_PWR_BRAKE_N_BUF @S9S_MB_2U_LIB.S9S_MB_2U(SCH_1):GPU_NVS_PWR_BRAKE_N_BUF
  J112   T4     T4 CONN160_10131762101LF-CONN160_A    I76 @S9S_MB_2U_LIB.S9S_MB_2U(SCH_1):PAGE149
 R3397    2      B Q_RES_0402LF-33.2,1%,1/16W,CHIA    I37 @S9S_MB_2U_LIB.S9S_MB_2U(SCH_1):PAGE296

GPU_NVS_PWR_BRAKE_N_R @S9S_MB_2U_LIB.S9S_MB_2U(SCH_1):GPU_NVS_PWR_BRAKE_N_R
  U255    6     1Y 74LVC2G07DW7-74LVC2G07DW-7,SMLA    I16 @S9S_MB_2U_LIB.S9S_MB_2U(SCH_1):PAGE296
 R3462    1      A Q_RES_0402LF-100K,1%,1/16W,EMPA    I33 @S9S_MB_2U_LIB.S9S_MB_2U(SCH_1):PAGE296
 R3461    2      B Q_RES_0402LF-54.9K,1%,1/16W,CHA    I35 @S9S_MB_2U_LIB.S9S_MB_2U(SCH_1):PAGE296
 R3397    1      A Q_RES_0402LF-33.2,1%,1/16W,CHIA    I37 @S9S_MB_2U_LIB.S9S_MB_2U(SCH_1):PAGE296

GPU_NVS_PWR_BRAKE_R_N @S9S_MB_2U_LIB.S9S_MB_2U(SCH_1):GPU_NVS_PWR_BRAKE_R_N
 R3477    2      B Q_RES_0402LF-33.2,1%,1/16W,CHIA    I26 @S9S_MB_2U_LIB.S9S_MB_2U(SCH_1):PAGE314
  U249   A9  PT21B LCMXO3LF9400C5BG484C-LCMXO3LF-A   I188 @S9S_MB_2U_LIB.S9S_MB_2U(SCH_1):PAGE314

GPU_PEX_STRAP0 @S9S_MB_2U_LIB.S9S_MB_2U(SCH_1):GPU_PEX_STRAP0
  J111   A5     A5 CONN112_10137002101LF-CONN112_A    I74 @S9S_MB_2U_LIB.S9S_MB_2U(SCH_1):PAGE148
 R3518    1      A Q_RES_0402LF-0,5%,1/16W,CHIP,CA   I129 @S9S_MB_2U_LIB.S9S_MB_2U(SCH_1):PAGE214
 R3442    1      A Q_RES_0402LF-0,5%,1/16W,CHIP,CA     I6 @S9S_MB_2U_LIB.S9S_MB_2U(SCH_1):PAGE147

GPU_PEX_STRAP0_R @S9S_MB_2U_LIB.S9S_MB_2U(SCH_1):GPU_PEX_STRAP0_R
  U181   17  IO1_4 PCA9539RPW-PCA9539RPW,SMLF,IC,A    I66 @S9S_MB_2U_LIB.S9S_MB_2U(SCH_1):PAGE214
 R3518    2      B Q_RES_0402LF-0,5%,1/16W,CHIP,CA   I129 @S9S_MB_2U_LIB.S9S_MB_2U(SCH_1):PAGE214

GPU_PEX_STRAP1 @S9S_MB_2U_LIB.S9S_MB_2U(SCH_1):GPU_PEX_STRAP1
  J111   A1     A1 CONN112_10137002101LF-CONN112_A    I75 @S9S_MB_2U_LIB.S9S_MB_2U(SCH_1):PAGE148
 R3443    1      A Q_RES_0402LF-0,5%,1/16W,CHIP,CA     I5 @S9S_MB_2U_LIB.S9S_MB_2U(SCH_1):PAGE147
 R3517    1      A Q_RES_0402LF-0,5%,1/16W,CHIP,CA   I128 @S9S_MB_2U_LIB.S9S_MB_2U(SCH_1):PAGE214

GPU_PEX_STRAP1_R @S9S_MB_2U_LIB.S9S_MB_2U(SCH_1):GPU_PEX_STRAP1_R
  U181   18  IO1_5 PCA9539RPW-PCA9539RPW,SMLF,IC,A    I66 @S9S_MB_2U_LIB.S9S_MB_2U(SCH_1):PAGE214
 R3517    2      B Q_RES_0402LF-0,5%,1/16W,CHIP,CA   I128 @S9S_MB_2U_LIB.S9S_MB_2U(SCH_1):PAGE214

GPU_PRSNT @S9S_MB_2U_LIB.S9S_MB_2U(SCH_1):GPU_PRSNT
  Q107    5     G2 MOSFET_NCH_DUAL-PJT138K,SMLF,IA   I157 @S9S_MB_2U_LIB.S9S_MB_2U(SCH_1):PAGE299
 R3474    2      B Q_RES_0402LF-4.7K,5%,1/16W,CHIA   I158 @S9S_MB_2U_LIB.S9S_MB_2U(SCH_1):PAGE299
  Q107    6     D1 MOSFET_NCH_DUAL-PJT138K,SMLF,IA   I160 @S9S_MB_2U_LIB.S9S_MB_2U(SCH_1):PAGE299
 R3770    1      A Q_RES_0402LF-0,5%,1/16W,CHIP,CA    I34 @S9S_MB_2U_LIB.S9S_MB_2U(SCH_1):PAGE230

GPU_PRSNT_N @S9S_MB_2U_LIB.S9S_MB_2U(SCH_1):GPU_PRSNT_N
  J111   N2     N2 CONN112_10137002101LF-CONN112_A    I75 @S9S_MB_2U_LIB.S9S_MB_2U(SCH_1):PAGE148
  Q107    2     G1 MOSFET_NCH_DUAL-PJT138K,SMLF,IA   I160 @S9S_MB_2U_LIB.S9S_MB_2U(SCH_1):PAGE299
 R3473    1      A Q_RES_0402LF-100K,1%,1/16W,EMPA   I163 @S9S_MB_2U_LIB.S9S_MB_2U(SCH_1):PAGE299
 R3487    2      B Q_RES_0402LF-10K,1%,1/16W,CHIPA   I166 @S9S_MB_2U_LIB.S9S_MB_2U(SCH_1):PAGE299

GPU_PRSNT_N_ISO @S9S_MB_2U_LIB.S9S_MB_2U(SCH_1):GPU_PRSNT_N_ISO
 C1978    1      A Q_CAP_0402-1000PF,50V,5%,EMPTYA   I152 @S9S_MB_2U_LIB.S9S_MB_2U(SCH_1):PAGE299
 R3475    2      B Q_RES_0402LF-4.7K,5%,1/16W,CHIA   I154 @S9S_MB_2U_LIB.S9S_MB_2U(SCH_1):PAGE299
  Q107    3     D2 MOSFET_NCH_DUAL-PJT138K,SMLF,IA   I157 @S9S_MB_2U_LIB.S9S_MB_2U(SCH_1):PAGE299
 R3486    1      A Q_RES_0402LF-33.2,1%,1/16W,CHIA    I15 @S9S_MB_2U_LIB.S9S_MB_2U(SCH_1):PAGE314
 R4729    1      A Q_RES_0402LF-0,5%,1/16W,CHIP,CA   I140 @S9S_MB_2U_LIB.S9S_MB_2U(SCH_1):PAGE214

GPU_PRSNT_N_ISO_R @S9S_MB_2U_LIB.S9S_MB_2U(SCH_1):GPU_PRSNT_N_ISO_R
 R3486    2      B Q_RES_0402LF-33.2,1%,1/16W,CHIA    I15 @S9S_MB_2U_LIB.S9S_MB_2U(SCH_1):PAGE314
  U249  E11  PT24C LCMXO3LF9400C5BG484C-LCMXO3LF-A   I188 @S9S_MB_2U_LIB.S9S_MB_2U(SCH_1):PAGE314

GPU_PRSNT_N_ISO_R1 @S9S_MB_2U_LIB.S9S_MB_2U(SCH_1):GPU_PRSNT_N_ISO_R1
  U181    9  IO0_5 PCA9539RPW-PCA9539RPW,SMLF,IC,A    I66 @S9S_MB_2U_LIB.S9S_MB_2U(SCH_1):PAGE214
 R4729    2      B Q_RES_0402LF-0,5%,1/16W,CHIP,CA   I140 @S9S_MB_2U_LIB.S9S_MB_2U(SCH_1):PAGE214

GPU_PRSNT_R @S9S_MB_2U_LIB.S9S_MB_2U(SCH_1):GPU_PRSNT_R
  U278    2      B 74LVC1G08W57-74LVC1G08W5-7,SMLA    I31 @S9S_MB_2U_LIB.S9S_MB_2U(SCH_1):PAGE230
 R3770    2      B Q_RES_0402LF-0,5%,1/16W,CHIP,CA    I34 @S9S_MB_2U_LIB.S9S_MB_2U(SCH_1):PAGE230

GPU_WP_HW_CTRL_ISO @S9S_MB_2U_LIB.S9S_MB_2U(SCH_1):GPU_WP_HW_CTRL_ISO
  J105   A3     A3 CONN112_10137002101LF-CONN112_A    I65 @S9S_MB_2U_LIB.S9S_MB_2U(SCH_1):PAGE142
  Q106    6     D1 MOSFET_NCH_DUAL-PJT138K,SMLF,IA   I135 @S9S_MB_2U_LIB.S9S_MB_2U(SCH_1):PAGE299
 R3472    2      B Q_RES_0402LF-0,5%,1/16W,EMPTY,A   I147 @S9S_MB_2U_LIB.S9S_MB_2U(SCH_1):PAGE299

GPU_WP_HW_CTRL_N @S9S_MB_2U_LIB.S9S_MB_2U(SCH_1):GPU_WP_HW_CTRL_N
  Q106    2     G1 MOSFET_NCH_DUAL-PJT138K,SMLF,IA   I135 @S9S_MB_2U_LIB.S9S_MB_2U(SCH_1):PAGE299
 R3471    1      A Q_RES_0402LF-10K,1%,1/16W,CHIPA   I144 @S9S_MB_2U_LIB.S9S_MB_2U(SCH_1):PAGE299
 R3470    2      B Q_RES_0402LF-10K,1%,1/16W,EMPTA   I145 @S9S_MB_2U_LIB.S9S_MB_2U(SCH_1):PAGE299
 R3485    1      A Q_RES_0402LF-33.2,1%,1/16W,CHIA    I18 @S9S_MB_2U_LIB.S9S_MB_2U(SCH_1):PAGE314

GPU_WP_HW_CTRL_R_N @S9S_MB_2U_LIB.S9S_MB_2U(SCH_1):GPU_WP_HW_CTRL_R_N
 R3485    2      B Q_RES_0402LF-33.2,1%,1/16W,CHIA    I18 @S9S_MB_2U_LIB.S9S_MB_2U(SCH_1):PAGE314
  U249  A11  PT24B LCMXO3LF9400C5BG484C-LCMXO3LF-A   I188 @S9S_MB_2U_LIB.S9S_MB_2U(SCH_1):PAGE314

HDD_ACTIVITY_BUF @S9S_MB_2U_LIB.S9S_MB_2U(SCH_1):HDD_ACTIVITY_BUF
 R3296    2      B Q_RES_0402LF-4.7K,1%,1/16W,CHIA   I324 @S9S_MB_2U_LIB.S9S_MB_2U(SCH_1):PAGE182
  U259    6     1Y SN74LVC2G07DCKR_SMLF-SN74LVC2GA   I327 @S9S_MB_2U_LIB.S9S_MB_2U(SCH_1):PAGE182
   Q95    2     G1 MOSFET_NCH_DUAL-PJT138K,SMLF,IA   I342 @S9S_MB_2U_LIB.S9S_MB_2U(SCH_1):PAGE182

HDD_ACTIVITY_BUF_N @S9S_MB_2U_LIB.S9S_MB_2U(SCH_1):HDD_ACTIVITY_BUF_N
 R3298    2      B Q_RES_0402LF-10K,1%,1/16W,CHIPA   I306 @S9S_MB_2U_LIB.S9S_MB_2U(SCH_1):PAGE182
 R5377    1      A Q_RES_0402LF-0,5%,1/16W,CHIP,CA   I312 @S9S_MB_2U_LIB.S9S_MB_2U(SCH_1):PAGE182
   Q95    6     D1 MOSFET_NCH_DUAL-PJT138K,SMLF,IA   I342 @S9S_MB_2U_LIB.S9S_MB_2U(SCH_1):PAGE182

HGX_DETECT @S9S_MB_2U_LIB.S9S_MB_2U(SCH_1):HGX_DETECT
  Q148    5     G2 MOSFET_NCH_DUAL-PJT138K,SMLF,IA    I55 @S9S_MB_2U_LIB.S9S_MB_2U(SCH_1):PAGE139
 R4545    2      B Q_RES_0402LF-4.7K,5%,1/16W,CHIA    I57 @S9S_MB_2U_LIB.S9S_MB_2U(SCH_1):PAGE139
  Q148    6     D1 MOSFET_NCH_DUAL-PJT138K,SMLF,IA    I61 @S9S_MB_2U_LIB.S9S_MB_2U(SCH_1):PAGE139

HGX_DETECT_N @S9S_MB_2U_LIB.S9S_MB_2U(SCH_1):HGX_DETECT_N
  Q148    2     G1 MOSFET_NCH_DUAL-PJT138K,SMLF,IA    I61 @S9S_MB_2U_LIB.S9S_MB_2U(SCH_1):PAGE139
 R4544    1      A Q_RES_0402LF-100K,1%,1/16W,EMPA    I62 @S9S_MB_2U_LIB.S9S_MB_2U(SCH_1):PAGE139
 R4556    2      B Q_RES_0402LF-33.2,1%,1/16W,CHIA   I143 @S9S_MB_2U_LIB.S9S_MB_2U(SCH_1):PAGE312
 R4543    2      B Q_RES_0402LF-4.7K,5%,1/16W,CHIA    I85 @S9S_MB_2U_LIB.S9S_MB_2U(SCH_1):PAGE139

HGX_DETECT_N_ISO @S9S_MB_2U_LIB.S9S_MB_2U(SCH_1):HGX_DETECT_N_ISO
  J112   A3     A3 CONN160_10131762101LF-CONN160_A    I76 @S9S_MB_2U_LIB.S9S_MB_2U(SCH_1):PAGE149
 R2656    1      A Q_RES_0402LF-100,1%,1/16W,EMPTA    I11 @S9S_MB_2U_LIB.S9S_MB_2U(SCH_1):PAGE147
 R4546    2      B Q_RES_0402LF-4.7K,5%,1/16W,EMPA    I50 @S9S_MB_2U_LIB.S9S_MB_2U(SCH_1):PAGE139
 C2340    1      A Q_CAP_0402-1000PF,50V,5%,EMPTYA    I52 @S9S_MB_2U_LIB.S9S_MB_2U(SCH_1):PAGE139
  Q148    3     D2 MOSFET_NCH_DUAL-PJT138K,SMLF,IA    I55 @S9S_MB_2U_LIB.S9S_MB_2U(SCH_1):PAGE139

HGX_DETECT_N_R @S9S_MB_2U_LIB.S9S_MB_2U(SCH_1):HGX_DETECT_N_R
  U249 AB20  PB44A LCMXO3LF9400C5BG484C-LCMXO3LF-A     I1 @S9S_MB_2U_LIB.S9S_MB_2U(SCH_1):PAGE312
 R4556    1      A Q_RES_0402LF-33.2,1%,1/16W,CHIA   I143 @S9S_MB_2U_LIB.S9S_MB_2U(SCH_1):PAGE312

HPDB_HSC_PWRGD @S9S_MB_2U_LIB.S9S_MB_2U(SCH_1):HPDB_HSC_PWRGD
 R4552    1      A Q_RES_0402LF-100K,1%,1/16W,CHIA    I50 @S9S_MB_2U_LIB.S9S_MB_2U(SCH_1):PAGE230
 R4551    2      B Q_RES_0402LF-54.9K,1%,1/16W,EMA    I51 @S9S_MB_2U_LIB.S9S_MB_2U(SCH_1):PAGE230
  Q145    2     G1 MOSFET_NCH_DUAL-PJT138K,SMLF,IA    I53 @S9S_MB_2U_LIB.S9S_MB_2U(SCH_1):PAGE230
 R2802    2      B Q_RES_0402LF-0,5%,1/16W,CHIP,CA    I39 @S9S_MB_2U_LIB.S9S_MB_2U(SCH_1):PAGE233

HPDB_HSC_PWRGD_ISO @S9S_MB_2U_LIB.S9S_MB_2U(SCH_1):HPDB_HSC_PWRGD_ISO
 R4557    1      A Q_RES_0402LF-33.2,1%,1/16W,CHIA   I145 @S9S_MB_2U_LIB.S9S_MB_2U(SCH_1):PAGE312
  Q145    3     D2 MOSFET_NCH_DUAL-PJT138K,SMLF,IA    I58 @S9S_MB_2U_LIB.S9S_MB_2U(SCH_1):PAGE230
 R4554    2      B Q_RES_0402LF-4.7K,5%,1/16W,CHIA    I59 @S9S_MB_2U_LIB.S9S_MB_2U(SCH_1):PAGE230
 C2342    1      A Q_CAP_0402-1000PF,50V,5%,EMPTYA    I62 @S9S_MB_2U_LIB.S9S_MB_2U(SCH_1):PAGE230

HPDB_HSC_PWRGD_ISO_R @S9S_MB_2U_LIB.S9S_MB_2U(SCH_1):HPDB_HSC_PWRGD_ISO_R
  U249 AA20  PB44B LCMXO3LF9400C5BG484C-LCMXO3LF-A     I1 @S9S_MB_2U_LIB.S9S_MB_2U(SCH_1):PAGE312
 R4557    2      B Q_RES_0402LF-33.2,1%,1/16W,CHIA   I145 @S9S_MB_2U_LIB.S9S_MB_2U(SCH_1):PAGE312

HPDB_HSC_PWRGD_N @S9S_MB_2U_LIB.S9S_MB_2U(SCH_1):HPDB_HSC_PWRGD_N
  Q145    6     D1 MOSFET_NCH_DUAL-PJT138K,SMLF,IA    I53 @S9S_MB_2U_LIB.S9S_MB_2U(SCH_1):PAGE230
 R4553    2      B Q_RES_0402LF-4.7K,5%,1/16W,CHIA    I55 @S9S_MB_2U_LIB.S9S_MB_2U(SCH_1):PAGE230
  Q145    5     G2 MOSFET_NCH_DUAL-PJT138K,SMLF,IA    I58 @S9S_MB_2U_LIB.S9S_MB_2U(SCH_1):PAGE230

HPDB_HSC_PWRGD_R @S9S_MB_2U_LIB.S9S_MB_2U(SCH_1):HPDB_HSC_PWRGD_R
   J45   C3     C3 CONN60_101062636003K02LF-CONN6A    I12 @S9S_MB_2U_LIB.S9S_MB_2U(SCH_1):PAGE233
 R2802    1      A Q_RES_0402LF-0,5%,1/16W,CHIP,CA    I39 @S9S_MB_2U_LIB.S9S_MB_2U(SCH_1):PAGE233
 C2295    1      A Q_CAP_0402-0.1UF,25V,10%,EMPTYA    I54 @S9S_MB_2U_LIB.S9S_MB_2U(SCH_1):PAGE233

HP_E1S_0_P3V3_PWRGD @S9S_MB_2U_LIB.S9S_MB_2U(SCH_1):HP_E1S_0_P3V3_PWRGD
  U336    2 RESET_L APX80929SAG7-APX809-29SAG-7,SMA   I329 @S9S_MB_2U_LIB.S9S_MB_2U(SCH_1):PAGE297
 R4767    1      A Q_RES_0402LF-49.9,1%,1/16W,CHIA   I331 @S9S_MB_2U_LIB.S9S_MB_2U(SCH_1):PAGE297

HP_E1S_0_P3V3_PWRGD_PLD @S9S_MB_2U_LIB.S9S_MB_2U(SCH_1):HP_E1S_0_P3V3_PWRGD_PLD
  U249   K1  PL14B LCMXO3LF9400C5BG484C-LCMXO3LF-A    I33 @S9S_MB_2U_LIB.S9S_MB_2U(SCH_1):PAGE311
 R4767    2      B Q_RES_0402LF-49.9,1%,1/16W,CHIA   I331 @S9S_MB_2U_LIB.S9S_MB_2U(SCH_1):PAGE297

HP_LVC3_E1S_0_HSC_PWRGD @S9S_MB_2U_LIB.S9S_MB_2U(SCH_1):HP_LVC3_E1S_0_HSC_PWRGD
 R3972    2      B Q_RES_0402LF-0,5%,1/16W,EMPTY,A    I68 @S9S_MB_2U_LIB.S9S_MB_2U(SCH_1):PAGE324
 R3978    2      B Q_RES_0402LF-100K,1%,1/16W,EMPA    I76 @S9S_MB_2U_LIB.S9S_MB_2U(SCH_1):PAGE324
 PU292   10     PG RS31312R-RS31312R,SMLF,IC,AL03A    I49 @S9S_MB_2U_LIB.S9S_MB_2U(SCH_1):PAGE323
 R4765    1      A Q_RES_0402LF-33.2,1%,1/16W,CHIA    I90 @S9S_MB_2U_LIB.S9S_MB_2U(SCH_1):PAGE311
 R3948    2      B Q_RES_0402LF-10K,1%,1/16W,CHIPA    I64 @S9S_MB_2U_LIB.S9S_MB_2U(SCH_1):PAGE323

HP_LVC3_E1S_0_HSC_PWRGD_PLD @S9S_MB_2U_LIB.S9S_MB_2U(SCH_1):HP_LVC3_E1S_0_HSC_PWRGD_PLD
  U249   K2  PL14A LCMXO3LF9400C5BG484C-LCMXO3LF-A    I33 @S9S_MB_2U_LIB.S9S_MB_2U(SCH_1):PAGE311
 R4765    2      B Q_RES_0402LF-33.2,1%,1/16W,CHIA    I90 @S9S_MB_2U_LIB.S9S_MB_2U(SCH_1):PAGE311

HP_LVC3_OCP_V3_1_ATTN_OUT_SW_N @S9S_MB_2U_LIB.S9S_MB_2U(SCH_1):HP_LVC3_OCP_V3_1_ATTN_OUT_SW_N
 R1147    2      B Q_RES_0402LF-0,5%,1/16W,CHIP,CA    I47 @S9S_MB_2U_LIB.S9S_MB_2U(SCH_1):PAGE153
 R1149    2      B Q_RES_0402LF-10K,1%,1/16W,CHIPA    I50 @S9S_MB_2U_LIB.S9S_MB_2U(SCH_1):PAGE153
  U209    7   P0_3 PCA9555APW-PCA9555APW,SMLF,IC,A   I206 @S9S_MB_2U_LIB.S9S_MB_2U(SCH_1):PAGE154

HP_LVC3_OCP_V3_1_EN @S9S_MB_2U_LIB.S9S_MB_2U(SCH_1):HP_LVC3_OCP_V3_1_EN
  U208    4      Y 74LVC1G08W57-74LVC1G08W5-7,SMLA   I190 @S9S_MB_2U_LIB.S9S_MB_2U(SCH_1):PAGE154
 R3263    2      B Q_RES_0402LF-0,5%,1/16W,CHIP,CA    I21 @S9S_MB_2U_LIB.S9S_MB_2U(SCH_1):PAGE216
 R3845    1      A Q_RES_0402LF-0,5%,1/16W,EMPTY,A    I46 @S9S_MB_2U_LIB.S9S_MB_2U(SCH_1):PAGE236
 R4061    1      A Q_RES_0402LF-0,5%,1/16W,EMPTY,A     I4 @S9S_MB_2U_LIB.S9S_MB_2U(SCH_1):PAGE153
 R5487    1      A Q_RES_0402LF-0,5%,1/16W,CHIP,CA    I19 @S9S_MB_2U_LIB.S9S_MB_2U(SCH_1):PAGE153
 R3834    1      A Q_RES_0402LF-0,5%,1/16W,CHIP,CA    I65 @S9S_MB_2U_LIB.S9S_MB_2U(SCH_1):PAGE236

HP_LVC3_OCP_V3_1_FUSE_PWRGD @S9S_MB_2U_LIB.S9S_MB_2U(SCH_1):HP_LVC3_OCP_V3_1_FUSE_PWRGD
  U249   L7  PL13A LCMXO3LF9400C5BG484C-LCMXO3LF-A    I33 @S9S_MB_2U_LIB.S9S_MB_2U(SCH_1):PAGE311
 R4751    2      B Q_RES_0402LF-33.2,1%,1/16W,CHIA    I79 @S9S_MB_2U_LIB.S9S_MB_2U(SCH_1):PAGE311

HP_LVC3_OCP_V3_1_HSC_PWRGD_PLD_ @S9S_MB_2U_LIB.S9S_MB_2U(SCH_1):HP_LVC3_OCP_V3_1_HSC_PWRGD_PLD_R
  U249  Y22  PR28A LCMXO3LF9400C5BG484C-LCMXO3LF-A     I1 @S9S_MB_2U_LIB.S9S_MB_2U(SCH_1):PAGE313
 R4600    2      B Q_RES_0402LF-0,5%,1/16W,CHIP,CA   I160 @S9S_MB_2U_LIB.S9S_MB_2U(SCH_1):PAGE313

HP_LVC3_OCP_V3_1_P12V_PWRGD @S9S_MB_2U_LIB.S9S_MB_2U(SCH_1):HP_LVC3_OCP_V3_1_P12V_PWRGD
 R3144    2      B Q_RES_0402LF-0,5%,1/16W,EMPTY,A    I82 @S9S_MB_2U_LIB.S9S_MB_2U(SCH_1):PAGE153
 R3797    2      B Q_RES_0402LF-100K,1%,1/16W,EMPA    I92 @S9S_MB_2U_LIB.S9S_MB_2U(SCH_1):PAGE153
 R4600    1      A Q_RES_0402LF-0,5%,1/16W,CHIP,CA   I160 @S9S_MB_2U_LIB.S9S_MB_2U(SCH_1):PAGE313
  U322    2      B 74LVC1G08W57-74LVC1G08W5-7,SMLA   I221 @S9S_MB_2U_LIB.S9S_MB_2U(SCH_1):PAGE154
 PU204   10     PG RS31312R-RS31312R,SMLF,IC,AL03A    I70 @S9S_MB_2U_LIB.S9S_MB_2U(SCH_1):PAGE236
 R4532    2      B Q_RES_0402LF-10K,1%,1/16W,CHIPA    I76 @S9S_MB_2U_LIB.S9S_MB_2U(SCH_1):PAGE236

HP_LVC3_OCP_V3_1_PRSNT2 @S9S_MB_2U_LIB.S9S_MB_2U(SCH_1):HP_LVC3_OCP_V3_1_PRSNT2
 R1129    2      B Q_RES_0402LF-1K,1%,1/16W,CHIP,A   I172 @S9S_MB_2U_LIB.S9S_MB_2U(SCH_1):PAGE154
   U49    D  DRAIN MOSFET_N_SMLF-BSS138K,BSS138K,A   I177 @S9S_MB_2U_LIB.S9S_MB_2U(SCH_1):PAGE154
  U208    2      B 74LVC1G08W57-74LVC1G08W5-7,SMLA   I190 @S9S_MB_2U_LIB.S9S_MB_2U(SCH_1):PAGE154

HP_LVC3_OCP_V3_1_PRSNT2_N @S9S_MB_2U_LIB.S9S_MB_2U(SCH_1):HP_LVC3_OCP_V3_1_PRSNT2_N
   U49    G   GATE MOSFET_N_SMLF-BSS138K,BSS138K,A   I177 @S9S_MB_2U_LIB.S9S_MB_2U(SCH_1):PAGE154
 R1150    2      B Q_RES_0402LF-10K,1%,1/16W,CHIPA    I74 @S9S_MB_2U_LIB.S9S_MB_2U(SCH_1):PAGE153
  U209    8   P0_4 PCA9555APW-PCA9555APW,SMLF,IC,A   I206 @S9S_MB_2U_LIB.S9S_MB_2U(SCH_1):PAGE154
 R1148    2      B Q_RES_0402LF-0,5%,1/16W,CHIP,CA    I46 @S9S_MB_2U_LIB.S9S_MB_2U(SCH_1):PAGE153

HP_LVC3_OCP_V3_1_PRSNT2_N_R @S9S_MB_2U_LIB.S9S_MB_2U(SCH_1):HP_LVC3_OCP_V3_1_PRSNT2_N_R
 R4752    1      A Q_RES_0402LF-0,5%,1/16W,CHIP,CA    I45 @S9S_MB_2U_LIB.S9S_MB_2U(SCH_1):PAGE153
 R1147    1      A Q_RES_0402LF-0,5%,1/16W,CHIP,CA    I47 @S9S_MB_2U_LIB.S9S_MB_2U(SCH_1):PAGE153
  U212    6     1Y 74LVC2G07DW7-74LVC2G07DW-7,SMLA    I23 @S9S_MB_2U_LIB.S9S_MB_2U(SCH_1):PAGE153
  U212    4     2Y 74LVC2G07DW7-74LVC2G07DW-7,SMLA    I23 @S9S_MB_2U_LIB.S9S_MB_2U(SCH_1):PAGE153
  U211    6     1Y 74LVC2G07DW7-74LVC2G07DW-7,SMLA    I26 @S9S_MB_2U_LIB.S9S_MB_2U(SCH_1):PAGE153
  U211    4     2Y 74LVC2G07DW7-74LVC2G07DW-7,SMLA    I26 @S9S_MB_2U_LIB.S9S_MB_2U(SCH_1):PAGE153
 R1148    1      A Q_RES_0402LF-0,5%,1/16W,CHIP,CA    I46 @S9S_MB_2U_LIB.S9S_MB_2U(SCH_1):PAGE153

HP_LVC3_OCP_V3_1_PRSNT2_PLD_N @S9S_MB_2U_LIB.S9S_MB_2U(SCH_1):HP_LVC3_OCP_V3_1_PRSNT2_PLD_N
  U249   K4  PL13C LCMXO3LF9400C5BG484C-LCMXO3LF-A    I33 @S9S_MB_2U_LIB.S9S_MB_2U(SCH_1):PAGE311
 R4752    2      B Q_RES_0402LF-0,5%,1/16W,CHIP,CA    I45 @S9S_MB_2U_LIB.S9S_MB_2U(SCH_1):PAGE153
 R4762    2      B Q_RES_0402LF-10K,1%,1/16W,CHIPA    I76 @S9S_MB_2U_LIB.S9S_MB_2U(SCH_1):PAGE153

HP_LVC3_OCP_V3_1_PWRGD @S9S_MB_2U_LIB.S9S_MB_2U(SCH_1):HP_LVC3_OCP_V3_1_PWRGD
  U322    4      Y 74LVC1G08W57-74LVC1G08W5-7,SMLA   I221 @S9S_MB_2U_LIB.S9S_MB_2U(SCH_1):PAGE154
 R4618    1      A Q_RES_0402LF-33.2,1%,1/16W,CHIA   I237 @S9S_MB_2U_LIB.S9S_MB_2U(SCH_1):PAGE154

HP_LVC3_OCP_V3_1_PWRGD_R @S9S_MB_2U_LIB.S9S_MB_2U(SCH_1):HP_LVC3_OCP_V3_1_PWRGD_R
  U210    1      A 74LVC1G08W57-74LVC1G08W5-7,SMLA   I189 @S9S_MB_2U_LIB.S9S_MB_2U(SCH_1):PAGE154
 R4618    2      B Q_RES_0402LF-33.2,1%,1/16W,CHIA   I237 @S9S_MB_2U_LIB.S9S_MB_2U(SCH_1):PAGE154
 R4746    1      A Q_RES_0402LF-33.2,1%,1/16W,CHIA   I245 @S9S_MB_2U_LIB.S9S_MB_2U(SCH_1):PAGE154
 R4751    1      A Q_RES_0402LF-33.2,1%,1/16W,CHIA    I79 @S9S_MB_2U_LIB.S9S_MB_2U(SCH_1):PAGE311

HP_LVC3_OCP_V3_1_PWRGD_R2 @S9S_MB_2U_LIB.S9S_MB_2U(SCH_1):HP_LVC3_OCP_V3_1_PWRGD_R2
  U334    1      A 74LVC1G08W57-74LVC1G08W5-7,SMLA   I243 @S9S_MB_2U_LIB.S9S_MB_2U(SCH_1):PAGE154
 R4746    2      B Q_RES_0402LF-33.2,1%,1/16W,CHIA   I245 @S9S_MB_2U_LIB.S9S_MB_2U(SCH_1):PAGE154
 R4748    1      A Q_RES_0402LF-0,5%,1/16W,EMPTY,A   I253 @S9S_MB_2U_LIB.S9S_MB_2U(SCH_1):PAGE154

HP_LVC3_OCP_V3_1_R_EN @S9S_MB_2U_LIB.S9S_MB_2U(SCH_1):HP_LVC3_OCP_V3_1_R_EN
 R3263    1      A Q_RES_0402LF-0,5%,1/16W,CHIP,CA    I21 @S9S_MB_2U_LIB.S9S_MB_2U(SCH_1):PAGE216
  U236    5     EN PCA9617ADP-PCA9617ADP,SMLF,IC,A    I28 @S9S_MB_2U_LIB.S9S_MB_2U(SCH_1):PAGE216

HP_LVC3_OCP_V3_2_ATTN_OUT_SW_N @S9S_MB_2U_LIB.S9S_MB_2U(SCH_1):HP_LVC3_OCP_V3_2_ATTN_OUT_SW_N
 R3143    2      B Q_RES_0402LF-0,5%,1/16W,CHIP,CA    I56 @S9S_MB_2U_LIB.S9S_MB_2U(SCH_1):PAGE131
   U51    7   P0_3 PCA9555APW-PCA9555APW,SMLF,IC,A    I66 @S9S_MB_2U_LIB.S9S_MB_2U(SCH_1):PAGE132
 R3145    2      B Q_RES_0402LF-10K,1%,1/16W,CHIPA    I64 @S9S_MB_2U_LIB.S9S_MB_2U(SCH_1):PAGE131

HP_LVC3_OCP_V3_2_EN @S9S_MB_2U_LIB.S9S_MB_2U(SCH_1):HP_LVC3_OCP_V3_2_EN
   U50    4      Y 74LVC1G08W57-74LVC1G08W5-7,SMLA     I9 @S9S_MB_2U_LIB.S9S_MB_2U(SCH_1):PAGE132
 R3264    2      B Q_RES_0402LF-0,5%,1/16W,CHIP,CA     I7 @S9S_MB_2U_LIB.S9S_MB_2U(SCH_1):PAGE216
 R4060    1      A Q_RES_0402LF-0,5%,1/16W,CHIP,CA    I35 @S9S_MB_2U_LIB.S9S_MB_2U(SCH_1):PAGE131
 R4059    1      A Q_RES_0402LF-0,5%,1/16W,EMPTY,A     I6 @S9S_MB_2U_LIB.S9S_MB_2U(SCH_1):PAGE131
 R3631    1      A Q_RES_0402LF-0,5%,1/16W,EMPTY,A    I44 @S9S_MB_2U_LIB.S9S_MB_2U(SCH_1):PAGE237
 R3630    1      A Q_RES_0402LF-0,5%,1/16W,CHIP,CA    I66 @S9S_MB_2U_LIB.S9S_MB_2U(SCH_1):PAGE237

HP_LVC3_OCP_V3_2_FUSE_PWRGD @S9S_MB_2U_LIB.S9S_MB_2U(SCH_1):HP_LVC3_OCP_V3_2_FUSE_PWRGD
  U249   K5  PL13B LCMXO3LF9400C5BG484C-LCMXO3LF-A    I33 @S9S_MB_2U_LIB.S9S_MB_2U(SCH_1):PAGE311
 R4760    2      B Q_RES_0402LF-33.2,1%,1/16W,CHIA    I86 @S9S_MB_2U_LIB.S9S_MB_2U(SCH_1):PAGE311

HP_LVC3_OCP_V3_2_HSC_PWRGD_PLD_ @S9S_MB_2U_LIB.S9S_MB_2U(SCH_1):HP_LVC3_OCP_V3_2_HSC_PWRGD_PLD_R
  U249  U20  PR27D LCMXO3LF9400C5BG484C-LCMXO3LF-A     I1 @S9S_MB_2U_LIB.S9S_MB_2U(SCH_1):PAGE313
 R4599    2      B Q_RES_0402LF-0,5%,1/16W,CHIP,CA   I159 @S9S_MB_2U_LIB.S9S_MB_2U(SCH_1):PAGE313

HP_LVC3_OCP_V3_2_P12V_PWRGD @S9S_MB_2U_LIB.S9S_MB_2U(SCH_1):HP_LVC3_OCP_V3_2_P12V_PWRGD
 R3831    2      B Q_RES_0402LF-0,5%,1/16W,EMPTY,A    I78 @S9S_MB_2U_LIB.S9S_MB_2U(SCH_1):PAGE131
 R3825    2      B Q_RES_0402LF-100K,1%,1/16W,EMPA    I81 @S9S_MB_2U_LIB.S9S_MB_2U(SCH_1):PAGE131
 R4599    1      A Q_RES_0402LF-0,5%,1/16W,CHIP,CA   I159 @S9S_MB_2U_LIB.S9S_MB_2U(SCH_1):PAGE313
  U323    2      B 74LVC1G08W57-74LVC1G08W5-7,SMLA    I92 @S9S_MB_2U_LIB.S9S_MB_2U(SCH_1):PAGE132
 PU206   10     PG RS31312R-RS31312R,SMLF,IC,AL03A    I70 @S9S_MB_2U_LIB.S9S_MB_2U(SCH_1):PAGE237
 R3848    2      B Q_RES_0402LF-10K,1%,1/16W,CHIPA    I75 @S9S_MB_2U_LIB.S9S_MB_2U(SCH_1):PAGE237

HP_LVC3_OCP_V3_2_PRSNT2 @S9S_MB_2U_LIB.S9S_MB_2U(SCH_1):HP_LVC3_OCP_V3_2_PRSNT2
 R3155    2      B Q_RES_0402LF-1K,1%,1/16W,CHIP,A     I7 @S9S_MB_2U_LIB.S9S_MB_2U(SCH_1):PAGE132
   U50    2      B 74LVC1G08W57-74LVC1G08W5-7,SMLA     I9 @S9S_MB_2U_LIB.S9S_MB_2U(SCH_1):PAGE132
  U215    D  DRAIN MOSFET_N_SMLF-BSS138K,BSS138K,A     I3 @S9S_MB_2U_LIB.S9S_MB_2U(SCH_1):PAGE132

HP_LVC3_OCP_V3_2_PRSNT2_N @S9S_MB_2U_LIB.S9S_MB_2U(SCH_1):HP_LVC3_OCP_V3_2_PRSNT2_N
  U215    G   GATE MOSFET_N_SMLF-BSS138K,BSS138K,A     I3 @S9S_MB_2U_LIB.S9S_MB_2U(SCH_1):PAGE132
 R3142    2      B Q_RES_0402LF-0,5%,1/16W,CHIP,CA    I57 @S9S_MB_2U_LIB.S9S_MB_2U(SCH_1):PAGE131
 R3147    2      B Q_RES_0402LF-10K,1%,1/16W,CHIPA    I66 @S9S_MB_2U_LIB.S9S_MB_2U(SCH_1):PAGE131
   U51    8   P0_4 PCA9555APW-PCA9555APW,SMLF,IC,A    I66 @S9S_MB_2U_LIB.S9S_MB_2U(SCH_1):PAGE132

HP_LVC3_OCP_V3_2_PRSNT2_N_R @S9S_MB_2U_LIB.S9S_MB_2U(SCH_1):HP_LVC3_OCP_V3_2_PRSNT2_N_R
 R3142    1      A Q_RES_0402LF-0,5%,1/16W,CHIP,CA    I57 @S9S_MB_2U_LIB.S9S_MB_2U(SCH_1):PAGE131
   U59    6     1Y 74LVC2G07DW7-74LVC2G07DW-7,SMLA    I19 @S9S_MB_2U_LIB.S9S_MB_2U(SCH_1):PAGE131
   U59    4     2Y 74LVC2G07DW7-74LVC2G07DW-7,SMLA    I19 @S9S_MB_2U_LIB.S9S_MB_2U(SCH_1):PAGE131
   U58    6     1Y 74LVC2G07DW7-74LVC2G07DW-7,SMLA    I25 @S9S_MB_2U_LIB.S9S_MB_2U(SCH_1):PAGE131
   U58    4     2Y 74LVC2G07DW7-74LVC2G07DW-7,SMLA    I25 @S9S_MB_2U_LIB.S9S_MB_2U(SCH_1):PAGE131
 R3143    1      A Q_RES_0402LF-0,5%,1/16W,CHIP,CA    I56 @S9S_MB_2U_LIB.S9S_MB_2U(SCH_1):PAGE131
 R4753    1      A Q_RES_0402LF-0,5%,1/16W,CHIP,CA    I55 @S9S_MB_2U_LIB.S9S_MB_2U(SCH_1):PAGE131

HP_LVC3_OCP_V3_2_PRSNT2_PLD_N @S9S_MB_2U_LIB.S9S_MB_2U(SCH_1):HP_LVC3_OCP_V3_2_PRSNT2_PLD_N
  U249   K3  PL13D LCMXO3LF9400C5BG484C-LCMXO3LF-A    I33 @S9S_MB_2U_LIB.S9S_MB_2U(SCH_1):PAGE311
 R4761    2      B Q_RES_0402LF-10K,1%,1/16W,CHIPA    I70 @S9S_MB_2U_LIB.S9S_MB_2U(SCH_1):PAGE131
 R4753    2      B Q_RES_0402LF-0,5%,1/16W,CHIP,CA    I55 @S9S_MB_2U_LIB.S9S_MB_2U(SCH_1):PAGE131

HP_LVC3_OCP_V3_2_PWRGD @S9S_MB_2U_LIB.S9S_MB_2U(SCH_1):HP_LVC3_OCP_V3_2_PWRGD
  U323    4      Y 74LVC1G08W57-74LVC1G08W5-7,SMLA    I92 @S9S_MB_2U_LIB.S9S_MB_2U(SCH_1):PAGE132
 R4617    1      A Q_RES_0402LF-33.2,1%,1/16W,CHIA    I99 @S9S_MB_2U_LIB.S9S_MB_2U(SCH_1):PAGE132

HP_LVC3_OCP_V3_2_PWRGD_R @S9S_MB_2U_LIB.S9S_MB_2U(SCH_1):HP_LVC3_OCP_V3_2_PWRGD_R
   U53    1      A 74LVC1G08W57-74LVC1G08W5-7,SMLA    I56 @S9S_MB_2U_LIB.S9S_MB_2U(SCH_1):PAGE132
 R4617    2      B Q_RES_0402LF-33.2,1%,1/16W,CHIA    I99 @S9S_MB_2U_LIB.S9S_MB_2U(SCH_1):PAGE132
 R4754    1      A Q_RES_0402LF-33.2,1%,1/16W,CHIA   I104 @S9S_MB_2U_LIB.S9S_MB_2U(SCH_1):PAGE132
 R4760    1      A Q_RES_0402LF-33.2,1%,1/16W,CHIA    I86 @S9S_MB_2U_LIB.S9S_MB_2U(SCH_1):PAGE311

HP_LVC3_OCP_V3_2_PWRGD_R2 @S9S_MB_2U_LIB.S9S_MB_2U(SCH_1):HP_LVC3_OCP_V3_2_PWRGD_R2
 R4754    2      B Q_RES_0402LF-33.2,1%,1/16W,CHIA   I104 @S9S_MB_2U_LIB.S9S_MB_2U(SCH_1):PAGE132
  U335    1      A 74LVC1G08W57-74LVC1G08W5-7,SMLA   I108 @S9S_MB_2U_LIB.S9S_MB_2U(SCH_1):PAGE132
 R4757    1      A Q_RES_0402LF-0,5%,1/16W,EMPTY,A   I112 @S9S_MB_2U_LIB.S9S_MB_2U(SCH_1):PAGE132

HP_LVC3_OCP_V3_2_R_EN @S9S_MB_2U_LIB.S9S_MB_2U(SCH_1):HP_LVC3_OCP_V3_2_R_EN
  U235    5     EN PCA9617ADP-PCA9617ADP,SMLF,IC,A     I5 @S9S_MB_2U_LIB.S9S_MB_2U(SCH_1):PAGE216
 R3264    1      A Q_RES_0402LF-0,5%,1/16W,CHIP,CA     I7 @S9S_MB_2U_LIB.S9S_MB_2U(SCH_1):PAGE216

HP_LVC3_SCM_HSC_PWRGD @S9S_MB_2U_LIB.S9S_MB_2U(SCH_1):HP_LVC3_SCM_HSC_PWRGD
PR4012    2      B Q_RES_0402LF-0,5%,1/16W,EMPTY,A    I74 @S9S_MB_2U_LIB.S9S_MB_2U(SCH_1):PAGE229
 R4015    2      B Q_RES_0402LF-100K,1%,1/16W,EMPA    I81 @S9S_MB_2U_LIB.S9S_MB_2U(SCH_1):PAGE229
 R4771    1      A Q_RES_0402LF-33.2,1%,1/16W,CHIA    I95 @S9S_MB_2U_LIB.S9S_MB_2U(SCH_1):PAGE311
 R4770    2      B Q_RES_0402LF-0,5%,1/16W,CHIP,CA    I91 @S9S_MB_2U_LIB.S9S_MB_2U(SCH_1):PAGE229

HP_LVC3_SCM_HSC_PWRGD_PLD @S9S_MB_2U_LIB.S9S_MB_2U(SCH_1):HP_LVC3_SCM_HSC_PWRGD_PLD
  U249   L5  PL14D LCMXO3LF9400C5BG484C-LCMXO3LF-A    I33 @S9S_MB_2U_LIB.S9S_MB_2U(SCH_1):PAGE311
 R4771    2      B Q_RES_0402LF-33.2,1%,1/16W,CHIA    I95 @S9S_MB_2U_LIB.S9S_MB_2U(SCH_1):PAGE311

HP_LVC3_SCM_HSC_PWRGD_R @S9S_MB_2U_LIB.S9S_MB_2U(SCH_1):HP_LVC3_SCM_HSC_PWRGD_R
 PU299   10     PG RS31312R-RS31312R,SMLF,IC,AL03A    I90 @S9S_MB_2U_LIB.S9S_MB_2U(SCH_1):PAGE229
 R4770    1      A Q_RES_0402LF-0,5%,1/16W,CHIP,CA    I91 @S9S_MB_2U_LIB.S9S_MB_2U(SCH_1):PAGE229
 R3836    2      B Q_RES_0402LF-10K,1%,1/16W,CHIPA    I92 @S9S_MB_2U_LIB.S9S_MB_2U(SCH_1):PAGE229

HP_OCP_V3_1_EN @S9S_MB_2U_LIB.S9S_MB_2U(SCH_1):HP_OCP_V3_1_EN
  U208    1      A 74LVC1G08W57-74LVC1G08W5-7,SMLA   I190 @S9S_MB_2U_LIB.S9S_MB_2U(SCH_1):PAGE154
  U209    6   P0_2 PCA9555APW-PCA9555APW,SMLF,IC,A   I206 @S9S_MB_2U_LIB.S9S_MB_2U(SCH_1):PAGE154
 R4764    2      B Q_RES_0402LF-10K,1%,1/16W,CHIPA   I257 @S9S_MB_2U_LIB.S9S_MB_2U(SCH_1):PAGE154

HP_OCP_V3_1_RST @S9S_MB_2U_LIB.S9S_MB_2U(SCH_1):HP_OCP_V3_1_RST
   U52    2 RESET_L APX80929SAG7-APX809-29SAG-7,SMA   I228 @S9S_MB_2U_LIB.S9S_MB_2U(SCH_1):PAGE154
 R4614    1      A Q_RES_0402LF-33.2,1%,1/16W,CHIA   I238 @S9S_MB_2U_LIB.S9S_MB_2U(SCH_1):PAGE154

HP_OCP_V3_1_RST_R @S9S_MB_2U_LIB.S9S_MB_2U(SCH_1):HP_OCP_V3_1_RST_R
  U322    1      A 74LVC1G08W57-74LVC1G08W5-7,SMLA   I221 @S9S_MB_2U_LIB.S9S_MB_2U(SCH_1):PAGE154
 R4613    2      B Q_RES_0402LF-0,5%,1/16W,EMPTY,A   I232 @S9S_MB_2U_LIB.S9S_MB_2U(SCH_1):PAGE154
 R3160    2      B Q_RES_0402LF-1K,1%,1/16W,EMPTYA   I235 @S9S_MB_2U_LIB.S9S_MB_2U(SCH_1):PAGE154
 R4614    2      B Q_RES_0402LF-33.2,1%,1/16W,CHIA   I238 @S9S_MB_2U_LIB.S9S_MB_2U(SCH_1):PAGE154

HP_OCP_V3_2_EN @S9S_MB_2U_LIB.S9S_MB_2U(SCH_1):HP_OCP_V3_2_EN
   U50    1      A 74LVC1G08W57-74LVC1G08W5-7,SMLA     I9 @S9S_MB_2U_LIB.S9S_MB_2U(SCH_1):PAGE132
   U51    6   P0_2 PCA9555APW-PCA9555APW,SMLF,IC,A    I66 @S9S_MB_2U_LIB.S9S_MB_2U(SCH_1):PAGE132
 R4763    2      B Q_RES_0402LF-10K,1%,1/16W,CHIPA   I119 @S9S_MB_2U_LIB.S9S_MB_2U(SCH_1):PAGE132

HP_OCP_V3_2_RST @S9S_MB_2U_LIB.S9S_MB_2U(SCH_1):HP_OCP_V3_2_RST
  U216    2 RESET_L APX80929SAG7-APX809-29SAG-7,SMA    I85 @S9S_MB_2U_LIB.S9S_MB_2U(SCH_1):PAGE132
 R4616    1      A Q_RES_0402LF-33.2,1%,1/16W,CHIA   I100 @S9S_MB_2U_LIB.S9S_MB_2U(SCH_1):PAGE132

HP_OCP_V3_2_RST_R @S9S_MB_2U_LIB.S9S_MB_2U(SCH_1):HP_OCP_V3_2_RST_R
  U323    1      A 74LVC1G08W57-74LVC1G08W5-7,SMLA    I92 @S9S_MB_2U_LIB.S9S_MB_2U(SCH_1):PAGE132
 R1132    2      B Q_RES_0402LF-1K,1%,1/16W,EMPTYA    I95 @S9S_MB_2U_LIB.S9S_MB_2U(SCH_1):PAGE132
 R4615    2      B Q_RES_0402LF-0,5%,1/16W,EMPTY,A    I96 @S9S_MB_2U_LIB.S9S_MB_2U(SCH_1):PAGE132
 R4616    2      B Q_RES_0402LF-33.2,1%,1/16W,CHIA   I100 @S9S_MB_2U_LIB.S9S_MB_2U(SCH_1):PAGE132

HSC_ADDR @S9S_MB_2U_LIB.S9S_MB_2U(SCH_1):HSC_ADDR
 PU289   23   ADDR MP5990GMA1111Z-MP5990GMA-1111-A    I56 @S9S_MB_2U_LIB.S9S_MB_2U(SCH_1):PAGE303
PR3930    2      B Q_RES_0402LF-0,5%,1/16W,CHIP,CA    I32 @S9S_MB_2U_LIB.S9S_MB_2U(SCH_1):PAGE303
PR3929    1      A Q_RES_0402LF-1K,1%,1/16W,EMPTYA    I42 @S9S_MB_2U_LIB.S9S_MB_2U(SCH_1):PAGE303

HSC_CS @S9S_MB_2U_LIB.S9S_MB_2U(SCH_1):HSC_CS
 PU289   20     CS MP5990GMA1111Z-MP5990GMA-1111-A    I56 @S9S_MB_2U_LIB.S9S_MB_2U(SCH_1):PAGE303
PR1131    1      A Q_RES_0402LF-2K,0.1%,1/16W,CHIA    I58 @S9S_MB_2U_LIB.S9S_MB_2U(SCH_1):PAGE303

HSC_CSOUT @S9S_MB_2U_LIB.S9S_MB_2U(SCH_1):HSC_CSOUT
  PJ42   16     16 SCONN21_9193031121LF-SCONN21_9A    I34 @S9S_MB_2U_LIB.S9S_MB_2U(SCH_1):PAGE327
 R4667    1      A Q_RES_0402LF-160K,1%,1/16W,EMPA    I14 @S9S_MB_2U_LIB.S9S_MB_2U(SCH_1):PAGE326
 R4669    1      A Q_RES_0402LF-160K,1%,1/16W,EMPA    I25 @S9S_MB_2U_LIB.S9S_MB_2U(SCH_1):PAGE326
 R4693    1      A Q_RES_0402LF-0,5%,1/16W,EMPTY,A    I29 @S9S_MB_2U_LIB.S9S_MB_2U(SCH_1):PAGE326
 R4795    1      A Q_RES_0402LF-160K,1%,1/16W,EMPA    I78 @S9S_MB_2U_LIB.S9S_MB_2U(SCH_1):PAGE326

HSC_CS_1 @S9S_MB_2U_LIB.S9S_MB_2U(SCH_1):HSC_CS_1
PR3914    1      A Q_RES_0402LF-2K,0.1%,1/16W,CHIA    I30 @S9S_MB_2U_LIB.S9S_MB_2U(SCH_1):PAGE301
 PU287   23     CS MP5991GLUZ-MP5991GLU-Z,SMLF,ICA    I35 @S9S_MB_2U_LIB.S9S_MB_2U(SCH_1):PAGE301

HSC_CS_2 @S9S_MB_2U_LIB.S9S_MB_2U(SCH_1):HSC_CS_2
PR3915    1      A Q_RES_0402LF-2K,0.1%,1/16W,CHIA    I12 @S9S_MB_2U_LIB.S9S_MB_2U(SCH_1):PAGE301
 PU288   23     CS MP5991GLUZ-MP5991GLU-Z,SMLF,ICA    I14 @S9S_MB_2U_LIB.S9S_MB_2U(SCH_1):PAGE301

HSC_CS_3 @S9S_MB_2U_LIB.S9S_MB_2U(SCH_1):HSC_CS_3
PR3986    1      A Q_RES_0402LF-2K,0.1%,1/16W,CHIA    I30 @S9S_MB_2U_LIB.S9S_MB_2U(SCH_1):PAGE325
 PU296   23     CS MP5991GLUZ-MP5991GLU-Z,SMLF,ICA    I35 @S9S_MB_2U_LIB.S9S_MB_2U(SCH_1):PAGE325

HSC_CS_4 @S9S_MB_2U_LIB.S9S_MB_2U(SCH_1):HSC_CS_4
PR3987    1      A Q_RES_0402LF-2K,0.1%,1/16W,CHIA    I12 @S9S_MB_2U_LIB.S9S_MB_2U(SCH_1):PAGE325
 PU297   23     CS MP5991GLUZ-MP5991GLU-Z,SMLF,ICA    I17 @S9S_MB_2U_LIB.S9S_MB_2U(SCH_1):PAGE325

HSC_D_OC @S9S_MB_2U_LIB.S9S_MB_2U(SCH_1):HSC_D_OC
 R4056    1      A Q_RES_0402LF-0,5%,1/16W,CHIP,CA    I80 @S9S_MB_2U_LIB.S9S_MB_2U(SCH_1):PAGE312
 R3936    2      B Q_RES_0402LF-4.7K,1%,1/16W,CHIA    I85 @S9S_MB_2U_LIB.S9S_MB_2U(SCH_1):PAGE303
 R4693    2      B Q_RES_0402LF-0,5%,1/16W,EMPTY,A    I29 @S9S_MB_2U_LIB.S9S_MB_2U(SCH_1):PAGE326
  U369    6   OUTB TPS3700DDCR-TPS3700DDCR,SMLF,EA    I30 @S9S_MB_2U_LIB.S9S_MB_2U(SCH_1):PAGE326
 R4652    2      B Q_RES_0402LF-0,5%,1/16W,EMPTY,A    I48 @S9S_MB_2U_LIB.S9S_MB_2U(SCH_1):PAGE326
 R4671    2      B Q_RES_0402LF-10K,1%,1/16W,EMPTA    I51 @S9S_MB_2U_LIB.S9S_MB_2U(SCH_1):PAGE326
 R3934    2      B Q_RES_0402LF-22,1%,1/16W,CHIP,A    I82 @S9S_MB_2U_LIB.S9S_MB_2U(SCH_1):PAGE303

HSC_D_OC_1 @S9S_MB_2U_LIB.S9S_MB_2U(SCH_1):HSC_D_OC_1
PR3919    1      A Q_RES_0402LF-0,5%,1/16W,CHIP,CA    I49 @S9S_MB_2U_LIB.S9S_MB_2U(SCH_1):PAGE301
 PU287    3   D_OC MP5991GLUZ-MP5991GLU-Z,SMLF,ICA    I35 @S9S_MB_2U_LIB.S9S_MB_2U(SCH_1):PAGE301

HSC_D_OC_2 @S9S_MB_2U_LIB.S9S_MB_2U(SCH_1):HSC_D_OC_2
PR3921    1      A Q_RES_0402LF-0,5%,1/16W,CHIP,CA    I39 @S9S_MB_2U_LIB.S9S_MB_2U(SCH_1):PAGE301
 PU288    3   D_OC MP5991GLUZ-MP5991GLU-Z,SMLF,ICA    I14 @S9S_MB_2U_LIB.S9S_MB_2U(SCH_1):PAGE301

HSC_D_OC_3 @S9S_MB_2U_LIB.S9S_MB_2U(SCH_1):HSC_D_OC_3
 PU296    3   D_OC MP5991GLUZ-MP5991GLU-Z,SMLF,ICA    I35 @S9S_MB_2U_LIB.S9S_MB_2U(SCH_1):PAGE325
PR3992    1      A Q_RES_0402LF-0,5%,1/16W,CHIP,CA    I50 @S9S_MB_2U_LIB.S9S_MB_2U(SCH_1):PAGE325

HSC_D_OC_4 @S9S_MB_2U_LIB.S9S_MB_2U(SCH_1):HSC_D_OC_4
 PU297    3   D_OC MP5991GLUZ-MP5991GLU-Z,SMLF,ICA    I17 @S9S_MB_2U_LIB.S9S_MB_2U(SCH_1):PAGE325
PR3994    1      A Q_RES_0402LF-0,5%,1/16W,CHIP,CA    I40 @S9S_MB_2U_LIB.S9S_MB_2U(SCH_1):PAGE325

HSC_D_OC_R @S9S_MB_2U_LIB.S9S_MB_2U(SCH_1):HSC_D_OC_R
PR3921    2      B Q_RES_0402LF-0,5%,1/16W,CHIP,CA    I39 @S9S_MB_2U_LIB.S9S_MB_2U(SCH_1):PAGE301
PR3919    2      B Q_RES_0402LF-0,5%,1/16W,CHIP,CA    I49 @S9S_MB_2U_LIB.S9S_MB_2U(SCH_1):PAGE301
 PU289   37   D_OC MP5990GMA1111Z-MP5990GMA-1111-A    I56 @S9S_MB_2U_LIB.S9S_MB_2U(SCH_1):PAGE303
PR3994    2      B Q_RES_0402LF-0,5%,1/16W,CHIP,CA    I40 @S9S_MB_2U_LIB.S9S_MB_2U(SCH_1):PAGE325
PR3992    2      B Q_RES_0402LF-0,5%,1/16W,CHIP,CA    I50 @S9S_MB_2U_LIB.S9S_MB_2U(SCH_1):PAGE325
 R3934    1      A Q_RES_0402LF-22,1%,1/16W,CHIP,A    I82 @S9S_MB_2U_LIB.S9S_MB_2U(SCH_1):PAGE303

HSC_D_OC_R1 @S9S_MB_2U_LIB.S9S_MB_2U(SCH_1):HSC_D_OC_R1
  U249  W10  PB21B LCMXO3LF9400C5BG484C-LCMXO3LF-A     I1 @S9S_MB_2U_LIB.S9S_MB_2U(SCH_1):PAGE312
 R4056    2      B Q_RES_0402LF-0,5%,1/16W,CHIP,CA    I80 @S9S_MB_2U_LIB.S9S_MB_2U(SCH_1):PAGE312

HSC_D_OC_R2 @S9S_MB_2U_LIB.S9S_MB_2U(SCH_1):HSC_D_OC_R2
  U344    4 OUTPUT AP331AWG7-AP331AWG-7,SMLF,EMPTA    I66 @S9S_MB_2U_LIB.S9S_MB_2U(SCH_1):PAGE326
 R4793    2      B Q_RES_0402LF-1M,1%,1/16W,EMPTYA    I68 @S9S_MB_2U_LIB.S9S_MB_2U(SCH_1):PAGE326
 R4794    1      A Q_RES_0402LF-33.2,1%,1/16W,EMPA    I72 @S9S_MB_2U_LIB.S9S_MB_2U(SCH_1):PAGE326

HSC_EN @S9S_MB_2U_LIB.S9S_MB_2U(SCH_1):HSC_EN
  U290    D      D MOSFET_NCH_GDS_ESD_PROTECTED-2A     I5 @S9S_MB_2U_LIB.S9S_MB_2U(SCH_1):PAGE303
 R2585    1      A Q_RES_0402LF-31.6K,1%,1/16W,CHA     I7 @S9S_MB_2U_LIB.S9S_MB_2U(SCH_1):PAGE303
  PJ42   14     14 SCONN21_9193031121LF-SCONN21_9A    I34 @S9S_MB_2U_LIB.S9S_MB_2U(SCH_1):PAGE327
 R4901    2      B Q_RES_0402LF-82K,1%,1/16W,CHIPA    I26 @S9S_MB_2U_LIB.S9S_MB_2U(SCH_1):PAGE303
 C2179    1      A Q_CAP_C0402-100NF,50V,10%,X7R,A    I29 @S9S_MB_2U_LIB.S9S_MB_2U(SCH_1):PAGE303
 R2586    1      A Q_RES_0402LF-0,5%,1/16W,CHIP,CA    I44 @S9S_MB_2U_LIB.S9S_MB_2U(SCH_1):PAGE303

HSC_EN_R @S9S_MB_2U_LIB.S9S_MB_2U(SCH_1):HSC_EN_R
 PU289   26     EN MP5990GMA1111Z-MP5990GMA-1111-A    I56 @S9S_MB_2U_LIB.S9S_MB_2U(SCH_1):PAGE303
 R2586    2      B Q_RES_0402LF-0,5%,1/16W,CHIP,CA    I44 @S9S_MB_2U_LIB.S9S_MB_2U(SCH_1):PAGE303

HSC_FAULT @S9S_MB_2U_LIB.S9S_MB_2U(SCH_1):HSC_FAULT
 PU297    5    GOK MP5991GLUZ-MP5991GLU-Z,SMLF,ICA    I17 @S9S_MB_2U_LIB.S9S_MB_2U(SCH_1):PAGE325
 PU289   39    GOK MP5990GMA1111Z-MP5990GMA-1111-A    I56 @S9S_MB_2U_LIB.S9S_MB_2U(SCH_1):PAGE303
 PU296    5    GOK MP5991GLUZ-MP5991GLU-Z,SMLF,ICA    I35 @S9S_MB_2U_LIB.S9S_MB_2U(SCH_1):PAGE325
 R2588    1      A Q_RES_0402LF-22,1%,1/16W,CHIP,A    I81 @S9S_MB_2U_LIB.S9S_MB_2U(SCH_1):PAGE303
 PU287    5    GOK MP5991GLUZ-MP5991GLU-Z,SMLF,ICA    I35 @S9S_MB_2U_LIB.S9S_MB_2U(SCH_1):PAGE301
 PU288    5    GOK MP5991GLUZ-MP5991GLU-Z,SMLF,ICA    I14 @S9S_MB_2U_LIB.S9S_MB_2U(SCH_1):PAGE301

HSC_FLT_TYPE @S9S_MB_2U_LIB.S9S_MB_2U(SCH_1):HSC_FLT_TYPE
PR3995    2      B Q_RES_0402LF-0,5%,1/16W,CHIP,CA    I39 @S9S_MB_2U_LIB.S9S_MB_2U(SCH_1):PAGE325
PR3993    2      B Q_RES_0402LF-0,5%,1/16W,CHIP,CA    I49 @S9S_MB_2U_LIB.S9S_MB_2U(SCH_1):PAGE325
 PU289   40 FLT_TYPE MP5990GMA1111Z-MP5990GMA-1111-A    I56 @S9S_MB_2U_LIB.S9S_MB_2U(SCH_1):PAGE303
PR3922    2      B Q_RES_0402LF-0,5%,1/16W,CHIP,CA    I40 @S9S_MB_2U_LIB.S9S_MB_2U(SCH_1):PAGE301
PR3920    2      B Q_RES_0402LF-0,5%,1/16W,CHIP,CA    I50 @S9S_MB_2U_LIB.S9S_MB_2U(SCH_1):PAGE301

HSC_FLT_TYPE_1 @S9S_MB_2U_LIB.S9S_MB_2U(SCH_1):HSC_FLT_TYPE_1
 PU287    6 FLT_TYPE MP5991GLUZ-MP5991GLU-Z,SMLF,ICA    I35 @S9S_MB_2U_LIB.S9S_MB_2U(SCH_1):PAGE301
PR3920    1      A Q_RES_0402LF-0,5%,1/16W,CHIP,CA    I50 @S9S_MB_2U_LIB.S9S_MB_2U(SCH_1):PAGE301

HSC_FLT_TYPE_2 @S9S_MB_2U_LIB.S9S_MB_2U(SCH_1):HSC_FLT_TYPE_2
PR3922    1      A Q_RES_0402LF-0,5%,1/16W,CHIP,CA    I40 @S9S_MB_2U_LIB.S9S_MB_2U(SCH_1):PAGE301
 PU288    6 FLT_TYPE MP5991GLUZ-MP5991GLU-Z,SMLF,ICA    I14 @S9S_MB_2U_LIB.S9S_MB_2U(SCH_1):PAGE301

HSC_FLT_TYPE_3 @S9S_MB_2U_LIB.S9S_MB_2U(SCH_1):HSC_FLT_TYPE_3
PR3993    1      A Q_RES_0402LF-0,5%,1/16W,CHIP,CA    I49 @S9S_MB_2U_LIB.S9S_MB_2U(SCH_1):PAGE325
 PU296    6 FLT_TYPE MP5991GLUZ-MP5991GLU-Z,SMLF,ICA    I35 @S9S_MB_2U_LIB.S9S_MB_2U(SCH_1):PAGE325

HSC_FLT_TYPE_4 @S9S_MB_2U_LIB.S9S_MB_2U(SCH_1):HSC_FLT_TYPE_4
PR3995    1      A Q_RES_0402LF-0,5%,1/16W,CHIP,CA    I39 @S9S_MB_2U_LIB.S9S_MB_2U(SCH_1):PAGE325
 PU297    6 FLT_TYPE MP5991GLUZ-MP5991GLU-Z,SMLF,ICA    I17 @S9S_MB_2U_LIB.S9S_MB_2U(SCH_1):PAGE325

HSC_IMON @S9S_MB_2U_LIB.S9S_MB_2U(SCH_1):HSC_IMON
PR1101    1      A Q_RES_0402LF-2K,0.1%,1/16W,CHIA    I13 @S9S_MB_2U_LIB.S9S_MB_2U(SCH_1):PAGE301
PR3991    1      A Q_RES_0402LF-2K,0.1%,1/16W,CHIA    I13 @S9S_MB_2U_LIB.S9S_MB_2U(SCH_1):PAGE325
PR3990    1      A Q_RES_0402LF-2K,0.1%,1/16W,CHIA    I34 @S9S_MB_2U_LIB.S9S_MB_2U(SCH_1):PAGE325
PR3918    1      A Q_RES_0402LF-2K,0.1%,1/16W,CHIA    I34 @S9S_MB_2U_LIB.S9S_MB_2U(SCH_1):PAGE301
 PU297   22   IMON MP5991GLUZ-MP5991GLU-Z,SMLF,ICA    I17 @S9S_MB_2U_LIB.S9S_MB_2U(SCH_1):PAGE325
 PU289   21   IMON MP5990GMA1111Z-MP5990GMA-1111-A    I56 @S9S_MB_2U_LIB.S9S_MB_2U(SCH_1):PAGE303
 PU296   22   IMON MP5991GLUZ-MP5991GLU-Z,SMLF,ICA    I35 @S9S_MB_2U_LIB.S9S_MB_2U(SCH_1):PAGE325
 PU287   22   IMON MP5991GLUZ-MP5991GLU-Z,SMLF,ICA    I35 @S9S_MB_2U_LIB.S9S_MB_2U(SCH_1):PAGE301
 PU288   22   IMON MP5991GLUZ-MP5991GLU-Z,SMLF,ICA    I14 @S9S_MB_2U_LIB.S9S_MB_2U(SCH_1):PAGE301
PC2193    1      A Q_CAP_C0402-0.047UF,25V,10%,X7A    I89 @S9S_MB_2U_LIB.S9S_MB_2U(SCH_1):PAGE303
PR1133    1      A Q_RES_0402LF-2K,0.1%,1/16W,CHIA    I91 @S9S_MB_2U_LIB.S9S_MB_2U(SCH_1):PAGE303

HSC_MODE @S9S_MB_2U_LIB.S9S_MB_2U(SCH_1):HSC_MODE
 PU289   41   MODE MP5990GMA1111Z-MP5990GMA-1111-A    I56 @S9S_MB_2U_LIB.S9S_MB_2U(SCH_1):PAGE303
PR3937    1      A Q_RES_0402LF-120K,1%,1/16W,CHIA    I84 @S9S_MB_2U_LIB.S9S_MB_2U(SCH_1):PAGE303

HSC_MODE_1 @S9S_MB_2U_LIB.S9S_MB_2U(SCH_1):HSC_MODE_1
 PU287    8   MODE MP5991GLUZ-MP5991GLU-Z,SMLF,ICA    I35 @S9S_MB_2U_LIB.S9S_MB_2U(SCH_1):PAGE301
PR1134    2      B Q_RES_0402LF-120K,1%,1/16W,CHIA    I32 @S9S_MB_2U_LIB.S9S_MB_2U(SCH_1):PAGE301

HSC_MODE_2 @S9S_MB_2U_LIB.S9S_MB_2U(SCH_1):HSC_MODE_2
PR3912    2      B Q_RES_0402LF-120K,1%,1/16W,CHIA    I15 @S9S_MB_2U_LIB.S9S_MB_2U(SCH_1):PAGE301
 PU288    8   MODE MP5991GLUZ-MP5991GLU-Z,SMLF,ICA    I14 @S9S_MB_2U_LIB.S9S_MB_2U(SCH_1):PAGE301

HSC_MODE_3 @S9S_MB_2U_LIB.S9S_MB_2U(SCH_1):HSC_MODE_3
 PU296    8   MODE MP5991GLUZ-MP5991GLU-Z,SMLF,ICA    I35 @S9S_MB_2U_LIB.S9S_MB_2U(SCH_1):PAGE325
PR3982    2      B Q_RES_0402LF-120K,1%,1/16W,CHIA    I32 @S9S_MB_2U_LIB.S9S_MB_2U(SCH_1):PAGE325

HSC_MODE_4 @S9S_MB_2U_LIB.S9S_MB_2U(SCH_1):HSC_MODE_4
 PU297    8   MODE MP5991GLUZ-MP5991GLU-Z,SMLF,ICA    I17 @S9S_MB_2U_LIB.S9S_MB_2U(SCH_1):PAGE325
PR3984    2      B Q_RES_0402LF-120K,1%,1/16W,CHIA    I14 @S9S_MB_2U_LIB.S9S_MB_2U(SCH_1):PAGE325

HSC_NC1_1 @S9S_MB_2U_LIB.S9S_MB_2U(SCH_1):HSC_NC1_1
 PU287    7    NC1 MP5991GLUZ-MP5991GLU-Z,SMLF,ICA    I35 @S9S_MB_2U_LIB.S9S_MB_2U(SCH_1):PAGE301

HSC_NC1_2 @S9S_MB_2U_LIB.S9S_MB_2U(SCH_1):HSC_NC1_2
 PU288    7    NC1 MP5991GLUZ-MP5991GLU-Z,SMLF,ICA    I14 @S9S_MB_2U_LIB.S9S_MB_2U(SCH_1):PAGE301

HSC_NC1_3 @S9S_MB_2U_LIB.S9S_MB_2U(SCH_1):HSC_NC1_3
 PU296    7    NC1 MP5991GLUZ-MP5991GLU-Z,SMLF,ICA    I35 @S9S_MB_2U_LIB.S9S_MB_2U(SCH_1):PAGE325

HSC_NC1_4 @S9S_MB_2U_LIB.S9S_MB_2U(SCH_1):HSC_NC1_4
 PU297    7    NC1 MP5991GLUZ-MP5991GLU-Z,SMLF,ICA    I17 @S9S_MB_2U_LIB.S9S_MB_2U(SCH_1):PAGE325

HSC_OCREF @S9S_MB_2U_LIB.S9S_MB_2U(SCH_1):HSC_OCREF
PC2347    1      A Q_CAP_0402-1NF,50V,10%,EMPTY,CA    I29 @S9S_MB_2U_LIB.S9S_MB_2U(SCH_1):PAGE301
PC2349    1      A Q_CAP_0402-1NF,50V,10%,EMPTY,CA    I11 @S9S_MB_2U_LIB.S9S_MB_2U(SCH_1):PAGE325
PC2348    1      A Q_CAP_0402-1NF,50V,10%,EMPTY,CA    I11 @S9S_MB_2U_LIB.S9S_MB_2U(SCH_1):PAGE301
 PU297   24  OCREF MP5991GLUZ-MP5991GLU-Z,SMLF,ICA    I17 @S9S_MB_2U_LIB.S9S_MB_2U(SCH_1):PAGE325
 PU289   22  OCREF MP5990GMA1111Z-MP5990GMA-1111-A    I56 @S9S_MB_2U_LIB.S9S_MB_2U(SCH_1):PAGE303
 PU296   24  OCREF MP5991GLUZ-MP5991GLU-Z,SMLF,ICA    I35 @S9S_MB_2U_LIB.S9S_MB_2U(SCH_1):PAGE325
 PU287   24  OCREF MP5991GLUZ-MP5991GLU-Z,SMLF,ICA    I35 @S9S_MB_2U_LIB.S9S_MB_2U(SCH_1):PAGE301
 PU288   24  OCREF MP5991GLUZ-MP5991GLU-Z,SMLF,ICA    I14 @S9S_MB_2U_LIB.S9S_MB_2U(SCH_1):PAGE301
PC2350    1      A Q_CAP_0402-1NF,50V,10%,EMPTY,CA    I29 @S9S_MB_2U_LIB.S9S_MB_2U(SCH_1):PAGE325

HSC_OC_VOL @S9S_MB_2U_LIB.S9S_MB_2U(SCH_1):HSC_OC_VOL
  U344    3    IN+ AP331AWG7-AP331AWG-7,SMLF,EMPTA    I66 @S9S_MB_2U_LIB.S9S_MB_2U(SCH_1):PAGE326
 R4793    1      A Q_RES_0402LF-1M,1%,1/16W,EMPTYA    I68 @S9S_MB_2U_LIB.S9S_MB_2U(SCH_1):PAGE326
 C2389    1      A Q_CAP_C0402-100NF,50V,10%,EMPTA    I76 @S9S_MB_2U_LIB.S9S_MB_2U(SCH_1):PAGE326
 R4796    1      A Q_RES_0402LF-10K,1%,1/16W,EMPTA    I77 @S9S_MB_2U_LIB.S9S_MB_2U(SCH_1):PAGE326
 R4795    2      B Q_RES_0402LF-160K,1%,1/16W,EMPA    I78 @S9S_MB_2U_LIB.S9S_MB_2U(SCH_1):PAGE326

HSC_ON @S9S_MB_2U_LIB.S9S_MB_2U(SCH_1):HSC_ON
PC2183    1      A Q_CAP_0402-220PF,50V,10%,EMPTYA     I2 @S9S_MB_2U_LIB.S9S_MB_2U(SCH_1):PAGE301
 PU297    4     ON MP5991GLUZ-MP5991GLU-Z,SMLF,ICA    I17 @S9S_MB_2U_LIB.S9S_MB_2U(SCH_1):PAGE325
 PU296    4     ON MP5991GLUZ-MP5991GLU-Z,SMLF,ICA    I35 @S9S_MB_2U_LIB.S9S_MB_2U(SCH_1):PAGE325
 PU287    4     ON MP5991GLUZ-MP5991GLU-Z,SMLF,ICA    I35 @S9S_MB_2U_LIB.S9S_MB_2U(SCH_1):PAGE301
 PU288    4     ON MP5991GLUZ-MP5991GLU-Z,SMLF,ICA    I14 @S9S_MB_2U_LIB.S9S_MB_2U(SCH_1):PAGE301
PR3928    1      A Q_RES_0402LF-0,5%,1/16W,CHIP,CA    I41 @S9S_MB_2U_LIB.S9S_MB_2U(SCH_1):PAGE303
PC2224    1      A Q_CAP_0402-220PF,50V,10%,EMPTYA    I23 @S9S_MB_2U_LIB.S9S_MB_2U(SCH_1):PAGE325
PC2182    1      A Q_CAP_0402-220PF,50V,10%,X7R,TA    I23 @S9S_MB_2U_LIB.S9S_MB_2U(SCH_1):PAGE301
PC2225    1      A Q_CAP_0402-220PF,50V,10%,EMPTYA     I2 @S9S_MB_2U_LIB.S9S_MB_2U(SCH_1):PAGE325

HSC_ON_R @S9S_MB_2U_LIB.S9S_MB_2U(SCH_1):HSC_ON_R
 PU289   38     ON MP5990GMA1111Z-MP5990GMA-1111-A    I56 @S9S_MB_2U_LIB.S9S_MB_2U(SCH_1):PAGE303
PR3928    2      B Q_RES_0402LF-0,5%,1/16W,CHIP,CA    I41 @S9S_MB_2U_LIB.S9S_MB_2U(SCH_1):PAGE303

HSC_SCREF @S9S_MB_2U_LIB.S9S_MB_2U(SCH_1):HSC_SCREF
PR3916    1      A Q_RES_0402LF-0,5%,1/16W,CHIP,CA    I33 @S9S_MB_2U_LIB.S9S_MB_2U(SCH_1):PAGE301
PR3989    1      A Q_RES_0402LF-0,5%,1/16W,CHIP,CA    I16 @S9S_MB_2U_LIB.S9S_MB_2U(SCH_1):PAGE325
 PU289   25 SCREF_OCWREF MP5990GMA1111Z-MP5990GMA-1111-A    I56 @S9S_MB_2U_LIB.S9S_MB_2U(SCH_1):PAGE303
PR3917    1      A Q_RES_0402LF-0,5%,1/16W,CHIP,CA    I17 @S9S_MB_2U_LIB.S9S_MB_2U(SCH_1):PAGE301
PR3988    1      A Q_RES_0402LF-0,5%,1/16W,CHIP,CA    I33 @S9S_MB_2U_LIB.S9S_MB_2U(SCH_1):PAGE325

HSC_SCREF_1 @S9S_MB_2U_LIB.S9S_MB_2U(SCH_1):HSC_SCREF_1
PR3916    2      B Q_RES_0402LF-0,5%,1/16W,CHIP,CA    I33 @S9S_MB_2U_LIB.S9S_MB_2U(SCH_1):PAGE301
 PU287   17 SCREF_OCWREF MP5991GLUZ-MP5991GLU-Z,SMLF,ICA    I35 @S9S_MB_2U_LIB.S9S_MB_2U(SCH_1):PAGE301

HSC_SCREF_2 @S9S_MB_2U_LIB.S9S_MB_2U(SCH_1):HSC_SCREF_2
PR3917    2      B Q_RES_0402LF-0,5%,1/16W,CHIP,CA    I17 @S9S_MB_2U_LIB.S9S_MB_2U(SCH_1):PAGE301
 PU288   17 SCREF_OCWREF MP5991GLUZ-MP5991GLU-Z,SMLF,ICA    I14 @S9S_MB_2U_LIB.S9S_MB_2U(SCH_1):PAGE301

HSC_SCREF_3 @S9S_MB_2U_LIB.S9S_MB_2U(SCH_1):HSC_SCREF_3
 PU296   17 SCREF_OCWREF MP5991GLUZ-MP5991GLU-Z,SMLF,ICA    I35 @S9S_MB_2U_LIB.S9S_MB_2U(SCH_1):PAGE325
PR3988    2      B Q_RES_0402LF-0,5%,1/16W,CHIP,CA    I33 @S9S_MB_2U_LIB.S9S_MB_2U(SCH_1):PAGE325

HSC_SCREF_4 @S9S_MB_2U_LIB.S9S_MB_2U(SCH_1):HSC_SCREF_4
PR3989    2      B Q_RES_0402LF-0,5%,1/16W,CHIP,CA    I16 @S9S_MB_2U_LIB.S9S_MB_2U(SCH_1):PAGE325
 PU297   17 SCREF_OCWREF MP5991GLUZ-MP5991GLU-Z,SMLF,ICA    I17 @S9S_MB_2U_LIB.S9S_MB_2U(SCH_1):PAGE325

HSC_SS @S9S_MB_2U_LIB.S9S_MB_2U(SCH_1):HSC_SS
 PU297   19     SS MP5991GLUZ-MP5991GLU-Z,SMLF,ICA    I17 @S9S_MB_2U_LIB.S9S_MB_2U(SCH_1):PAGE325
 PU289   16     SS MP5990GMA1111Z-MP5990GMA-1111-A    I56 @S9S_MB_2U_LIB.S9S_MB_2U(SCH_1):PAGE303
 PU296   19     SS MP5991GLUZ-MP5991GLU-Z,SMLF,ICA    I35 @S9S_MB_2U_LIB.S9S_MB_2U(SCH_1):PAGE325
 PU287   19     SS MP5991GLUZ-MP5991GLU-Z,SMLF,ICA    I35 @S9S_MB_2U_LIB.S9S_MB_2U(SCH_1):PAGE301
PC2227    1      A Q_CAP_0402-0.068UF,16V,10%,X7RA    I38 @S9S_MB_2U_LIB.S9S_MB_2U(SCH_1):PAGE325
 PU288   19     SS MP5991GLUZ-MP5991GLU-Z,SMLF,ICA    I14 @S9S_MB_2U_LIB.S9S_MB_2U(SCH_1):PAGE301
PC2191    1      A Q_CAP_0402-0.068UF,16V,10%,X7RA    I69 @S9S_MB_2U_LIB.S9S_MB_2U(SCH_1):PAGE303
PC2185    1      A Q_CAP_0402-0.068UF,16V,10%,X7RA    I37 @S9S_MB_2U_LIB.S9S_MB_2U(SCH_1):PAGE301
PC2184    1      A Q_CAP_0402-0.068UF,16V,10%,X7RA    I47 @S9S_MB_2U_LIB.S9S_MB_2U(SCH_1):PAGE301
PC2226    1      A Q_CAP_0402-0.068UF,16V,10%,X7RA    I48 @S9S_MB_2U_LIB.S9S_MB_2U(SCH_1):PAGE325

HSC_TYPE_ADC @S9S_MB_2U_LIB.S9S_MB_2U(SCH_1):HSC_TYPE_ADC
 C2363    1      A Q_CAP_0402-0.1UF,25V,10%,EMPTYA    I15 @S9S_MB_2U_LIB.S9S_MB_2U(SCH_1):PAGE240
  PJ42   17     17 SCONN21_9193031121LF-SCONN21_9A    I34 @S9S_MB_2U_LIB.S9S_MB_2U(SCH_1):PAGE327
  U331   11    BUS INA230AIRGTR-INA230AIRGTR,SMLFA    I39 @S9S_MB_2U_LIB.S9S_MB_2U(SCH_1):PAGE240

HSC_TYPE_ADC_A0 @S9S_MB_2U_LIB.S9S_MB_2U(SCH_1):HSC_TYPE_ADC_A0
 R4691    1      A Q_RES_0402LF-0,5%,1/16W,EMPTY,A    I16 @S9S_MB_2U_LIB.S9S_MB_2U(SCH_1):PAGE240
 R4688    2      B Q_RES_0402LF-4.7K,1%,1/16W,EMPA    I18 @S9S_MB_2U_LIB.S9S_MB_2U(SCH_1):PAGE240
  U331    2     A0 INA230AIRGTR-INA230AIRGTR,SMLFA    I39 @S9S_MB_2U_LIB.S9S_MB_2U(SCH_1):PAGE240

HSC_TYPE_ADC_A1 @S9S_MB_2U_LIB.S9S_MB_2U(SCH_1):HSC_TYPE_ADC_A1
 R4687    2      B Q_RES_0402LF-4.7K,1%,1/16W,EMPA    I19 @S9S_MB_2U_LIB.S9S_MB_2U(SCH_1):PAGE240
  U331    1     A1 INA230AIRGTR-INA230AIRGTR,SMLFA    I39 @S9S_MB_2U_LIB.S9S_MB_2U(SCH_1):PAGE240

HSC_VDD @S9S_MB_2U_LIB.S9S_MB_2U(SCH_1):HSC_VDD
PR3980    2      B Q_RES_0402LF-0,5%,1/16W,CHIP,CA    I21 @S9S_MB_2U_LIB.S9S_MB_2U(SCH_1):PAGE325
PR3911    2      B Q_RES_0402LF-0,5%,1/16W,CHIP,CA     I5 @S9S_MB_2U_LIB.S9S_MB_2U(SCH_1):PAGE301
PR3910    2      B Q_RES_0402LF-0,5%,1/16W,CHIP,CA    I21 @S9S_MB_2U_LIB.S9S_MB_2U(SCH_1):PAGE301
 R3936    1      A Q_RES_0402LF-4.7K,1%,1/16W,CHIA    I85 @S9S_MB_2U_LIB.S9S_MB_2U(SCH_1):PAGE303
PR2149    2      B Q_RES_0402LF-0,5%,1/16W,CHIP,CA    I24 @S9S_MB_2U_LIB.S9S_MB_2U(SCH_1):PAGE303
PR2106    1      A Q_RES_0402LF-10K,1%,1/16W,CHIPA    I43 @S9S_MB_2U_LIB.S9S_MB_2U(SCH_1):PAGE303
 R2587    1      A Q_RES_0402LF-4.7K,1%,1/16W,CHIA    I93 @S9S_MB_2U_LIB.S9S_MB_2U(SCH_1):PAGE303
PR3981    2      B Q_RES_0402LF-0,5%,1/16W,CHIP,CA     I5 @S9S_MB_2U_LIB.S9S_MB_2U(SCH_1):PAGE325

HSC_VDD18 @S9S_MB_2U_LIB.S9S_MB_2U(SCH_1):HSC_VDD18
 PU289   19  VDD18 MP5990GMA1111Z-MP5990GMA-1111-A    I56 @S9S_MB_2U_LIB.S9S_MB_2U(SCH_1):PAGE303
PC2103    1      A Q_CAP_C0402-1UF,25V,10%,X6S,CHA    I35 @S9S_MB_2U_LIB.S9S_MB_2U(SCH_1):PAGE303
PR3929    2      B Q_RES_0402LF-1K,1%,1/16W,EMPTYA    I42 @S9S_MB_2U_LIB.S9S_MB_2U(SCH_1):PAGE303

HSC_VDD_R @S9S_MB_2U_LIB.S9S_MB_2U(SCH_1):HSC_VDD_R
 PU289   17 VDD33_1 MP5990GMA1111Z-MP5990GMA-1111-A    I56 @S9S_MB_2U_LIB.S9S_MB_2U(SCH_1):PAGE303
 PU289   45 VDD33_2 MP5990GMA1111Z-MP5990GMA-1111-A    I56 @S9S_MB_2U_LIB.S9S_MB_2U(SCH_1):PAGE303
PR2149    1      A Q_RES_0402LF-0,5%,1/16W,CHIP,CA    I24 @S9S_MB_2U_LIB.S9S_MB_2U(SCH_1):PAGE303
PC2186    1      A Q_CAP_C0402-1UF,25V,10%,X6S,CHA    I14 @S9S_MB_2U_LIB.S9S_MB_2U(SCH_1):PAGE303
PC2187    1      A Q_CAP_C0402-1UF,25V,10%,X6S,CHA    I23 @S9S_MB_2U_LIB.S9S_MB_2U(SCH_1):PAGE303

HSC_VDD_R_1 @S9S_MB_2U_LIB.S9S_MB_2U(SCH_1):HSC_VDD_R_1
PC1525    1      A Q_CAP_C0402-1UF,25V,10%,X6S,CHA    I20 @S9S_MB_2U_LIB.S9S_MB_2U(SCH_1):PAGE301
PR3910    1      A Q_RES_0402LF-0,5%,1/16W,CHIP,CA    I21 @S9S_MB_2U_LIB.S9S_MB_2U(SCH_1):PAGE301
 PU287   21  VDD33 MP5991GLUZ-MP5991GLU-Z,SMLF,ICA    I35 @S9S_MB_2U_LIB.S9S_MB_2U(SCH_1):PAGE301

HSC_VDD_R_2 @S9S_MB_2U_LIB.S9S_MB_2U(SCH_1):HSC_VDD_R_2
PC2181    1      A Q_CAP_C0402-1UF,25V,10%,X6S,CHA     I4 @S9S_MB_2U_LIB.S9S_MB_2U(SCH_1):PAGE301
PR3911    1      A Q_RES_0402LF-0,5%,1/16W,CHIP,CA     I5 @S9S_MB_2U_LIB.S9S_MB_2U(SCH_1):PAGE301
 PU288   21  VDD33 MP5991GLUZ-MP5991GLU-Z,SMLF,ICA    I14 @S9S_MB_2U_LIB.S9S_MB_2U(SCH_1):PAGE301

HSC_VDD_R_3 @S9S_MB_2U_LIB.S9S_MB_2U(SCH_1):HSC_VDD_R_3
PR3980    1      A Q_RES_0402LF-0,5%,1/16W,CHIP,CA    I21 @S9S_MB_2U_LIB.S9S_MB_2U(SCH_1):PAGE325
 PU296   21  VDD33 MP5991GLUZ-MP5991GLU-Z,SMLF,ICA    I35 @S9S_MB_2U_LIB.S9S_MB_2U(SCH_1):PAGE325
PC3272    1      A Q_CAP_C0402-1UF,25V,10%,X6S,CHA    I19 @S9S_MB_2U_LIB.S9S_MB_2U(SCH_1):PAGE325

HSC_VDD_R_4 @S9S_MB_2U_LIB.S9S_MB_2U(SCH_1):HSC_VDD_R_4
 PU297   21  VDD33 MP5991GLUZ-MP5991GLU-Z,SMLF,ICA    I17 @S9S_MB_2U_LIB.S9S_MB_2U(SCH_1):PAGE325
PC2223    1      A Q_CAP_C0402-1UF,25V,10%,X6S,CHA     I4 @S9S_MB_2U_LIB.S9S_MB_2U(SCH_1):PAGE325
PR3981    1      A Q_RES_0402LF-0,5%,1/16W,CHIP,CA     I5 @S9S_MB_2U_LIB.S9S_MB_2U(SCH_1):PAGE325

HSC_VIN_UVW_N @S9S_MB_2U_LIB.S9S_MB_2U(SCH_1):HSC_VIN_UVW_N
 PU289   14 VIN_UVW# MP5990GMA1111Z-MP5990GMA-1111-A    I56 @S9S_MB_2U_LIB.S9S_MB_2U(SCH_1):PAGE303
PR2106    2      B Q_RES_0402LF-10K,1%,1/16W,CHIPA    I43 @S9S_MB_2U_LIB.S9S_MB_2U(SCH_1):PAGE303

HSC_VOSEN @S9S_MB_2U_LIB.S9S_MB_2U(SCH_1):HSC_VOSEN
 PU289   24  VOSEN MP5990GMA1111Z-MP5990GMA-1111-A    I56 @S9S_MB_2U_LIB.S9S_MB_2U(SCH_1):PAGE303
PR3932    1      A Q_RES_0402LF-4.99K,0.1%,1/16W,A    I59 @S9S_MB_2U_LIB.S9S_MB_2U(SCH_1):PAGE303
PR3931    2      B Q_RES_0402LF-75K,0.1%,1/16W,CHA    I86 @S9S_MB_2U_LIB.S9S_MB_2U(SCH_1):PAGE303
PC2190    1      A Q_CAP_C0402-0.01UF,50V,10%,X7RA    I75 @S9S_MB_2U_LIB.S9S_MB_2U(SCH_1):PAGE303

HSC_VSENSE @S9S_MB_2U_LIB.S9S_MB_2U(SCH_1):HSC_VSENSE
PR3926    2      B Q_RES_0402LF-75K,0.1%,1/16W,CHA    I52 @S9S_MB_2U_LIB.S9S_MB_2U(SCH_1):PAGE303
 PU289    9 VINSEN MP5990GMA1111Z-MP5990GMA-1111-A    I56 @S9S_MB_2U_LIB.S9S_MB_2U(SCH_1):PAGE303
PR3927    1      A Q_RES_0402LF-4.99K,0.1%,1/16W,A    I40 @S9S_MB_2U_LIB.S9S_MB_2U(SCH_1):PAGE303
PC2189    1      A Q_CAP_C0402-0.01UF,50V,10%,X7RA    I45 @S9S_MB_2U_LIB.S9S_MB_2U(SCH_1):PAGE303

HSC_VTEMP @S9S_MB_2U_LIB.S9S_MB_2U(SCH_1):HSC_VTEMP
 PU297   18  VTEMP MP5991GLUZ-MP5991GLU-Z,SMLF,ICA    I17 @S9S_MB_2U_LIB.S9S_MB_2U(SCH_1):PAGE325
 PU289   15  VTEMP MP5990GMA1111Z-MP5990GMA-1111-A    I56 @S9S_MB_2U_LIB.S9S_MB_2U(SCH_1):PAGE303
 PU296   18  VTEMP MP5991GLUZ-MP5991GLU-Z,SMLF,ICA    I35 @S9S_MB_2U_LIB.S9S_MB_2U(SCH_1):PAGE325
 PU287   18  VTEMP MP5991GLUZ-MP5991GLU-Z,SMLF,ICA    I35 @S9S_MB_2U_LIB.S9S_MB_2U(SCH_1):PAGE301
 PU288   18  VTEMP MP5991GLUZ-MP5991GLU-Z,SMLF,ICA    I14 @S9S_MB_2U_LIB.S9S_MB_2U(SCH_1):PAGE301
PC2192    1      A Q_CAP_C0402-0.001UF,50V,10%,X7A    I77 @S9S_MB_2U_LIB.S9S_MB_2U(SCH_1):PAGE303
PR3935    1      A Q_RES_0402LF-10K,1%,1/16W,CHIPA    I79 @S9S_MB_2U_LIB.S9S_MB_2U(SCH_1):PAGE303

H_CPU0_BMCINIT_LVC1 @S9S_MB_2U_LIB.S9S_MB_2U(SCH_1):H_CPU0_BMCINIT_LVC1
    U2 BN23 BMCINIT SOCKET4677_AZIF0045P001C01CS-SA    I57 @S9S_MB_2U_LIB.S9S_MB_2U(SCH_1):PAGE13
  R278    2      B Q_RES_0402LF-240,1%,1/16W,EMPTA    I61 @S9S_MB_2U_LIB.S9S_MB_2U(SCH_1):PAGE119

H_CPU0_CATERR_LVC1_R_N @S9S_MB_2U_LIB.S9S_MB_2U(SCH_1):H_CPU0_CATERR_LVC1_R_N
    U2 BP24 CATERR_N SOCKET4677_AZIF0045P001C01CS-SA     I1 @S9S_MB_2U_LIB.S9S_MB_2U(SCH_1):PAGE14
  R297    1      A Q_RES_0402LF-0,5%,1/16W,CHIP,CA    I23 @S9S_MB_2U_LIB.S9S_MB_2U(SCH_1):PAGE118

H_CPU0_ERR0_LVC1_R_N @S9S_MB_2U_LIB.S9S_MB_2U(SCH_1):H_CPU0_ERR0_LVC1_R_N
    U2 BF22 ERROR_N0 SOCKET4677_AZIF0045P001C01CS-SA     I1 @S9S_MB_2U_LIB.S9S_MB_2U(SCH_1):PAGE14
  R336    1      A Q_RES_0402LF-0,5%,1/16W,CHIP,CA   I159 @S9S_MB_2U_LIB.S9S_MB_2U(SCH_1):PAGE322

H_CPU0_ERR1_LVC1_R_N @S9S_MB_2U_LIB.S9S_MB_2U(SCH_1):H_CPU0_ERR1_LVC1_R_N
    U2 AY22 ERROR_N1 SOCKET4677_AZIF0045P001C01CS-SA     I1 @S9S_MB_2U_LIB.S9S_MB_2U(SCH_1):PAGE14
  R340    1      A Q_RES_0402LF-0,5%,1/16W,CHIP,CA   I164 @S9S_MB_2U_LIB.S9S_MB_2U(SCH_1):PAGE322

H_CPU0_ERR2_LVC1_R_N @S9S_MB_2U_LIB.S9S_MB_2U(SCH_1):H_CPU0_ERR2_LVC1_R_N
    U2 BD22 ERROR_N2 SOCKET4677_AZIF0045P001C01CS-SA     I1 @S9S_MB_2U_LIB.S9S_MB_2U(SCH_1):PAGE14
  R344    1      A Q_RES_0402LF-0,5%,1/16W,CHIP,CA   I157 @S9S_MB_2U_LIB.S9S_MB_2U(SCH_1):PAGE322

H_CPU0_MEMHOT_IN_LVC1_N @S9S_MB_2U_LIB.S9S_MB_2U(SCH_1):H_CPU0_MEMHOT_IN_LVC1_N
    U2 AU21 MEMHOT_IN_N SOCKET4677_AZIF0045P001C01CS-SA     I1 @S9S_MB_2U_LIB.S9S_MB_2U(SCH_1):PAGE14
 R4293    2      B Q_RES_0402LF-100,1%,1/16W,CHIPA    I34 @S9S_MB_2U_LIB.S9S_MB_2U(SCH_1):PAGE122

H_CPU0_MEMHOT_IN_LVC1_R1_N @S9S_MB_2U_LIB.S9S_MB_2U(SCH_1):H_CPU0_MEMHOT_IN_LVC1_R1_N
  R208    2      B Q_RES_0402LF-0,5%,1/16W,CHIP,CA    I16 @S9S_MB_2U_LIB.S9S_MB_2U(SCH_1):PAGE122
 R4293    1      A Q_RES_0402LF-100,1%,1/16W,CHIPA    I34 @S9S_MB_2U_LIB.S9S_MB_2U(SCH_1):PAGE122
  R219    2      B Q_RES_0402LF-100,1%,1/16W,CHIPA    I37 @S9S_MB_2U_LIB.S9S_MB_2U(SCH_1):PAGE122

H_CPU0_MEMHOT_IN_LVC1_R_N @S9S_MB_2U_LIB.S9S_MB_2U(SCH_1):H_CPU0_MEMHOT_IN_LVC1_R_N
  U249   T7  PL30D LCMXO3LF9400C5BG484C-LCMXO3LF-A    I33 @S9S_MB_2U_LIB.S9S_MB_2U(SCH_1):PAGE311
  R208    1      A Q_RES_0402LF-0,5%,1/16W,CHIP,CA    I16 @S9S_MB_2U_LIB.S9S_MB_2U(SCH_1):PAGE122

H_CPU0_MEMHOT_OUT @S9S_MB_2U_LIB.S9S_MB_2U(SCH_1):H_CPU0_MEMHOT_OUT
  Q143    3     C2 BC847BPN-BC847BPN,SMLF,IC,BA00A    I12 @S9S_MB_2U_LIB.S9S_MB_2U(SCH_1):PAGE122
 R4403    1      A Q_RES_0402LF-1.5K,1%,1/16W,CHIA    I21 @S9S_MB_2U_LIB.S9S_MB_2U(SCH_1):PAGE122

H_CPU0_MEMHOT_OUT_LVC1_N @S9S_MB_2U_LIB.S9S_MB_2U(SCH_1):H_CPU0_MEMHOT_OUT_LVC1_N
  U249   T3  PL26A LCMXO3LF9400C5BG484C-LCMXO3LF-A    I33 @S9S_MB_2U_LIB.S9S_MB_2U(SCH_1):PAGE311
 R4407    2      B Q_RES_0402LF-33.2,1%,1/16W,CHIA    I31 @S9S_MB_2U_LIB.S9S_MB_2U(SCH_1):PAGE122

H_CPU0_MEMHOT_OUT_LVC1_R_N @S9S_MB_2U_LIB.S9S_MB_2U(SCH_1):H_CPU0_MEMHOT_OUT_LVC1_R_N
    U2 CF26 MEMHOT_OUT_N SOCKET4677_AZIF0045P001C01CS-SA     I1 @S9S_MB_2U_LIB.S9S_MB_2U(SCH_1):PAGE14
 R4401    2      B Q_RES_0402LF-100,1%,1/16W,CHIPA     I8 @S9S_MB_2U_LIB.S9S_MB_2U(SCH_1):PAGE122
  R203    1      A Q_RES_0402LF-1.5K,1%,1/16W,CHIA     I9 @S9S_MB_2U_LIB.S9S_MB_2U(SCH_1):PAGE122

H_CPU0_MEMHOT_OUT_R @S9S_MB_2U_LIB.S9S_MB_2U(SCH_1):H_CPU0_MEMHOT_OUT_R
 R4403    2      B Q_RES_0402LF-1.5K,1%,1/16W,CHIA    I21 @S9S_MB_2U_LIB.S9S_MB_2U(SCH_1):PAGE122
  Q143    2     B1 BC847BPN-BC847BPN,SMLF,IC,BA00A    I22 @S9S_MB_2U_LIB.S9S_MB_2U(SCH_1):PAGE122

H_CPU0_MEMHOT_OUT_VT_N @S9S_MB_2U_LIB.S9S_MB_2U(SCH_1):H_CPU0_MEMHOT_OUT_VT_N
  Q143    6     C1 BC847BPN-BC847BPN,SMLF,IC,BA00A    I22 @S9S_MB_2U_LIB.S9S_MB_2U(SCH_1):PAGE122
 R4405    2      B Q_RES_0402LF-4.75K,1%,1/16W,CHA    I27 @S9S_MB_2U_LIB.S9S_MB_2U(SCH_1):PAGE122
 R4407    1      A Q_RES_0402LF-33.2,1%,1/16W,CHIA    I31 @S9S_MB_2U_LIB.S9S_MB_2U(SCH_1):PAGE122

H_CPU0_MEMHOT_OUT_VT_R_N @S9S_MB_2U_LIB.S9S_MB_2U(SCH_1):H_CPU0_MEMHOT_OUT_VT_R_N
  R203    2      B Q_RES_0402LF-1.5K,1%,1/16W,CHIA     I9 @S9S_MB_2U_LIB.S9S_MB_2U(SCH_1):PAGE122
  Q143    5     B2 BC847BPN-BC847BPN,SMLF,IC,BA00A    I12 @S9S_MB_2U_LIB.S9S_MB_2U(SCH_1):PAGE122

H_CPU0_MEMTRIP @S9S_MB_2U_LIB.S9S_MB_2U(SCH_1):H_CPU0_MEMTRIP
  Q141    3     C2 BC847BPN-BC847BPN,SMLF,IC,BA00A    I12 @S9S_MB_2U_LIB.S9S_MB_2U(SCH_1):PAGE123
 R4409    1      A Q_RES_0402LF-1.5K,1%,1/16W,CHIA    I15 @S9S_MB_2U_LIB.S9S_MB_2U(SCH_1):PAGE123

H_CPU0_MEMTRIP_LVC1_N @S9S_MB_2U_LIB.S9S_MB_2U(SCH_1):H_CPU0_MEMTRIP_LVC1_N
  U249   R6  PL25C LCMXO3LF9400C5BG484C-LCMXO3LF-A    I33 @S9S_MB_2U_LIB.S9S_MB_2U(SCH_1):PAGE311
 R4413    2      B Q_RES_0402LF-33.2,1%,1/16W,CHIA    I33 @S9S_MB_2U_LIB.S9S_MB_2U(SCH_1):PAGE123

H_CPU0_MEMTRIP_LVC1_R_N @S9S_MB_2U_LIB.S9S_MB_2U(SCH_1):H_CPU0_MEMTRIP_LVC1_R_N
    U2 AV24 MEMTRIP_N SOCKET4677_AZIF0045P001C01CS-SA     I1 @S9S_MB_2U_LIB.S9S_MB_2U(SCH_1):PAGE14
  R205    1      A Q_RES_0402LF-1.5K,1%,1/16W,CHIA    I10 @S9S_MB_2U_LIB.S9S_MB_2U(SCH_1):PAGE123
  R200    2      B Q_RES_0402LF-100,1%,1/16W,CHIPA    I19 @S9S_MB_2U_LIB.S9S_MB_2U(SCH_1):PAGE123

H_CPU0_MEMTRIP_OUT_VT_R_N @S9S_MB_2U_LIB.S9S_MB_2U(SCH_1):H_CPU0_MEMTRIP_OUT_VT_R_N
  R205    2      B Q_RES_0402LF-1.5K,1%,1/16W,CHIA    I10 @S9S_MB_2U_LIB.S9S_MB_2U(SCH_1):PAGE123
  Q141    5     B2 BC847BPN-BC847BPN,SMLF,IC,BA00A    I12 @S9S_MB_2U_LIB.S9S_MB_2U(SCH_1):PAGE123

H_CPU0_MEMTRIP_R @S9S_MB_2U_LIB.S9S_MB_2U(SCH_1):H_CPU0_MEMTRIP_R
 R4409    2      B Q_RES_0402LF-1.5K,1%,1/16W,CHIA    I15 @S9S_MB_2U_LIB.S9S_MB_2U(SCH_1):PAGE123
  Q141    2     B1 BC847BPN-BC847BPN,SMLF,IC,BA00A    I18 @S9S_MB_2U_LIB.S9S_MB_2U(SCH_1):PAGE123

H_CPU0_MEMTRIP_VT_N @S9S_MB_2U_LIB.S9S_MB_2U(SCH_1):H_CPU0_MEMTRIP_VT_N
  Q141    6     C1 BC847BPN-BC847BPN,SMLF,IC,BA00A    I18 @S9S_MB_2U_LIB.S9S_MB_2U(SCH_1):PAGE123
 R4411    2      B Q_RES_0402LF-4.75K,1%,1/16W,CHA    I32 @S9S_MB_2U_LIB.S9S_MB_2U(SCH_1):PAGE123
 R4413    1      A Q_RES_0402LF-33.2,1%,1/16W,CHIA    I33 @S9S_MB_2U_LIB.S9S_MB_2U(SCH_1):PAGE123

H_CPU0_NMI_LVC1_N @S9S_MB_2U_LIB.S9S_MB_2U(SCH_1):H_CPU0_NMI_LVC1_N
    U2 AV18    NMI SOCKET4677_AZIF0045P001C01CS-SA     I1 @S9S_MB_2U_LIB.S9S_MB_2U(SCH_1):PAGE14
  R195    2      B Q_RES_0402LF-49.9,1%,1/16W,CHIA     I6 @S9S_MB_2U_LIB.S9S_MB_2U(SCH_1):PAGE123
  R197    2      B Q_RES_0402LF-301,1%,1/16W,CHIPA    I27 @S9S_MB_2U_LIB.S9S_MB_2U(SCH_1):PAGE123

H_CPU0_PMDOWN_CPU1 @S9S_MB_2U_LIB.S9S_MB_2U(SCH_1):H_CPU0_PMDOWN_CPU1
   R11    2      B Q_RES_0402LF-33.2,1%,1/16W,CHIA    I79 @S9S_MB_2U_LIB.S9S_MB_2U(SCH_1):PAGE14
    U1 CN25 PMSYNC0 SOCKET4677_AZIF0045P001C01CS-SA    I29 @S9S_MB_2U_LIB.S9S_MB_2U(SCH_1):PAGE45

H_CPU0_PMDOWN_CPU1_R @S9S_MB_2U_LIB.S9S_MB_2U(SCH_1):H_CPU0_PMDOWN_CPU1_R
    U2 CW39 PMDOWN0 SOCKET4677_AZIF0045P001C01CS-SA     I1 @S9S_MB_2U_LIB.S9S_MB_2U(SCH_1):PAGE14
 R2362    1      A Q_RES_0402LF-33.2,1%,1/16W,CHIA   I122 @S9S_MB_2U_LIB.S9S_MB_2U(SCH_1):PAGE14

H_CPU0_PMDOWN_CPU1_R1 @S9S_MB_2U_LIB.S9S_MB_2U(SCH_1):H_CPU0_PMDOWN_CPU1_R1
   R11    1      A Q_RES_0402LF-33.2,1%,1/16W,CHIA    I79 @S9S_MB_2U_LIB.S9S_MB_2U(SCH_1):PAGE14
 R2362    2      B Q_RES_0402LF-33.2,1%,1/16W,CHIA   I122 @S9S_MB_2U_LIB.S9S_MB_2U(SCH_1):PAGE14

H_CPU0_PMDOWN_PCH @S9S_MB_2U_LIB.S9S_MB_2U(SCH_1):H_CPU0_PMDOWN_PCH
    R7    2      B Q_RES_0402LF-33.2,1%,1/16W,CHIA    I66 @S9S_MB_2U_LIB.S9S_MB_2U(SCH_1):PAGE14
    U4  AE7 GPP_L_1_PM_DOWN_0 EMMITSBURG_REV0P9-GFNOCPU04302A    I22 @S9S_MB_2U_LIB.S9S_MB_2U(SCH_1):PAGE176

H_CPU0_PMDOWN_PCH_R @S9S_MB_2U_LIB.S9S_MB_2U(SCH_1):H_CPU0_PMDOWN_PCH_R
    R7    1      A Q_RES_0402LF-33.2,1%,1/16W,CHIA    I66 @S9S_MB_2U_LIB.S9S_MB_2U(SCH_1):PAGE14
 R1959    2      B Q_RES_0402LF-0,5%,1/16W,CHIP,CA   I115 @S9S_MB_2U_LIB.S9S_MB_2U(SCH_1):PAGE14

H_CPU0_PMDOWN_PCH_R2 @S9S_MB_2U_LIB.S9S_MB_2U(SCH_1):H_CPU0_PMDOWN_PCH_R2
    U2 CY40 PMDOWN_PCH SOCKET4677_AZIF0045P001C01CS-SA     I1 @S9S_MB_2U_LIB.S9S_MB_2U(SCH_1):PAGE14
 R1959    1      A Q_RES_0402LF-0,5%,1/16W,CHIP,CA   I115 @S9S_MB_2U_LIB.S9S_MB_2U(SCH_1):PAGE14

H_CPU0_PMSYNC_CPU1 @S9S_MB_2U_LIB.S9S_MB_2U(SCH_1):H_CPU0_PMSYNC_CPU1
    U1 CW39 PMDOWN0 SOCKET4677_AZIF0045P001C01CS-SA    I29 @S9S_MB_2U_LIB.S9S_MB_2U(SCH_1):PAGE45
 R4089    2      B Q_RES_0402LF-33.2,1%,1/16W,CHIA   I128 @S9S_MB_2U_LIB.S9S_MB_2U(SCH_1):PAGE14

H_CPU0_PMSYNC_CPU1_R @S9S_MB_2U_LIB.S9S_MB_2U(SCH_1):H_CPU0_PMSYNC_CPU1_R
    U2 CN25 PMSYNC0 SOCKET4677_AZIF0045P001C01CS-SA     I1 @S9S_MB_2U_LIB.S9S_MB_2U(SCH_1):PAGE14
  R322    1      A Q_RES_0402LF-33.2,1%,1/16W,CHIA    I90 @S9S_MB_2U_LIB.S9S_MB_2U(SCH_1):PAGE14

H_CPU0_PMSYNC_CPU1_R1 @S9S_MB_2U_LIB.S9S_MB_2U(SCH_1):H_CPU0_PMSYNC_CPU1_R1
  R322    2      B Q_RES_0402LF-33.2,1%,1/16W,CHIA    I90 @S9S_MB_2U_LIB.S9S_MB_2U(SCH_1):PAGE14
 R4089    1      A Q_RES_0402LF-33.2,1%,1/16W,CHIA   I128 @S9S_MB_2U_LIB.S9S_MB_2U(SCH_1):PAGE14

H_CPU0_PMSYNC_PCH @S9S_MB_2U_LIB.S9S_MB_2U(SCH_1):H_CPU0_PMSYNC_PCH
    U2 DA39 PMSYNC_PCH SOCKET4677_AZIF0045P001C01CS-SA     I1 @S9S_MB_2U_LIB.S9S_MB_2U(SCH_1):PAGE14
   R10    2      B Q_RES_0402LF-33.2,1%,1/16W,CHIA    I78 @S9S_MB_2U_LIB.S9S_MB_2U(SCH_1):PAGE14

H_CPU0_PMSYNC_PCH_R @S9S_MB_2U_LIB.S9S_MB_2U(SCH_1):H_CPU0_PMSYNC_PCH_R
   R10    1      A Q_RES_0402LF-33.2,1%,1/16W,CHIA    I78 @S9S_MB_2U_LIB.S9S_MB_2U(SCH_1):PAGE14
 R1960    2      B Q_RES_0402LF-0,5%,1/16W,CHIP,CA   I117 @S9S_MB_2U_LIB.S9S_MB_2U(SCH_1):PAGE14

H_CPU0_PMSYNC_PCH_R2 @S9S_MB_2U_LIB.S9S_MB_2U(SCH_1):H_CPU0_PMSYNC_PCH_R2
 R1960    1      A Q_RES_0402LF-0,5%,1/16W,CHIP,CA   I117 @S9S_MB_2U_LIB.S9S_MB_2U(SCH_1):PAGE14
    U4  AF8 GPP_L_0_PM_SYNC_0 EMMITSBURG_REV0P9-GFNOCPU04302A    I22 @S9S_MB_2U_LIB.S9S_MB_2U(SCH_1):PAGE176

H_CPU0_PM_FAST_WAKE_N @S9S_MB_2U_LIB.S9S_MB_2U(SCH_1):H_CPU0_PM_FAST_WAKE_N
    U2 CP20 PMFAST_WAKE_N SOCKET4677_AZIF0045P001C01CS-SA     I1 @S9S_MB_2U_LIB.S9S_MB_2U(SCH_1):PAGE14
 R1240    1      A Q_RES_0402LF-0,5%,1/16W,CHIP,CA     I9 @S9S_MB_2U_LIB.S9S_MB_2U(SCH_1):PAGE117

H_CPU0_PRDY_QS_GTL_R_N @S9S_MB_2U_LIB.S9S_MB_2U(SCH_1):H_CPU0_PRDY_QS_GTL_R_N
    R1    2      B Q_RES_0402LF-10,1%,1/16W,CHIP,A    I18 @S9S_MB_2U_LIB.S9S_MB_2U(SCH_1):PAGE13
    U2 BP26 PRDY_N SOCKET4677_AZIF0045P001C01CS-SA    I57 @S9S_MB_2U_LIB.S9S_MB_2U(SCH_1):PAGE13

H_CPU0_PREQ_QS_GTL_R_N @S9S_MB_2U_LIB.S9S_MB_2U(SCH_1):H_CPU0_PREQ_QS_GTL_R_N
    R2    2      B Q_RES_0402LF-100,1%,1/16W,CHIPA    I16 @S9S_MB_2U_LIB.S9S_MB_2U(SCH_1):PAGE13
    U2 AV22 PREQ_N SOCKET4677_AZIF0045P001C01CS-SA    I57 @S9S_MB_2U_LIB.S9S_MB_2U(SCH_1):PAGE13

H_CPU0_PROCHOT_LVC1_N @S9S_MB_2U_LIB.S9S_MB_2U(SCH_1):H_CPU0_PROCHOT_LVC1_N
    U2 AU19 PROCHOT_N SOCKET4677_AZIF0045P001C01CS-SA     I1 @S9S_MB_2U_LIB.S9S_MB_2U(SCH_1):PAGE14
  R239    2      B Q_RES_0402LF-0,5%,1/16W,CHIP,CA     I7 @S9S_MB_2U_LIB.S9S_MB_2U(SCH_1):PAGE121
  R243    2      B Q_RES_0402LF-100,1%,1/16W,CHIPA    I23 @S9S_MB_2U_LIB.S9S_MB_2U(SCH_1):PAGE121

H_CPU0_PROCHOT_LVC1_R_N @S9S_MB_2U_LIB.S9S_MB_2U(SCH_1):H_CPU0_PROCHOT_LVC1_R_N
  U249   W4  PL30B LCMXO3LF9400C5BG484C-LCMXO3LF-A    I33 @S9S_MB_2U_LIB.S9S_MB_2U(SCH_1):PAGE311
  R239    1      A Q_RES_0402LF-0,5%,1/16W,CHIP,CA     I7 @S9S_MB_2U_LIB.S9S_MB_2U(SCH_1):PAGE121

H_CPU0_RMCA_LVC1_R_N @S9S_MB_2U_LIB.S9S_MB_2U(SCH_1):H_CPU0_RMCA_LVC1_R_N
    U2 BH22 RMCA_N SOCKET4677_AZIF0045P001C01CS-SA     I1 @S9S_MB_2U_LIB.S9S_MB_2U(SCH_1):PAGE16
  R302    1      A Q_RES_0402LF-0,5%,1/16W,CHIP,CA   I101 @S9S_MB_2U_LIB.S9S_MB_2U(SCH_1):PAGE118

H_CPU0_THERMTRIP_LVC1_N @S9S_MB_2U_LIB.S9S_MB_2U(SCH_1):H_CPU0_THERMTRIP_LVC1_N
  U249   T2  PL25A LCMXO3LF9400C5BG484C-LCMXO3LF-A    I33 @S9S_MB_2U_LIB.S9S_MB_2U(SCH_1):PAGE311
 R4399    2      B Q_RES_0402LF-33.2,1%,1/16W,CHIA    I35 @S9S_MB_2U_LIB.S9S_MB_2U(SCH_1):PAGE121

H_CPU0_THERMTRIP_LVC1_R_N @S9S_MB_2U_LIB.S9S_MB_2U(SCH_1):H_CPU0_THERMTRIP_LVC1_R_N
    U2 BL62 THERMTRIP_N SOCKET4677_AZIF0045P001C01CS-SA     I1 @S9S_MB_2U_LIB.S9S_MB_2U(SCH_1):PAGE14
 R4395    2      B Q_RES_0402LF-100,1%,1/16W,CHIPA    I13 @S9S_MB_2U_LIB.S9S_MB_2U(SCH_1):PAGE121
  R237    1      A Q_RES_0402LF-1.5K,1%,1/16W,CHIA    I15 @S9S_MB_2U_LIB.S9S_MB_2U(SCH_1):PAGE121

H_CPU0_THERMTRIP_N @S9S_MB_2U_LIB.S9S_MB_2U(SCH_1):H_CPU0_THERMTRIP_N
 R4397    1      A Q_RES_0402LF-1.5K,1%,1/16W,CHIA    I16 @S9S_MB_2U_LIB.S9S_MB_2U(SCH_1):PAGE121
  Q138    3     C2 BC847BPN-BC847BPN,SMLF,IC,BA00A    I17 @S9S_MB_2U_LIB.S9S_MB_2U(SCH_1):PAGE121

H_CPU0_THERMTRIP_R_N @S9S_MB_2U_LIB.S9S_MB_2U(SCH_1):H_CPU0_THERMTRIP_R_N
 R4397    2      B Q_RES_0402LF-1.5K,1%,1/16W,CHIA    I16 @S9S_MB_2U_LIB.S9S_MB_2U(SCH_1):PAGE121
  Q138    2     B1 BC847BPN-BC847BPN,SMLF,IC,BA00A    I31 @S9S_MB_2U_LIB.S9S_MB_2U(SCH_1):PAGE121

H_CPU0_THERMTRIP_VT_N @S9S_MB_2U_LIB.S9S_MB_2U(SCH_1):H_CPU0_THERMTRIP_VT_N
  Q138    6     C1 BC847BPN-BC847BPN,SMLF,IC,BA00A    I31 @S9S_MB_2U_LIB.S9S_MB_2U(SCH_1):PAGE121
  R241    2      B Q_RES_0402LF-4.75K,1%,1/16W,CHA    I33 @S9S_MB_2U_LIB.S9S_MB_2U(SCH_1):PAGE121
 R4399    1      A Q_RES_0402LF-33.2,1%,1/16W,CHIA    I35 @S9S_MB_2U_LIB.S9S_MB_2U(SCH_1):PAGE121

H_CPU0_THERMTRIP_VT_R_N @S9S_MB_2U_LIB.S9S_MB_2U(SCH_1):H_CPU0_THERMTRIP_VT_R_N
  R237    2      B Q_RES_0402LF-1.5K,1%,1/16W,CHIA    I15 @S9S_MB_2U_LIB.S9S_MB_2U(SCH_1):PAGE121
  Q138    5     B2 BC847BPN-BC847BPN,SMLF,IC,BA00A    I17 @S9S_MB_2U_LIB.S9S_MB_2U(SCH_1):PAGE121

H_CPU1_BMCINIT_LVC1 @S9S_MB_2U_LIB.S9S_MB_2U(SCH_1):H_CPU1_BMCINIT_LVC1
    U1 BN23 BMCINIT SOCKET4677_AZIF0045P001C01CS-SA    I51 @S9S_MB_2U_LIB.S9S_MB_2U(SCH_1):PAGE44
  R264    2      B Q_RES_0402LF-240,1%,1/16W,EMPTA    I98 @S9S_MB_2U_LIB.S9S_MB_2U(SCH_1):PAGE119

H_CPU1_CATERR_LVC1_R_N @S9S_MB_2U_LIB.S9S_MB_2U(SCH_1):H_CPU1_CATERR_LVC1_R_N
    U1 BP24 CATERR_N SOCKET4677_AZIF0045P001C01CS-SA    I29 @S9S_MB_2U_LIB.S9S_MB_2U(SCH_1):PAGE45
  R299    1      A Q_RES_0402LF-0,5%,1/16W,CHIP,CA    I63 @S9S_MB_2U_LIB.S9S_MB_2U(SCH_1):PAGE118

H_CPU1_ERR0_LVC1_R_N @S9S_MB_2U_LIB.S9S_MB_2U(SCH_1):H_CPU1_ERR0_LVC1_R_N
    U1 BF22 ERROR_N0 SOCKET4677_AZIF0045P001C01CS-SA    I29 @S9S_MB_2U_LIB.S9S_MB_2U(SCH_1):PAGE45
  R337    1      A Q_RES_0402LF-0,5%,1/16W,CHIP,CA   I160 @S9S_MB_2U_LIB.S9S_MB_2U(SCH_1):PAGE322

H_CPU1_ERR1_LVC1_R_N @S9S_MB_2U_LIB.S9S_MB_2U(SCH_1):H_CPU1_ERR1_LVC1_R_N
    U1 AY22 ERROR_N1 SOCKET4677_AZIF0045P001C01CS-SA    I29 @S9S_MB_2U_LIB.S9S_MB_2U(SCH_1):PAGE45
  R341    1      A Q_RES_0402LF-0,5%,1/16W,CHIP,CA   I163 @S9S_MB_2U_LIB.S9S_MB_2U(SCH_1):PAGE322

H_CPU1_ERR2_LVC1_R_N @S9S_MB_2U_LIB.S9S_MB_2U(SCH_1):H_CPU1_ERR2_LVC1_R_N
    U1 BD22 ERROR_N2 SOCKET4677_AZIF0045P001C01CS-SA    I29 @S9S_MB_2U_LIB.S9S_MB_2U(SCH_1):PAGE45
  R345    1      A Q_RES_0402LF-0,5%,1/16W,CHIP,CA   I158 @S9S_MB_2U_LIB.S9S_MB_2U(SCH_1):PAGE322

H_CPU1_MEMHOT_IN_LVC1_N @S9S_MB_2U_LIB.S9S_MB_2U(SCH_1):H_CPU1_MEMHOT_IN_LVC1_N
    U1 AU21 MEMHOT_IN_N SOCKET4677_AZIF0045P001C01CS-SA    I29 @S9S_MB_2U_LIB.S9S_MB_2U(SCH_1):PAGE45
 R4294    2      B Q_RES_0402LF-100,1%,1/16W,CHIPA    I33 @S9S_MB_2U_LIB.S9S_MB_2U(SCH_1):PAGE122

H_CPU1_MEMHOT_IN_LVC1_R1_N @S9S_MB_2U_LIB.S9S_MB_2U(SCH_1):H_CPU1_MEMHOT_IN_LVC1_R1_N
  R210    2      B Q_RES_0402LF-0,5%,1/16W,CHIP,CA    I15 @S9S_MB_2U_LIB.S9S_MB_2U(SCH_1):PAGE122
  R220    2      B Q_RES_0402LF-100,1%,1/16W,CHIPA    I29 @S9S_MB_2U_LIB.S9S_MB_2U(SCH_1):PAGE122
 R4294    1      A Q_RES_0402LF-100,1%,1/16W,CHIPA    I33 @S9S_MB_2U_LIB.S9S_MB_2U(SCH_1):PAGE122

H_CPU1_MEMHOT_IN_LVC1_R_N @S9S_MB_2U_LIB.S9S_MB_2U(SCH_1):H_CPU1_MEMHOT_IN_LVC1_R_N
  U249   V5  PL30C LCMXO3LF9400C5BG484C-LCMXO3LF-A    I33 @S9S_MB_2U_LIB.S9S_MB_2U(SCH_1):PAGE311
  R210    1      A Q_RES_0402LF-0,5%,1/16W,CHIP,CA    I15 @S9S_MB_2U_LIB.S9S_MB_2U(SCH_1):PAGE122

H_CPU1_MEMHOT_OUT @S9S_MB_2U_LIB.S9S_MB_2U(SCH_1):H_CPU1_MEMHOT_OUT
  Q142    3     C2 BC847BPN-BC847BPN,SMLF,IC,BA00A    I10 @S9S_MB_2U_LIB.S9S_MB_2U(SCH_1):PAGE122
 R4404    1      A Q_RES_0402LF-1.5K,1%,1/16W,CHIA    I20 @S9S_MB_2U_LIB.S9S_MB_2U(SCH_1):PAGE122

H_CPU1_MEMHOT_OUT_LVC1_N @S9S_MB_2U_LIB.S9S_MB_2U(SCH_1):H_CPU1_MEMHOT_OUT_LVC1_N
  U249   R7  PL25D LCMXO3LF9400C5BG484C-LCMXO3LF-A    I33 @S9S_MB_2U_LIB.S9S_MB_2U(SCH_1):PAGE311
 R4408    2      B Q_RES_0402LF-33.2,1%,1/16W,CHIA    I18 @S9S_MB_2U_LIB.S9S_MB_2U(SCH_1):PAGE122

H_CPU1_MEMHOT_OUT_LVC1_R_N @S9S_MB_2U_LIB.S9S_MB_2U(SCH_1):H_CPU1_MEMHOT_OUT_LVC1_R_N
    U1 CF26 MEMHOT_OUT_N SOCKET4677_AZIF0045P001C01CS-SA    I29 @S9S_MB_2U_LIB.S9S_MB_2U(SCH_1):PAGE45
 R4402    2      B Q_RES_0402LF-100,1%,1/16W,CHIPA     I5 @S9S_MB_2U_LIB.S9S_MB_2U(SCH_1):PAGE122
  R204    1      A Q_RES_0402LF-1.5K,1%,1/16W,CHIA     I6 @S9S_MB_2U_LIB.S9S_MB_2U(SCH_1):PAGE122

H_CPU1_MEMHOT_OUT_R @S9S_MB_2U_LIB.S9S_MB_2U(SCH_1):H_CPU1_MEMHOT_OUT_R
  Q142    2     B1 BC847BPN-BC847BPN,SMLF,IC,BA00A    I17 @S9S_MB_2U_LIB.S9S_MB_2U(SCH_1):PAGE122
 R4404    2      B Q_RES_0402LF-1.5K,1%,1/16W,CHIA    I20 @S9S_MB_2U_LIB.S9S_MB_2U(SCH_1):PAGE122

H_CPU1_MEMHOT_OUT_VT_N @S9S_MB_2U_LIB.S9S_MB_2U(SCH_1):H_CPU1_MEMHOT_OUT_VT_N
  Q142    6     C1 BC847BPN-BC847BPN,SMLF,IC,BA00A    I17 @S9S_MB_2U_LIB.S9S_MB_2U(SCH_1):PAGE122
 R4408    1      A Q_RES_0402LF-33.2,1%,1/16W,CHIA    I18 @S9S_MB_2U_LIB.S9S_MB_2U(SCH_1):PAGE122
 R4406    2      B Q_RES_0402LF-4.75K,1%,1/16W,CHA    I24 @S9S_MB_2U_LIB.S9S_MB_2U(SCH_1):PAGE122

H_CPU1_MEMHOT_OUT_VT_R_N @S9S_MB_2U_LIB.S9S_MB_2U(SCH_1):H_CPU1_MEMHOT_OUT_VT_R_N
  R204    2      B Q_RES_0402LF-1.5K,1%,1/16W,CHIA     I6 @S9S_MB_2U_LIB.S9S_MB_2U(SCH_1):PAGE122
  Q142    5     B2 BC847BPN-BC847BPN,SMLF,IC,BA00A    I10 @S9S_MB_2U_LIB.S9S_MB_2U(SCH_1):PAGE122

H_CPU1_MEMTRIP @S9S_MB_2U_LIB.S9S_MB_2U(SCH_1):H_CPU1_MEMTRIP
  Q140    3     C2 BC847BPN-BC847BPN,SMLF,IC,BA00A    I11 @S9S_MB_2U_LIB.S9S_MB_2U(SCH_1):PAGE123
 R4410    1      A Q_RES_0402LF-1.5K,1%,1/16W,CHIA    I14 @S9S_MB_2U_LIB.S9S_MB_2U(SCH_1):PAGE123

H_CPU1_MEMTRIP_LVC1_N @S9S_MB_2U_LIB.S9S_MB_2U(SCH_1):H_CPU1_MEMTRIP_LVC1_N
  U249   U1  PL25B LCMXO3LF9400C5BG484C-LCMXO3LF-A    I33 @S9S_MB_2U_LIB.S9S_MB_2U(SCH_1):PAGE311
 R4414    2      B Q_RES_0402LF-33.2,1%,1/16W,CHIA    I31 @S9S_MB_2U_LIB.S9S_MB_2U(SCH_1):PAGE123

H_CPU1_MEMTRIP_LVC1_R_N @S9S_MB_2U_LIB.S9S_MB_2U(SCH_1):H_CPU1_MEMTRIP_LVC1_R_N
    U1 AV24 MEMTRIP_N SOCKET4677_AZIF0045P001C01CS-SA    I29 @S9S_MB_2U_LIB.S9S_MB_2U(SCH_1):PAGE45
  R206    1      A Q_RES_0402LF-1.5K,1%,1/16W,CHIA     I8 @S9S_MB_2U_LIB.S9S_MB_2U(SCH_1):PAGE123
  R202    2      B Q_RES_0402LF-100,1%,1/16W,CHIPA     I7 @S9S_MB_2U_LIB.S9S_MB_2U(SCH_1):PAGE123

H_CPU1_MEMTRIP_OUT_VT_R_N @S9S_MB_2U_LIB.S9S_MB_2U(SCH_1):H_CPU1_MEMTRIP_OUT_VT_R_N
  R206    2      B Q_RES_0402LF-1.5K,1%,1/16W,CHIA     I8 @S9S_MB_2U_LIB.S9S_MB_2U(SCH_1):PAGE123
  Q140    5     B2 BC847BPN-BC847BPN,SMLF,IC,BA00A    I11 @S9S_MB_2U_LIB.S9S_MB_2U(SCH_1):PAGE123

H_CPU1_MEMTRIP_R @S9S_MB_2U_LIB.S9S_MB_2U(SCH_1):H_CPU1_MEMTRIP_R
 R4410    2      B Q_RES_0402LF-1.5K,1%,1/16W,CHIA    I14 @S9S_MB_2U_LIB.S9S_MB_2U(SCH_1):PAGE123
  Q140    2     B1 BC847BPN-BC847BPN,SMLF,IC,BA00A    I16 @S9S_MB_2U_LIB.S9S_MB_2U(SCH_1):PAGE123

H_CPU1_MEMTRIP_VT_N @S9S_MB_2U_LIB.S9S_MB_2U(SCH_1):H_CPU1_MEMTRIP_VT_N
  Q140    6     C1 BC847BPN-BC847BPN,SMLF,IC,BA00A    I16 @S9S_MB_2U_LIB.S9S_MB_2U(SCH_1):PAGE123
 R4412    2      B Q_RES_0402LF-4.75K,1%,1/16W,CHA    I29 @S9S_MB_2U_LIB.S9S_MB_2U(SCH_1):PAGE123
 R4414    1      A Q_RES_0402LF-33.2,1%,1/16W,CHIA    I31 @S9S_MB_2U_LIB.S9S_MB_2U(SCH_1):PAGE123

H_CPU1_NMI_LVC1_N @S9S_MB_2U_LIB.S9S_MB_2U(SCH_1):H_CPU1_NMI_LVC1_N
    U1 AV18    NMI SOCKET4677_AZIF0045P001C01CS-SA    I29 @S9S_MB_2U_LIB.S9S_MB_2U(SCH_1):PAGE45
  R196    2      B Q_RES_0402LF-49.9,1%,1/16W,CHIA     I5 @S9S_MB_2U_LIB.S9S_MB_2U(SCH_1):PAGE123
  R198    2      B Q_RES_0402LF-301,1%,1/16W,CHIPA    I23 @S9S_MB_2U_LIB.S9S_MB_2U(SCH_1):PAGE123

H_CPU1_PM_FAST_WAKE_N @S9S_MB_2U_LIB.S9S_MB_2U(SCH_1):H_CPU1_PM_FAST_WAKE_N
    U1 CP20 PMFAST_WAKE_N SOCKET4677_AZIF0045P001C01CS-SA    I29 @S9S_MB_2U_LIB.S9S_MB_2U(SCH_1):PAGE45
 R3023    2      B Q_RES_0402LF-0,5%,1/16W,CHIP,CA    I10 @S9S_MB_2U_LIB.S9S_MB_2U(SCH_1):PAGE117

H_CPU1_PRDY_QS_GTL_R_N @S9S_MB_2U_LIB.S9S_MB_2U(SCH_1):H_CPU1_PRDY_QS_GTL_R_N
   R61    2      B Q_RES_0402LF-10,1%,1/16W,CHIP,A    I16 @S9S_MB_2U_LIB.S9S_MB_2U(SCH_1):PAGE44
    U1 BP26 PRDY_N SOCKET4677_AZIF0045P001C01CS-SA    I51 @S9S_MB_2U_LIB.S9S_MB_2U(SCH_1):PAGE44

H_CPU1_PREQ_QS_GTL_R_N @S9S_MB_2U_LIB.S9S_MB_2U(SCH_1):H_CPU1_PREQ_QS_GTL_R_N
   R62    2      B Q_RES_0402LF-100,1%,1/16W,CHIPA    I11 @S9S_MB_2U_LIB.S9S_MB_2U(SCH_1):PAGE44
    U1 AV22 PREQ_N SOCKET4677_AZIF0045P001C01CS-SA    I51 @S9S_MB_2U_LIB.S9S_MB_2U(SCH_1):PAGE44

H_CPU1_PROCHOT_LVC1_N @S9S_MB_2U_LIB.S9S_MB_2U(SCH_1):H_CPU1_PROCHOT_LVC1_N
    U1 AU19 PROCHOT_N SOCKET4677_AZIF0045P001C01CS-SA    I29 @S9S_MB_2U_LIB.S9S_MB_2U(SCH_1):PAGE45
  R240    2      B Q_RES_0402LF-0,5%,1/16W,CHIP,CA     I5 @S9S_MB_2U_LIB.S9S_MB_2U(SCH_1):PAGE121
  R244    2      B Q_RES_0402LF-100,1%,1/16W,CHIPA    I19 @S9S_MB_2U_LIB.S9S_MB_2U(SCH_1):PAGE121

H_CPU1_PROCHOT_LVC1_R_N @S9S_MB_2U_LIB.S9S_MB_2U(SCH_1):H_CPU1_PROCHOT_LVC1_R_N
  U249   Y3  PL30A LCMXO3LF9400C5BG484C-LCMXO3LF-A    I33 @S9S_MB_2U_LIB.S9S_MB_2U(SCH_1):PAGE311
  R240    1      A Q_RES_0402LF-0,5%,1/16W,CHIP,CA     I5 @S9S_MB_2U_LIB.S9S_MB_2U(SCH_1):PAGE121

H_CPU1_RMCA_LVC1_R_N @S9S_MB_2U_LIB.S9S_MB_2U(SCH_1):H_CPU1_RMCA_LVC1_R_N
    U1 BH22 RMCA_N SOCKET4677_AZIF0045P001C01CS-SA    I16 @S9S_MB_2U_LIB.S9S_MB_2U(SCH_1):PAGE47
  R304    1      A Q_RES_0402LF-0,5%,1/16W,CHIP,CA   I102 @S9S_MB_2U_LIB.S9S_MB_2U(SCH_1):PAGE118

H_CPU1_THERMTRIP_LVC1_N @S9S_MB_2U_LIB.S9S_MB_2U(SCH_1):H_CPU1_THERMTRIP_LVC1_N
  U249   P7  PL24D LCMXO3LF9400C5BG484C-LCMXO3LF-A    I33 @S9S_MB_2U_LIB.S9S_MB_2U(SCH_1):PAGE311
 R4400    2      B Q_RES_0402LF-33.2,1%,1/16W,CHIA    I29 @S9S_MB_2U_LIB.S9S_MB_2U(SCH_1):PAGE121

H_CPU1_THERMTRIP_LVC1_R_N @S9S_MB_2U_LIB.S9S_MB_2U(SCH_1):H_CPU1_THERMTRIP_LVC1_R_N
    U1 BL62 THERMTRIP_N SOCKET4677_AZIF0045P001C01CS-SA    I29 @S9S_MB_2U_LIB.S9S_MB_2U(SCH_1):PAGE45
 R4396    2      B Q_RES_0402LF-100,1%,1/16W,CHIPA     I4 @S9S_MB_2U_LIB.S9S_MB_2U(SCH_1):PAGE121
  R238    1      A Q_RES_0402LF-1.5K,1%,1/16W,CHIA     I6 @S9S_MB_2U_LIB.S9S_MB_2U(SCH_1):PAGE121

H_CPU1_THERMTRIP_N @S9S_MB_2U_LIB.S9S_MB_2U(SCH_1):H_CPU1_THERMTRIP_N
  Q139    3     C2 BC847BPN-BC847BPN,SMLF,IC,BA00A     I8 @S9S_MB_2U_LIB.S9S_MB_2U(SCH_1):PAGE121
 R4398    1      A Q_RES_0402LF-1.5K,1%,1/16W,CHIA    I10 @S9S_MB_2U_LIB.S9S_MB_2U(SCH_1):PAGE121

H_CPU1_THERMTRIP_R_N @S9S_MB_2U_LIB.S9S_MB_2U(SCH_1):H_CPU1_THERMTRIP_R_N
 R4398    2      B Q_RES_0402LF-1.5K,1%,1/16W,CHIA    I10 @S9S_MB_2U_LIB.S9S_MB_2U(SCH_1):PAGE121
  Q139    2     B1 BC847BPN-BC847BPN,SMLF,IC,BA00A    I21 @S9S_MB_2U_LIB.S9S_MB_2U(SCH_1):PAGE121

H_CPU1_THERMTRIP_VT_N @S9S_MB_2U_LIB.S9S_MB_2U(SCH_1):H_CPU1_THERMTRIP_VT_N
  Q139    6     C1 BC847BPN-BC847BPN,SMLF,IC,BA00A    I21 @S9S_MB_2U_LIB.S9S_MB_2U(SCH_1):PAGE121
  R242    2      B Q_RES_0402LF-4.75K,1%,1/16W,CHA    I26 @S9S_MB_2U_LIB.S9S_MB_2U(SCH_1):PAGE121
 R4400    1      A Q_RES_0402LF-33.2,1%,1/16W,CHIA    I29 @S9S_MB_2U_LIB.S9S_MB_2U(SCH_1):PAGE121

H_CPU1_THERMTRIP_VT_R_N @S9S_MB_2U_LIB.S9S_MB_2U(SCH_1):H_CPU1_THERMTRIP_VT_R_N
  R238    2      B Q_RES_0402LF-1.5K,1%,1/16W,CHIA     I6 @S9S_MB_2U_LIB.S9S_MB_2U(SCH_1):PAGE121
  Q139    5     B2 BC847BPN-BC847BPN,SMLF,IC,BA00A     I8 @S9S_MB_2U_LIB.S9S_MB_2U(SCH_1):PAGE121

H_CPU_CATERR_LVC1_R_N @S9S_MB_2U_LIB.S9S_MB_2U(SCH_1):H_CPU_CATERR_LVC1_R_N
  R297    2      B Q_RES_0402LF-0,5%,1/16W,CHIP,CA    I23 @S9S_MB_2U_LIB.S9S_MB_2U(SCH_1):PAGE118
  R299    2      B Q_RES_0402LF-0,5%,1/16W,CHIP,CA    I63 @S9S_MB_2U_LIB.S9S_MB_2U(SCH_1):PAGE118
  R296    2      B Q_RES_0402LF-301,1%,1/16W,CHIPA    I65 @S9S_MB_2U_LIB.S9S_MB_2U(SCH_1):PAGE118
  R298    2      B Q_RES_0402LF-301,1%,1/16W,CHIPA    I67 @S9S_MB_2U_LIB.S9S_MB_2U(SCH_1):PAGE118
  U301    2     B0 GTL2014PW-GTL2014PW,SMLF,IC,ALA    I91 @S9S_MB_2U_LIB.S9S_MB_2U(SCH_1):PAGE321
  U301    3     B1 GTL2014PW-GTL2014PW,SMLF,IC,ALA    I91 @S9S_MB_2U_LIB.S9S_MB_2U(SCH_1):PAGE321

H_CPU_CATERR_LVC2_BMC_N @S9S_MB_2U_LIB.S9S_MB_2U(SCH_1):H_CPU_CATERR_LVC2_BMC_N
 R4621    2      B Q_RES_0402LF-33.2,1%,1/16W,CHIA   I101 @S9S_MB_2U_LIB.S9S_MB_2U(SCH_1):PAGE321
   J41 OB13 GND_OB13 SCONN168_ME1016810202011-SCONNA   I173 @S9S_MB_2U_LIB.S9S_MB_2U(SCH_1):PAGE227

H_CPU_CATERR_LVC2_BMC_R_N @S9S_MB_2U_LIB.S9S_MB_2U(SCH_1):H_CPU_CATERR_LVC2_BMC_R_N
  U301   13     A0 GTL2014PW-GTL2014PW,SMLF,IC,ALA    I91 @S9S_MB_2U_LIB.S9S_MB_2U(SCH_1):PAGE321
 R4621    1      A Q_RES_0402LF-33.2,1%,1/16W,CHIA   I101 @S9S_MB_2U_LIB.S9S_MB_2U(SCH_1):PAGE321

H_CPU_CATERR_LVC2_R1_N @S9S_MB_2U_LIB.S9S_MB_2U(SCH_1):H_CPU_CATERR_LVC2_R1_N
 R4023    1      A Q_RES_0402LF-33.2,1%,1/16W,CHIA    I80 @S9S_MB_2U_LIB.S9S_MB_2U(SCH_1):PAGE321
  U301   12     A1 GTL2014PW-GTL2014PW,SMLF,IC,ALA    I91 @S9S_MB_2U_LIB.S9S_MB_2U(SCH_1):PAGE321

H_CPU_CATERR_LVC2_R2_N @S9S_MB_2U_LIB.S9S_MB_2U(SCH_1):H_CPU_CATERR_LVC2_R2_N
  U249   Y2  PL29D LCMXO3LF9400C5BG484C-LCMXO3LF-A    I33 @S9S_MB_2U_LIB.S9S_MB_2U(SCH_1):PAGE311
 R4023    2      B Q_RES_0402LF-33.2,1%,1/16W,CHIA    I80 @S9S_MB_2U_LIB.S9S_MB_2U(SCH_1):PAGE321

H_CPU_ERR0_LVC1_N @S9S_MB_2U_LIB.S9S_MB_2U(SCH_1):H_CPU_ERR0_LVC1_N
  U306    6     B3 GTL2014PW-GTL2014PW,SMLF,IC,ALA    I80 @S9S_MB_2U_LIB.S9S_MB_2U(SCH_1):PAGE322
  R338    2      B Q_RES_0402LF-0,5%,1/16W,CHIP,CA   I173 @S9S_MB_2U_LIB.S9S_MB_2U(SCH_1):PAGE322

H_CPU_ERR0_LVC1_R_N @S9S_MB_2U_LIB.S9S_MB_2U(SCH_1):H_CPU_ERR0_LVC1_R_N
  R336    2      B Q_RES_0402LF-0,5%,1/16W,CHIP,CA   I159 @S9S_MB_2U_LIB.S9S_MB_2U(SCH_1):PAGE322
  R337    2      B Q_RES_0402LF-0,5%,1/16W,CHIP,CA   I160 @S9S_MB_2U_LIB.S9S_MB_2U(SCH_1):PAGE322
 R4390    2      B Q_RES_0402LF-150,1%,1/16W,CHIPA   I169 @S9S_MB_2U_LIB.S9S_MB_2U(SCH_1):PAGE322
  R338    1      A Q_RES_0402LF-0,5%,1/16W,CHIP,CA   I173 @S9S_MB_2U_LIB.S9S_MB_2U(SCH_1):PAGE322

H_CPU_ERR0_LVC2_N @S9S_MB_2U_LIB.S9S_MB_2U(SCH_1):H_CPU_ERR0_LVC2_N
  U249   T6  PL26D LCMXO3LF9400C5BG484C-LCMXO3LF-A    I33 @S9S_MB_2U_LIB.S9S_MB_2U(SCH_1):PAGE311
 R4050    2      B Q_RES_0402LF-33.2,1%,1/16W,CHIA   I184 @S9S_MB_2U_LIB.S9S_MB_2U(SCH_1):PAGE322

H_CPU_ERR0_LVC2_R_N @S9S_MB_2U_LIB.S9S_MB_2U(SCH_1):H_CPU_ERR0_LVC2_R_N
  U306    9     A3 GTL2014PW-GTL2014PW,SMLF,IC,ALA    I80 @S9S_MB_2U_LIB.S9S_MB_2U(SCH_1):PAGE322
 R4392    1      A Q_RES_0402LF-33.2,1%,1/16W,CHIA   I183 @S9S_MB_2U_LIB.S9S_MB_2U(SCH_1):PAGE322
 R4050    1      A Q_RES_0402LF-33.2,1%,1/16W,CHIA   I184 @S9S_MB_2U_LIB.S9S_MB_2U(SCH_1):PAGE322

H_CPU_ERR0_PCH_R_N @S9S_MB_2U_LIB.S9S_MB_2U(SCH_1):H_CPU_ERR0_PCH_R_N
    U4   J7 CPU_ERR0_N EMMITSBURG_REV0P9-GFNOCPU04302A    I36 @S9S_MB_2U_LIB.S9S_MB_2U(SCH_1):PAGE174
 R1260    2      B Q_RES_0402LF-10K,1%,1/16W,EMPTA    I17 @S9S_MB_2U_LIB.S9S_MB_2U(SCH_1):PAGE192
 R4392    2      B Q_RES_0402LF-33.2,1%,1/16W,CHIA   I183 @S9S_MB_2U_LIB.S9S_MB_2U(SCH_1):PAGE322

H_CPU_ERR1_LVC1_N @S9S_MB_2U_LIB.S9S_MB_2U(SCH_1):H_CPU_ERR1_LVC1_N
  U306    5     B2 GTL2014PW-GTL2014PW,SMLF,IC,ALA    I80 @S9S_MB_2U_LIB.S9S_MB_2U(SCH_1):PAGE322
  R342    2      B Q_RES_0402LF-0,5%,1/16W,CHIP,CA   I172 @S9S_MB_2U_LIB.S9S_MB_2U(SCH_1):PAGE322

H_CPU_ERR1_LVC1_R_N @S9S_MB_2U_LIB.S9S_MB_2U(SCH_1):H_CPU_ERR1_LVC1_R_N
  R341    2      B Q_RES_0402LF-0,5%,1/16W,CHIP,CA   I163 @S9S_MB_2U_LIB.S9S_MB_2U(SCH_1):PAGE322
  R340    2      B Q_RES_0402LF-0,5%,1/16W,CHIP,CA   I164 @S9S_MB_2U_LIB.S9S_MB_2U(SCH_1):PAGE322
  R342    1      A Q_RES_0402LF-0,5%,1/16W,CHIP,CA   I172 @S9S_MB_2U_LIB.S9S_MB_2U(SCH_1):PAGE322
 R4388    2      B Q_RES_0402LF-150,1%,1/16W,CHIPA   I174 @S9S_MB_2U_LIB.S9S_MB_2U(SCH_1):PAGE322

H_CPU_ERR1_LVC2_N @S9S_MB_2U_LIB.S9S_MB_2U(SCH_1):H_CPU_ERR1_LVC2_N
  U249   T5  PL26C LCMXO3LF9400C5BG484C-LCMXO3LF-A    I33 @S9S_MB_2U_LIB.S9S_MB_2U(SCH_1):PAGE311
 R4051    2      B Q_RES_0402LF-33.2,1%,1/16W,CHIA    I94 @S9S_MB_2U_LIB.S9S_MB_2U(SCH_1):PAGE322

H_CPU_ERR1_LVC2_R_N @S9S_MB_2U_LIB.S9S_MB_2U(SCH_1):H_CPU_ERR1_LVC2_R_N
  U306   10     A2 GTL2014PW-GTL2014PW,SMLF,IC,ALA    I80 @S9S_MB_2U_LIB.S9S_MB_2U(SCH_1):PAGE322
 R4051    1      A Q_RES_0402LF-33.2,1%,1/16W,CHIA    I94 @S9S_MB_2U_LIB.S9S_MB_2U(SCH_1):PAGE322
 R4393    1      A Q_RES_0402LF-33.2,1%,1/16W,CHIA   I188 @S9S_MB_2U_LIB.S9S_MB_2U(SCH_1):PAGE322

H_CPU_ERR1_PCH_R_N @S9S_MB_2U_LIB.S9S_MB_2U(SCH_1):H_CPU_ERR1_PCH_R_N
    U4   G7 CPU_ERR1_N EMMITSBURG_REV0P9-GFNOCPU04302A    I36 @S9S_MB_2U_LIB.S9S_MB_2U(SCH_1):PAGE174
 R3042    2      B Q_RES_0402LF-10K,1%,1/16W,EMPTA    I18 @S9S_MB_2U_LIB.S9S_MB_2U(SCH_1):PAGE192
 R4393    2      B Q_RES_0402LF-33.2,1%,1/16W,CHIA   I188 @S9S_MB_2U_LIB.S9S_MB_2U(SCH_1):PAGE322

H_CPU_ERR2_LVC1_N @S9S_MB_2U_LIB.S9S_MB_2U(SCH_1):H_CPU_ERR2_LVC1_N
  U306    3     B1 GTL2014PW-GTL2014PW,SMLF,IC,ALA    I80 @S9S_MB_2U_LIB.S9S_MB_2U(SCH_1):PAGE322
  R346    2      B Q_RES_0402LF-0,5%,1/16W,CHIP,CA   I171 @S9S_MB_2U_LIB.S9S_MB_2U(SCH_1):PAGE322

H_CPU_ERR2_LVC1_R_N @S9S_MB_2U_LIB.S9S_MB_2U(SCH_1):H_CPU_ERR2_LVC1_R_N
  R344    2      B Q_RES_0402LF-0,5%,1/16W,CHIP,CA   I157 @S9S_MB_2U_LIB.S9S_MB_2U(SCH_1):PAGE322
  R345    2      B Q_RES_0402LF-0,5%,1/16W,CHIP,CA   I158 @S9S_MB_2U_LIB.S9S_MB_2U(SCH_1):PAGE322
  R346    1      A Q_RES_0402LF-0,5%,1/16W,CHIP,CA   I171 @S9S_MB_2U_LIB.S9S_MB_2U(SCH_1):PAGE322
 R4389    2      B Q_RES_0402LF-150,1%,1/16W,CHIPA   I177 @S9S_MB_2U_LIB.S9S_MB_2U(SCH_1):PAGE322

H_CPU_ERR2_LVC2_N @S9S_MB_2U_LIB.S9S_MB_2U(SCH_1):H_CPU_ERR2_LVC2_N
  U249   T4  PL26B LCMXO3LF9400C5BG484C-LCMXO3LF-A    I33 @S9S_MB_2U_LIB.S9S_MB_2U(SCH_1):PAGE311
 R4052    2      B Q_RES_0402LF-33.2,1%,1/16W,CHIA   I187 @S9S_MB_2U_LIB.S9S_MB_2U(SCH_1):PAGE322

H_CPU_ERR2_LVC2_R_N @S9S_MB_2U_LIB.S9S_MB_2U(SCH_1):H_CPU_ERR2_LVC2_R_N
  U306   12     A1 GTL2014PW-GTL2014PW,SMLF,IC,ALA    I80 @S9S_MB_2U_LIB.S9S_MB_2U(SCH_1):PAGE322
 R4052    1      A Q_RES_0402LF-33.2,1%,1/16W,CHIA   I187 @S9S_MB_2U_LIB.S9S_MB_2U(SCH_1):PAGE322
 R4394    1      A Q_RES_0402LF-33.2,1%,1/16W,CHIA   I189 @S9S_MB_2U_LIB.S9S_MB_2U(SCH_1):PAGE322

H_CPU_ERR2_PCH_R_N @S9S_MB_2U_LIB.S9S_MB_2U(SCH_1):H_CPU_ERR2_PCH_R_N
    U4   L7 CPU_ERR2_N EMMITSBURG_REV0P9-GFNOCPU04302A    I36 @S9S_MB_2U_LIB.S9S_MB_2U(SCH_1):PAGE174
 R1262    2      B Q_RES_0402LF-10K,1%,1/16W,EMPTA    I11 @S9S_MB_2U_LIB.S9S_MB_2U(SCH_1):PAGE192
 R4394    2      B Q_RES_0402LF-33.2,1%,1/16W,CHIA   I189 @S9S_MB_2U_LIB.S9S_MB_2U(SCH_1):PAGE322

H_CPU_NMI_LVC1_N @S9S_MB_2U_LIB.S9S_MB_2U(SCH_1):H_CPU_NMI_LVC1_N
  R188    2      B Q_RES_0402LF-0,5%,1/16W,CHIP,CA     I4 @S9S_MB_2U_LIB.S9S_MB_2U(SCH_1):PAGE123
  R196    1      A Q_RES_0402LF-49.9,1%,1/16W,CHIA     I5 @S9S_MB_2U_LIB.S9S_MB_2U(SCH_1):PAGE123
  R195    1      A Q_RES_0402LF-49.9,1%,1/16W,CHIA     I6 @S9S_MB_2U_LIB.S9S_MB_2U(SCH_1):PAGE123

H_CPU_NMI_LVC1_R_N @S9S_MB_2U_LIB.S9S_MB_2U(SCH_1):H_CPU_NMI_LVC1_R_N
  U249  AA1  PL29B LCMXO3LF9400C5BG484C-LCMXO3LF-A    I33 @S9S_MB_2U_LIB.S9S_MB_2U(SCH_1):PAGE311
  R188    1      A Q_RES_0402LF-0,5%,1/16W,CHIP,CA     I4 @S9S_MB_2U_LIB.S9S_MB_2U(SCH_1):PAGE123

H_CPU_PM_FAST_WAKE_N @S9S_MB_2U_LIB.S9S_MB_2U(SCH_1):H_CPU_PM_FAST_WAKE_N
 R1240    2      B Q_RES_0402LF-0,5%,1/16W,CHIP,CA     I9 @S9S_MB_2U_LIB.S9S_MB_2U(SCH_1):PAGE117
 R3023    1      A Q_RES_0402LF-0,5%,1/16W,CHIP,CA    I10 @S9S_MB_2U_LIB.S9S_MB_2U(SCH_1):PAGE117
 R1242    2      B Q_RES_0402LF-301,1%,1/16W,CHIPA    I13 @S9S_MB_2U_LIB.S9S_MB_2U(SCH_1):PAGE117
 R1244    2      B Q_RES_0402LF-301,1%,1/16W,CHIPA    I16 @S9S_MB_2U_LIB.S9S_MB_2U(SCH_1):PAGE117

H_CPU_PRDY_QS_GTL_N @S9S_MB_2U_LIB.S9S_MB_2U(SCH_1):H_CPU_PRDY_QS_GTL_N
    R1    1      A Q_RES_0402LF-10,1%,1/16W,CHIP,A    I18 @S9S_MB_2U_LIB.S9S_MB_2U(SCH_1):PAGE13
   R61    1      A Q_RES_0402LF-10,1%,1/16W,CHIP,A    I16 @S9S_MB_2U_LIB.S9S_MB_2U(SCH_1):PAGE44
   U18    8     3B 74CBTLV3126PW-74CBTLV3126PW,SMA   I129 @S9S_MB_2U_LIB.S9S_MB_2U(SCH_1):PAGE134
  R759    2      B Q_RES_0402LF-150,1%,1/16W,CHIPA   I169 @S9S_MB_2U_LIB.S9S_MB_2U(SCH_1):PAGE134

H_CPU_PREQ_QS_GTL_N @S9S_MB_2U_LIB.S9S_MB_2U(SCH_1):H_CPU_PREQ_QS_GTL_N
    R2    1      A Q_RES_0402LF-100,1%,1/16W,CHIPA    I16 @S9S_MB_2U_LIB.S9S_MB_2U(SCH_1):PAGE13
   R62    1      A Q_RES_0402LF-100,1%,1/16W,CHIPA    I11 @S9S_MB_2U_LIB.S9S_MB_2U(SCH_1):PAGE44
   U18   11     4B 74CBTLV3126PW-74CBTLV3126PW,SMA   I129 @S9S_MB_2U_LIB.S9S_MB_2U(SCH_1):PAGE134
  R758    2      B Q_RES_0402LF-150,1%,1/16W,CHIPA   I168 @S9S_MB_2U_LIB.S9S_MB_2U(SCH_1):PAGE134

H_CPU_RMCA_LVC1_R_N @S9S_MB_2U_LIB.S9S_MB_2U(SCH_1):H_CPU_RMCA_LVC1_R_N
  R301    2      B Q_RES_0402LF-301,1%,1/16W,CHIPA    I73 @S9S_MB_2U_LIB.S9S_MB_2U(SCH_1):PAGE118
  R303    2      B Q_RES_0402LF-301,1%,1/16W,CHIPA    I76 @S9S_MB_2U_LIB.S9S_MB_2U(SCH_1):PAGE118
  U301    5     B2 GTL2014PW-GTL2014PW,SMLF,IC,ALA    I91 @S9S_MB_2U_LIB.S9S_MB_2U(SCH_1):PAGE321
  R302    2      B Q_RES_0402LF-0,5%,1/16W,CHIP,CA   I101 @S9S_MB_2U_LIB.S9S_MB_2U(SCH_1):PAGE118
  R304    2      B Q_RES_0402LF-0,5%,1/16W,CHIP,CA   I102 @S9S_MB_2U_LIB.S9S_MB_2U(SCH_1):PAGE118

H_CPU_RMCA_LVC2_R1_N @S9S_MB_2U_LIB.S9S_MB_2U(SCH_1):H_CPU_RMCA_LVC2_R1_N
 R4022    1      A Q_RES_0402LF-33.2,1%,1/16W,CHIA    I79 @S9S_MB_2U_LIB.S9S_MB_2U(SCH_1):PAGE321
  U301   10     A2 GTL2014PW-GTL2014PW,SMLF,IC,ALA    I91 @S9S_MB_2U_LIB.S9S_MB_2U(SCH_1):PAGE321

H_CPU_RMCA_LVC2_R2_N @S9S_MB_2U_LIB.S9S_MB_2U(SCH_1):H_CPU_RMCA_LVC2_R2_N
  U249   Y1  PL29A LCMXO3LF9400C5BG484C-LCMXO3LF-A    I33 @S9S_MB_2U_LIB.S9S_MB_2U(SCH_1):PAGE311
 R4022    2      B Q_RES_0402LF-33.2,1%,1/16W,CHIA    I79 @S9S_MB_2U_LIB.S9S_MB_2U(SCH_1):PAGE321

H_DBP_PRDY_N_PCH @S9S_MB_2U_LIB.S9S_MB_2U(SCH_1):H_DBP_PRDY_N_PCH
  R756    2      B Q_RES_0402LF-10,1%,1/16W,CHIP,A   I148 @S9S_MB_2U_LIB.S9S_MB_2U(SCH_1):PAGE134
  R751    2      B Q_RES_0402LF-150,1%,1/16W,CHIPA   I177 @S9S_MB_2U_LIB.S9S_MB_2U(SCH_1):PAGE134
    U4 BB37 PRDY_N EMMITSBURG_REV0P9-GFNOCPU04302A    I36 @S9S_MB_2U_LIB.S9S_MB_2U(SCH_1):PAGE174

H_DBP_PREQ_N_PCH @S9S_MB_2U_LIB.S9S_MB_2U(SCH_1):H_DBP_PREQ_N_PCH
  R755    2      B Q_RES_0402LF-10,1%,1/16W,CHIP,A   I147 @S9S_MB_2U_LIB.S9S_MB_2U(SCH_1):PAGE134
  R750    2      B Q_RES_0402LF-150,1%,1/16W,CHIPA   I178 @S9S_MB_2U_LIB.S9S_MB_2U(SCH_1):PAGE134
    U4 BF37 PREQ_N EMMITSBURG_REV0P9-GFNOCPU04302A    I36 @S9S_MB_2U_LIB.S9S_MB_2U(SCH_1):PAGE174

H_PMAX_TRIGGER_IO_CPU0 @S9S_MB_2U_LIB.S9S_MB_2U(SCH_1):H_PMAX_TRIGGER_IO_CPU0
    U2 BD24 PMAX_TRIGGER_IO SOCKET4677_AZIF0045P001C01CS-SA     I1 @S9S_MB_2U_LIB.S9S_MB_2U(SCH_1):PAGE16
 R1241    1      A Q_RES_0402LF-249,1%,1/16W,CHIPA    I17 @S9S_MB_2U_LIB.S9S_MB_2U(SCH_1):PAGE117

H_PMAX_TRIGGER_IO_CPU1 @S9S_MB_2U_LIB.S9S_MB_2U(SCH_1):H_PMAX_TRIGGER_IO_CPU1
    U1 BD24 PMAX_TRIGGER_IO SOCKET4677_AZIF0045P001C01CS-SA    I16 @S9S_MB_2U_LIB.S9S_MB_2U(SCH_1):PAGE47
 R1243    1      A Q_RES_0402LF-249,1%,1/16W,CHIPA    I19 @S9S_MB_2U_LIB.S9S_MB_2U(SCH_1):PAGE117

H_THERMTRIP_LVC1_N @S9S_MB_2U_LIB.S9S_MB_2U(SCH_1):H_THERMTRIP_LVC1_N
    U4   F3 CPU_THRMTRIP_N EMMITSBURG_REV0P9-GFNOCPU04302A    I36 @S9S_MB_2U_LIB.S9S_MB_2U(SCH_1):PAGE174
 R1249    2      B Q_RES_0402LF-0,5%,1/16W,CHIP,CA     I2 @S9S_MB_2U_LIB.S9S_MB_2U(SCH_1):PAGE191
 R1266    2      B Q_RES_0402LF-75,1%,1/16W,CHIP,A    I38 @S9S_MB_2U_LIB.S9S_MB_2U(SCH_1):PAGE191

I3C_BMC_SWB_BUF_R_SCL @S9S_MB_2U_LIB.S9S_MB_2U(SCH_1):I3C_BMC_SWB_BUF_R_SCL
 R2675    1      A Q_RES_0402LF-33.2,1%,1/16W,CHIA    I72 @S9S_MB_2U_LIB.S9S_MB_2U(SCH_1):PAGE222
 R2725    2      B Q_RES_0402LF-0,5%,1/16W,CHIP,CA    I29 @S9S_MB_2U_LIB.S9S_MB_2U(SCH_1):PAGE222
  U176    2 SCL_OUT LTC4307CMS8-LTC4307CMS8,SMLF,EA    I31 @S9S_MB_2U_LIB.S9S_MB_2U(SCH_1):PAGE222
 R2670    2      B Q_RES_0402LF-4.7K,5%,1/16W,EMPA    I77 @S9S_MB_2U_LIB.S9S_MB_2U(SCH_1):PAGE222

I3C_BMC_SWB_BUF_R_SDA @S9S_MB_2U_LIB.S9S_MB_2U(SCH_1):I3C_BMC_SWB_BUF_R_SDA
 R2706    2      B Q_RES_0402LF-0,5%,1/16W,CHIP,CA    I30 @S9S_MB_2U_LIB.S9S_MB_2U(SCH_1):PAGE222
  U176    7 SDA_OUT LTC4307CMS8-LTC4307CMS8,SMLF,EA    I31 @S9S_MB_2U_LIB.S9S_MB_2U(SCH_1):PAGE222
 R2674    1      A Q_RES_0402LF-27.4,1%,1/16W,CHIA    I71 @S9S_MB_2U_LIB.S9S_MB_2U(SCH_1):PAGE222
 R2668    2      B Q_RES_0402LF-4.7K,5%,1/16W,EMPA    I75 @S9S_MB_2U_LIB.S9S_MB_2U(SCH_1):PAGE222

I3C_BMC_SWB_BUF_SCL @S9S_MB_2U_LIB.S9S_MB_2U(SCH_1):I3C_BMC_SWB_BUF_SCL
  J106   N4     N4 CONN112_10137002101LF-CONN112_A    I65 @S9S_MB_2U_LIB.S9S_MB_2U(SCH_1):PAGE144
 R2675    2      B Q_RES_0402LF-33.2,1%,1/16W,CHIA    I72 @S9S_MB_2U_LIB.S9S_MB_2U(SCH_1):PAGE222

I3C_BMC_SWB_BUF_SDA @S9S_MB_2U_LIB.S9S_MB_2U(SCH_1):I3C_BMC_SWB_BUF_SDA
  J106   N2     N2 CONN112_10137002101LF-CONN112_A    I65 @S9S_MB_2U_LIB.S9S_MB_2U(SCH_1):PAGE144
 R2674    2      B Q_RES_0402LF-27.4,1%,1/16W,CHIA    I71 @S9S_MB_2U_LIB.S9S_MB_2U(SCH_1):PAGE222

I3C_BMC_SWB_R_SCL @S9S_MB_2U_LIB.S9S_MB_2U(SCH_1):I3C_BMC_SWB_R_SCL
 R3112    2      B Q_RES_0402LF-33.2,1%,1/16W,CHIA    I18 @S9S_MB_2U_LIB.S9S_MB_2U(SCH_1):PAGE222
 R2725    1      A Q_RES_0402LF-0,5%,1/16W,CHIP,CA    I29 @S9S_MB_2U_LIB.S9S_MB_2U(SCH_1):PAGE222
  U176    3 SCL_IN LTC4307CMS8-LTC4307CMS8,SMLF,EA    I31 @S9S_MB_2U_LIB.S9S_MB_2U(SCH_1):PAGE222

I3C_BMC_SWB_R_SDA @S9S_MB_2U_LIB.S9S_MB_2U(SCH_1):I3C_BMC_SWB_R_SDA
 R3111    2      B Q_RES_0402LF-0,5%,1/16W,CHIP,CA    I17 @S9S_MB_2U_LIB.S9S_MB_2U(SCH_1):PAGE222
 R2706    1      A Q_RES_0402LF-0,5%,1/16W,CHIP,CA    I30 @S9S_MB_2U_LIB.S9S_MB_2U(SCH_1):PAGE222
  U176    6 SDA_IN LTC4307CMS8-LTC4307CMS8,SMLF,EA    I31 @S9S_MB_2U_LIB.S9S_MB_2U(SCH_1):PAGE222

I3C_BMC_SWB_SCL @S9S_MB_2U_LIB.S9S_MB_2U(SCH_1):I3C_BMC_SWB_SCL
 R1336    1      A Q_RES_0402LF-2.2K,5%,1/16W,EMPA   I177 @S9S_MB_2U_LIB.S9S_MB_2U(SCH_1):PAGE228
 R3112    1      A Q_RES_0402LF-33.2,1%,1/16W,CHIA    I18 @S9S_MB_2U_LIB.S9S_MB_2U(SCH_1):PAGE222
   J41   A9 SMRST# SCONN168_ME1016810202011-SCONNA   I173 @S9S_MB_2U_LIB.S9S_MB_2U(SCH_1):PAGE227

I3C_BMC_SWB_SDA @S9S_MB_2U_LIB.S9S_MB_2U(SCH_1):I3C_BMC_SWB_SDA
 R1460    1      A Q_RES_0402LF-2.2K,5%,1/16W,EMPA   I176 @S9S_MB_2U_LIB.S9S_MB_2U(SCH_1):PAGE228
 R3111    1      A Q_RES_0402LF-0,5%,1/16W,CHIP,CA    I17 @S9S_MB_2U_LIB.S9S_MB_2U(SCH_1):PAGE222
   J41  A10 PRSNTA# SCONN168_ME1016810202011-SCONNA   I173 @S9S_MB_2U_LIB.S9S_MB_2U(SCH_1):PAGE227

I3C_SPD_DDRABCD_CPU0_BMC_R_SCL @S9S_MB_2U_LIB.S9S_MB_2U(SCH_1):I3C_SPD_DDRABCD_CPU0_BMC_R_SCL
  R593    1      A Q_RES_0402LF-0,5%,1/16W,CHIP,CA   I311 @S9S_MB_2U_LIB.S9S_MB_2U(SCH_1):PAGE228
   J41  OA5 RBT_ARB_OUT SCONN168_ME1016810202011-SCONNA   I173 @S9S_MB_2U_LIB.S9S_MB_2U(SCH_1):PAGE227

I3C_SPD_DDRABCD_CPU0_BMC_R_SDA @S9S_MB_2U_LIB.S9S_MB_2U(SCH_1):I3C_SPD_DDRABCD_CPU0_BMC_R_SDA
  R594    1      A Q_RES_0402LF-0,5%,1/16W,CHIP,CA   I312 @S9S_MB_2U_LIB.S9S_MB_2U(SCH_1):PAGE228
   J41  OA6 SLOT_ID1 SCONN168_ME1016810202011-SCONNA   I173 @S9S_MB_2U_LIB.S9S_MB_2U(SCH_1):PAGE227

I3C_SPD_DDRABCD_CPU0_BMC_SCL @S9S_MB_2U_LIB.S9S_MB_2U(SCH_1):I3C_SPD_DDRABCD_CPU0_BMC_SCL
  R593    2      B Q_RES_0402LF-0,5%,1/16W,CHIP,CA   I311 @S9S_MB_2U_LIB.S9S_MB_2U(SCH_1):PAGE228
   U15    3    I1A QS3VH257QG8_SMLF-QS3VH257QG8,IA    I19 @S9S_MB_2U_LIB.S9S_MB_2U(SCH_1):PAGE217

I3C_SPD_DDRABCD_CPU0_BMC_SDA @S9S_MB_2U_LIB.S9S_MB_2U(SCH_1):I3C_SPD_DDRABCD_CPU0_BMC_SDA
  R594    2      B Q_RES_0402LF-0,5%,1/16W,CHIP,CA   I312 @S9S_MB_2U_LIB.S9S_MB_2U(SCH_1):PAGE228
   U15    6    I1B QS3VH257QG8_SMLF-QS3VH257QG8,IA    I19 @S9S_MB_2U_LIB.S9S_MB_2U(SCH_1):PAGE217

I3C_SPD_DDRABCD_CPU0_LVC1_R_SCL @S9S_MB_2U_LIB.S9S_MB_2U(SCH_1):I3C_SPD_DDRABCD_CPU0_LVC1_R_SCL
   U15    4     YA QS3VH257QG8_SMLF-QS3VH257QG8,IA    I19 @S9S_MB_2U_LIB.S9S_MB_2U(SCH_1):PAGE217
  R682    2      B Q_RES_0402LF-0,5%,1/16W,EMPTY,A    I20 @S9S_MB_2U_LIB.S9S_MB_2U(SCH_1):PAGE217
  R691    1      A Q_RES_0402LF-0,5%,1/16W,CHIP,CA    I39 @S9S_MB_2U_LIB.S9S_MB_2U(SCH_1):PAGE217

I3C_SPD_DDRABCD_CPU0_LVC1_R_SDA @S9S_MB_2U_LIB.S9S_MB_2U(SCH_1):I3C_SPD_DDRABCD_CPU0_LVC1_R_SDA
  R683    2      B Q_RES_0402LF-0,5%,1/16W,EMPTY,A    I18 @S9S_MB_2U_LIB.S9S_MB_2U(SCH_1):PAGE217
   U15    7     YB QS3VH257QG8_SMLF-QS3VH257QG8,IA    I19 @S9S_MB_2U_LIB.S9S_MB_2U(SCH_1):PAGE217
  R692    1      A Q_RES_0402LF-33.2,1%,1/16W,CHIA    I40 @S9S_MB_2U_LIB.S9S_MB_2U(SCH_1):PAGE217

I3C_SPD_DDRABCD_CPU0_LVC1_SCL @S9S_MB_2U_LIB.S9S_MB_2U(SCH_1):I3C_SPD_DDRABCD_CPU0_LVC1_SCL
 R3875    2      B Q_RES_0402LF-49.9,1%,1/16W,CHIA   I204 @S9S_MB_2U_LIB.S9S_MB_2U(SCH_1):PAGE82
 R3876    2      B Q_RES_0402LF-49.9,1%,1/16W,CHIA   I182 @S9S_MB_2U_LIB.S9S_MB_2U(SCH_1):PAGE83
 R3877    2      B Q_RES_0402LF-49.9,1%,1/16W,CHIA   I182 @S9S_MB_2U_LIB.S9S_MB_2U(SCH_1):PAGE84
 R3878    2      B Q_RES_0402LF-49.9,1%,1/16W,CHIA   I180 @S9S_MB_2U_LIB.S9S_MB_2U(SCH_1):PAGE85
 R3879    2      B Q_RES_0402LF-49.9,1%,1/16W,CHIA   I180 @S9S_MB_2U_LIB.S9S_MB_2U(SCH_1):PAGE86
 R3880    2      B Q_RES_0402LF-49.9,1%,1/16W,CHIA   I180 @S9S_MB_2U_LIB.S9S_MB_2U(SCH_1):PAGE87
 R3881    2      B Q_RES_0402LF-49.9,1%,1/16W,CHIA   I180 @S9S_MB_2U_LIB.S9S_MB_2U(SCH_1):PAGE88
 R3882    2      B Q_RES_0402LF-49.9,1%,1/16W,CHIA   I180 @S9S_MB_2U_LIB.S9S_MB_2U(SCH_1):PAGE89
  R691    2      B Q_RES_0402LF-0,5%,1/16W,CHIP,CA    I39 @S9S_MB_2U_LIB.S9S_MB_2U(SCH_1):PAGE217

I3C_SPD_DDRABCD_CPU0_LVC1_SCL_1 @S9S_MB_2U_LIB.S9S_MB_2U(SCH_1):I3C_SPD_DDRABCD_CPU0_LVC1_SCL_R2
    J2    4   HSCL SCONN288_ADR50017P087CC-SCONN2A   I177 @S9S_MB_2U_LIB.S9S_MB_2U(SCH_1):PAGE83
 R3876    1      A Q_RES_0402LF-49.9,1%,1/16W,CHIA   I182 @S9S_MB_2U_LIB.S9S_MB_2U(SCH_1):PAGE83

I3C_SPD_DDRABCD_CPU0_LVC1_SCL_2 @S9S_MB_2U_LIB.S9S_MB_2U(SCH_1):I3C_SPD_DDRABCD_CPU0_LVC1_SCL_R3
    J3    4   HSCL SCONN288_ADR50017P130CC-SCONN2A   I180 @S9S_MB_2U_LIB.S9S_MB_2U(SCH_1):PAGE84
 R3877    1      A Q_RES_0402LF-49.9,1%,1/16W,CHIA   I182 @S9S_MB_2U_LIB.S9S_MB_2U(SCH_1):PAGE84

I3C_SPD_DDRABCD_CPU0_LVC1_SCL_3 @S9S_MB_2U_LIB.S9S_MB_2U(SCH_1):I3C_SPD_DDRABCD_CPU0_LVC1_SCL_R4
    J4    4   HSCL SCONN288_ADR50017P087CC-SCONN2A    I23 @S9S_MB_2U_LIB.S9S_MB_2U(SCH_1):PAGE85
 R3878    1      A Q_RES_0402LF-49.9,1%,1/16W,CHIA   I180 @S9S_MB_2U_LIB.S9S_MB_2U(SCH_1):PAGE85

I3C_SPD_DDRABCD_CPU0_LVC1_SCL_4 @S9S_MB_2U_LIB.S9S_MB_2U(SCH_1):I3C_SPD_DDRABCD_CPU0_LVC1_SCL_R5
    J5    4   HSCL SCONN288_ADR50017P130CC-SCONN2A    I24 @S9S_MB_2U_LIB.S9S_MB_2U(SCH_1):PAGE86
 R3879    1      A Q_RES_0402LF-49.9,1%,1/16W,CHIA   I180 @S9S_MB_2U_LIB.S9S_MB_2U(SCH_1):PAGE86

I3C_SPD_DDRABCD_CPU0_LVC1_SCL_5 @S9S_MB_2U_LIB.S9S_MB_2U(SCH_1):I3C_SPD_DDRABCD_CPU0_LVC1_SCL_R6
    J6    4   HSCL SCONN288_ADR50017P087CC-SCONN2A    I46 @S9S_MB_2U_LIB.S9S_MB_2U(SCH_1):PAGE87
 R3880    1      A Q_RES_0402LF-49.9,1%,1/16W,CHIA   I180 @S9S_MB_2U_LIB.S9S_MB_2U(SCH_1):PAGE87

I3C_SPD_DDRABCD_CPU0_LVC1_SCL_6 @S9S_MB_2U_LIB.S9S_MB_2U(SCH_1):I3C_SPD_DDRABCD_CPU0_LVC1_SCL_R7
    J7    4   HSCL SCONN288_ADR50017P130CC-SCONN2A    I12 @S9S_MB_2U_LIB.S9S_MB_2U(SCH_1):PAGE88
 R3881    1      A Q_RES_0402LF-49.9,1%,1/16W,CHIA   I180 @S9S_MB_2U_LIB.S9S_MB_2U(SCH_1):PAGE88

I3C_SPD_DDRABCD_CPU0_LVC1_SCL_7 @S9S_MB_2U_LIB.S9S_MB_2U(SCH_1):I3C_SPD_DDRABCD_CPU0_LVC1_SCL_R8
    J8    4   HSCL SCONN288_ADR50017P087CC-SCONN2A    I50 @S9S_MB_2U_LIB.S9S_MB_2U(SCH_1):PAGE89
 R3882    1      A Q_RES_0402LF-49.9,1%,1/16W,CHIA   I180 @S9S_MB_2U_LIB.S9S_MB_2U(SCH_1):PAGE89

I3C_SPD_DDRABCD_CPU0_LVC1_SCL_R @S9S_MB_2U_LIB.S9S_MB_2U(SCH_1):I3C_SPD_DDRABCD_CPU0_LVC1_SCL_R1
    J1    4   HSCL SCONN288_ADR50017P130CC-SCONN2A   I198 @S9S_MB_2U_LIB.S9S_MB_2U(SCH_1):PAGE82
 R3875    1      A Q_RES_0402LF-49.9,1%,1/16W,CHIA   I204 @S9S_MB_2U_LIB.S9S_MB_2U(SCH_1):PAGE82

I3C_SPD_DDRABCD_CPU0_LVC1_SDA @S9S_MB_2U_LIB.S9S_MB_2U(SCH_1):I3C_SPD_DDRABCD_CPU0_LVC1_SDA
    J1    5   HSDA SCONN288_ADR50017P130CC-SCONN2A   I198 @S9S_MB_2U_LIB.S9S_MB_2U(SCH_1):PAGE82
    J2    5   HSDA SCONN288_ADR50017P087CC-SCONN2A   I177 @S9S_MB_2U_LIB.S9S_MB_2U(SCH_1):PAGE83
    J4    5   HSDA SCONN288_ADR50017P087CC-SCONN2A    I23 @S9S_MB_2U_LIB.S9S_MB_2U(SCH_1):PAGE85
    J5    5   HSDA SCONN288_ADR50017P130CC-SCONN2A    I24 @S9S_MB_2U_LIB.S9S_MB_2U(SCH_1):PAGE86
    J6    5   HSDA SCONN288_ADR50017P087CC-SCONN2A    I46 @S9S_MB_2U_LIB.S9S_MB_2U(SCH_1):PAGE87
    J7    5   HSDA SCONN288_ADR50017P130CC-SCONN2A    I12 @S9S_MB_2U_LIB.S9S_MB_2U(SCH_1):PAGE88
    J8    5   HSDA SCONN288_ADR50017P087CC-SCONN2A    I50 @S9S_MB_2U_LIB.S9S_MB_2U(SCH_1):PAGE89
    J3    5   HSDA SCONN288_ADR50017P130CC-SCONN2A   I180 @S9S_MB_2U_LIB.S9S_MB_2U(SCH_1):PAGE84
  R692    2      B Q_RES_0402LF-33.2,1%,1/16W,CHIA    I40 @S9S_MB_2U_LIB.S9S_MB_2U(SCH_1):PAGE217

I3C_SPD_DDRABCD_CPU0_R_SCL @S9S_MB_2U_LIB.S9S_MB_2U(SCH_1):I3C_SPD_DDRABCD_CPU0_R_SCL
   U15    2    I0A QS3VH257QG8_SMLF-QS3VH257QG8,IA    I19 @S9S_MB_2U_LIB.S9S_MB_2U(SCH_1):PAGE217
  R682    1      A Q_RES_0402LF-0,5%,1/16W,EMPTY,A    I20 @S9S_MB_2U_LIB.S9S_MB_2U(SCH_1):PAGE217
  R687    2      B Q_RES_0402LF-0,5%,1/16W,CHIP,CA    I34 @S9S_MB_2U_LIB.S9S_MB_2U(SCH_1):PAGE217

I3C_SPD_DDRABCD_CPU0_R_SDA @S9S_MB_2U_LIB.S9S_MB_2U(SCH_1):I3C_SPD_DDRABCD_CPU0_R_SDA
  R683    1      A Q_RES_0402LF-0,5%,1/16W,EMPTY,A    I18 @S9S_MB_2U_LIB.S9S_MB_2U(SCH_1):PAGE217
   U15    5    I0B QS3VH257QG8_SMLF-QS3VH257QG8,IA    I19 @S9S_MB_2U_LIB.S9S_MB_2U(SCH_1):PAGE217
  R688    2      B Q_RES_0402LF-33.2,1%,1/16W,CHIA    I35 @S9S_MB_2U_LIB.S9S_MB_2U(SCH_1):PAGE217

I3C_SPD_DDRABCD_CPU0_SCL @S9S_MB_2U_LIB.S9S_MB_2U(SCH_1):I3C_SPD_DDRABCD_CPU0_SCL
    U2 BT22 DDR0123_SPDSCL SOCKET4677_AZIF0045P001C01CS-SA    I57 @S9S_MB_2U_LIB.S9S_MB_2U(SCH_1):PAGE13
  R679    2      B Q_RES_0402LF-499,1%,1/16W,CHIPA    I29 @S9S_MB_2U_LIB.S9S_MB_2U(SCH_1):PAGE217
  R687    1      A Q_RES_0402LF-0,5%,1/16W,CHIP,CA    I34 @S9S_MB_2U_LIB.S9S_MB_2U(SCH_1):PAGE217

I3C_SPD_DDRABCD_CPU0_SDA @S9S_MB_2U_LIB.S9S_MB_2U(SCH_1):I3C_SPD_DDRABCD_CPU0_SDA
    U2 BY22 DDR0123_SPDSDA SOCKET4677_AZIF0045P001C01CS-SA    I57 @S9S_MB_2U_LIB.S9S_MB_2U(SCH_1):PAGE13
  R680    2      B Q_RES_0402LF-499,1%,1/16W,CHIPA    I30 @S9S_MB_2U_LIB.S9S_MB_2U(SCH_1):PAGE217
  R688    1      A Q_RES_0402LF-33.2,1%,1/16W,CHIA    I35 @S9S_MB_2U_LIB.S9S_MB_2U(SCH_1):PAGE217

I3C_SPD_DDRABCD_CPU1_BMC_R_SCL @S9S_MB_2U_LIB.S9S_MB_2U(SCH_1):I3C_SPD_DDRABCD_CPU1_BMC_R_SCL
  R597    1      A Q_RES_0402LF-0,5%,1/16W,CHIP,CA   I316 @S9S_MB_2U_LIB.S9S_MB_2U(SCH_1):PAGE228
   J41  OA9 RBT_TXD0 SCONN168_ME1016810202011-SCONNA   I173 @S9S_MB_2U_LIB.S9S_MB_2U(SCH_1):PAGE227

I3C_SPD_DDRABCD_CPU1_BMC_R_SDA @S9S_MB_2U_LIB.S9S_MB_2U(SCH_1):I3C_SPD_DDRABCD_CPU1_BMC_R_SDA
  R598    1      A Q_RES_0402LF-0,5%,1/16W,CHIP,CA   I315 @S9S_MB_2U_LIB.S9S_MB_2U(SCH_1):PAGE228
   J41 OA10 GND_OA10 SCONN168_ME1016810202011-SCONNA   I173 @S9S_MB_2U_LIB.S9S_MB_2U(SCH_1):PAGE227

I3C_SPD_DDRABCD_CPU1_BMC_SCL @S9S_MB_2U_LIB.S9S_MB_2U(SCH_1):I3C_SPD_DDRABCD_CPU1_BMC_SCL
  R597    2      B Q_RES_0402LF-0,5%,1/16W,CHIP,CA   I316 @S9S_MB_2U_LIB.S9S_MB_2U(SCH_1):PAGE228
   U14    3    I1A QS3VH257QG8_SMLF-QS3VH257QG8,IA    I12 @S9S_MB_2U_LIB.S9S_MB_2U(SCH_1):PAGE218

I3C_SPD_DDRABCD_CPU1_BMC_SDA @S9S_MB_2U_LIB.S9S_MB_2U(SCH_1):I3C_SPD_DDRABCD_CPU1_BMC_SDA
  R598    2      B Q_RES_0402LF-0,5%,1/16W,CHIP,CA   I315 @S9S_MB_2U_LIB.S9S_MB_2U(SCH_1):PAGE228
   U14    6    I1B QS3VH257QG8_SMLF-QS3VH257QG8,IA    I12 @S9S_MB_2U_LIB.S9S_MB_2U(SCH_1):PAGE218

I3C_SPD_DDRABCD_CPU1_LVC1_R_SCL @S9S_MB_2U_LIB.S9S_MB_2U(SCH_1):I3C_SPD_DDRABCD_CPU1_LVC1_R_SCL
   U14    4     YA QS3VH257QG8_SMLF-QS3VH257QG8,IA    I12 @S9S_MB_2U_LIB.S9S_MB_2U(SCH_1):PAGE218
  R665    2      B Q_RES_0402LF-0,5%,1/16W,EMPTY,A    I23 @S9S_MB_2U_LIB.S9S_MB_2U(SCH_1):PAGE218
  R674    1      A Q_RES_0402LF-0,5%,1/16W,CHIP,CA    I37 @S9S_MB_2U_LIB.S9S_MB_2U(SCH_1):PAGE218

I3C_SPD_DDRABCD_CPU1_LVC1_R_SDA @S9S_MB_2U_LIB.S9S_MB_2U(SCH_1):I3C_SPD_DDRABCD_CPU1_LVC1_R_SDA
  R666    2      B Q_RES_0402LF-0,5%,1/16W,EMPTY,A    I22 @S9S_MB_2U_LIB.S9S_MB_2U(SCH_1):PAGE218
   U14    7     YB QS3VH257QG8_SMLF-QS3VH257QG8,IA    I12 @S9S_MB_2U_LIB.S9S_MB_2U(SCH_1):PAGE218
  R675    1      A Q_RES_0402LF-33.2,1%,1/16W,CHIA    I36 @S9S_MB_2U_LIB.S9S_MB_2U(SCH_1):PAGE218

I3C_SPD_DDRABCD_CPU1_LVC1_SCL @S9S_MB_2U_LIB.S9S_MB_2U(SCH_1):I3C_SPD_DDRABCD_CPU1_LVC1_SCL
 R3891    2      B Q_RES_0402LF-49.9,1%,1/16W,CHIA   I179 @S9S_MB_2U_LIB.S9S_MB_2U(SCH_1):PAGE98
 R3892    2      B Q_RES_0402LF-49.9,1%,1/16W,CHIA   I180 @S9S_MB_2U_LIB.S9S_MB_2U(SCH_1):PAGE99
 R3893    2      B Q_RES_0402LF-49.9,1%,1/16W,CHIA   I180 @S9S_MB_2U_LIB.S9S_MB_2U(SCH_1):PAGE100
 R3894    2      B Q_RES_0402LF-49.9,1%,1/16W,CHIA   I180 @S9S_MB_2U_LIB.S9S_MB_2U(SCH_1):PAGE101
 R3895    2      B Q_RES_0402LF-49.9,1%,1/16W,CHIA   I180 @S9S_MB_2U_LIB.S9S_MB_2U(SCH_1):PAGE102
 R3896    2      B Q_RES_0402LF-49.9,1%,1/16W,CHIA   I180 @S9S_MB_2U_LIB.S9S_MB_2U(SCH_1):PAGE103
 R3897    2      B Q_RES_0402LF-49.9,1%,1/16W,CHIA   I180 @S9S_MB_2U_LIB.S9S_MB_2U(SCH_1):PAGE104
 R3898    2      B Q_RES_0402LF-49.9,1%,1/16W,CHIA   I183 @S9S_MB_2U_LIB.S9S_MB_2U(SCH_1):PAGE105
  R674    2      B Q_RES_0402LF-0,5%,1/16W,CHIP,CA    I37 @S9S_MB_2U_LIB.S9S_MB_2U(SCH_1):PAGE218

I3C_SPD_DDRABCD_CPU1_LVC1_SCL_1 @S9S_MB_2U_LIB.S9S_MB_2U(SCH_1):I3C_SPD_DDRABCD_CPU1_LVC1_SCL_R2
   J18    4   HSCL SCONN288_ADR50017P087CC-SCONN2A    I24 @S9S_MB_2U_LIB.S9S_MB_2U(SCH_1):PAGE99
 R3892    1      A Q_RES_0402LF-49.9,1%,1/16W,CHIA   I180 @S9S_MB_2U_LIB.S9S_MB_2U(SCH_1):PAGE99

I3C_SPD_DDRABCD_CPU1_LVC1_SCL_2 @S9S_MB_2U_LIB.S9S_MB_2U(SCH_1):I3C_SPD_DDRABCD_CPU1_LVC1_SCL_R3
   J19    4   HSCL SCONN288_ADR50017P130CC-SCONN2A    I25 @S9S_MB_2U_LIB.S9S_MB_2U(SCH_1):PAGE100
 R3893    1      A Q_RES_0402LF-49.9,1%,1/16W,CHIA   I180 @S9S_MB_2U_LIB.S9S_MB_2U(SCH_1):PAGE100

I3C_SPD_DDRABCD_CPU1_LVC1_SCL_3 @S9S_MB_2U_LIB.S9S_MB_2U(SCH_1):I3C_SPD_DDRABCD_CPU1_LVC1_SCL_R4
   J20    4   HSCL SCONN288_ADR50017P087CC-SCONN2A    I47 @S9S_MB_2U_LIB.S9S_MB_2U(SCH_1):PAGE101
 R3894    1      A Q_RES_0402LF-49.9,1%,1/16W,CHIA   I180 @S9S_MB_2U_LIB.S9S_MB_2U(SCH_1):PAGE101

I3C_SPD_DDRABCD_CPU1_LVC1_SCL_4 @S9S_MB_2U_LIB.S9S_MB_2U(SCH_1):I3C_SPD_DDRABCD_CPU1_LVC1_SCL_R5
   J21    4   HSCL SCONN288_ADR50017P130CC-SCONN2A    I13 @S9S_MB_2U_LIB.S9S_MB_2U(SCH_1):PAGE102
 R3895    1      A Q_RES_0402LF-49.9,1%,1/16W,CHIA   I180 @S9S_MB_2U_LIB.S9S_MB_2U(SCH_1):PAGE102

I3C_SPD_DDRABCD_CPU1_LVC1_SCL_5 @S9S_MB_2U_LIB.S9S_MB_2U(SCH_1):I3C_SPD_DDRABCD_CPU1_LVC1_SCL_R6
   J22    4   HSCL SCONN288_ADR50017P087CC-SCONN2A    I51 @S9S_MB_2U_LIB.S9S_MB_2U(SCH_1):PAGE103
 R3896    1      A Q_RES_0402LF-49.9,1%,1/16W,CHIA   I180 @S9S_MB_2U_LIB.S9S_MB_2U(SCH_1):PAGE103

I3C_SPD_DDRABCD_CPU1_LVC1_SCL_6 @S9S_MB_2U_LIB.S9S_MB_2U(SCH_1):I3C_SPD_DDRABCD_CPU1_LVC1_SCL_R7
   J23    4   HSCL SCONN288_ADR50017P130CC-SCONN2A    I25 @S9S_MB_2U_LIB.S9S_MB_2U(SCH_1):PAGE104
 R3897    1      A Q_RES_0402LF-49.9,1%,1/16W,CHIA   I180 @S9S_MB_2U_LIB.S9S_MB_2U(SCH_1):PAGE104

I3C_SPD_DDRABCD_CPU1_LVC1_SCL_7 @S9S_MB_2U_LIB.S9S_MB_2U(SCH_1):I3C_SPD_DDRABCD_CPU1_LVC1_SCL_R8
   J24    4   HSCL SCONN288_ADR50017P087CC-SCONN2A   I178 @S9S_MB_2U_LIB.S9S_MB_2U(SCH_1):PAGE105
 R3898    1      A Q_RES_0402LF-49.9,1%,1/16W,CHIA   I183 @S9S_MB_2U_LIB.S9S_MB_2U(SCH_1):PAGE105

I3C_SPD_DDRABCD_CPU1_LVC1_SCL_R @S9S_MB_2U_LIB.S9S_MB_2U(SCH_1):I3C_SPD_DDRABCD_CPU1_LVC1_SCL_R1
   J17    4   HSCL SCONN288_ADR50017P130CC-SCONN2A    I12 @S9S_MB_2U_LIB.S9S_MB_2U(SCH_1):PAGE98
 R3891    1      A Q_RES_0402LF-49.9,1%,1/16W,CHIA   I179 @S9S_MB_2U_LIB.S9S_MB_2U(SCH_1):PAGE98

I3C_SPD_DDRABCD_CPU1_LVC1_SDA @S9S_MB_2U_LIB.S9S_MB_2U(SCH_1):I3C_SPD_DDRABCD_CPU1_LVC1_SDA
   J17    5   HSDA SCONN288_ADR50017P130CC-SCONN2A    I12 @S9S_MB_2U_LIB.S9S_MB_2U(SCH_1):PAGE98
   J18    5   HSDA SCONN288_ADR50017P087CC-SCONN2A    I24 @S9S_MB_2U_LIB.S9S_MB_2U(SCH_1):PAGE99
   J19    5   HSDA SCONN288_ADR50017P130CC-SCONN2A    I25 @S9S_MB_2U_LIB.S9S_MB_2U(SCH_1):PAGE100
   J20    5   HSDA SCONN288_ADR50017P087CC-SCONN2A    I47 @S9S_MB_2U_LIB.S9S_MB_2U(SCH_1):PAGE101
   J21    5   HSDA SCONN288_ADR50017P130CC-SCONN2A    I13 @S9S_MB_2U_LIB.S9S_MB_2U(SCH_1):PAGE102
   J22    5   HSDA SCONN288_ADR50017P087CC-SCONN2A    I51 @S9S_MB_2U_LIB.S9S_MB_2U(SCH_1):PAGE103
   J23    5   HSDA SCONN288_ADR50017P130CC-SCONN2A    I25 @S9S_MB_2U_LIB.S9S_MB_2U(SCH_1):PAGE104
   J24    5   HSDA SCONN288_ADR50017P087CC-SCONN2A   I178 @S9S_MB_2U_LIB.S9S_MB_2U(SCH_1):PAGE105
  R675    2      B Q_RES_0402LF-33.2,1%,1/16W,CHIA    I36 @S9S_MB_2U_LIB.S9S_MB_2U(SCH_1):PAGE218

I3C_SPD_DDRABCD_CPU1_R_SCL @S9S_MB_2U_LIB.S9S_MB_2U(SCH_1):I3C_SPD_DDRABCD_CPU1_R_SCL
  R670    2      B Q_RES_0402LF-0,5%,1/16W,CHIP,CA    I32 @S9S_MB_2U_LIB.S9S_MB_2U(SCH_1):PAGE218
   U14    2    I0A QS3VH257QG8_SMLF-QS3VH257QG8,IA    I12 @S9S_MB_2U_LIB.S9S_MB_2U(SCH_1):PAGE218
  R665    1      A Q_RES_0402LF-0,5%,1/16W,EMPTY,A    I23 @S9S_MB_2U_LIB.S9S_MB_2U(SCH_1):PAGE218

I3C_SPD_DDRABCD_CPU1_R_SDA @S9S_MB_2U_LIB.S9S_MB_2U(SCH_1):I3C_SPD_DDRABCD_CPU1_R_SDA
  R666    1      A Q_RES_0402LF-0,5%,1/16W,EMPTY,A    I22 @S9S_MB_2U_LIB.S9S_MB_2U(SCH_1):PAGE218
  R671    2      B Q_RES_0402LF-33.2,1%,1/16W,CHIA    I33 @S9S_MB_2U_LIB.S9S_MB_2U(SCH_1):PAGE218
   U14    5    I0B QS3VH257QG8_SMLF-QS3VH257QG8,IA    I12 @S9S_MB_2U_LIB.S9S_MB_2U(SCH_1):PAGE218

I3C_SPD_DDRABCD_CPU1_SCL @S9S_MB_2U_LIB.S9S_MB_2U(SCH_1):I3C_SPD_DDRABCD_CPU1_SCL
    U1 BT22 DDR0123_SPDSCL SOCKET4677_AZIF0045P001C01CS-SA    I51 @S9S_MB_2U_LIB.S9S_MB_2U(SCH_1):PAGE44
  R670    1      A Q_RES_0402LF-0,5%,1/16W,CHIP,CA    I32 @S9S_MB_2U_LIB.S9S_MB_2U(SCH_1):PAGE218
  R662    2      B Q_RES_0402LF-499,1%,1/16W,CHIPA    I17 @S9S_MB_2U_LIB.S9S_MB_2U(SCH_1):PAGE218

I3C_SPD_DDRABCD_CPU1_SDA @S9S_MB_2U_LIB.S9S_MB_2U(SCH_1):I3C_SPD_DDRABCD_CPU1_SDA
    U1 BY22 DDR0123_SPDSDA SOCKET4677_AZIF0045P001C01CS-SA    I51 @S9S_MB_2U_LIB.S9S_MB_2U(SCH_1):PAGE44
  R663    2      B Q_RES_0402LF-499,1%,1/16W,CHIPA    I18 @S9S_MB_2U_LIB.S9S_MB_2U(SCH_1):PAGE218
  R671    1      A Q_RES_0402LF-33.2,1%,1/16W,CHIA    I33 @S9S_MB_2U_LIB.S9S_MB_2U(SCH_1):PAGE218

I3C_SPD_DDREFGH_CPU0_BMC_R_SCL @S9S_MB_2U_LIB.S9S_MB_2U(SCH_1):I3C_SPD_DDREFGH_CPU0_BMC_R_SCL
  R595    1      A Q_RES_0402LF-0,5%,1/16W,CHIP,CA   I314 @S9S_MB_2U_LIB.S9S_MB_2U(SCH_1):PAGE228
   J41  OA7 RBT_TX_EN SCONN168_ME1016810202011-SCONNA   I173 @S9S_MB_2U_LIB.S9S_MB_2U(SCH_1):PAGE227

I3C_SPD_DDREFGH_CPU0_BMC_R_SDA @S9S_MB_2U_LIB.S9S_MB_2U(SCH_1):I3C_SPD_DDREFGH_CPU0_BMC_R_SDA
  R596    1      A Q_RES_0402LF-0,5%,1/16W,CHIP,CA   I313 @S9S_MB_2U_LIB.S9S_MB_2U(SCH_1):PAGE228
   J41  OA8 RBT_TXD1 SCONN168_ME1016810202011-SCONNA   I173 @S9S_MB_2U_LIB.S9S_MB_2U(SCH_1):PAGE227

I3C_SPD_DDREFGH_CPU0_BMC_SCL @S9S_MB_2U_LIB.S9S_MB_2U(SCH_1):I3C_SPD_DDREFGH_CPU0_BMC_SCL
  R595    2      B Q_RES_0402LF-0,5%,1/16W,CHIP,CA   I314 @S9S_MB_2U_LIB.S9S_MB_2U(SCH_1):PAGE228
   U15   10    I1C QS3VH257QG8_SMLF-QS3VH257QG8,IA    I19 @S9S_MB_2U_LIB.S9S_MB_2U(SCH_1):PAGE217

I3C_SPD_DDREFGH_CPU0_BMC_SDA @S9S_MB_2U_LIB.S9S_MB_2U(SCH_1):I3C_SPD_DDREFGH_CPU0_BMC_SDA
  R596    2      B Q_RES_0402LF-0,5%,1/16W,CHIP,CA   I313 @S9S_MB_2U_LIB.S9S_MB_2U(SCH_1):PAGE228
   U15   13    I1D QS3VH257QG8_SMLF-QS3VH257QG8,IA    I19 @S9S_MB_2U_LIB.S9S_MB_2U(SCH_1):PAGE217

I3C_SPD_DDREFGH_CPU0_LVC1_R_SCL @S9S_MB_2U_LIB.S9S_MB_2U(SCH_1):I3C_SPD_DDREFGH_CPU0_LVC1_R_SCL
  R684    2      B Q_RES_0402LF-0,5%,1/16W,EMPTY,A    I17 @S9S_MB_2U_LIB.S9S_MB_2U(SCH_1):PAGE217
   U15    9     YC QS3VH257QG8_SMLF-QS3VH257QG8,IA    I19 @S9S_MB_2U_LIB.S9S_MB_2U(SCH_1):PAGE217
  R693    1      A Q_RES_0402LF-0,5%,1/16W,CHIP,CA    I38 @S9S_MB_2U_LIB.S9S_MB_2U(SCH_1):PAGE217

I3C_SPD_DDREFGH_CPU0_LVC1_R_SDA @S9S_MB_2U_LIB.S9S_MB_2U(SCH_1):I3C_SPD_DDREFGH_CPU0_LVC1_R_SDA
  R685    2      B Q_RES_0402LF-0,5%,1/16W,EMPTY,A    I16 @S9S_MB_2U_LIB.S9S_MB_2U(SCH_1):PAGE217
   U15   12     YD QS3VH257QG8_SMLF-QS3VH257QG8,IA    I19 @S9S_MB_2U_LIB.S9S_MB_2U(SCH_1):PAGE217
  R694    1      A Q_RES_0402LF-33.2,1%,1/16W,CHIA    I37 @S9S_MB_2U_LIB.S9S_MB_2U(SCH_1):PAGE217

I3C_SPD_DDREFGH_CPU0_LVC1_SCL @S9S_MB_2U_LIB.S9S_MB_2U(SCH_1):I3C_SPD_DDREFGH_CPU0_LVC1_SCL
 R3883    2      B Q_RES_0402LF-49.9,1%,1/16W,CHIA   I179 @S9S_MB_2U_LIB.S9S_MB_2U(SCH_1):PAGE90
 R3884    2      B Q_RES_0402LF-49.9,1%,1/16W,CHIA   I179 @S9S_MB_2U_LIB.S9S_MB_2U(SCH_1):PAGE91
 R3885    2      B Q_RES_0402LF-49.9,1%,1/16W,CHIA   I179 @S9S_MB_2U_LIB.S9S_MB_2U(SCH_1):PAGE92
 R3886    2      B Q_RES_0402LF-49.9,1%,1/16W,CHIA   I179 @S9S_MB_2U_LIB.S9S_MB_2U(SCH_1):PAGE93
 R3887    2      B Q_RES_0402LF-49.9,1%,1/16W,CHIA   I179 @S9S_MB_2U_LIB.S9S_MB_2U(SCH_1):PAGE94
 R3888    2      B Q_RES_0402LF-49.9,1%,1/16W,CHIA   I179 @S9S_MB_2U_LIB.S9S_MB_2U(SCH_1):PAGE95
 R3889    2      B Q_RES_0402LF-49.9,1%,1/16W,CHIA   I179 @S9S_MB_2U_LIB.S9S_MB_2U(SCH_1):PAGE96
 R3890    2      B Q_RES_0402LF-49.9,1%,1/16W,CHIA   I179 @S9S_MB_2U_LIB.S9S_MB_2U(SCH_1):PAGE97
  R693    2      B Q_RES_0402LF-0,5%,1/16W,CHIP,CA    I38 @S9S_MB_2U_LIB.S9S_MB_2U(SCH_1):PAGE217

I3C_SPD_DDREFGH_CPU0_LVC1_SCL_1 @S9S_MB_2U_LIB.S9S_MB_2U(SCH_1):I3C_SPD_DDREFGH_CPU0_LVC1_SCL_R2
   J10    4   HSCL SCONN288_ADR50017P087CC-SCONN2A    I13 @S9S_MB_2U_LIB.S9S_MB_2U(SCH_1):PAGE91
 R3884    1      A Q_RES_0402LF-49.9,1%,1/16W,CHIA   I179 @S9S_MB_2U_LIB.S9S_MB_2U(SCH_1):PAGE91

I3C_SPD_DDREFGH_CPU0_LVC1_SCL_2 @S9S_MB_2U_LIB.S9S_MB_2U(SCH_1):I3C_SPD_DDREFGH_CPU0_LVC1_SCL_R3
   J11    4   HSCL SCONN288_ADR50017P130CC-SCONN2A    I25 @S9S_MB_2U_LIB.S9S_MB_2U(SCH_1):PAGE92
 R3885    1      A Q_RES_0402LF-49.9,1%,1/16W,CHIA   I179 @S9S_MB_2U_LIB.S9S_MB_2U(SCH_1):PAGE92

I3C_SPD_DDREFGH_CPU0_LVC1_SCL_3 @S9S_MB_2U_LIB.S9S_MB_2U(SCH_1):I3C_SPD_DDREFGH_CPU0_LVC1_SCL_R4
   J12    4   HSCL SCONN288_ADR50017P087CC-SCONN2A    I24 @S9S_MB_2U_LIB.S9S_MB_2U(SCH_1):PAGE93
 R3886    1      A Q_RES_0402LF-49.9,1%,1/16W,CHIA   I179 @S9S_MB_2U_LIB.S9S_MB_2U(SCH_1):PAGE93

I3C_SPD_DDREFGH_CPU0_LVC1_SCL_4 @S9S_MB_2U_LIB.S9S_MB_2U(SCH_1):I3C_SPD_DDREFGH_CPU0_LVC1_SCL_R5
   J13    4   HSCL SCONN288_ADR50017P130CC-SCONN2A    I11 @S9S_MB_2U_LIB.S9S_MB_2U(SCH_1):PAGE94
 R3887    1      A Q_RES_0402LF-49.9,1%,1/16W,CHIA   I179 @S9S_MB_2U_LIB.S9S_MB_2U(SCH_1):PAGE94

I3C_SPD_DDREFGH_CPU0_LVC1_SCL_5 @S9S_MB_2U_LIB.S9S_MB_2U(SCH_1):I3C_SPD_DDREFGH_CPU0_LVC1_SCL_R6
   J14    4   HSCL SCONN288_ADR50017P087CC-SCONN2A    I47 @S9S_MB_2U_LIB.S9S_MB_2U(SCH_1):PAGE95
 R3888    1      A Q_RES_0402LF-49.9,1%,1/16W,CHIA   I179 @S9S_MB_2U_LIB.S9S_MB_2U(SCH_1):PAGE95

I3C_SPD_DDREFGH_CPU0_LVC1_SCL_6 @S9S_MB_2U_LIB.S9S_MB_2U(SCH_1):I3C_SPD_DDREFGH_CPU0_LVC1_SCL_R7
   J15    4   HSCL SCONN288_ADR50017P130CC-SCONN2A    I48 @S9S_MB_2U_LIB.S9S_MB_2U(SCH_1):PAGE96
 R3889    1      A Q_RES_0402LF-49.9,1%,1/16W,CHIA   I179 @S9S_MB_2U_LIB.S9S_MB_2U(SCH_1):PAGE96

I3C_SPD_DDREFGH_CPU0_LVC1_SCL_7 @S9S_MB_2U_LIB.S9S_MB_2U(SCH_1):I3C_SPD_DDREFGH_CPU0_LVC1_SCL_R8
   J16    4   HSCL SCONN288_ADR50017P087CC-SCONN2A     I6 @S9S_MB_2U_LIB.S9S_MB_2U(SCH_1):PAGE97
 R3890    1      A Q_RES_0402LF-49.9,1%,1/16W,CHIA   I179 @S9S_MB_2U_LIB.S9S_MB_2U(SCH_1):PAGE97

I3C_SPD_DDREFGH_CPU0_LVC1_SCL_R @S9S_MB_2U_LIB.S9S_MB_2U(SCH_1):I3C_SPD_DDREFGH_CPU0_LVC1_SCL_R1
    J9    4   HSCL SCONN288_ADR50017P130CC-SCONN2A    I12 @S9S_MB_2U_LIB.S9S_MB_2U(SCH_1):PAGE90
 R3883    1      A Q_RES_0402LF-49.9,1%,1/16W,CHIA   I179 @S9S_MB_2U_LIB.S9S_MB_2U(SCH_1):PAGE90

I3C_SPD_DDREFGH_CPU0_LVC1_SDA @S9S_MB_2U_LIB.S9S_MB_2U(SCH_1):I3C_SPD_DDREFGH_CPU0_LVC1_SDA
    J9    5   HSDA SCONN288_ADR50017P130CC-SCONN2A    I12 @S9S_MB_2U_LIB.S9S_MB_2U(SCH_1):PAGE90
   J10    5   HSDA SCONN288_ADR50017P087CC-SCONN2A    I13 @S9S_MB_2U_LIB.S9S_MB_2U(SCH_1):PAGE91
   J11    5   HSDA SCONN288_ADR50017P130CC-SCONN2A    I25 @S9S_MB_2U_LIB.S9S_MB_2U(SCH_1):PAGE92
   J12    5   HSDA SCONN288_ADR50017P087CC-SCONN2A    I24 @S9S_MB_2U_LIB.S9S_MB_2U(SCH_1):PAGE93
   J13    5   HSDA SCONN288_ADR50017P130CC-SCONN2A    I11 @S9S_MB_2U_LIB.S9S_MB_2U(SCH_1):PAGE94
   J14    5   HSDA SCONN288_ADR50017P087CC-SCONN2A    I47 @S9S_MB_2U_LIB.S9S_MB_2U(SCH_1):PAGE95
   J15    5   HSDA SCONN288_ADR50017P130CC-SCONN2A    I48 @S9S_MB_2U_LIB.S9S_MB_2U(SCH_1):PAGE96
   J16    5   HSDA SCONN288_ADR50017P087CC-SCONN2A     I6 @S9S_MB_2U_LIB.S9S_MB_2U(SCH_1):PAGE97
  R694    2      B Q_RES_0402LF-33.2,1%,1/16W,CHIA    I37 @S9S_MB_2U_LIB.S9S_MB_2U(SCH_1):PAGE217

I3C_SPD_DDREFGH_CPU0_R_SCL @S9S_MB_2U_LIB.S9S_MB_2U(SCH_1):I3C_SPD_DDREFGH_CPU0_R_SCL
  R684    1      A Q_RES_0402LF-0,5%,1/16W,EMPTY,A    I17 @S9S_MB_2U_LIB.S9S_MB_2U(SCH_1):PAGE217
   U15   11    I0C QS3VH257QG8_SMLF-QS3VH257QG8,IA    I19 @S9S_MB_2U_LIB.S9S_MB_2U(SCH_1):PAGE217
  R689    2      B Q_RES_0402LF-0,5%,1/16W,CHIP,CA    I25 @S9S_MB_2U_LIB.S9S_MB_2U(SCH_1):PAGE217

I3C_SPD_DDREFGH_CPU0_R_SDA @S9S_MB_2U_LIB.S9S_MB_2U(SCH_1):I3C_SPD_DDREFGH_CPU0_R_SDA
  R685    1      A Q_RES_0402LF-0,5%,1/16W,EMPTY,A    I16 @S9S_MB_2U_LIB.S9S_MB_2U(SCH_1):PAGE217
   U15   14    I0D QS3VH257QG8_SMLF-QS3VH257QG8,IA    I19 @S9S_MB_2U_LIB.S9S_MB_2U(SCH_1):PAGE217
  R690    2      B Q_RES_0402LF-33.2,1%,1/16W,CHIA    I26 @S9S_MB_2U_LIB.S9S_MB_2U(SCH_1):PAGE217

I3C_SPD_DDREFGH_CPU0_SCL @S9S_MB_2U_LIB.S9S_MB_2U(SCH_1):I3C_SPD_DDREFGH_CPU0_SCL
    U2 CU17 DDR4567_SPDSCL SOCKET4677_AZIF0045P001C01CS-SA    I57 @S9S_MB_2U_LIB.S9S_MB_2U(SCH_1):PAGE13
  R689    1      A Q_RES_0402LF-0,5%,1/16W,CHIP,CA    I25 @S9S_MB_2U_LIB.S9S_MB_2U(SCH_1):PAGE217
  R681    2      B Q_RES_0402LF-499,1%,1/16W,CHIPA    I32 @S9S_MB_2U_LIB.S9S_MB_2U(SCH_1):PAGE217

I3C_SPD_DDREFGH_CPU0_SDA @S9S_MB_2U_LIB.S9S_MB_2U(SCH_1):I3C_SPD_DDREFGH_CPU0_SDA
    U2 CT18 DDR4567_SPDSDA SOCKET4677_AZIF0045P001C01CS-SA    I57 @S9S_MB_2U_LIB.S9S_MB_2U(SCH_1):PAGE13
  R690    1      A Q_RES_0402LF-33.2,1%,1/16W,CHIA    I26 @S9S_MB_2U_LIB.S9S_MB_2U(SCH_1):PAGE217
  R686    2      B Q_RES_0402LF-499,1%,1/16W,CHIPA    I33 @S9S_MB_2U_LIB.S9S_MB_2U(SCH_1):PAGE217

I3C_SPD_DDREFGH_CPU1_BMC_R_SCL @S9S_MB_2U_LIB.S9S_MB_2U(SCH_1):I3C_SPD_DDREFGH_CPU1_BMC_R_SCL
  R599    1      A Q_RES_0402LF-0,5%,1/16W,CHIP,CA   I317 @S9S_MB_2U_LIB.S9S_MB_2U(SCH_1):PAGE228
   J41 OA11 REFCLKN3 SCONN168_ME1016810202011-SCONNA   I173 @S9S_MB_2U_LIB.S9S_MB_2U(SCH_1):PAGE227

I3C_SPD_DDREFGH_CPU1_BMC_R_SDA @S9S_MB_2U_LIB.S9S_MB_2U(SCH_1):I3C_SPD_DDREFGH_CPU1_BMC_R_SDA
  R600    1      A Q_RES_0402LF-0,5%,1/16W,CHIP,CA   I318 @S9S_MB_2U_LIB.S9S_MB_2U(SCH_1):PAGE228
   J41 OA12 REFCLKP3 SCONN168_ME1016810202011-SCONNA   I173 @S9S_MB_2U_LIB.S9S_MB_2U(SCH_1):PAGE227

I3C_SPD_DDREFGH_CPU1_BMC_SCL @S9S_MB_2U_LIB.S9S_MB_2U(SCH_1):I3C_SPD_DDREFGH_CPU1_BMC_SCL
  R599    2      B Q_RES_0402LF-0,5%,1/16W,CHIP,CA   I317 @S9S_MB_2U_LIB.S9S_MB_2U(SCH_1):PAGE228
   U14   10    I1C QS3VH257QG8_SMLF-QS3VH257QG8,IA    I12 @S9S_MB_2U_LIB.S9S_MB_2U(SCH_1):PAGE218

I3C_SPD_DDREFGH_CPU1_BMC_SDA @S9S_MB_2U_LIB.S9S_MB_2U(SCH_1):I3C_SPD_DDREFGH_CPU1_BMC_SDA
  R600    2      B Q_RES_0402LF-0,5%,1/16W,CHIP,CA   I318 @S9S_MB_2U_LIB.S9S_MB_2U(SCH_1):PAGE228
   U14   13    I1D QS3VH257QG8_SMLF-QS3VH257QG8,IA    I12 @S9S_MB_2U_LIB.S9S_MB_2U(SCH_1):PAGE218

I3C_SPD_DDREFGH_CPU1_LVC1_R_SCL @S9S_MB_2U_LIB.S9S_MB_2U(SCH_1):I3C_SPD_DDREFGH_CPU1_LVC1_R_SCL
   U14    9     YC QS3VH257QG8_SMLF-QS3VH257QG8,IA    I12 @S9S_MB_2U_LIB.S9S_MB_2U(SCH_1):PAGE218
  R667    2      B Q_RES_0402LF-0,5%,1/16W,EMPTY,A    I21 @S9S_MB_2U_LIB.S9S_MB_2U(SCH_1):PAGE218
  R676    1      A Q_RES_0402LF-0,5%,1/16W,CHIP,CA    I35 @S9S_MB_2U_LIB.S9S_MB_2U(SCH_1):PAGE218

I3C_SPD_DDREFGH_CPU1_LVC1_R_SDA @S9S_MB_2U_LIB.S9S_MB_2U(SCH_1):I3C_SPD_DDREFGH_CPU1_LVC1_R_SDA
   U14   12     YD QS3VH257QG8_SMLF-QS3VH257QG8,IA    I12 @S9S_MB_2U_LIB.S9S_MB_2U(SCH_1):PAGE218
  R668    2      B Q_RES_0402LF-0,5%,1/16W,EMPTY,A    I20 @S9S_MB_2U_LIB.S9S_MB_2U(SCH_1):PAGE218
  R677    1      A Q_RES_0402LF-33.2,1%,1/16W,CHIA    I34 @S9S_MB_2U_LIB.S9S_MB_2U(SCH_1):PAGE218

I3C_SPD_DDREFGH_CPU1_LVC1_SCL @S9S_MB_2U_LIB.S9S_MB_2U(SCH_1):I3C_SPD_DDREFGH_CPU1_LVC1_SCL
 R3899    2      B Q_RES_0402LF-49.9,1%,1/16W,CHIA   I183 @S9S_MB_2U_LIB.S9S_MB_2U(SCH_1):PAGE106
 R3900    2      B Q_RES_0402LF-49.9,1%,1/16W,CHIA   I183 @S9S_MB_2U_LIB.S9S_MB_2U(SCH_1):PAGE107
 R3901    2      B Q_RES_0402LF-49.9,1%,1/16W,CHIA   I182 @S9S_MB_2U_LIB.S9S_MB_2U(SCH_1):PAGE108
 R3902    2      B Q_RES_0402LF-49.9,1%,1/16W,CHIA   I180 @S9S_MB_2U_LIB.S9S_MB_2U(SCH_1):PAGE109
 R3903    2      B Q_RES_0402LF-49.9,1%,1/16W,CHIA   I182 @S9S_MB_2U_LIB.S9S_MB_2U(SCH_1):PAGE110
 R3904    2      B Q_RES_0402LF-49.9,1%,1/16W,CHIA   I182 @S9S_MB_2U_LIB.S9S_MB_2U(SCH_1):PAGE111
 R3905    2      B Q_RES_0402LF-49.9,1%,1/16W,CHIA   I183 @S9S_MB_2U_LIB.S9S_MB_2U(SCH_1):PAGE112
 R3906    2      B Q_RES_0402LF-49.9,1%,1/16W,CHIA   I182 @S9S_MB_2U_LIB.S9S_MB_2U(SCH_1):PAGE113
  R676    2      B Q_RES_0402LF-0,5%,1/16W,CHIP,CA    I35 @S9S_MB_2U_LIB.S9S_MB_2U(SCH_1):PAGE218

I3C_SPD_DDREFGH_CPU1_LVC1_SCL_1 @S9S_MB_2U_LIB.S9S_MB_2U(SCH_1):I3C_SPD_DDREFGH_CPU1_LVC1_SCL_R2
   J26    4   HSCL SCONN288_ADR50017P087CC-SCONN2A   I180 @S9S_MB_2U_LIB.S9S_MB_2U(SCH_1):PAGE107
 R3900    1      A Q_RES_0402LF-49.9,1%,1/16W,CHIA   I183 @S9S_MB_2U_LIB.S9S_MB_2U(SCH_1):PAGE107

I3C_SPD_DDREFGH_CPU1_LVC1_SCL_2 @S9S_MB_2U_LIB.S9S_MB_2U(SCH_1):I3C_SPD_DDREFGH_CPU1_LVC1_SCL_R3
   J27    4   HSCL SCONN288_ADR50017P130CC-SCONN2A   I179 @S9S_MB_2U_LIB.S9S_MB_2U(SCH_1):PAGE108
 R3901    1      A Q_RES_0402LF-49.9,1%,1/16W,CHIA   I182 @S9S_MB_2U_LIB.S9S_MB_2U(SCH_1):PAGE108

I3C_SPD_DDREFGH_CPU1_LVC1_SCL_3 @S9S_MB_2U_LIB.S9S_MB_2U(SCH_1):I3C_SPD_DDREFGH_CPU1_LVC1_SCL_R4
   J28    4   HSCL SCONN288_ADR50017P087CC-SCONN2A    I47 @S9S_MB_2U_LIB.S9S_MB_2U(SCH_1):PAGE109
 R3902    1      A Q_RES_0402LF-49.9,1%,1/16W,CHIA   I180 @S9S_MB_2U_LIB.S9S_MB_2U(SCH_1):PAGE109

I3C_SPD_DDREFGH_CPU1_LVC1_SCL_4 @S9S_MB_2U_LIB.S9S_MB_2U(SCH_1):I3C_SPD_DDREFGH_CPU1_LVC1_SCL_R5
   J29    4   HSCL SCONN288_ADR50017P130CC-SCONN2A   I179 @S9S_MB_2U_LIB.S9S_MB_2U(SCH_1):PAGE110
 R3903    1      A Q_RES_0402LF-49.9,1%,1/16W,CHIA   I182 @S9S_MB_2U_LIB.S9S_MB_2U(SCH_1):PAGE110

I3C_SPD_DDREFGH_CPU1_LVC1_SCL_5 @S9S_MB_2U_LIB.S9S_MB_2U(SCH_1):I3C_SPD_DDREFGH_CPU1_LVC1_SCL_R6
   J30    4   HSCL SCONN288_ADR50017P087CC-SCONN2A   I179 @S9S_MB_2U_LIB.S9S_MB_2U(SCH_1):PAGE111
 R3904    1      A Q_RES_0402LF-49.9,1%,1/16W,CHIA   I182 @S9S_MB_2U_LIB.S9S_MB_2U(SCH_1):PAGE111

I3C_SPD_DDREFGH_CPU1_LVC1_SCL_6 @S9S_MB_2U_LIB.S9S_MB_2U(SCH_1):I3C_SPD_DDREFGH_CPU1_LVC1_SCL_R7
   J31    4   HSCL SCONN288_ADR50017P130CC-SCONN2A   I180 @S9S_MB_2U_LIB.S9S_MB_2U(SCH_1):PAGE112
 R3905    1      A Q_RES_0402LF-49.9,1%,1/16W,CHIA   I183 @S9S_MB_2U_LIB.S9S_MB_2U(SCH_1):PAGE112

I3C_SPD_DDREFGH_CPU1_LVC1_SCL_7 @S9S_MB_2U_LIB.S9S_MB_2U(SCH_1):I3C_SPD_DDREFGH_CPU1_LVC1_SCL_R8
   J32    4   HSCL SCONN288_ADR50017P087CC-SCONN2A   I179 @S9S_MB_2U_LIB.S9S_MB_2U(SCH_1):PAGE113
 R3906    1      A Q_RES_0402LF-49.9,1%,1/16W,CHIA   I182 @S9S_MB_2U_LIB.S9S_MB_2U(SCH_1):PAGE113

I3C_SPD_DDREFGH_CPU1_LVC1_SCL_R @S9S_MB_2U_LIB.S9S_MB_2U(SCH_1):I3C_SPD_DDREFGH_CPU1_LVC1_SCL_R1
   J25    4   HSCL SCONN288_ADR50017P130CC-SCONN2A   I180 @S9S_MB_2U_LIB.S9S_MB_2U(SCH_1):PAGE106
 R3899    1      A Q_RES_0402LF-49.9,1%,1/16W,CHIA   I183 @S9S_MB_2U_LIB.S9S_MB_2U(SCH_1):PAGE106

I3C_SPD_DDREFGH_CPU1_LVC1_SDA @S9S_MB_2U_LIB.S9S_MB_2U(SCH_1):I3C_SPD_DDREFGH_CPU1_LVC1_SDA
   J25    5   HSDA SCONN288_ADR50017P130CC-SCONN2A   I180 @S9S_MB_2U_LIB.S9S_MB_2U(SCH_1):PAGE106
   J26    5   HSDA SCONN288_ADR50017P087CC-SCONN2A   I180 @S9S_MB_2U_LIB.S9S_MB_2U(SCH_1):PAGE107
   J27    5   HSDA SCONN288_ADR50017P130CC-SCONN2A   I179 @S9S_MB_2U_LIB.S9S_MB_2U(SCH_1):PAGE108
   J28    5   HSDA SCONN288_ADR50017P087CC-SCONN2A    I47 @S9S_MB_2U_LIB.S9S_MB_2U(SCH_1):PAGE109
   J29    5   HSDA SCONN288_ADR50017P130CC-SCONN2A   I179 @S9S_MB_2U_LIB.S9S_MB_2U(SCH_1):PAGE110
   J30    5   HSDA SCONN288_ADR50017P087CC-SCONN2A   I179 @S9S_MB_2U_LIB.S9S_MB_2U(SCH_1):PAGE111
   J31    5   HSDA SCONN288_ADR50017P130CC-SCONN2A   I180 @S9S_MB_2U_LIB.S9S_MB_2U(SCH_1):PAGE112
   J32    5   HSDA SCONN288_ADR50017P087CC-SCONN2A   I179 @S9S_MB_2U_LIB.S9S_MB_2U(SCH_1):PAGE113
  R677    2      B Q_RES_0402LF-33.2,1%,1/16W,CHIA    I34 @S9S_MB_2U_LIB.S9S_MB_2U(SCH_1):PAGE218

I3C_SPD_DDREFGH_CPU1_R_SCL @S9S_MB_2U_LIB.S9S_MB_2U(SCH_1):I3C_SPD_DDREFGH_CPU1_R_SCL
  R672    2      B Q_RES_0402LF-0,5%,1/16W,CHIP,CA    I30 @S9S_MB_2U_LIB.S9S_MB_2U(SCH_1):PAGE218
   U14   11    I0C QS3VH257QG8_SMLF-QS3VH257QG8,IA    I12 @S9S_MB_2U_LIB.S9S_MB_2U(SCH_1):PAGE218
  R667    1      A Q_RES_0402LF-0,5%,1/16W,EMPTY,A    I21 @S9S_MB_2U_LIB.S9S_MB_2U(SCH_1):PAGE218

I3C_SPD_DDREFGH_CPU1_R_SDA @S9S_MB_2U_LIB.S9S_MB_2U(SCH_1):I3C_SPD_DDREFGH_CPU1_R_SDA
  R673    2      B Q_RES_0402LF-33.2,1%,1/16W,CHIA    I31 @S9S_MB_2U_LIB.S9S_MB_2U(SCH_1):PAGE218
   U14   14    I0D QS3VH257QG8_SMLF-QS3VH257QG8,IA    I12 @S9S_MB_2U_LIB.S9S_MB_2U(SCH_1):PAGE218
  R668    1      A Q_RES_0402LF-0,5%,1/16W,EMPTY,A    I20 @S9S_MB_2U_LIB.S9S_MB_2U(SCH_1):PAGE218

I3C_SPD_DDREFGH_CPU1_SCL @S9S_MB_2U_LIB.S9S_MB_2U(SCH_1):I3C_SPD_DDREFGH_CPU1_SCL
    U1 CU17 DDR4567_SPDSCL SOCKET4677_AZIF0045P001C01CS-SA    I51 @S9S_MB_2U_LIB.S9S_MB_2U(SCH_1):PAGE44
  R664    2      B Q_RES_0402LF-499,1%,1/16W,CHIPA    I28 @S9S_MB_2U_LIB.S9S_MB_2U(SCH_1):PAGE218
  R672    1      A Q_RES_0402LF-0,5%,1/16W,CHIP,CA    I30 @S9S_MB_2U_LIB.S9S_MB_2U(SCH_1):PAGE218

I3C_SPD_DDREFGH_CPU1_SDA @S9S_MB_2U_LIB.S9S_MB_2U(SCH_1):I3C_SPD_DDREFGH_CPU1_SDA
    U1 CT18 DDR4567_SPDSDA SOCKET4677_AZIF0045P001C01CS-SA    I51 @S9S_MB_2U_LIB.S9S_MB_2U(SCH_1):PAGE44
  R673    1      A Q_RES_0402LF-33.2,1%,1/16W,CHIA    I31 @S9S_MB_2U_LIB.S9S_MB_2U(SCH_1):PAGE218
  R669    2      B Q_RES_0402LF-499,1%,1/16W,CHIPA    I29 @S9S_MB_2U_LIB.S9S_MB_2U(SCH_1):PAGE218

INA230_1_A0 @S9S_MB_2U_LIB.S9S_MB_2U(SCH_1):INA230_1_A0
  U266    2     A0 INA230AIRGTR-INA230AIRGTR,SMLFB    I30 @S9S_MB_2U_LIB.S9S_MB_2U(SCH_1):PAGE295
 R3617    2      B Q_RES_0402LF-4.7K,1%,1/16W,EMPA    I40 @S9S_MB_2U_LIB.S9S_MB_2U(SCH_1):PAGE295
 R3627    2      B Q_RES_0402LF-4.7K,1%,1/16W,CHIA    I89 @S9S_MB_2U_LIB.S9S_MB_2U(SCH_1):PAGE295

INA230_1_A1 @S9S_MB_2U_LIB.S9S_MB_2U(SCH_1):INA230_1_A1
  U266    1     A1 INA230AIRGTR-INA230AIRGTR,SMLFB    I30 @S9S_MB_2U_LIB.S9S_MB_2U(SCH_1):PAGE295
 R3616    2      B Q_RES_0402LF-4.7K,1%,1/16W,CHIA    I31 @S9S_MB_2U_LIB.S9S_MB_2U(SCH_1):PAGE295
 R3628    2      B Q_RES_0402LF-4.7K,1%,1/16W,EMPA    I88 @S9S_MB_2U_LIB.S9S_MB_2U(SCH_1):PAGE295

INA230_2_A0 @S9S_MB_2U_LIB.S9S_MB_2U(SCH_1):INA230_2_A0
  U276    2     A0 INA230AIRGTR-INA230AIRGTR,SMLFB   I129 @S9S_MB_2U_LIB.S9S_MB_2U(SCH_1):PAGE295
 R3764    2      B Q_RES_0402LF-4.7K,1%,1/16W,EMPA   I135 @S9S_MB_2U_LIB.S9S_MB_2U(SCH_1):PAGE295
 R3751    1      A Q_RES_0402LF-0,5%,1/16W,CHIP,CA   I146 @S9S_MB_2U_LIB.S9S_MB_2U(SCH_1):PAGE295

INA230_2_A1 @S9S_MB_2U_LIB.S9S_MB_2U(SCH_1):INA230_2_A1
  U276    1     A1 INA230AIRGTR-INA230AIRGTR,SMLFB   I129 @S9S_MB_2U_LIB.S9S_MB_2U(SCH_1):PAGE295
 R3763    2      B Q_RES_0402LF-4.7K,1%,1/16W,CHIA   I136 @S9S_MB_2U_LIB.S9S_MB_2U(SCH_1):PAGE295

INA230_3_A0 @S9S_MB_2U_LIB.S9S_MB_2U(SCH_1):INA230_3_A0
  U263    2     A0 INA230AIRGTR-INA230AIRGTR,SMLFB    I94 @S9S_MB_2U_LIB.S9S_MB_2U(SCH_1):PAGE163
 R3620    1      A Q_RES_0402LF-0,5%,1/16W,CHIP,CA   I100 @S9S_MB_2U_LIB.S9S_MB_2U(SCH_1):PAGE163
 R3609    2      B Q_RES_0402LF-4.7K,1%,1/16W,EMPA   I104 @S9S_MB_2U_LIB.S9S_MB_2U(SCH_1):PAGE163

INA230_3_A1 @S9S_MB_2U_LIB.S9S_MB_2U(SCH_1):INA230_3_A1
  U263    1     A1 INA230AIRGTR-INA230AIRGTR,SMLFB    I94 @S9S_MB_2U_LIB.S9S_MB_2U(SCH_1):PAGE163
 R3608    2      B Q_RES_0402LF-4.7K,1%,1/16W,CHIA   I103 @S9S_MB_2U_LIB.S9S_MB_2U(SCH_1):PAGE163

INA230_4_A0 @S9S_MB_2U_LIB.S9S_MB_2U(SCH_1):INA230_4_A0
 R3611    2      B Q_RES_0402LF-4.7K,1%,1/16W,CHIA    I36 @S9S_MB_2U_LIB.S9S_MB_2U(SCH_1):PAGE163
  U264    2     A0 INA230AIRGTR-INA230AIRGTR,SMLFB    I46 @S9S_MB_2U_LIB.S9S_MB_2U(SCH_1):PAGE163
 R3621    2      B Q_RES_0402LF-4.7K,1%,1/16W,EMPA    I87 @S9S_MB_2U_LIB.S9S_MB_2U(SCH_1):PAGE163

INA230_4_A1 @S9S_MB_2U_LIB.S9S_MB_2U(SCH_1):INA230_4_A1
 R3610    2      B Q_RES_0402LF-4.7K,1%,1/16W,EMPA    I45 @S9S_MB_2U_LIB.S9S_MB_2U(SCH_1):PAGE163
  U264    1     A1 INA230AIRGTR-INA230AIRGTR,SMLFB    I46 @S9S_MB_2U_LIB.S9S_MB_2U(SCH_1):PAGE163
 R3623    2      B Q_RES_0402LF-4.7K,1%,1/16W,CHIA    I86 @S9S_MB_2U_LIB.S9S_MB_2U(SCH_1):PAGE163

INA230_5_A0 @S9S_MB_2U_LIB.S9S_MB_2U(SCH_1):INA230_5_A0
 R3613    2      B Q_RES_0402LF-4.7K,1%,1/16W,EMPA    I59 @S9S_MB_2U_LIB.S9S_MB_2U(SCH_1):PAGE163
  U265    2     A0 INA230AIRGTR-INA230AIRGTR,SMLFB    I69 @S9S_MB_2U_LIB.S9S_MB_2U(SCH_1):PAGE163
 R3622    2      B Q_RES_0402LF-4.7K,1%,1/16W,CHIA    I90 @S9S_MB_2U_LIB.S9S_MB_2U(SCH_1):PAGE163

INA230_5_A1 @S9S_MB_2U_LIB.S9S_MB_2U(SCH_1):INA230_5_A1
 R3612    2      B Q_RES_0402LF-4.7K,1%,1/16W,EMPA    I68 @S9S_MB_2U_LIB.S9S_MB_2U(SCH_1):PAGE163
  U265    1     A1 INA230AIRGTR-INA230AIRGTR,SMLFB    I69 @S9S_MB_2U_LIB.S9S_MB_2U(SCH_1):PAGE163
 R3624    2      B Q_RES_0402LF-4.7K,1%,1/16W,CHIA    I89 @S9S_MB_2U_LIB.S9S_MB_2U(SCH_1):PAGE163

IND_P0_CPL1 @S9S_MB_2U_LIB.S9S_MB_2U(SCH_1):IND_P0_CPL1
 PL114    2      2 Q_INDUCTOR4P_14-150NH,SMLF,INDA    I46 @S9S_MB_2U_LIB.S9S_MB_2U(SCH_1):PAGE253
   PL9    3      3 Q_INDUCTOR4P_14-150NH,SMLF,INDA    I32 @S9S_MB_2U_LIB.S9S_MB_2U(SCH_1):PAGE255

IND_P0_CPL2 @S9S_MB_2U_LIB.S9S_MB_2U(SCH_1):IND_P0_CPL2
 PL114    3      3 Q_INDUCTOR4P_14-150NH,SMLF,INDA    I46 @S9S_MB_2U_LIB.S9S_MB_2U(SCH_1):PAGE253
  PL13    2      2 Q_INDUCTOR4P_14-150NH,SMLF,INDA    I21 @S9S_MB_2U_LIB.S9S_MB_2U(SCH_1):PAGE253

IND_P0_CPL3 @S9S_MB_2U_LIB.S9S_MB_2U(SCH_1):IND_P0_CPL3
 PL112    2      2 Q_INDUCTOR4P_14-150NH,SMLF,INDA    I50 @S9S_MB_2U_LIB.S9S_MB_2U(SCH_1):PAGE254
  PL13    3      3 Q_INDUCTOR4P_14-150NH,SMLF,INDA    I21 @S9S_MB_2U_LIB.S9S_MB_2U(SCH_1):PAGE253

IND_P0_CPL4 @S9S_MB_2U_LIB.S9S_MB_2U(SCH_1):IND_P0_CPL4
 PL112    3      3 Q_INDUCTOR4P_14-150NH,SMLF,INDA    I50 @S9S_MB_2U_LIB.S9S_MB_2U(SCH_1):PAGE254
  PL11    2      2 Q_INDUCTOR4P_14-150NH,SMLF,INDA    I33 @S9S_MB_2U_LIB.S9S_MB_2U(SCH_1):PAGE254

IND_P0_CPL5 @S9S_MB_2U_LIB.S9S_MB_2U(SCH_1):IND_P0_CPL5
  PL11    3      3 Q_INDUCTOR4P_14-150NH,SMLF,INDA    I33 @S9S_MB_2U_LIB.S9S_MB_2U(SCH_1):PAGE254
  PL10    2      2 Q_INDUCTOR4P_14-150NH,SMLF,INDA    I50 @S9S_MB_2U_LIB.S9S_MB_2U(SCH_1):PAGE255

IND_P0_CPL6 @S9S_MB_2U_LIB.S9S_MB_2U(SCH_1):IND_P0_CPL6
   PL9    2      2 Q_INDUCTOR4P_14-150NH,SMLF,INDA    I32 @S9S_MB_2U_LIB.S9S_MB_2U(SCH_1):PAGE255
   PL8    3      3 Q_INDUCTOR4P_14-150NH,SMLF,INDA    I58 @S9S_MB_2U_LIB.S9S_MB_2U(SCH_1):PAGE256

IND_P0_CPL7 @S9S_MB_2U_LIB.S9S_MB_2U(SCH_1):IND_P0_CPL7
 PL105    1      1 Q_INDUCTOR_SMLF-120NH/69A,IND,A    I39 @S9S_MB_2U_LIB.S9S_MB_2U(SCH_1):PAGE256
   PL8    2      2 Q_INDUCTOR4P_14-150NH,SMLF,INDA    I58 @S9S_MB_2U_LIB.S9S_MB_2U(SCH_1):PAGE256

IND_P0_CPL8 @S9S_MB_2U_LIB.S9S_MB_2U(SCH_1):IND_P0_CPL8
  PL10    3      3 Q_INDUCTOR4P_14-150NH,SMLF,INDA    I50 @S9S_MB_2U_LIB.S9S_MB_2U(SCH_1):PAGE255
   PL7    2      2 Q_INDUCTOR4P_14-150NH,SMLF,INDA    I44 @S9S_MB_2U_LIB.S9S_MB_2U(SCH_1):PAGE256

IND_P1_CPL1 @S9S_MB_2U_LIB.S9S_MB_2U(SCH_1):IND_P1_CPL1
  PL31    2      2 Q_INDUCTOR4P_14-150NH,SMLF,INDA    I74 @S9S_MB_2U_LIB.S9S_MB_2U(SCH_1):PAGE271
  PL30    3      3 Q_INDUCTOR4P_14-150NH,SMLF,INDA    I18 @S9S_MB_2U_LIB.S9S_MB_2U(SCH_1):PAGE271

IND_P1_CPL2 @S9S_MB_2U_LIB.S9S_MB_2U(SCH_1):IND_P1_CPL2
  PL29    3      3 Q_INDUCTOR4P_14-150NH,SMLF,INDA    I51 @S9S_MB_2U_LIB.S9S_MB_2U(SCH_1):PAGE272
  PL30    2      2 Q_INDUCTOR4P_14-150NH,SMLF,INDA    I18 @S9S_MB_2U_LIB.S9S_MB_2U(SCH_1):PAGE271

IND_P1_CPL3 @S9S_MB_2U_LIB.S9S_MB_2U(SCH_1):IND_P1_CPL3
  PL28    3      3 Q_INDUCTOR4P_14-150NH,SMLF,INDA    I37 @S9S_MB_2U_LIB.S9S_MB_2U(SCH_1):PAGE272
  PL29    2      2 Q_INDUCTOR4P_14-150NH,SMLF,INDA    I51 @S9S_MB_2U_LIB.S9S_MB_2U(SCH_1):PAGE272

IND_P1_CPL4 @S9S_MB_2U_LIB.S9S_MB_2U(SCH_1):IND_P1_CPL4
  PL27    3      3 Q_INDUCTOR4P_14-150NH,SMLF,INDA    I48 @S9S_MB_2U_LIB.S9S_MB_2U(SCH_1):PAGE273
  PL28    2      2 Q_INDUCTOR4P_14-150NH,SMLF,INDA    I37 @S9S_MB_2U_LIB.S9S_MB_2U(SCH_1):PAGE272

IND_P1_CPL5 @S9S_MB_2U_LIB.S9S_MB_2U(SCH_1):IND_P1_CPL5
  PL27    2      2 Q_INDUCTOR4P_14-150NH,SMLF,INDA    I48 @S9S_MB_2U_LIB.S9S_MB_2U(SCH_1):PAGE273
  PL24    3      3 Q_INDUCTOR4P_14-150NH,SMLF,INDA    I43 @S9S_MB_2U_LIB.S9S_MB_2U(SCH_1):PAGE274

IND_P1_CPL6 @S9S_MB_2U_LIB.S9S_MB_2U(SCH_1):IND_P1_CPL6
  PL31    3      3 Q_INDUCTOR4P_14-150NH,SMLF,INDA    I74 @S9S_MB_2U_LIB.S9S_MB_2U(SCH_1):PAGE271
  PL26    2      2 Q_INDUCTOR4P_14-150NH,SMLF,INDA    I28 @S9S_MB_2U_LIB.S9S_MB_2U(SCH_1):PAGE273

IND_P1_CPL7 @S9S_MB_2U_LIB.S9S_MB_2U(SCH_1):IND_P1_CPL7
  PL26    3      3 Q_INDUCTOR4P_14-150NH,SMLF,INDA    I28 @S9S_MB_2U_LIB.S9S_MB_2U(SCH_1):PAGE273
  PL25    2      2 Q_INDUCTOR4P_14-150NH,SMLF,INDA    I58 @S9S_MB_2U_LIB.S9S_MB_2U(SCH_1):PAGE274

IND_P1_CPL8 @S9S_MB_2U_LIB.S9S_MB_2U(SCH_1):IND_P1_CPL8
  PL24    2      2 Q_INDUCTOR4P_14-150NH,SMLF,INDA    I43 @S9S_MB_2U_LIB.S9S_MB_2U(SCH_1):PAGE274
 PL106    1      1 Q_INDUCTOR_SMLF-120NH/69A,IND,A    I23 @S9S_MB_2U_LIB.S9S_MB_2U(SCH_1):PAGE274

IRQ0_A57 @S9S_MB_2U_LIB.S9S_MB_2U(SCH_1):IRQ0_A57
  R506    2      B Q_RES_0402LF-0,5%,1/16W,CHIP,CA    I18 @S9S_MB_2U_LIB.S9S_MB_2U(SCH_1):PAGE227
   J41  A56 PERN12 SCONN168_ME1016810202011-SCONNA   I173 @S9S_MB_2U_LIB.S9S_MB_2U(SCH_1):PAGE227

IRQ_BMC_CPU_NMI_R1 @S9S_MB_2U_LIB.S9S_MB_2U(SCH_1):IRQ_BMC_CPU_NMI_R1
  U249  U13  PB29D LCMXO3LF9400C5BG484C-LCMXO3LF-A     I1 @S9S_MB_2U_LIB.S9S_MB_2U(SCH_1):PAGE312
 R1465    2      B Q_RES_0402LF-10K,1%,1/16W,EMPTA     I3 @S9S_MB_2U_LIB.S9S_MB_2U(SCH_1):PAGE312

IRQ_BMC_PCH_NMI @S9S_MB_2U_LIB.S9S_MB_2U(SCH_1):IRQ_BMC_PCH_NMI
    U4 BF13 GPPC_A_17_SRCCLKREQ_N_7 EMMITSBURG_REV0P9-GFNOCPU04302A    I93 @S9S_MB_2U_LIB.S9S_MB_2U(SCH_1):PAGE175
 R1268    2      B Q_RES_0402LF-33.2,1%,1/16W,CHIA   I222 @S9S_MB_2U_LIB.S9S_MB_2U(SCH_1):PAGE175
 R1269    1      A Q_RES_0402LF-4.75K,1%,1/16W,CHA   I225 @S9S_MB_2U_LIB.S9S_MB_2U(SCH_1):PAGE175

IRQ_BMC_PCH_NMI_R @S9S_MB_2U_LIB.S9S_MB_2U(SCH_1):IRQ_BMC_PCH_NMI_R
 R1268    1      A Q_RES_0402LF-33.2,1%,1/16W,CHIA   I222 @S9S_MB_2U_LIB.S9S_MB_2U(SCH_1):PAGE175
  U249  AB4   PB8B LCMXO3LF9400C5BG484C-LCMXO3LF-A     I1 @S9S_MB_2U_LIB.S9S_MB_2U(SCH_1):PAGE312

IRQ_ESPI_LPC_SERIRQ_ALERT_N @S9S_MB_2U_LIB.S9S_MB_2U(SCH_1):IRQ_ESPI_LPC_SERIRQ_ALERT_N
   U60    4      A NC7SB3157_SMLF-NC7SB3157P6X,NCA    I34 @S9S_MB_2U_LIB.S9S_MB_2U(SCH_1):PAGE190
 R1215    1      A Q_RES_0402LF-49.9,1%,1/16W,CHIA    I38 @S9S_MB_2U_LIB.S9S_MB_2U(SCH_1):PAGE190

IRQ_ESPI_LPC_SERIRQ_ALERT_R_N @S9S_MB_2U_LIB.S9S_MB_2U(SCH_1):IRQ_ESPI_LPC_SERIRQ_ALERT_R_N
 R1215    2      B Q_RES_0402LF-49.9,1%,1/16W,CHIA    I38 @S9S_MB_2U_LIB.S9S_MB_2U(SCH_1):PAGE190
   J41   B3 +12V_EDGE_B3 SCONN168_ME1016810202011-SCONNA   I173 @S9S_MB_2U_LIB.S9S_MB_2U(SCH_1):PAGE227

IRQ_HSC_FAULT_N @S9S_MB_2U_LIB.S9S_MB_2U(SCH_1):IRQ_HSC_FAULT_N
 R3043    1      A Q_RES_0402LF-33.2,1%,1/16W,CHIA   I111 @S9S_MB_2U_LIB.S9S_MB_2U(SCH_1):PAGE314
 R2588    2      B Q_RES_0402LF-22,1%,1/16W,CHIP,A    I81 @S9S_MB_2U_LIB.S9S_MB_2U(SCH_1):PAGE303
  PJ42   13     13 SCONN21_9193031121LF-SCONN21_9A    I34 @S9S_MB_2U_LIB.S9S_MB_2U(SCH_1):PAGE327
 R2587    2      B Q_RES_0402LF-4.7K,1%,1/16W,CHIA    I93 @S9S_MB_2U_LIB.S9S_MB_2U(SCH_1):PAGE303

IRQ_HSC_FAULT_R1_N @S9S_MB_2U_LIB.S9S_MB_2U(SCH_1):IRQ_HSC_FAULT_R1_N
 R3043    2      B Q_RES_0402LF-33.2,1%,1/16W,CHIA   I111 @S9S_MB_2U_LIB.S9S_MB_2U(SCH_1):PAGE314
  U249   B5  PT13A LCMXO3LF9400C5BG484C-LCMXO3LF-A   I188 @S9S_MB_2U_LIB.S9S_MB_2U(SCH_1):PAGE314

IRQ_LPC_PIRQA_N_ESPI_ALERT0_N @S9S_MB_2U_LIB.S9S_MB_2U(SCH_1):IRQ_LPC_PIRQA_N_ESPI_ALERT0_N
    U4 BG20 GPPC_A_0_ESPI_ALERT0_N EMMITSBURG_REV0P9-GFNOCPU04302A    I93 @S9S_MB_2U_LIB.S9S_MB_2U(SCH_1):PAGE175
 R1214    1      A Q_RES_0402LF-0,5%,1/16W,CHIP,CA    I33 @S9S_MB_2U_LIB.S9S_MB_2U(SCH_1):PAGE190
 R1253    2      B Q_RES_0402LF-1K,1%,1/16W,CHIP,A    I23 @S9S_MB_2U_LIB.S9S_MB_2U(SCH_1):PAGE192

IRQ_LPC_PIRQA_N_ESPI_ALERT0_R_N @S9S_MB_2U_LIB.S9S_MB_2U(SCH_1):IRQ_LPC_PIRQA_N_ESPI_ALERT0_R_N
 R1214    2      B Q_RES_0402LF-0,5%,1/16W,CHIP,CA    I33 @S9S_MB_2U_LIB.S9S_MB_2U(SCH_1):PAGE190
   U60    1     B1 NC7SB3157_SMLF-NC7SB3157P6X,NCA    I34 @S9S_MB_2U_LIB.S9S_MB_2U(SCH_1):PAGE190

IRQ_LPC_SERIRQ_ESPI_CS1_N @S9S_MB_2U_LIB.S9S_MB_2U(SCH_1):IRQ_LPC_SERIRQ_ESPI_CS1_N
    U4 BE16 GPPC_A_7_ESPI_CS1_N EMMITSBURG_REV0P9-GFNOCPU04302A    I93 @S9S_MB_2U_LIB.S9S_MB_2U(SCH_1):PAGE175
 R1254    2      B Q_RES_0402LF-10K,1%,1/16W,CHIPA    I24 @S9S_MB_2U_LIB.S9S_MB_2U(SCH_1):PAGE192
 R4118    1      A Q_RES_0402LF-10,1%,1/16W,CHIP,A   I105 @S9S_MB_2U_LIB.S9S_MB_2U(SCH_1):PAGE190

IRQ_LPC_SERIRQ_ESPI_CS1_R_N @S9S_MB_2U_LIB.S9S_MB_2U(SCH_1):IRQ_LPC_SERIRQ_ESPI_CS1_R_N
   U60    3     B0 NC7SB3157_SMLF-NC7SB3157P6X,NCA    I34 @S9S_MB_2U_LIB.S9S_MB_2U(SCH_1):PAGE190
 R4118    2      B Q_RES_0402LF-10,1%,1/16W,CHIP,A   I105 @S9S_MB_2U_LIB.S9S_MB_2U(SCH_1):PAGE190

IRQ_LVC3_OCP_SFF_WAKE_N @S9S_MB_2U_LIB.S9S_MB_2U(SCH_1):IRQ_LVC3_OCP_SFF_WAKE_N
 R1824    2      B Q_RES_0402LF-10K,1%,1/16W,CHIPA    I62 @S9S_MB_2U_LIB.S9S_MB_2U(SCH_1):PAGE152
   J37  OA3  WAKE# SCONN168_ME1016810202011-SCONNA   I199 @S9S_MB_2U_LIB.S9S_MB_2U(SCH_1):PAGE150
   U82    2      A 74LVC1G126SE7-74LVC1G126SE-7,SA    I79 @S9S_MB_2U_LIB.S9S_MB_2U(SCH_1):PAGE152

IRQ_LVC3_OCP_V3_2_WAKE_N @S9S_MB_2U_LIB.S9S_MB_2U(SCH_1):IRQ_LVC3_OCP_V3_2_WAKE_N
 R3182    2      B Q_RES_0402LF-10K,1%,1/16W,CHIPA     I6 @S9S_MB_2U_LIB.S9S_MB_2U(SCH_1):PAGE156
   J35  OA3  WAKE# SCONN168_ME1016810202011-SCONNA   I303 @S9S_MB_2U_LIB.S9S_MB_2U(SCH_1):PAGE146
  U217    2      A 74LVC1G126SE7-74LVC1G126SE-7,SA    I79 @S9S_MB_2U_LIB.S9S_MB_2U(SCH_1):PAGE156

IRQ_LVC3_V3_2_WAKE_BUF_N @S9S_MB_2U_LIB.S9S_MB_2U(SCH_1):IRQ_LVC3_V3_2_WAKE_BUF_N
 R3193    1      A Q_RES_0402LF-33.2,1%,1/16W,CHIA    I55 @S9S_MB_2U_LIB.S9S_MB_2U(SCH_1):PAGE156
 R3192    2      B Q_RES_0402LF-4.7K,1%,1/16W,EMPA    I59 @S9S_MB_2U_LIB.S9S_MB_2U(SCH_1):PAGE156
  U219    4      Y 74LVC1G07GV-74LVC1G07GV,SMLF,IA    I61 @S9S_MB_2U_LIB.S9S_MB_2U(SCH_1):PAGE156

IRQ_LVC3_WAKE_BUF_N @S9S_MB_2U_LIB.S9S_MB_2U(SCH_1):IRQ_LVC3_WAKE_BUF_N
  U157    4      Y 74LVC1G07GV-74LVC1G07GV,SMLF,IA    I65 @S9S_MB_2U_LIB.S9S_MB_2U(SCH_1):PAGE152
 R2487    2      B Q_RES_0402LF-4.7K,1%,1/16W,EMPA    I71 @S9S_MB_2U_LIB.S9S_MB_2U(SCH_1):PAGE152
 R2489    1      A Q_RES_0402LF-33.2,1%,1/16W,CHIA    I75 @S9S_MB_2U_LIB.S9S_MB_2U(SCH_1):PAGE152

IRQ_LVC3_WAKE_N @S9S_MB_2U_LIB.S9S_MB_2U(SCH_1):IRQ_LVC3_WAKE_N
 R2489    2      B Q_RES_0402LF-33.2,1%,1/16W,CHIA    I75 @S9S_MB_2U_LIB.S9S_MB_2U(SCH_1):PAGE152
    U4 AH11 WAKE_N EMMITSBURG_REV0P9-GFNOCPU04302A    I36 @S9S_MB_2U_LIB.S9S_MB_2U(SCH_1):PAGE174
 R3193    2      B Q_RES_0402LF-33.2,1%,1/16W,CHIA    I55 @S9S_MB_2U_LIB.S9S_MB_2U(SCH_1):PAGE156
 R3301    1      A Q_RES_0402LF-33.2,1%,1/16W,CHIA   I299 @S9S_MB_2U_LIB.S9S_MB_2U(SCH_1):PAGE182
  R494    2      B Q_RES_0402LF-1K,1%,1/16W,CHIP,A    I98 @S9S_MB_2U_LIB.S9S_MB_2U(SCH_1):PAGE174

IRQ_PCH_CPU_NMI_EVENT_N @S9S_MB_2U_LIB.S9S_MB_2U(SCH_1):IRQ_PCH_CPU_NMI_EVENT_N
 R1310    2      B Q_RES_0402LF-33.2,1%,1/16W,CHIA    I20 @S9S_MB_2U_LIB.S9S_MB_2U(SCH_1):PAGE193
  U249  V13  PB29C LCMXO3LF9400C5BG484C-LCMXO3LF-A     I1 @S9S_MB_2U_LIB.S9S_MB_2U(SCH_1):PAGE312

IRQ_PCH_CPU_NMI_EVENT_R_N @S9S_MB_2U_LIB.S9S_MB_2U(SCH_1):IRQ_PCH_CPU_NMI_EVENT_R_N
    U4 AP15 GPPC_S_8_NMI_N EMMITSBURG_REV0P9-GFNOCPU04302A    I27 @S9S_MB_2U_LIB.S9S_MB_2U(SCH_1):PAGE177
 R1459    2      B Q_RES_0402LF-10K,1%,1/16W,CHIPA    I51 @S9S_MB_2U_LIB.S9S_MB_2U(SCH_1):PAGE192
 R1310    1      A Q_RES_0402LF-33.2,1%,1/16W,CHIA    I20 @S9S_MB_2U_LIB.S9S_MB_2U(SCH_1):PAGE193

IRQ_PCH_SCI_WHEA_N @S9S_MB_2U_LIB.S9S_MB_2U(SCH_1):IRQ_PCH_SCI_WHEA_N
    U4  AB2 GPP_D_10_BM_BUSY_N_SX_EXIT_HOLDOFF_N EMMITSBURG_REV0P9-GFNOCPU04302A    I93 @S9S_MB_2U_LIB.S9S_MB_2U(SCH_1):PAGE175
 R3040    2      B Q_RES_0402LF-1K,1%,1/16W,CHIP,A     I1 @S9S_MB_2U_LIB.S9S_MB_2U(SCH_1):PAGE192
 R1944    2      B Q_RES_0402LF-0,5%,1/16W,CHIP,CA   I170 @S9S_MB_2U_LIB.S9S_MB_2U(SCH_1):PAGE312

IRQ_PCH_SCI_WHEA_R_N @S9S_MB_2U_LIB.S9S_MB_2U(SCH_1):IRQ_PCH_SCI_WHEA_R_N
  U249  W13  PB30D LCMXO3LF9400C5BG484C-LCMXO3LF-A     I1 @S9S_MB_2U_LIB.S9S_MB_2U(SCH_1):PAGE312
 R1944    1      A Q_RES_0402LF-0,5%,1/16W,CHIP,CA   I170 @S9S_MB_2U_LIB.S9S_MB_2U(SCH_1):PAGE312

IRQ_PSU_ALERT_R_N @S9S_MB_2U_LIB.S9S_MB_2U(SCH_1):IRQ_PSU_ALERT_R_N
  U249  Y13  PB30C LCMXO3LF9400C5BG484C-LCMXO3LF-A     I1 @S9S_MB_2U_LIB.S9S_MB_2U(SCH_1):PAGE312
 R3049    2      B Q_RES_0402LF-0,5%,1/16W,CHIP,CA   I176 @S9S_MB_2U_LIB.S9S_MB_2U(SCH_1):PAGE312

IRQ_PSYS_CRIT_N @S9S_MB_2U_LIB.S9S_MB_2U(SCH_1):IRQ_PSYS_CRIT_N
  U249 AA12 PB29B||PCLKC2_1 LCMXO3LF9400C5BG484C-LCMXO3LF-A     I1 @S9S_MB_2U_LIB.S9S_MB_2U(SCH_1):PAGE312
 R2376    1      A Q_RES_0402LF-0,5%,1/16W,CHIP,CA    I17 @S9S_MB_2U_LIB.S9S_MB_2U(SCH_1):PAGE252

IRQ_PVCCD_CPU0_VRHOT_LVC3_N @S9S_MB_2U_LIB.S9S_MB_2U(SCH_1):IRQ_PVCCD_CPU0_VRHOT_LVC3_N
 R2405    2      B Q_RES_0402LF-0,5%,1/16W,CHIP,CA    I60 @S9S_MB_2U_LIB.S9S_MB_2U(SCH_1):PAGE264
  U249  AA4   PB8A LCMXO3LF9400C5BG484C-LCMXO3LF-A     I1 @S9S_MB_2U_LIB.S9S_MB_2U(SCH_1):PAGE312
 R2404    2      B Q_RES_0402LF-1K,1%,1/16W,CHIP,A    I85 @S9S_MB_2U_LIB.S9S_MB_2U(SCH_1):PAGE264

IRQ_PVCCD_CPU0_VRHOT_LVC3_R_N @S9S_MB_2U_LIB.S9S_MB_2U(SCH_1):IRQ_PVCCD_CPU0_VRHOT_LVC3_R_N
 R2405    1      A Q_RES_0402LF-0,5%,1/16W,CHIP,CA    I60 @S9S_MB_2U_LIB.S9S_MB_2U(SCH_1):PAGE264
  PU35   14 NVRHOT# ISL69260IRAZT-ISL69260IRAZ-T,SA    I53 @S9S_MB_2U_LIB.S9S_MB_2U(SCH_1):PAGE264

IRQ_PVCCD_CPU1_VRHOT_LVC3_N @S9S_MB_2U_LIB.S9S_MB_2U(SCH_1):IRQ_PVCCD_CPU1_VRHOT_LVC3_N
  U249 AA13  PB30B LCMXO3LF9400C5BG484C-LCMXO3LF-A     I1 @S9S_MB_2U_LIB.S9S_MB_2U(SCH_1):PAGE312
 R2557    2      B Q_RES_0402LF-0,5%,1/16W,CHIP,CA    I58 @S9S_MB_2U_LIB.S9S_MB_2U(SCH_1):PAGE282
  R223    2      B Q_RES_0402LF-1K,1%,1/16W,CHIP,A    I85 @S9S_MB_2U_LIB.S9S_MB_2U(SCH_1):PAGE282

IRQ_PVCCD_CPU1_VRHOT_LVC3_R_N @S9S_MB_2U_LIB.S9S_MB_2U(SCH_1):IRQ_PVCCD_CPU1_VRHOT_LVC3_R_N
  PU18   14 NVRHOT# ISL69260IRAZT-ISL69260IRAZ-T,SA    I53 @S9S_MB_2U_LIB.S9S_MB_2U(SCH_1):PAGE282
 R2557    1      A Q_RES_0402LF-0,5%,1/16W,CHIP,CA    I58 @S9S_MB_2U_LIB.S9S_MB_2U(SCH_1):PAGE282

IRQ_PVCCFA_CPU0_VRHOT_N @S9S_MB_2U_LIB.S9S_MB_2U(SCH_1):IRQ_PVCCFA_CPU0_VRHOT_N
   PU5   14 NVRHOT# ISL69260IRAZT-ISL69260IRAZ-T,SA    I65 @S9S_MB_2U_LIB.S9S_MB_2U(SCH_1):PAGE260
 R2597    1      A Q_RES_0402LF-0,5%,1/16W,CHIP,CA    I78 @S9S_MB_2U_LIB.S9S_MB_2U(SCH_1):PAGE260

IRQ_PVCCFA_CPU0_VRHOT_R_N @S9S_MB_2U_LIB.S9S_MB_2U(SCH_1):IRQ_PVCCFA_CPU0_VRHOT_R_N
  U249  J21  PR12A LCMXO3LF9400C5BG484C-LCMXO3LF-A     I1 @S9S_MB_2U_LIB.S9S_MB_2U(SCH_1):PAGE313
 R2398    2      B Q_RES_0402LF-1K,1%,1/16W,CHIP,A    I79 @S9S_MB_2U_LIB.S9S_MB_2U(SCH_1):PAGE260
 R2597    2      B Q_RES_0402LF-0,5%,1/16W,CHIP,CA    I78 @S9S_MB_2U_LIB.S9S_MB_2U(SCH_1):PAGE260

IRQ_PVCCFA_CPU1_VRHOT_N @S9S_MB_2U_LIB.S9S_MB_2U(SCH_1):IRQ_PVCCFA_CPU1_VRHOT_N
  PU22   14 NVRHOT# ISL69260IRAZT-ISL69260IRAZ-T,SA    I38 @S9S_MB_2U_LIB.S9S_MB_2U(SCH_1):PAGE278
 R2574    1      A Q_RES_0402LF-0,5%,1/16W,CHIP,CA    I70 @S9S_MB_2U_LIB.S9S_MB_2U(SCH_1):PAGE278

IRQ_PVCCFA_CPU1_VRHOT_R_N @S9S_MB_2U_LIB.S9S_MB_2U(SCH_1):IRQ_PVCCFA_CPU1_VRHOT_R_N
  U249  J22  PR12B LCMXO3LF9400C5BG484C-LCMXO3LF-A     I1 @S9S_MB_2U_LIB.S9S_MB_2U(SCH_1):PAGE313
 R2573    2      B Q_RES_0402LF-1K,1%,1/16W,CHIP,A    I73 @S9S_MB_2U_LIB.S9S_MB_2U(SCH_1):PAGE278
 R2574    2      B Q_RES_0402LF-0,5%,1/16W,CHIP,CA    I70 @S9S_MB_2U_LIB.S9S_MB_2U(SCH_1):PAGE278

IRQ_PVCCIN_CPU0_VRHOT_N @S9S_MB_2U_LIB.S9S_MB_2U(SCH_1):IRQ_PVCCIN_CPU0_VRHOT_N
  PU14   18 NVRHOT RAA229126GNPHA0-RAA229126GNP#HA    I63 @S9S_MB_2U_LIB.S9S_MB_2U(SCH_1):PAGE252
 R4593    2      B Q_RES_0402LF-0,5%,1/16W,CHIP,CA    I66 @S9S_MB_2U_LIB.S9S_MB_2U(SCH_1):PAGE252

IRQ_PVCCIN_CPU0_VRHOT_R_N @S9S_MB_2U_LIB.S9S_MB_2U(SCH_1):IRQ_PVCCIN_CPU0_VRHOT_R_N
  U249  T21  PR21B LCMXO3LF9400C5BG484C-LCMXO3LF-A     I1 @S9S_MB_2U_LIB.S9S_MB_2U(SCH_1):PAGE313
 R4593    1      A Q_RES_0402LF-0,5%,1/16W,CHIP,CA    I66 @S9S_MB_2U_LIB.S9S_MB_2U(SCH_1):PAGE252
 R2373    2      B Q_RES_0402LF-1K,1%,1/16W,CHIP,A    I23 @S9S_MB_2U_LIB.S9S_MB_2U(SCH_1):PAGE252

IRQ_PVCCIN_CPU1_VRHOT_N @S9S_MB_2U_LIB.S9S_MB_2U(SCH_1):IRQ_PVCCIN_CPU1_VRHOT_N
 R2523    2      B Q_RES_0402LF-0,5%,1/16W,CHIP,CA    I36 @S9S_MB_2U_LIB.S9S_MB_2U(SCH_1):PAGE270
  PU29   18 NVRHOT RAA229126GNPHA0-RAA229126GNP#HA    I33 @S9S_MB_2U_LIB.S9S_MB_2U(SCH_1):PAGE270

IRQ_PVCCIN_CPU1_VRHOT_R_N @S9S_MB_2U_LIB.S9S_MB_2U(SCH_1):IRQ_PVCCIN_CPU1_VRHOT_R_N
  U249  P19  PR21C LCMXO3LF9400C5BG484C-LCMXO3LF-A     I1 @S9S_MB_2U_LIB.S9S_MB_2U(SCH_1):PAGE313
 R2522    2      B Q_RES_0402LF-1K,1%,1/16W,CHIP,A    I25 @S9S_MB_2U_LIB.S9S_MB_2U(SCH_1):PAGE270
 R2523    1      A Q_RES_0402LF-0,5%,1/16W,CHIP,CA    I36 @S9S_MB_2U_LIB.S9S_MB_2U(SCH_1):PAGE270

IRQ_SGPIO_INTR_N @S9S_MB_2U_LIB.S9S_MB_2U(SCH_1):IRQ_SGPIO_INTR_N
 R1812    1      A Q_RES_0402LF-33.2,1%,1/16W,CHIA   I111 @S9S_MB_2U_LIB.S9S_MB_2U(SCH_1):PAGE211
   J41  B40  PETP7 SCONN168_ME1016810202011-SCONNA   I173 @S9S_MB_2U_LIB.S9S_MB_2U(SCH_1):PAGE227

IRQ_SGPIO_INTR_N_R @S9S_MB_2U_LIB.S9S_MB_2U(SCH_1):IRQ_SGPIO_INTR_N_R
 R1812    2      B Q_RES_0402LF-33.2,1%,1/16W,CHIA   I111 @S9S_MB_2U_LIB.S9S_MB_2U(SCH_1):PAGE211
  U249 AB12 PB29A||PCLKT2_1 LCMXO3LF9400C5BG484C-LCMXO3LF-A     I1 @S9S_MB_2U_LIB.S9S_MB_2U(SCH_1):PAGE312

IRQ_SMI_ACTIVE_BMC_N @S9S_MB_2U_LIB.S9S_MB_2U(SCH_1):IRQ_SMI_ACTIVE_BMC_N
 R1309    2      B Q_RES_0402LF-33.2,1%,1/16W,CHIA    I10 @S9S_MB_2U_LIB.S9S_MB_2U(SCH_1):PAGE193
  R506    1      A Q_RES_0402LF-0,5%,1/16W,CHIP,CA    I18 @S9S_MB_2U_LIB.S9S_MB_2U(SCH_1):PAGE227

IRQ_SMI_ACTIVE_N @S9S_MB_2U_LIB.S9S_MB_2U(SCH_1):IRQ_SMI_ACTIVE_N
    U4 AV18 GPPC_S_9_SMI_N EMMITSBURG_REV0P9-GFNOCPU04302A    I27 @S9S_MB_2U_LIB.S9S_MB_2U(SCH_1):PAGE177
 R1458    2      B Q_RES_0402LF-10K,1%,1/16W,CHIPA    I50 @S9S_MB_2U_LIB.S9S_MB_2U(SCH_1):PAGE192
 R1309    1      A Q_RES_0402LF-33.2,1%,1/16W,CHIA    I10 @S9S_MB_2U_LIB.S9S_MB_2U(SCH_1):PAGE193

IRQ_SML0_ALERT_N @S9S_MB_2U_LIB.S9S_MB_2U(SCH_1):IRQ_SML0_ALERT_N
    U4  AU2 GPPC_C_2_ME_SML0ALERT_N EMMITSBURG_REV0P9-GFNOCPU04302A    I93 @S9S_MB_2U_LIB.S9S_MB_2U(SCH_1):PAGE175
 R1600    1      A Q_RES_0402LF-33.2,1%,1/16W,CHIA   I148 @S9S_MB_2U_LIB.S9S_MB_2U(SCH_1):PAGE175
 R1601    1      A Q_RES_0402LF-10K,1%,1/16W,CHIPA   I151 @S9S_MB_2U_LIB.S9S_MB_2U(SCH_1):PAGE175

IRQ_SML0_ALERT_R1_N @S9S_MB_2U_LIB.S9S_MB_2U(SCH_1):IRQ_SML0_ALERT_R1_N
 R3103    2      B Q_RES_0402LF-0,5%,1/16W,CHIP,CA    I28 @S9S_MB_2U_LIB.S9S_MB_2U(SCH_1):PAGE215
  J100    4      4 SCONN20_513860200CV01-SCONN20_A    I32 @S9S_MB_2U_LIB.S9S_MB_2U(SCH_1):PAGE215

IRQ_SML0_ALERT_R_N @S9S_MB_2U_LIB.S9S_MB_2U(SCH_1):IRQ_SML0_ALERT_R_N
 R1600    2      B Q_RES_0402LF-33.2,1%,1/16W,CHIA   I148 @S9S_MB_2U_LIB.S9S_MB_2U(SCH_1):PAGE175
 R3103    1      A Q_RES_0402LF-0,5%,1/16W,CHIP,CA    I28 @S9S_MB_2U_LIB.S9S_MB_2U(SCH_1):PAGE215
  U249   B8  PT20A LCMXO3LF9400C5BG484C-LCMXO3LF-A   I188 @S9S_MB_2U_LIB.S9S_MB_2U(SCH_1):PAGE314

IRQ_SML1_PMBUS_ALERT @S9S_MB_2U_LIB.S9S_MB_2U(SCH_1):IRQ_SML1_PMBUS_ALERT
 PU289   10   ALT# MP5990GMA1111Z-MP5990GMA-1111-A    I56 @S9S_MB_2U_LIB.S9S_MB_2U(SCH_1):PAGE303
 R3924    2      B Q_RES_0402LF-0,5%,1/16W,CHIP,CA    I17 @S9S_MB_2U_LIB.S9S_MB_2U(SCH_1):PAGE303
 R3925    1      A Q_RES_0402LF-1K,1%,1/16W,CHIP,A    I33 @S9S_MB_2U_LIB.S9S_MB_2U(SCH_1):PAGE303

IRQ_SML1_PMBUS_ALERT_N @S9S_MB_2U_LIB.S9S_MB_2U(SCH_1):IRQ_SML1_PMBUS_ALERT_N
    U4  AR4 GPPC_C_8_ME_SML1ALERT_N EMMITSBURG_REV0P9-GFNOCPU04302A    I93 @S9S_MB_2U_LIB.S9S_MB_2U(SCH_1):PAGE175
 R1656    1      A Q_RES_0402LF-33.2,1%,1/16W,CHIA   I178 @S9S_MB_2U_LIB.S9S_MB_2U(SCH_1):PAGE175
 R1657    1      A Q_RES_0402LF-33.2,1%,1/16W,CHIA   I180 @S9S_MB_2U_LIB.S9S_MB_2U(SCH_1):PAGE175
 R3051    2      B Q_RES_0402LF-0,5%,1/16W,CHIP,CA     I2 @S9S_MB_2U_LIB.S9S_MB_2U(SCH_1):PAGE215
 R3049    1      A Q_RES_0402LF-0,5%,1/16W,CHIP,CA   I176 @S9S_MB_2U_LIB.S9S_MB_2U(SCH_1):PAGE312
 R3924    1      A Q_RES_0402LF-0,5%,1/16W,CHIP,CA    I17 @S9S_MB_2U_LIB.S9S_MB_2U(SCH_1):PAGE303
  PJ42   20     20 SCONN21_9193031121LF-SCONN21_9A    I34 @S9S_MB_2U_LIB.S9S_MB_2U(SCH_1):PAGE327

IRQ_SML1_PMBUS_ALERT_R_N @S9S_MB_2U_LIB.S9S_MB_2U(SCH_1):IRQ_SML1_PMBUS_ALERT_R_N
 R3051    1      A Q_RES_0402LF-0,5%,1/16W,CHIP,CA     I2 @S9S_MB_2U_LIB.S9S_MB_2U(SCH_1):PAGE215
  J100    8      8 SCONN20_513860200CV01-SCONN20_A    I32 @S9S_MB_2U_LIB.S9S_MB_2U(SCH_1):PAGE215

IRQ_SML1_PMBUS_BMC_ALERT_N @S9S_MB_2U_LIB.S9S_MB_2U(SCH_1):IRQ_SML1_PMBUS_BMC_ALERT_N
 R1657    2      B Q_RES_0402LF-33.2,1%,1/16W,CHIA   I180 @S9S_MB_2U_LIB.S9S_MB_2U(SCH_1):PAGE175
  U249   D8  PT15B LCMXO3LF9400C5BG484C-LCMXO3LF-A   I188 @S9S_MB_2U_LIB.S9S_MB_2U(SCH_1):PAGE314

IRQ_SML1_PMBUS_PLD_ALERT_N @S9S_MB_2U_LIB.S9S_MB_2U(SCH_1):IRQ_SML1_PMBUS_PLD_ALERT_N
 R1656    2      B Q_RES_0402LF-33.2,1%,1/16W,CHIA   I178 @S9S_MB_2U_LIB.S9S_MB_2U(SCH_1):PAGE175
  U249   A8  PT20B LCMXO3LF9400C5BG484C-LCMXO3LF-A   I188 @S9S_MB_2U_LIB.S9S_MB_2U(SCH_1):PAGE314

IRQ_TPM_SPI_N @S9S_MB_2U_LIB.S9S_MB_2U(SCH_1):IRQ_TPM_SPI_N
    U4   N4 GPP_I_21 EMMITSBURG_REV0P9-GFNOCPU04302A    I22 @S9S_MB_2U_LIB.S9S_MB_2U(SCH_1):PAGE176
  R401    2      B Q_RES_0402LF-10K,1%,1/16W,EMPTA    I69 @S9S_MB_2U_LIB.S9S_MB_2U(SCH_1):PAGE192
  U249 AB13  PB30A LCMXO3LF9400C5BG484C-LCMXO3LF-A     I1 @S9S_MB_2U_LIB.S9S_MB_2U(SCH_1):PAGE312

IRQ_UV_DETECT_N @S9S_MB_2U_LIB.S9S_MB_2U(SCH_1):IRQ_UV_DETECT_N
 R3045    1      A Q_RES_0402LF-0,5%,1/16W,CHIP,CA   I164 @S9S_MB_2U_LIB.S9S_MB_2U(SCH_1):PAGE312
  U325    D  DRAIN MOSFET_N_SMLF-BSS138K,BSS138K,A    I38 @S9S_MB_2U_LIB.S9S_MB_2U(SCH_1):PAGE326
 R4620    2      B Q_RES_0402LF-4.7K,5%,1/16W,CHIA    I45 @S9S_MB_2U_LIB.S9S_MB_2U(SCH_1):PAGE326
 R4785    2      B Q_RES_0402LF-10K,1%,1/16W,EMPTA    I25 @S9S_MB_2U_LIB.S9S_MB_2U(SCH_1):PAGE329
 R4783    2      B Q_RES_0402LF-33.2,1%,1/16W,EMPA    I27 @S9S_MB_2U_LIB.S9S_MB_2U(SCH_1):PAGE329

IRQ_UV_DETECT_R2_N @S9S_MB_2U_LIB.S9S_MB_2U(SCH_1):IRQ_UV_DETECT_R2_N
  U340    4 OUTPUT AP331AWG7-AP331AWG-7,SMLF,EMPTA    I23 @S9S_MB_2U_LIB.S9S_MB_2U(SCH_1):PAGE329
 R4783    1      A Q_RES_0402LF-33.2,1%,1/16W,EMPA    I27 @S9S_MB_2U_LIB.S9S_MB_2U(SCH_1):PAGE329
 R4779    2      B Q_RES_0402LF-1M,1%,1/16W,CHIP,A    I31 @S9S_MB_2U_LIB.S9S_MB_2U(SCH_1):PAGE329

IRQ_UV_DETECT_R_N @S9S_MB_2U_LIB.S9S_MB_2U(SCH_1):IRQ_UV_DETECT_R_N
  U249   Y4   PB7C LCMXO3LF9400C5BG484C-LCMXO3LF-A     I1 @S9S_MB_2U_LIB.S9S_MB_2U(SCH_1):PAGE312
 R3045    2      B Q_RES_0402LF-0,5%,1/16W,CHIP,CA   I164 @S9S_MB_2U_LIB.S9S_MB_2U(SCH_1):PAGE312

JTAG_BMC_CPU_TCK @S9S_MB_2U_LIB.S9S_MB_2U(SCH_1):JTAG_BMC_CPU_TCK
   U86    4    2OE 74CBTLV3126PW-74CBTLV3126PW,SMA    I84 @S9S_MB_2U_LIB.S9S_MB_2U(SCH_1):PAGE137
 R3027    1      A Q_RES_0402LF-1K,1%,1/16W,CHIP,A   I105 @S9S_MB_2U_LIB.S9S_MB_2U(SCH_1):PAGE137
   U85    3     B0 NC7SB3157_SMLF-NC7SB3157P6X,NCA   I109 @S9S_MB_2U_LIB.S9S_MB_2U(SCH_1):PAGE137

JTAG_BMC_DBP_PREQ_N @S9S_MB_2U_LIB.S9S_MB_2U(SCH_1):JTAG_BMC_DBP_PREQ_N
 R1383    2      B Q_RES_0402LF-1K,1%,1/16W,CHIP,A     I1 @S9S_MB_2U_LIB.S9S_MB_2U(SCH_1):PAGE226
 R3057    2      B Q_RES_0402LF-33.2,1%,1/16W,CHIA    I12 @S9S_MB_2U_LIB.S9S_MB_2U(SCH_1):PAGE226
 R1832    1      A Q_RES_0402LF-0,5%,1/16W,EMPTY,A    I80 @S9S_MB_2U_LIB.S9S_MB_2U(SCH_1):PAGE226
   J41  A49 GND_A49 SCONN168_ME1016810202011-SCONNA   I173 @S9S_MB_2U_LIB.S9S_MB_2U(SCH_1):PAGE227

JTAG_BMC_DBP_TCK @S9S_MB_2U_LIB.S9S_MB_2U(SCH_1):JTAG_BMC_DBP_TCK
   U85    4      A NC7SB3157_SMLF-NC7SB3157P6X,NCA   I109 @S9S_MB_2U_LIB.S9S_MB_2U(SCH_1):PAGE137
   U97    4    2Y1 NX3L2267GM-NX3L2267GM,SMLF,IC,A    I38 @S9S_MB_2U_LIB.S9S_MB_2U(SCH_1):PAGE226

JTAG_BMC_DBP_TDI @S9S_MB_2U_LIB.S9S_MB_2U(SCH_1):JTAG_BMC_DBP_TDI
 R1345    2      B Q_RES_0402LF-0,5%,1/16W,CHIP,CA    I13 @S9S_MB_2U_LIB.S9S_MB_2U(SCH_1):PAGE226
   U96    2    1Y1 NX3L2267GM-NX3L2267GM,SMLF,IC,A    I68 @S9S_MB_2U_LIB.S9S_MB_2U(SCH_1):PAGE226
 R2507    2      B Q_RES_0402LF-1K,1%,1/16W,CHIP,A    I88 @S9S_MB_2U_LIB.S9S_MB_2U(SCH_1):PAGE226

JTAG_BMC_DBP_TDI_R @S9S_MB_2U_LIB.S9S_MB_2U(SCH_1):JTAG_BMC_DBP_TDI_R
 R1345    1      A Q_RES_0402LF-0,5%,1/16W,CHIP,CA    I13 @S9S_MB_2U_LIB.S9S_MB_2U(SCH_1):PAGE226
   U84   10     A2 GTL2014PW-GTL2014PW,SMLF,IC,ALA    I18 @S9S_MB_2U_LIB.S9S_MB_2U(SCH_1):PAGE226

JTAG_BMC_DBP_TDO @S9S_MB_2U_LIB.S9S_MB_2U(SCH_1):JTAG_BMC_DBP_TDO
 R1380    2      B Q_RES_0402LF-1K,1%,1/16W,CHIP,A    I31 @S9S_MB_2U_LIB.S9S_MB_2U(SCH_1):PAGE226
  R483    2      B Q_RES_0402LF-0,5%,1/16W,CHIP,CA    I37 @S9S_MB_2U_LIB.S9S_MB_2U(SCH_1):PAGE226
   U96    4    2Y1 NX3L2267GM-NX3L2267GM,SMLF,IC,A    I68 @S9S_MB_2U_LIB.S9S_MB_2U(SCH_1):PAGE226

JTAG_BMC_DBP_TDO_R @S9S_MB_2U_LIB.S9S_MB_2U(SCH_1):JTAG_BMC_DBP_TDO_R
  R483    1      A Q_RES_0402LF-0,5%,1/16W,CHIP,CA    I37 @S9S_MB_2U_LIB.S9S_MB_2U(SCH_1):PAGE226
   U83    9     A3 GTL2014PW-GTL2014PW,SMLF,IC,ALA    I45 @S9S_MB_2U_LIB.S9S_MB_2U(SCH_1):PAGE226

JTAG_BMC_DBP_TMS @S9S_MB_2U_LIB.S9S_MB_2U(SCH_1):JTAG_BMC_DBP_TMS
 R1184    2      B Q_RES_0402LF-0,5%,1/16W,CHIP,CA    I14 @S9S_MB_2U_LIB.S9S_MB_2U(SCH_1):PAGE226
   U97    2    1Y1 NX3L2267GM-NX3L2267GM,SMLF,IC,A    I38 @S9S_MB_2U_LIB.S9S_MB_2U(SCH_1):PAGE226
 R2506    2      B Q_RES_0402LF-1K,1%,1/16W,CHIP,A    I87 @S9S_MB_2U_LIB.S9S_MB_2U(SCH_1):PAGE226

JTAG_BMC_DBP_TMS_R @S9S_MB_2U_LIB.S9S_MB_2U(SCH_1):JTAG_BMC_DBP_TMS_R
 R1184    1      A Q_RES_0402LF-0,5%,1/16W,CHIP,CA    I14 @S9S_MB_2U_LIB.S9S_MB_2U(SCH_1):PAGE226
   U84    9     A3 GTL2014PW-GTL2014PW,SMLF,IC,ALA    I18 @S9S_MB_2U_LIB.S9S_MB_2U(SCH_1):PAGE226

JTAG_BMC_PCH_TCK @S9S_MB_2U_LIB.S9S_MB_2U(SCH_1):JTAG_BMC_PCH_TCK
   U86   10    3OE 74CBTLV3126PW-74CBTLV3126PW,SMA    I84 @S9S_MB_2U_LIB.S9S_MB_2U(SCH_1):PAGE137
 R3026    1      A Q_RES_0402LF-1K,1%,1/16W,CHIP,A   I106 @S9S_MB_2U_LIB.S9S_MB_2U(SCH_1):PAGE137
   U85    1     B1 NC7SB3157_SMLF-NC7SB3157P6X,NCA   I109 @S9S_MB_2U_LIB.S9S_MB_2U(SCH_1):PAGE137

JTAG_BMC_PLD_TCK @S9S_MB_2U_LIB.S9S_MB_2U(SCH_1):JTAG_BMC_PLD_TCK
  R806    2      B Q_RES_0402LF-33.2,1%,1/16W,CHIA    I54 @S9S_MB_2U_LIB.S9S_MB_2U(SCH_1):PAGE210
  R930    1      A Q_RES_0402LF-4.7K,1%,1/16W,CHIA    I63 @S9S_MB_2U_LIB.S9S_MB_2U(SCH_1):PAGE210
   U97    3    2Y0 NX3L2267GM-NX3L2267GM,SMLF,IC,A    I38 @S9S_MB_2U_LIB.S9S_MB_2U(SCH_1):PAGE226
   J43    8      8 CONN8_210HP1080BR1-CONN8_210-HA    I79 @S9S_MB_2U_LIB.S9S_MB_2U(SCH_1):PAGE210

JTAG_BMC_PLD_TDI @S9S_MB_2U_LIB.S9S_MB_2U(SCH_1):JTAG_BMC_PLD_TDI
  R803    2      B Q_RES_0402LF-33.2,1%,1/16W,CHIA    I19 @S9S_MB_2U_LIB.S9S_MB_2U(SCH_1):PAGE210
  R927    2      B Q_RES_0402LF-10K,1%,1/16W,CHIPA    I61 @S9S_MB_2U_LIB.S9S_MB_2U(SCH_1):PAGE210
   U96    1    1Y0 NX3L2267GM-NX3L2267GM,SMLF,IC,A    I68 @S9S_MB_2U_LIB.S9S_MB_2U(SCH_1):PAGE226
   J43    3      3 CONN8_210HP1080BR1-CONN8_210-HA    I79 @S9S_MB_2U_LIB.S9S_MB_2U(SCH_1):PAGE210

JTAG_BMC_PLD_TDO @S9S_MB_2U_LIB.S9S_MB_2U(SCH_1):JTAG_BMC_PLD_TDO
  R804    2      B Q_RES_0402LF-33.2,1%,1/16W,CHIA    I20 @S9S_MB_2U_LIB.S9S_MB_2U(SCH_1):PAGE210
  R928    2      B Q_RES_0402LF-10K,1%,1/16W,CHIPA    I60 @S9S_MB_2U_LIB.S9S_MB_2U(SCH_1):PAGE210
   U96    3    2Y0 NX3L2267GM-NX3L2267GM,SMLF,IC,A    I68 @S9S_MB_2U_LIB.S9S_MB_2U(SCH_1):PAGE226
   J43    2      2 CONN8_210HP1080BR1-CONN8_210-HA    I79 @S9S_MB_2U_LIB.S9S_MB_2U(SCH_1):PAGE210

JTAG_BMC_PLD_TMS @S9S_MB_2U_LIB.S9S_MB_2U(SCH_1):JTAG_BMC_PLD_TMS
  R805    2      B Q_RES_0402LF-33.2,1%,1/16W,CHIA    I25 @S9S_MB_2U_LIB.S9S_MB_2U(SCH_1):PAGE210
  R929    2      B Q_RES_0402LF-10K,1%,1/16W,CHIPA    I59 @S9S_MB_2U_LIB.S9S_MB_2U(SCH_1):PAGE210
   U97    1    1Y0 NX3L2267GM-NX3L2267GM,SMLF,IC,A    I38 @S9S_MB_2U_LIB.S9S_MB_2U(SCH_1):PAGE226
   J43    6      6 CONN8_210HP1080BR1-CONN8_210-HA    I79 @S9S_MB_2U_LIB.S9S_MB_2U(SCH_1):PAGE210

JTAG_BMC_SW_OE @S9S_MB_2U_LIB.S9S_MB_2U(SCH_1):JTAG_BMC_SW_OE
 R4625    1      A Q_RES_0402LF-100,1%,1/16W,CHIPA   I140 @S9S_MB_2U_LIB.S9S_MB_2U(SCH_1):PAGE314
 R4635    1      A Q_RES_0402LF-10K,1%,1/16W,CHIPA     I3 @S9S_MB_2U_LIB.S9S_MB_2U(SCH_1):PAGE235
 R4634    2      B Q_RES_0402LF-1K,1%,1/16W,EMPTYA     I4 @S9S_MB_2U_LIB.S9S_MB_2U(SCH_1):PAGE235
  JP16    2      2 CONN3_210HP1030BR1-CONN3_210-HB    I13 @S9S_MB_2U_LIB.S9S_MB_2U(SCH_1):PAGE235
 R4624    1      A Q_RES_0402LF-0,5%,1/16W,CHIP,CA    I14 @S9S_MB_2U_LIB.S9S_MB_2U(SCH_1):PAGE235

JTAG_BMC_SW_PLD_OE @S9S_MB_2U_LIB.S9S_MB_2U(SCH_1):JTAG_BMC_SW_PLD_OE
 R4625    2      B Q_RES_0402LF-100,1%,1/16W,CHIPA   I140 @S9S_MB_2U_LIB.S9S_MB_2U(SCH_1):PAGE314
  U249  C18  PT41C LCMXO3LF9400C5BG484C-LCMXO3LF-A   I188 @S9S_MB_2U_LIB.S9S_MB_2U(SCH_1):PAGE314

JTAG_BMC_SW_R_OE @S9S_MB_2U_LIB.S9S_MB_2U(SCH_1):JTAG_BMC_SW_R_OE
 R4624    2      B Q_RES_0402LF-0,5%,1/16W,CHIP,CA    I14 @S9S_MB_2U_LIB.S9S_MB_2U(SCH_1):PAGE235
  U327    1    1OE 74CBTLV3126PW-74CBTLV3126PW,SMA    I19 @S9S_MB_2U_LIB.S9S_MB_2U(SCH_1):PAGE235
  U327    4    2OE 74CBTLV3126PW-74CBTLV3126PW,SMA    I19 @S9S_MB_2U_LIB.S9S_MB_2U(SCH_1):PAGE235
  U327   10    3OE 74CBTLV3126PW-74CBTLV3126PW,SMA    I19 @S9S_MB_2U_LIB.S9S_MB_2U(SCH_1):PAGE235
  U327   13    4OE 74CBTLV3126PW-74CBTLV3126PW,SMA    I19 @S9S_MB_2U_LIB.S9S_MB_2U(SCH_1):PAGE235

JTAG_BMC_SW_TCK @S9S_MB_2U_LIB.S9S_MB_2U(SCH_1):JTAG_BMC_SW_TCK
   U97    6     2Z NX3L2267GM-NX3L2267GM,SMLF,IC,A    I38 @S9S_MB_2U_LIB.S9S_MB_2U(SCH_1):PAGE226
 R4633    2      B Q_RES_0402LF-0,5%,1/16W,CHIP,CA    I24 @S9S_MB_2U_LIB.S9S_MB_2U(SCH_1):PAGE235

JTAG_BMC_SW_TCK_R @S9S_MB_2U_LIB.S9S_MB_2U(SCH_1):JTAG_BMC_SW_TCK_R
  U327    3     1B 74CBTLV3126PW-74CBTLV3126PW,SMA    I19 @S9S_MB_2U_LIB.S9S_MB_2U(SCH_1):PAGE235
 R4633    1      A Q_RES_0402LF-0,5%,1/16W,CHIP,CA    I24 @S9S_MB_2U_LIB.S9S_MB_2U(SCH_1):PAGE235

JTAG_BMC_SW_TDI @S9S_MB_2U_LIB.S9S_MB_2U(SCH_1):JTAG_BMC_SW_TDI
   U96    9     1Z NX3L2267GM-NX3L2267GM,SMLF,IC,A    I68 @S9S_MB_2U_LIB.S9S_MB_2U(SCH_1):PAGE226
 R4631    2      B Q_RES_0402LF-0,5%,1/16W,CHIP,CA    I25 @S9S_MB_2U_LIB.S9S_MB_2U(SCH_1):PAGE235

JTAG_BMC_SW_TDI_R @S9S_MB_2U_LIB.S9S_MB_2U(SCH_1):JTAG_BMC_SW_TDI_R
 R4631    1      A Q_RES_0402LF-0,5%,1/16W,CHIP,CA    I25 @S9S_MB_2U_LIB.S9S_MB_2U(SCH_1):PAGE235
  U327    8     3B 74CBTLV3126PW-74CBTLV3126PW,SMA    I19 @S9S_MB_2U_LIB.S9S_MB_2U(SCH_1):PAGE235

JTAG_BMC_SW_TDO @S9S_MB_2U_LIB.S9S_MB_2U(SCH_1):JTAG_BMC_SW_TDO
   U96    6     2Z NX3L2267GM-NX3L2267GM,SMLF,IC,A    I68 @S9S_MB_2U_LIB.S9S_MB_2U(SCH_1):PAGE226
 R4630    2      B Q_RES_0402LF-0,5%,1/16W,CHIP,CA    I27 @S9S_MB_2U_LIB.S9S_MB_2U(SCH_1):PAGE235

JTAG_BMC_SW_TDO_R @S9S_MB_2U_LIB.S9S_MB_2U(SCH_1):JTAG_BMC_SW_TDO_R
 R4630    1      A Q_RES_0402LF-0,5%,1/16W,CHIP,CA    I27 @S9S_MB_2U_LIB.S9S_MB_2U(SCH_1):PAGE235
  U327   11     4B 74CBTLV3126PW-74CBTLV3126PW,SMA    I19 @S9S_MB_2U_LIB.S9S_MB_2U(SCH_1):PAGE235

JTAG_BMC_SW_TMS @S9S_MB_2U_LIB.S9S_MB_2U(SCH_1):JTAG_BMC_SW_TMS
   U97    9     1Z NX3L2267GM-NX3L2267GM,SMLF,IC,A    I38 @S9S_MB_2U_LIB.S9S_MB_2U(SCH_1):PAGE226
 R4632    2      B Q_RES_0402LF-0,5%,1/16W,CHIP,CA    I26 @S9S_MB_2U_LIB.S9S_MB_2U(SCH_1):PAGE235

JTAG_BMC_SW_TMS_R @S9S_MB_2U_LIB.S9S_MB_2U(SCH_1):JTAG_BMC_SW_TMS_R
  U327    6     2B 74CBTLV3126PW-74CBTLV3126PW,SMA    I19 @S9S_MB_2U_LIB.S9S_MB_2U(SCH_1):PAGE235
 R4632    1      A Q_RES_0402LF-0,5%,1/16W,CHIP,CA    I26 @S9S_MB_2U_LIB.S9S_MB_2U(SCH_1):PAGE235

JTAG_BMC_TCK @S9S_MB_2U_LIB.S9S_MB_2U(SCH_1):JTAG_BMC_TCK
 R4629    1      A Q_RES_0402LF-0,5%,1/16W,CHIP,CA    I15 @S9S_MB_2U_LIB.S9S_MB_2U(SCH_1):PAGE235
   J41  A34  PERP5 SCONN168_ME1016810202011-SCONNA   I173 @S9S_MB_2U_LIB.S9S_MB_2U(SCH_1):PAGE227

JTAG_BMC_TCK_R @S9S_MB_2U_LIB.S9S_MB_2U(SCH_1):JTAG_BMC_TCK_R
 R4629    2      B Q_RES_0402LF-0,5%,1/16W,CHIP,CA    I15 @S9S_MB_2U_LIB.S9S_MB_2U(SCH_1):PAGE235
  U327    2     1A 74CBTLV3126PW-74CBTLV3126PW,SMA    I19 @S9S_MB_2U_LIB.S9S_MB_2U(SCH_1):PAGE235

JTAG_BMC_TDI @S9S_MB_2U_LIB.S9S_MB_2U(SCH_1):JTAG_BMC_TDI
 R4627    1      A Q_RES_0402LF-0,5%,1/16W,CHIP,CA    I17 @S9S_MB_2U_LIB.S9S_MB_2U(SCH_1):PAGE235
   J41  A36  PERN6 SCONN168_ME1016810202011-SCONNA   I173 @S9S_MB_2U_LIB.S9S_MB_2U(SCH_1):PAGE227

JTAG_BMC_TDI_R @S9S_MB_2U_LIB.S9S_MB_2U(SCH_1):JTAG_BMC_TDI_R
 R4627    2      B Q_RES_0402LF-0,5%,1/16W,CHIP,CA    I17 @S9S_MB_2U_LIB.S9S_MB_2U(SCH_1):PAGE235
  U327    9     3A 74CBTLV3126PW-74CBTLV3126PW,SMA    I19 @S9S_MB_2U_LIB.S9S_MB_2U(SCH_1):PAGE235

JTAG_BMC_TDO @S9S_MB_2U_LIB.S9S_MB_2U(SCH_1):JTAG_BMC_TDO
 R4626    1      A Q_RES_0402LF-0,5%,1/16W,CHIP,CA    I18 @S9S_MB_2U_LIB.S9S_MB_2U(SCH_1):PAGE235
   J41  A37  PERP6 SCONN168_ME1016810202011-SCONNA   I173 @S9S_MB_2U_LIB.S9S_MB_2U(SCH_1):PAGE227

JTAG_BMC_TDO_R @S9S_MB_2U_LIB.S9S_MB_2U(SCH_1):JTAG_BMC_TDO_R
 R4626    2      B Q_RES_0402LF-0,5%,1/16W,CHIP,CA    I18 @S9S_MB_2U_LIB.S9S_MB_2U(SCH_1):PAGE235
  U327   12     4A 74CBTLV3126PW-74CBTLV3126PW,SMA    I19 @S9S_MB_2U_LIB.S9S_MB_2U(SCH_1):PAGE235

JTAG_BMC_TMS @S9S_MB_2U_LIB.S9S_MB_2U(SCH_1):JTAG_BMC_TMS
 R4628    1      A Q_RES_0402LF-0,5%,1/16W,CHIP,CA    I16 @S9S_MB_2U_LIB.S9S_MB_2U(SCH_1):PAGE235
   J41  A35 GND_A35 SCONN168_ME1016810202011-SCONNA   I173 @S9S_MB_2U_LIB.S9S_MB_2U(SCH_1):PAGE227

JTAG_BMC_TMS_R @S9S_MB_2U_LIB.S9S_MB_2U(SCH_1):JTAG_BMC_TMS_R
 R4628    2      B Q_RES_0402LF-0,5%,1/16W,CHIP,CA    I16 @S9S_MB_2U_LIB.S9S_MB_2U(SCH_1):PAGE235
  U327    5     2A 74CBTLV3126PW-74CBTLV3126PW,SMA    I19 @S9S_MB_2U_LIB.S9S_MB_2U(SCH_1):PAGE235

JTAG_CPU0_MUX_GTL_TDO @S9S_MB_2U_LIB.S9S_MB_2U(SCH_1):JTAG_CPU0_MUX_GTL_TDO
    U2 BW25    TDO SOCKET4677_AZIF0045P001C01CS-SA    I57 @S9S_MB_2U_LIB.S9S_MB_2U(SCH_1):PAGE13
   U22    1     B1 NC7SB3157_SMLF-NC7SB3157P6X,NCA    I71 @S9S_MB_2U_LIB.S9S_MB_2U(SCH_1):PAGE135
  R744    2      B Q_RES_0402LF-75,1%,1/16W,CHIP,A    I77 @S9S_MB_2U_LIB.S9S_MB_2U(SCH_1):PAGE135
   U16    1      Y 74LVC1G66GV-74LVC1G66GV,SMLF,IA   I115 @S9S_MB_2U_LIB.S9S_MB_2U(SCH_1):PAGE135

JTAG_CPU1_MUX_GTL_TDO @S9S_MB_2U_LIB.S9S_MB_2U(SCH_1):JTAG_CPU1_MUX_GTL_TDO
    U1 BW25    TDO SOCKET4677_AZIF0045P001C01CS-SA    I51 @S9S_MB_2U_LIB.S9S_MB_2U(SCH_1):PAGE44
   U22    3     B0 NC7SB3157_SMLF-NC7SB3157P6X,NCA    I71 @S9S_MB_2U_LIB.S9S_MB_2U(SCH_1):PAGE135
  R742    2      B Q_RES_0402LF-75,1%,1/16W,CHIP,A    I78 @S9S_MB_2U_LIB.S9S_MB_2U(SCH_1):PAGE135

JTAG_DBP_BMC_PRDY_N @S9S_MB_2U_LIB.S9S_MB_2U(SCH_1):JTAG_DBP_BMC_PRDY_N
 R1382    2      B Q_RES_0402LF-1K,1%,1/16W,CHIP,A    I20 @S9S_MB_2U_LIB.S9S_MB_2U(SCH_1):PAGE226
 R3056    2      B Q_RES_0402LF-33.2,1%,1/16W,CHIA    I36 @S9S_MB_2U_LIB.S9S_MB_2U(SCH_1):PAGE226
 R1831    1      A Q_RES_0402LF-0,5%,1/16W,EMPTY,A    I82 @S9S_MB_2U_LIB.S9S_MB_2U(SCH_1):PAGE226
   J41  A50 PERN10 SCONN168_ME1016810202011-SCONNA   I173 @S9S_MB_2U_LIB.S9S_MB_2U(SCH_1):PAGE227

JTAG_DBP_BMC_PRDY_R1_N @S9S_MB_2U_LIB.S9S_MB_2U(SCH_1):JTAG_DBP_BMC_PRDY_R1_N
 R3056    1      A Q_RES_0402LF-33.2,1%,1/16W,CHIA    I36 @S9S_MB_2U_LIB.S9S_MB_2U(SCH_1):PAGE226
   U83   12     A1 GTL2014PW-GTL2014PW,SMLF,IC,ALA    I45 @S9S_MB_2U_LIB.S9S_MB_2U(SCH_1):PAGE226

JTAG_DBP_BMC_PRDY_R_N @S9S_MB_2U_LIB.S9S_MB_2U(SCH_1):JTAG_DBP_BMC_PRDY_R_N
 R1831    2      B Q_RES_0402LF-0,5%,1/16W,EMPTY,A    I82 @S9S_MB_2U_LIB.S9S_MB_2U(SCH_1):PAGE226
  U249  AA9  PB19A LCMXO3LF9400C5BG484C-LCMXO3LF-A     I1 @S9S_MB_2U_LIB.S9S_MB_2U(SCH_1):PAGE312

JTAG_DBP_BMC_PREQ_R1_N @S9S_MB_2U_LIB.S9S_MB_2U(SCH_1):JTAG_DBP_BMC_PREQ_R1_N
 R3057    1      A Q_RES_0402LF-33.2,1%,1/16W,CHIA    I12 @S9S_MB_2U_LIB.S9S_MB_2U(SCH_1):PAGE226
   U84   13     A0 GTL2014PW-GTL2014PW,SMLF,IC,ALA    I18 @S9S_MB_2U_LIB.S9S_MB_2U(SCH_1):PAGE226

JTAG_DBP_BMC_PREQ_R_N @S9S_MB_2U_LIB.S9S_MB_2U(SCH_1):JTAG_DBP_BMC_PREQ_R_N
 R1832    2      B Q_RES_0402LF-0,5%,1/16W,EMPTY,A    I80 @S9S_MB_2U_LIB.S9S_MB_2U(SCH_1):PAGE226
  U249 AB18  PB41A LCMXO3LF9400C5BG484C-LCMXO3LF-A     I1 @S9S_MB_2U_LIB.S9S_MB_2U(SCH_1):PAGE312

JTAG_DBP_BOOT_HALT_N @S9S_MB_2U_LIB.S9S_MB_2U(SCH_1):JTAG_DBP_BOOT_HALT_N
  R778    2      B Q_RES_0402LF-1K,1%,1/16W,CHIP,A    I15 @S9S_MB_2U_LIB.S9S_MB_2U(SCH_1):PAGE133
   J42   36     36 SCONN60_ASP21410801-SCONN60_ASA    I44 @S9S_MB_2U_LIB.S9S_MB_2U(SCH_1):PAGE133
  R773    1      A Q_RES_0402LF-1K,1%,1/16W,CHIP,A   I124 @S9S_MB_2U_LIB.S9S_MB_2U(SCH_1):PAGE133

JTAG_DBP_CPU0_GTL_R_TCK @S9S_MB_2U_LIB.S9S_MB_2U(SCH_1):JTAG_DBP_CPU0_GTL_R_TCK
    R5    2      B Q_RES_0402LF-100,1%,1/16W,CHIPA    I24 @S9S_MB_2U_LIB.S9S_MB_2U(SCH_1):PAGE13
    U2 BT24    TCK SOCKET4677_AZIF0045P001C01CS-SA    I57 @S9S_MB_2U_LIB.S9S_MB_2U(SCH_1):PAGE13

JTAG_DBP_CPU0_GTL_R_TDI @S9S_MB_2U_LIB.S9S_MB_2U(SCH_1):JTAG_DBP_CPU0_GTL_R_TDI
    R4    2      B Q_RES_0402LF-200,1%,1/16W,CHIPA    I29 @S9S_MB_2U_LIB.S9S_MB_2U(SCH_1):PAGE13
    U2 BV24    TDI SOCKET4677_AZIF0045P001C01CS-SA    I57 @S9S_MB_2U_LIB.S9S_MB_2U(SCH_1):PAGE13

JTAG_DBP_CPU0_QS_GTL_R_TMS @S9S_MB_2U_LIB.S9S_MB_2U(SCH_1):JTAG_DBP_CPU0_QS_GTL_R_TMS
    R6    2      B Q_RES_0402LF-100,1%,1/16W,CHIPA    I25 @S9S_MB_2U_LIB.S9S_MB_2U(SCH_1):PAGE13
    U2 BR25    TMS SOCKET4677_AZIF0045P001C01CS-SA    I57 @S9S_MB_2U_LIB.S9S_MB_2U(SCH_1):PAGE13

JTAG_DBP_CPU1_GTL_R_TCK @S9S_MB_2U_LIB.S9S_MB_2U(SCH_1):JTAG_DBP_CPU1_GTL_R_TCK
   R65    2      B Q_RES_0402LF-100,1%,1/16W,CHIPA     I8 @S9S_MB_2U_LIB.S9S_MB_2U(SCH_1):PAGE44
    U1 BT24    TCK SOCKET4677_AZIF0045P001C01CS-SA    I51 @S9S_MB_2U_LIB.S9S_MB_2U(SCH_1):PAGE44

JTAG_DBP_CPU1_GTL_R_TDI @S9S_MB_2U_LIB.S9S_MB_2U(SCH_1):JTAG_DBP_CPU1_GTL_R_TDI
   R64    2      B Q_RES_0402LF-200,1%,1/16W,CHIPA     I9 @S9S_MB_2U_LIB.S9S_MB_2U(SCH_1):PAGE44
    U1 BV24    TDI SOCKET4677_AZIF0045P001C01CS-SA    I51 @S9S_MB_2U_LIB.S9S_MB_2U(SCH_1):PAGE44

JTAG_DBP_CPU1_QS_GTL_R_TMS @S9S_MB_2U_LIB.S9S_MB_2U(SCH_1):JTAG_DBP_CPU1_QS_GTL_R_TMS
   R66    2      B Q_RES_0402LF-100,1%,1/16W,CHIPA     I7 @S9S_MB_2U_LIB.S9S_MB_2U(SCH_1):PAGE44
    U1 BR25    TMS SOCKET4677_AZIF0045P001C01CS-SA    I51 @S9S_MB_2U_LIB.S9S_MB_2U(SCH_1):PAGE44

JTAG_DBP_CPU_GTL_TCK @S9S_MB_2U_LIB.S9S_MB_2U(SCH_1):JTAG_DBP_CPU_GTL_TCK
    R5    1      A Q_RES_0402LF-100,1%,1/16W,CHIPA    I24 @S9S_MB_2U_LIB.S9S_MB_2U(SCH_1):PAGE13
   R65    1      A Q_RES_0402LF-100,1%,1/16W,CHIPA     I8 @S9S_MB_2U_LIB.S9S_MB_2U(SCH_1):PAGE44
  R762    1      A Q_RES_0402LF-0,5%,1/16W,CHIP,CA    I71 @S9S_MB_2U_LIB.S9S_MB_2U(SCH_1):PAGE133
  R774    1      A Q_RES_0402LF-75,1%,1/16W,CHIP,A   I132 @S9S_MB_2U_LIB.S9S_MB_2U(SCH_1):PAGE133
 R1348    2      B Q_RES_0402LF-0,5%,1/16W,CHIP,CA    I88 @S9S_MB_2U_LIB.S9S_MB_2U(SCH_1):PAGE137
    U4 BD35  JTAGX EMMITSBURG_REV0P9-GFNOCPU04302A    I36 @S9S_MB_2U_LIB.S9S_MB_2U(SCH_1):PAGE174
 R1025    1      A Q_RES_0402LF-75,1%,1/16W,EMPTYA    I38 @S9S_MB_2U_LIB.S9S_MB_2U(SCH_1):PAGE174

JTAG_DBP_CPU_GTL_TCK_R @S9S_MB_2U_LIB.S9S_MB_2U(SCH_1):JTAG_DBP_CPU_GTL_TCK_R
   J42    3      3 SCONN60_ASP21410801-SCONN60_ASA    I44 @S9S_MB_2U_LIB.S9S_MB_2U(SCH_1):PAGE133
  R762    2      B Q_RES_0402LF-0,5%,1/16W,CHIP,CA    I71 @S9S_MB_2U_LIB.S9S_MB_2U(SCH_1):PAGE133

JTAG_DBP_CPU_GTL_TCK_R1 @S9S_MB_2U_LIB.S9S_MB_2U(SCH_1):JTAG_DBP_CPU_GTL_TCK_R1
   U86    6     2B 74CBTLV3126PW-74CBTLV3126PW,SMA    I84 @S9S_MB_2U_LIB.S9S_MB_2U(SCH_1):PAGE137
 R1348    1      A Q_RES_0402LF-0,5%,1/16W,CHIP,CA    I88 @S9S_MB_2U_LIB.S9S_MB_2U(SCH_1):PAGE137

JTAG_DBP_CPU_HOOK8_MBP2_GTL_N @S9S_MB_2U_LIB.S9S_MB_2U(SCH_1):JTAG_DBP_CPU_HOOK8_MBP2_GTL_N
   J42   55     55 SCONN60_ASP21410801-SCONN60_ASA    I44 @S9S_MB_2U_LIB.S9S_MB_2U(SCH_1):PAGE133
   U18    5     2A 74CBTLV3126PW-74CBTLV3126PW,SMA   I129 @S9S_MB_2U_LIB.S9S_MB_2U(SCH_1):PAGE134

JTAG_DBP_CPU_HOOK9_MBP3_GTL_N @S9S_MB_2U_LIB.S9S_MB_2U(SCH_1):JTAG_DBP_CPU_HOOK9_MBP3_GTL_N
   J42   53     53 SCONN60_ASP21410801-SCONN60_ASA    I44 @S9S_MB_2U_LIB.S9S_MB_2U(SCH_1):PAGE133
   U18    2     1A 74CBTLV3126PW-74CBTLV3126PW,SMA   I129 @S9S_MB_2U_LIB.S9S_MB_2U(SCH_1):PAGE134

JTAG_DBP_CPU_QS_GTL_TMS @S9S_MB_2U_LIB.S9S_MB_2U(SCH_1):JTAG_DBP_CPU_QS_GTL_TMS
    R6    1      A Q_RES_0402LF-100,1%,1/16W,CHIPA    I25 @S9S_MB_2U_LIB.S9S_MB_2U(SCH_1):PAGE13
   R66    1      A Q_RES_0402LF-100,1%,1/16W,CHIPA     I7 @S9S_MB_2U_LIB.S9S_MB_2U(SCH_1):PAGE44
   U17    3     1B 74CBTLV3126PW-74CBTLV3126PW,SMA    I80 @S9S_MB_2U_LIB.S9S_MB_2U(SCH_1):PAGE134
  R757    2      B Q_RES_0402LF-120,1%,1/16W,CHIPA   I166 @S9S_MB_2U_LIB.S9S_MB_2U(SCH_1):PAGE134

JTAG_DBP_FB_TDI @S9S_MB_2U_LIB.S9S_MB_2U(SCH_1):JTAG_DBP_FB_TDI
   U84    5     B2 GTL2014PW-GTL2014PW,SMLF,IC,ALA    I18 @S9S_MB_2U_LIB.S9S_MB_2U(SCH_1):PAGE226
  R481    2      B Q_RES_0402LF-0,5%,1/16W,CHIP,CA    I58 @S9S_MB_2U_LIB.S9S_MB_2U(SCH_1):PAGE226

JTAG_DBP_FB_TDO @S9S_MB_2U_LIB.S9S_MB_2U(SCH_1):JTAG_DBP_FB_TDO
   U83    6     B3 GTL2014PW-GTL2014PW,SMLF,IC,ALA    I45 @S9S_MB_2U_LIB.S9S_MB_2U(SCH_1):PAGE226
 R1366    2      B Q_RES_0402LF-100,1%,1/16W,CHIPA    I64 @S9S_MB_2U_LIB.S9S_MB_2U(SCH_1):PAGE226

JTAG_DBP_FB_TMS @S9S_MB_2U_LIB.S9S_MB_2U(SCH_1):JTAG_DBP_FB_TMS
   U84    6     B3 GTL2014PW-GTL2014PW,SMLF,IC,ALA    I18 @S9S_MB_2U_LIB.S9S_MB_2U(SCH_1):PAGE226
  R480    2      B Q_RES_0402LF-0,5%,1/16W,CHIP,CA    I59 @S9S_MB_2U_LIB.S9S_MB_2U(SCH_1):PAGE226

JTAG_DBP_PCH_DEBUG_CONSENT_N @S9S_MB_2U_LIB.S9S_MB_2U(SCH_1):JTAG_DBP_PCH_DEBUG_CONSENT_N
   J42   15     15 SCONN60_ASP21410801-SCONN60_ASA    I44 @S9S_MB_2U_LIB.S9S_MB_2U(SCH_1):PAGE133
  R771    1      A Q_RES_0402LF-1K,1%,1/16W,CHIP,A   I120 @S9S_MB_2U_LIB.S9S_MB_2U(SCH_1):PAGE133

JTAG_DBP_PMODE @S9S_MB_2U_LIB.S9S_MB_2U(SCH_1):JTAG_DBP_PMODE
   J42    7      7 SCONN60_ASP21410801-SCONN60_ASA    I44 @S9S_MB_2U_LIB.S9S_MB_2U(SCH_1):PAGE133
    U4 BE40 DBG_PMODE EMMITSBURG_REV0P9-GFNOCPU04302A    I36 @S9S_MB_2U_LIB.S9S_MB_2U(SCH_1):PAGE174
 R1026    1      A Q_RES_0402LF-1K,1%,1/16W,CHIP,A    I37 @S9S_MB_2U_LIB.S9S_MB_2U(SCH_1):PAGE174

JTAG_DBP_POWER_BTN_N @S9S_MB_2U_LIB.S9S_MB_2U(SCH_1):JTAG_DBP_POWER_BTN_N
   J42   40     40 SCONN60_ASP21410801-SCONN60_ASA    I44 @S9S_MB_2U_LIB.S9S_MB_2U(SCH_1):PAGE133
  R766    2      B Q_RES_0402LF-1K,1%,1/16W,EMPTYA   I111 @S9S_MB_2U_LIB.S9S_MB_2U(SCH_1):PAGE133
  C548    1      A Q_CAP_0402-0.1UF,25V,10%,X7R,CA   I130 @S9S_MB_2U_LIB.S9S_MB_2U(SCH_1):PAGE133

JTAG_DBP_PRDY_N @S9S_MB_2U_LIB.S9S_MB_2U(SCH_1):JTAG_DBP_PRDY_N
  R764    1      A Q_RES_0402LF-0,5%,1/16W,CHIP,CA    I83 @S9S_MB_2U_LIB.S9S_MB_2U(SCH_1):PAGE133
   U18    9     3A 74CBTLV3126PW-74CBTLV3126PW,SMA   I129 @S9S_MB_2U_LIB.S9S_MB_2U(SCH_1):PAGE134
  R756    1      A Q_RES_0402LF-10,1%,1/16W,CHIP,A   I148 @S9S_MB_2U_LIB.S9S_MB_2U(SCH_1):PAGE134
 R1367    1      A Q_RES_0402LF-100,1%,1/16W,CHIPA    I65 @S9S_MB_2U_LIB.S9S_MB_2U(SCH_1):PAGE226

JTAG_DBP_PRDY_R1_N @S9S_MB_2U_LIB.S9S_MB_2U(SCH_1):JTAG_DBP_PRDY_R1_N
   J42   11     11 SCONN60_ASP21410801-SCONN60_ASA    I44 @S9S_MB_2U_LIB.S9S_MB_2U(SCH_1):PAGE133
  R764    2      B Q_RES_0402LF-0,5%,1/16W,CHIP,CA    I83 @S9S_MB_2U_LIB.S9S_MB_2U(SCH_1):PAGE133

JTAG_DBP_PRDY_R_N @S9S_MB_2U_LIB.S9S_MB_2U(SCH_1):JTAG_DBP_PRDY_R_N
   U83    3     B1 GTL2014PW-GTL2014PW,SMLF,IC,ALA    I45 @S9S_MB_2U_LIB.S9S_MB_2U(SCH_1):PAGE226
 R1367    2      B Q_RES_0402LF-100,1%,1/16W,CHIPA    I65 @S9S_MB_2U_LIB.S9S_MB_2U(SCH_1):PAGE226

JTAG_DBP_PREQ_N @S9S_MB_2U_LIB.S9S_MB_2U(SCH_1):JTAG_DBP_PREQ_N
  R777    2      B Q_RES_0402LF-10,1%,1/16W,CHIP,A    I10 @S9S_MB_2U_LIB.S9S_MB_2U(SCH_1):PAGE133
   U18   12     4A 74CBTLV3126PW-74CBTLV3126PW,SMA   I129 @S9S_MB_2U_LIB.S9S_MB_2U(SCH_1):PAGE134
  R755    1      A Q_RES_0402LF-10,1%,1/16W,CHIP,A   I147 @S9S_MB_2U_LIB.S9S_MB_2U(SCH_1):PAGE134
  R482    1      A Q_RES_0402LF-0,5%,1/16W,CHIP,CA    I57 @S9S_MB_2U_LIB.S9S_MB_2U(SCH_1):PAGE226

JTAG_DBP_PREQ_N_R @S9S_MB_2U_LIB.S9S_MB_2U(SCH_1):JTAG_DBP_PREQ_N_R
  R777    1      A Q_RES_0402LF-10,1%,1/16W,CHIP,A    I10 @S9S_MB_2U_LIB.S9S_MB_2U(SCH_1):PAGE133
   J42   10     10 SCONN60_ASP21410801-SCONN60_ASA    I44 @S9S_MB_2U_LIB.S9S_MB_2U(SCH_1):PAGE133

JTAG_DBP_PREQ_R_N @S9S_MB_2U_LIB.S9S_MB_2U(SCH_1):JTAG_DBP_PREQ_R_N
   U84    2     B0 GTL2014PW-GTL2014PW,SMLF,IC,ALA    I18 @S9S_MB_2U_LIB.S9S_MB_2U(SCH_1):PAGE226
  R482    2      B Q_RES_0402LF-0,5%,1/16W,CHIP,CA    I57 @S9S_MB_2U_LIB.S9S_MB_2U(SCH_1):PAGE226

JTAG_DBP_PRESENT_R_N @S9S_MB_2U_LIB.S9S_MB_2U(SCH_1):JTAG_DBP_PRESENT_R_N
   J42   17     17 SCONN60_ASP21410801-SCONN60_ASA    I44 @S9S_MB_2U_LIB.S9S_MB_2U(SCH_1):PAGE133
  R768    2      B Q_RES_0402LF-1K,1%,1/16W,CHIP,A   I112 @S9S_MB_2U_LIB.S9S_MB_2U(SCH_1):PAGE133
 R1472    1      A Q_RES_0402LF-33.2,1%,1/16W,CHIA   I144 @S9S_MB_2U_LIB.S9S_MB_2U(SCH_1):PAGE133

JTAG_DBP_TCK_PCH @S9S_MB_2U_LIB.S9S_MB_2U(SCH_1):JTAG_DBP_TCK_PCH
  R765    1      A Q_RES_0402LF-0,5%,1/16W,CHIP,CA    I74 @S9S_MB_2U_LIB.S9S_MB_2U(SCH_1):PAGE133
 R1349    2      B Q_RES_0402LF-0,5%,1/16W,CHIP,CA    I87 @S9S_MB_2U_LIB.S9S_MB_2U(SCH_1):PAGE137
    U4 BF35 JTAG_TCK EMMITSBURG_REV0P9-GFNOCPU04302A    I36 @S9S_MB_2U_LIB.S9S_MB_2U(SCH_1):PAGE174
 R1024    1      A Q_RES_0402LF-100,1%,1/16W,CHIPA    I41 @S9S_MB_2U_LIB.S9S_MB_2U(SCH_1):PAGE174

JTAG_DBP_TCK_PCH_R @S9S_MB_2U_LIB.S9S_MB_2U(SCH_1):JTAG_DBP_TCK_PCH_R
   U86    8     3B 74CBTLV3126PW-74CBTLV3126PW,SMA    I84 @S9S_MB_2U_LIB.S9S_MB_2U(SCH_1):PAGE137
 R1349    1      A Q_RES_0402LF-0,5%,1/16W,CHIP,CA    I87 @S9S_MB_2U_LIB.S9S_MB_2U(SCH_1):PAGE137

JTAG_DBP_TCK_R_TCK @S9S_MB_2U_LIB.S9S_MB_2U(SCH_1):JTAG_DBP_TCK_R_TCK
   J42   51     51 SCONN60_ASP21410801-SCONN60_ASA    I44 @S9S_MB_2U_LIB.S9S_MB_2U(SCH_1):PAGE133
  R765    2      B Q_RES_0402LF-0,5%,1/16W,CHIP,CA    I74 @S9S_MB_2U_LIB.S9S_MB_2U(SCH_1):PAGE133

JTAG_DBP_TDI @S9S_MB_2U_LIB.S9S_MB_2U(SCH_1):JTAG_DBP_TDI
  R763    1      A Q_RES_0402LF-10,1%,1/16W,CHIP,A    I70 @S9S_MB_2U_LIB.S9S_MB_2U(SCH_1):PAGE133
   U17    5     2A 74CBTLV3126PW-74CBTLV3126PW,SMA    I80 @S9S_MB_2U_LIB.S9S_MB_2U(SCH_1):PAGE134
  R753    1      A Q_RES_0402LF-10,1%,1/16W,CHIP,A   I128 @S9S_MB_2U_LIB.S9S_MB_2U(SCH_1):PAGE134
  R481    1      A Q_RES_0402LF-0,5%,1/16W,CHIP,CA    I58 @S9S_MB_2U_LIB.S9S_MB_2U(SCH_1):PAGE226

JTAG_DBP_TDI_PCH @S9S_MB_2U_LIB.S9S_MB_2U(SCH_1):JTAG_DBP_TDI_PCH
  R753    2      B Q_RES_0402LF-10,1%,1/16W,CHIP,A   I128 @S9S_MB_2U_LIB.S9S_MB_2U(SCH_1):PAGE134
  R748    2      B Q_RES_0402LF-75,1%,1/16W,CHIP,A   I180 @S9S_MB_2U_LIB.S9S_MB_2U(SCH_1):PAGE134
    U4 BE38 JTAG_TDI EMMITSBURG_REV0P9-GFNOCPU04302A    I36 @S9S_MB_2U_LIB.S9S_MB_2U(SCH_1):PAGE174

JTAG_DBP_TDI_R @S9S_MB_2U_LIB.S9S_MB_2U(SCH_1):JTAG_DBP_TDI_R
   J42    5      5 SCONN60_ASP21410801-SCONN60_ASA    I44 @S9S_MB_2U_LIB.S9S_MB_2U(SCH_1):PAGE133
  R763    2      B Q_RES_0402LF-10,1%,1/16W,CHIP,A    I70 @S9S_MB_2U_LIB.S9S_MB_2U(SCH_1):PAGE133

JTAG_DBP_TDO @S9S_MB_2U_LIB.S9S_MB_2U(SCH_1):JTAG_DBP_TDO
  R776    2      B Q_RES_0402LF-100,1%,1/16W,CHIPA     I7 @S9S_MB_2U_LIB.S9S_MB_2U(SCH_1):PAGE133
   U17   12     4A 74CBTLV3126PW-74CBTLV3126PW,SMA    I80 @S9S_MB_2U_LIB.S9S_MB_2U(SCH_1):PAGE134
  R752    1      A Q_RES_0402LF-10,1%,1/16W,CHIP,A   I127 @S9S_MB_2U_LIB.S9S_MB_2U(SCH_1):PAGE134
 R1366    1      A Q_RES_0402LF-100,1%,1/16W,CHIPA    I64 @S9S_MB_2U_LIB.S9S_MB_2U(SCH_1):PAGE226

JTAG_DBP_TDO_PCH @S9S_MB_2U_LIB.S9S_MB_2U(SCH_1):JTAG_DBP_TDO_PCH
  R752    2      B Q_RES_0402LF-10,1%,1/16W,CHIP,A   I127 @S9S_MB_2U_LIB.S9S_MB_2U(SCH_1):PAGE134
  R747    2      B Q_RES_0402LF-150,1%,1/16W,CHIPA   I176 @S9S_MB_2U_LIB.S9S_MB_2U(SCH_1):PAGE134
    U4 BE36 JTAG_TDO EMMITSBURG_REV0P9-GFNOCPU04302A    I36 @S9S_MB_2U_LIB.S9S_MB_2U(SCH_1):PAGE174

JTAG_DBP_TDO_R @S9S_MB_2U_LIB.S9S_MB_2U(SCH_1):JTAG_DBP_TDO_R
  R776    1      A Q_RES_0402LF-100,1%,1/16W,CHIPA     I7 @S9S_MB_2U_LIB.S9S_MB_2U(SCH_1):PAGE133
   J42    4      4 SCONN60_ASP21410801-SCONN60_ASA    I44 @S9S_MB_2U_LIB.S9S_MB_2U(SCH_1):PAGE133

JTAG_DBP_TMS @S9S_MB_2U_LIB.S9S_MB_2U(SCH_1):JTAG_DBP_TMS
  R775    2      B Q_RES_0402LF-10,1%,1/16W,CHIP,A     I5 @S9S_MB_2U_LIB.S9S_MB_2U(SCH_1):PAGE133
   U17    2     1A 74CBTLV3126PW-74CBTLV3126PW,SMA    I80 @S9S_MB_2U_LIB.S9S_MB_2U(SCH_1):PAGE134
  R754    1      A Q_RES_0402LF-10,1%,1/16W,CHIP,A   I126 @S9S_MB_2U_LIB.S9S_MB_2U(SCH_1):PAGE134
  R480    1      A Q_RES_0402LF-0,5%,1/16W,CHIP,CA    I59 @S9S_MB_2U_LIB.S9S_MB_2U(SCH_1):PAGE226

JTAG_DBP_TMS_PCH @S9S_MB_2U_LIB.S9S_MB_2U(SCH_1):JTAG_DBP_TMS_PCH
  R754    2      B Q_RES_0402LF-10,1%,1/16W,CHIP,A   I126 @S9S_MB_2U_LIB.S9S_MB_2U(SCH_1):PAGE134
  R749    2      B Q_RES_0402LF-75,1%,1/16W,CHIP,A   I179 @S9S_MB_2U_LIB.S9S_MB_2U(SCH_1):PAGE134
    U4 BD37 JTAG_TMS EMMITSBURG_REV0P9-GFNOCPU04302A    I36 @S9S_MB_2U_LIB.S9S_MB_2U(SCH_1):PAGE174

JTAG_DBP_TMS_R @S9S_MB_2U_LIB.S9S_MB_2U(SCH_1):JTAG_DBP_TMS_R
  R775    1      A Q_RES_0402LF-10,1%,1/16W,CHIP,A     I5 @S9S_MB_2U_LIB.S9S_MB_2U(SCH_1):PAGE133
   J42    2      2 SCONN60_ASP21410801-SCONN60_ASA    I44 @S9S_MB_2U_LIB.S9S_MB_2U(SCH_1):PAGE133

JTAG_MUX_CPU0_GTL_TDI @S9S_MB_2U_LIB.S9S_MB_2U(SCH_1):JTAG_MUX_CPU0_GTL_TDI
    R4    1      A Q_RES_0402LF-200,1%,1/16W,CHIPA    I29 @S9S_MB_2U_LIB.S9S_MB_2U(SCH_1):PAGE13
   U21    3     B0 NC7SB3157_SMLF-NC7SB3157P6X,NCA    I58 @S9S_MB_2U_LIB.S9S_MB_2U(SCH_1):PAGE135
  R741    2      B Q_RES_0402LF-150,1%,1/16W,CHIPA    I66 @S9S_MB_2U_LIB.S9S_MB_2U(SCH_1):PAGE135

JTAG_MUX_CPU1_GTL_TDI @S9S_MB_2U_LIB.S9S_MB_2U(SCH_1):JTAG_MUX_CPU1_GTL_TDI
   R64    1      A Q_RES_0402LF-200,1%,1/16W,CHIPA     I9 @S9S_MB_2U_LIB.S9S_MB_2U(SCH_1):PAGE44
   U21    1     B1 NC7SB3157_SMLF-NC7SB3157P6X,NCA    I58 @S9S_MB_2U_LIB.S9S_MB_2U(SCH_1):PAGE135
  R743    2      B Q_RES_0402LF-150,1%,1/16W,CHIPA    I65 @S9S_MB_2U_LIB.S9S_MB_2U(SCH_1):PAGE135
   U16    2      Z 74LVC1G66GV-74LVC1G66GV,SMLF,IA   I115 @S9S_MB_2U_LIB.S9S_MB_2U(SCH_1):PAGE135

JTAG_MUX_QS_GTL_TDO @S9S_MB_2U_LIB.S9S_MB_2U(SCH_1):JTAG_MUX_QS_GTL_TDO
   U17   11     4B 74CBTLV3126PW-74CBTLV3126PW,SMA    I80 @S9S_MB_2U_LIB.S9S_MB_2U(SCH_1):PAGE134
   U22    4      A NC7SB3157_SMLF-NC7SB3157P6X,NCA    I71 @S9S_MB_2U_LIB.S9S_MB_2U(SCH_1):PAGE135

JTAG_PLD_JTAGEN @S9S_MB_2U_LIB.S9S_MB_2U(SCH_1):JTAG_PLD_JTAGEN
  R919    2      B Q_RES_0402LF-10K,1%,1/16W,CHIPA    I75 @S9S_MB_2U_LIB.S9S_MB_2U(SCH_1):PAGE210
  R920    1      A Q_RES_0402LF-1K,1%,1/16W,EMPTYA    I76 @S9S_MB_2U_LIB.S9S_MB_2U(SCH_1):PAGE210
  U249  E14 PT31C||JTAGENB LCMXO3LF9400C5BG484C-LCMXO3LF-A    I70 @S9S_MB_2U_LIB.S9S_MB_2U(SCH_1):PAGE311

JTAG_PLD_TCK_R @S9S_MB_2U_LIB.S9S_MB_2U(SCH_1):JTAG_PLD_TCK_R
  R806    1      A Q_RES_0402LF-33.2,1%,1/16W,CHIA    I54 @S9S_MB_2U_LIB.S9S_MB_2U(SCH_1):PAGE210
  U249  D10 PT22C||TCK LCMXO3LF9400C5BG484C-LCMXO3LF-A    I70 @S9S_MB_2U_LIB.S9S_MB_2U(SCH_1):PAGE311

JTAG_PLD_TDI_R @S9S_MB_2U_LIB.S9S_MB_2U(SCH_1):JTAG_PLD_TDI_R
  R803    1      A Q_RES_0402LF-33.2,1%,1/16W,CHIA    I19 @S9S_MB_2U_LIB.S9S_MB_2U(SCH_1):PAGE210
  U249   E9 PT15D||TDI LCMXO3LF9400C5BG484C-LCMXO3LF-A    I70 @S9S_MB_2U_LIB.S9S_MB_2U(SCH_1):PAGE311

JTAG_PLD_TDO_R @S9S_MB_2U_LIB.S9S_MB_2U(SCH_1):JTAG_PLD_TDO_R
  R804    1      A Q_RES_0402LF-33.2,1%,1/16W,CHIA    I20 @S9S_MB_2U_LIB.S9S_MB_2U(SCH_1):PAGE210
  U249   E8 PT15C||TDO LCMXO3LF9400C5BG484C-LCMXO3LF-A    I70 @S9S_MB_2U_LIB.S9S_MB_2U(SCH_1):PAGE311
 R1440    1      A Q_RES_0402LF-10K,1%,1/16W,EMPTA    I41 @S9S_MB_2U_LIB.S9S_MB_2U(SCH_1):PAGE209

JTAG_PLD_TMS_R @S9S_MB_2U_LIB.S9S_MB_2U(SCH_1):JTAG_PLD_TMS_R
  R805    1      A Q_RES_0402LF-33.2,1%,1/16W,CHIA    I25 @S9S_MB_2U_LIB.S9S_MB_2U(SCH_1):PAGE210
  U249  C10 PT22D||TMS LCMXO3LF9400C5BG484C-LCMXO3LF-A    I70 @S9S_MB_2U_LIB.S9S_MB_2U(SCH_1):PAGE311

JTAG_QS_MUX_GTL_TDI @S9S_MB_2U_LIB.S9S_MB_2U(SCH_1):JTAG_QS_MUX_GTL_TDI
   U17    6     2B 74CBTLV3126PW-74CBTLV3126PW,SMA    I80 @S9S_MB_2U_LIB.S9S_MB_2U(SCH_1):PAGE134
   U21    4      A NC7SB3157_SMLF-NC7SB3157P6X,NCA    I58 @S9S_MB_2U_LIB.S9S_MB_2U(SCH_1):PAGE135

JTAG_RST_DBP_RSMRST_N @S9S_MB_2U_LIB.S9S_MB_2U(SCH_1):JTAG_RST_DBP_RSMRST_N
   J42   42     42 SCONN60_ASP21410801-SCONN60_ASA    I44 @S9S_MB_2U_LIB.S9S_MB_2U(SCH_1):PAGE133
  R772    1      A Q_RES_0402LF-1K,1%,1/16W,CHIP,A   I118 @S9S_MB_2U_LIB.S9S_MB_2U(SCH_1):PAGE133

JTAG_RST_DBP_RST_CO_N @S9S_MB_2U_LIB.S9S_MB_2U(SCH_1):JTAG_RST_DBP_RST_CO_N
   J42    6      6 SCONN60_ASP21410801-SCONN60_ASA    I44 @S9S_MB_2U_LIB.S9S_MB_2U(SCH_1):PAGE133
  R767    2      B Q_RES_0402LF-1K,1%,1/16W,CHIP,A   I113 @S9S_MB_2U_LIB.S9S_MB_2U(SCH_1):PAGE133
  C549    1      A Q_CAP_0402-0.1UF,25V,10%,X7R,CA   I129 @S9S_MB_2U_LIB.S9S_MB_2U(SCH_1):PAGE133

JTAG_TRC_PCH_PTI0_CLK @S9S_MB_2U_LIB.S9S_MB_2U(SCH_1):JTAG_TRC_PCH_PTI0_CLK
   J42   13     13 SCONN60_ASP21410801-SCONN60_ASA    I44 @S9S_MB_2U_LIB.S9S_MB_2U(SCH_1):PAGE133
    U4 BD33 GPPC_B_0_GSXDOUT EMMITSBURG_REV0P9-GFNOCPU04302A    I93 @S9S_MB_2U_LIB.S9S_MB_2U(SCH_1):PAGE175

JTAG_TRC_PCH_PTI1_CLK @S9S_MB_2U_LIB.S9S_MB_2U(SCH_1):JTAG_TRC_PCH_PTI1_CLK
   J42   59     59 SCONN60_ASP21410801-SCONN60_ASA    I44 @S9S_MB_2U_LIB.S9S_MB_2U(SCH_1):PAGE133
    U4 BD23 GPPC_B_23 EMMITSBURG_REV0P9-GFNOCPU04302A    I93 @S9S_MB_2U_LIB.S9S_MB_2U(SCH_1):PAGE175

JTAG_TRC_PCH_PTI<0> @S9S_MB_2U_LIB.S9S_MB_2U(SCH_1):JTAG_TRC_PCH_PTI(0)
   J42   19     19 SCONN60_ASP21410801-SCONN60_ASA    I44 @S9S_MB_2U_LIB.S9S_MB_2U(SCH_1):PAGE133
    U4 BE32 GPPC_B_1_GSXSLOAD EMMITSBURG_REV0P9-GFNOCPU04302A    I93 @S9S_MB_2U_LIB.S9S_MB_2U(SCH_1):PAGE175

JTAG_TRC_PCH_PTI<10> @S9S_MB_2U_LIB.S9S_MB_2U(SCH_1):JTAG_TRC_PCH_PTI(10)
   J42   39     39 SCONN60_ASP21410801-SCONN60_ASA    I44 @S9S_MB_2U_LIB.S9S_MB_2U(SCH_1):PAGE133
    U4 BF27 GPPC_B_17_HS_UART1_TXD EMMITSBURG_REV0P9-GFNOCPU04302A    I93 @S9S_MB_2U_LIB.S9S_MB_2U(SCH_1):PAGE175

JTAG_TRC_PCH_PTI<11> @S9S_MB_2U_LIB.S9S_MB_2U(SCH_1):JTAG_TRC_PCH_PTI(11)
   J42   41     41 SCONN60_ASP21410801-SCONN60_ASA    I44 @S9S_MB_2U_LIB.S9S_MB_2U(SCH_1):PAGE133
    U4 BD25 GPPC_B_18_HS_UART1_RTS_N EMMITSBURG_REV0P9-GFNOCPU04302A    I93 @S9S_MB_2U_LIB.S9S_MB_2U(SCH_1):PAGE175

JTAG_TRC_PCH_PTI<12> @S9S_MB_2U_LIB.S9S_MB_2U(SCH_1):JTAG_TRC_PCH_PTI(12)
   J42   43     43 SCONN60_ASP21410801-SCONN60_ASA    I44 @S9S_MB_2U_LIB.S9S_MB_2U(SCH_1):PAGE133
    U4 BF25 GPPC_B_19_HS_UART1_CTS_N EMMITSBURG_REV0P9-GFNOCPU04302A    I93 @S9S_MB_2U_LIB.S9S_MB_2U(SCH_1):PAGE175

JTAG_TRC_PCH_PTI<13> @S9S_MB_2U_LIB.S9S_MB_2U(SCH_1):JTAG_TRC_PCH_PTI(13)
   J42   45     45 SCONN60_ASP21410801-SCONN60_ASA    I44 @S9S_MB_2U_LIB.S9S_MB_2U(SCH_1):PAGE133
    U4 BE24 GPPC_B_20 EMMITSBURG_REV0P9-GFNOCPU04302A    I93 @S9S_MB_2U_LIB.S9S_MB_2U(SCH_1):PAGE175

JTAG_TRC_PCH_PTI<14> @S9S_MB_2U_LIB.S9S_MB_2U(SCH_1):JTAG_TRC_PCH_PTI(14)
   J42   47     47 SCONN60_ASP21410801-SCONN60_ASA    I44 @S9S_MB_2U_LIB.S9S_MB_2U(SCH_1):PAGE133
    U4 BF23 GPPC_B_21 EMMITSBURG_REV0P9-GFNOCPU04302A    I93 @S9S_MB_2U_LIB.S9S_MB_2U(SCH_1):PAGE175

JTAG_TRC_PCH_PTI<15> @S9S_MB_2U_LIB.S9S_MB_2U(SCH_1):JTAG_TRC_PCH_PTI(15)
   J42   49     49 SCONN60_ASP21410801-SCONN60_ASA    I44 @S9S_MB_2U_LIB.S9S_MB_2U(SCH_1):PAGE133
    U4 BE22 GPPC_B_22 EMMITSBURG_REV0P9-GFNOCPU04302A    I93 @S9S_MB_2U_LIB.S9S_MB_2U(SCH_1):PAGE175

JTAG_TRC_PCH_PTI<1> @S9S_MB_2U_LIB.S9S_MB_2U(SCH_1):JTAG_TRC_PCH_PTI(1)
   J42   21     21 SCONN60_ASP21410801-SCONN60_ASA    I44 @S9S_MB_2U_LIB.S9S_MB_2U(SCH_1):PAGE133
    U4 BF33 GPPC_B_2_GSXDIN EMMITSBURG_REV0P9-GFNOCPU04302A    I93 @S9S_MB_2U_LIB.S9S_MB_2U(SCH_1):PAGE175

JTAG_TRC_PCH_PTI<2> @S9S_MB_2U_LIB.S9S_MB_2U(SCH_1):JTAG_TRC_PCH_PTI(2)
   J42   23     23 SCONN60_ASP21410801-SCONN60_ASA    I44 @S9S_MB_2U_LIB.S9S_MB_2U(SCH_1):PAGE133
    U4 BD31 GPPC_B_3_GSXRESET_N EMMITSBURG_REV0P9-GFNOCPU04302A    I93 @S9S_MB_2U_LIB.S9S_MB_2U(SCH_1):PAGE175

JTAG_TRC_PCH_PTI<3> @S9S_MB_2U_LIB.S9S_MB_2U(SCH_1):JTAG_TRC_PCH_PTI(3)
   J42   25     25 SCONN60_ASP21410801-SCONN60_ASA    I44 @S9S_MB_2U_LIB.S9S_MB_2U(SCH_1):PAGE133
    U4 BE30 GPPC_B_4_GSXCLK EMMITSBURG_REV0P9-GFNOCPU04302A    I93 @S9S_MB_2U_LIB.S9S_MB_2U(SCH_1):PAGE175

JTAG_TRC_PCH_PTI<4> @S9S_MB_2U_LIB.S9S_MB_2U(SCH_1):JTAG_TRC_PCH_PTI(4)
   J42   27     27 SCONN60_ASP21410801-SCONN60_ASA    I44 @S9S_MB_2U_LIB.S9S_MB_2U(SCH_1):PAGE133
    U4 BF31 GPPC_B_5_USB2_OCB_0 EMMITSBURG_REV0P9-GFNOCPU04302A    I93 @S9S_MB_2U_LIB.S9S_MB_2U(SCH_1):PAGE175

JTAG_TRC_PCH_PTI<5> @S9S_MB_2U_LIB.S9S_MB_2U(SCH_1):JTAG_TRC_PCH_PTI(5)
   J42   29     29 SCONN60_ASP21410801-SCONN60_ASA    I44 @S9S_MB_2U_LIB.S9S_MB_2U(SCH_1):PAGE133
    U4 BD29 GPPC_B_12_HS_UART0_RXD EMMITSBURG_REV0P9-GFNOCPU04302A    I93 @S9S_MB_2U_LIB.S9S_MB_2U(SCH_1):PAGE175

JTAG_TRC_PCH_PTI<6> @S9S_MB_2U_LIB.S9S_MB_2U(SCH_1):JTAG_TRC_PCH_PTI(6)
   J42   31     31 SCONN60_ASP21410801-SCONN60_ASA    I44 @S9S_MB_2U_LIB.S9S_MB_2U(SCH_1):PAGE133
    U4 BE28 GPPC_B_13_HS_UART0_TXD EMMITSBURG_REV0P9-GFNOCPU04302A    I93 @S9S_MB_2U_LIB.S9S_MB_2U(SCH_1):PAGE175
 R2132    1      A Q_RES_0402LF-0,5%,1/16W,EMPTY,A    I91 @S9S_MB_2U_LIB.S9S_MB_2U(SCH_1):PAGE190
 R2134    1      A Q_RES_0402LF-10K,1%,1/16W,CHIPA   I109 @S9S_MB_2U_LIB.S9S_MB_2U(SCH_1):PAGE189
  J104    2      2 CONN14_210HP207GBR1-CONN14_210A   I134 @S9S_MB_2U_LIB.S9S_MB_2U(SCH_1):PAGE189

JTAG_TRC_PCH_PTI<7> @S9S_MB_2U_LIB.S9S_MB_2U(SCH_1):JTAG_TRC_PCH_PTI(7)
   J42   33     33 SCONN60_ASP21410801-SCONN60_ASA    I44 @S9S_MB_2U_LIB.S9S_MB_2U(SCH_1):PAGE133
    U4 BF29 GPPC_B_14_HS_UART0_RTS_N EMMITSBURG_REV0P9-GFNOCPU04302A    I93 @S9S_MB_2U_LIB.S9S_MB_2U(SCH_1):PAGE175

JTAG_TRC_PCH_PTI<8> @S9S_MB_2U_LIB.S9S_MB_2U(SCH_1):JTAG_TRC_PCH_PTI(8)
   J42   35     35 SCONN60_ASP21410801-SCONN60_ASA    I44 @S9S_MB_2U_LIB.S9S_MB_2U(SCH_1):PAGE133
    U4 BD27 GPPC_B_15_HS_UART0_CTS_N EMMITSBURG_REV0P9-GFNOCPU04302A    I93 @S9S_MB_2U_LIB.S9S_MB_2U(SCH_1):PAGE175

JTAG_TRC_PCH_PTI<9> @S9S_MB_2U_LIB.S9S_MB_2U(SCH_1):JTAG_TRC_PCH_PTI(9)
   J42   37     37 SCONN60_ASP21410801-SCONN60_ASA    I44 @S9S_MB_2U_LIB.S9S_MB_2U(SCH_1):PAGE133
    U4 BE26 GPPC_B_16_HS_UART1_RXD EMMITSBURG_REV0P9-GFNOCPU04302A    I93 @S9S_MB_2U_LIB.S9S_MB_2U(SCH_1):PAGE175

LED_CPU_RMCA_CATERR @S9S_MB_2U_LIB.S9S_MB_2U(SCH_1):LED_CPU_RMCA_CATERR
   Q33    D      D MOSFET_NCH_GDS_ESD_PROTECTED-2A   I272 @S9S_MB_2U_LIB.S9S_MB_2U(SCH_1):PAGE207
    D6    A      A Q_LED_SMLF-LED_YELLOW,LTST-C19A   I279 @S9S_MB_2U_LIB.S9S_MB_2U(SCH_1):PAGE207
  R366    2      B Q_RES_0402LF-249,1%,1/16W,CHIPA   I280 @S9S_MB_2U_LIB.S9S_MB_2U(SCH_1):PAGE207

LED_CPU_RMCA_CATERR_R @S9S_MB_2U_LIB.S9S_MB_2U(SCH_1):LED_CPU_RMCA_CATERR_R
 R2339    1      A Q_RES_0402LF-22,5%,1/16W,CHIP,A   I268 @S9S_MB_2U_LIB.S9S_MB_2U(SCH_1):PAGE207
   Q33    S      S MOSFET_NCH_GDS_ESD_PROTECTED-2A   I272 @S9S_MB_2U_LIB.S9S_MB_2U(SCH_1):PAGE207

LED_FM_PCH_SLP_S3_N @S9S_MB_2U_LIB.S9S_MB_2U(SCH_1):LED_FM_PCH_SLP_S3_N
   D95    A      A Q_LED_SMLF-LED_BLUE,LTST-C281TA    I35 @S9S_MB_2U_LIB.S9S_MB_2U(SCH_1):PAGE242
 R3078    1      A Q_RES_0402LF-130,1%,1/16W,CHIPA    I41 @S9S_MB_2U_LIB.S9S_MB_2U(SCH_1):PAGE242

LED_FM_PCH_SLP_S3_N_D @S9S_MB_2U_LIB.S9S_MB_2U(SCH_1):LED_FM_PCH_SLP_S3_N_D
   Q78    6     D1 MOSFET_NCH_DUAL-PJT138K,SMLF,IA    I34 @S9S_MB_2U_LIB.S9S_MB_2U(SCH_1):PAGE242
   D95    C      C Q_LED_SMLF-LED_BLUE,LTST-C281TA    I35 @S9S_MB_2U_LIB.S9S_MB_2U(SCH_1):PAGE242

LED_FM_PCH_SLP_S4_N @S9S_MB_2U_LIB.S9S_MB_2U(SCH_1):LED_FM_PCH_SLP_S4_N
   D94    A      A Q_LED_SMLF-LED_BLUE,LTST-C281TA    I11 @S9S_MB_2U_LIB.S9S_MB_2U(SCH_1):PAGE242
 R3073    1      A Q_RES_0402LF-130,1%,1/16W,CHIPA    I12 @S9S_MB_2U_LIB.S9S_MB_2U(SCH_1):PAGE242

LED_FM_PCH_SLP_S4_N_D @S9S_MB_2U_LIB.S9S_MB_2U(SCH_1):LED_FM_PCH_SLP_S4_N_D
   Q77    3     D2 MOSFET_NCH_DUAL-PJT138K,SMLF,IA     I3 @S9S_MB_2U_LIB.S9S_MB_2U(SCH_1):PAGE242
   D94    C      C Q_LED_SMLF-LED_BLUE,LTST-C281TA    I11 @S9S_MB_2U_LIB.S9S_MB_2U(SCH_1):PAGE242

LED_HDD_ACTIVITY_B_N @S9S_MB_2U_LIB.S9S_MB_2U(SCH_1):LED_HDD_ACTIVITY_B_N
 R3297    1      A Q_RES_0402LF-10K,1%,1/16W,CHIPA   I303 @S9S_MB_2U_LIB.S9S_MB_2U(SCH_1):PAGE182
  U239    4      Y 74LVC1G126SE7-74LVC1G126SE-7,SA   I315 @S9S_MB_2U_LIB.S9S_MB_2U(SCH_1):PAGE182
 R4607    1      A Q_RES_0402LF-0,5%,1/16W,CHIP,CA   I183 @S9S_MB_2U_LIB.S9S_MB_2U(SCH_1):PAGE313
 R3254    2      B Q_RES_0402LF-0,5%,1/16W,EMPTY,A    I49 @S9S_MB_2U_LIB.S9S_MB_2U(SCH_1):PAGE227

LED_HDD_ACTIVITY_B_PLD_N @S9S_MB_2U_LIB.S9S_MB_2U(SCH_1):LED_HDD_ACTIVITY_B_PLD_N
  U249 AA22  PR29A LCMXO3LF9400C5BG484C-LCMXO3LF-A     I1 @S9S_MB_2U_LIB.S9S_MB_2U(SCH_1):PAGE313
 R4607    2      B Q_RES_0402LF-0,5%,1/16W,CHIP,CA   I183 @S9S_MB_2U_LIB.S9S_MB_2U(SCH_1):PAGE313

LED_HDD_ACTIVITY_N @S9S_MB_2U_LIB.S9S_MB_2U(SCH_1):LED_HDD_ACTIVITY_N
  U239    2      A 74LVC1G126SE7-74LVC1G126SE-7,SA   I315 @S9S_MB_2U_LIB.S9S_MB_2U(SCH_1):PAGE182
 R3295    2      B Q_RES_0402LF-4.7K,1%,1/16W,CHIA   I317 @S9S_MB_2U_LIB.S9S_MB_2U(SCH_1):PAGE182
 R3294    2      B Q_RES_0402LF-0,5%,1/16W,CHIP,CA   I320 @S9S_MB_2U_LIB.S9S_MB_2U(SCH_1):PAGE182

LED_M2_SSD_0_ACT_N @S9S_MB_2U_LIB.S9S_MB_2U(SCH_1):LED_M2_SSD_0_ACT_N
   J59   10 DAS_DSS#||LED1# SCONN75K_APCI0155P004A-SCONN75A   I178 @S9S_MB_2U_LIB.S9S_MB_2U(SCH_1):PAGE182
 R3294    1      A Q_RES_0402LF-0,5%,1/16W,CHIP,CA   I320 @S9S_MB_2U_LIB.S9S_MB_2U(SCH_1):PAGE182

LED_P12V_AUX_R1 @S9S_MB_2U_LIB.S9S_MB_2U(SCH_1):LED_P12V_AUX_R1
  D142    A      A Q_LED_SMLF-LED_BLUE,LTST-C281TA    I58 @S9S_MB_2U_LIB.S9S_MB_2U(SCH_1):PAGE241
 R4702    1      A Q_RES_0402LF-560,1%,1/16W,CHIPA    I64 @S9S_MB_2U_LIB.S9S_MB_2U(SCH_1):PAGE241

LED_P12V_AUX_R2 @S9S_MB_2U_LIB.S9S_MB_2U(SCH_1):LED_P12V_AUX_R2
 R4702    2      B Q_RES_0402LF-560,1%,1/16W,CHIPA    I64 @S9S_MB_2U_LIB.S9S_MB_2U(SCH_1):PAGE241
 R4704    1      A Q_RES_0402LF-560,1%,1/16W,CHIPA    I65 @S9S_MB_2U_LIB.S9S_MB_2U(SCH_1):PAGE241

LED_P12V_AUX_R3 @S9S_MB_2U_LIB.S9S_MB_2U(SCH_1):LED_P12V_AUX_R3
 R4704    2      B Q_RES_0402LF-560,1%,1/16W,CHIPA    I65 @S9S_MB_2U_LIB.S9S_MB_2U(SCH_1):PAGE241
 R4706    1      A Q_RES_0402LF-560,1%,1/16W,CHIPA    I66 @S9S_MB_2U_LIB.S9S_MB_2U(SCH_1):PAGE241

LED_P12V_PSU_R1 @S9S_MB_2U_LIB.S9S_MB_2U(SCH_1):LED_P12V_PSU_R1
  D143    A      A Q_LED_SMLF-LED_BLUE,LTST-C281TA    I49 @S9S_MB_2U_LIB.S9S_MB_2U(SCH_1):PAGE241
 R4703    1      A Q_RES_0402LF-560,1%,1/16W,CHIPA    I61 @S9S_MB_2U_LIB.S9S_MB_2U(SCH_1):PAGE241

LED_P12V_PSU_R2 @S9S_MB_2U_LIB.S9S_MB_2U(SCH_1):LED_P12V_PSU_R2
 R4703    2      B Q_RES_0402LF-560,1%,1/16W,CHIPA    I61 @S9S_MB_2U_LIB.S9S_MB_2U(SCH_1):PAGE241
 R4705    1      A Q_RES_0402LF-560,1%,1/16W,CHIPA    I62 @S9S_MB_2U_LIB.S9S_MB_2U(SCH_1):PAGE241

LED_P12V_PSU_R3 @S9S_MB_2U_LIB.S9S_MB_2U(SCH_1):LED_P12V_PSU_R3
 R4705    2      B Q_RES_0402LF-560,1%,1/16W,CHIPA    I62 @S9S_MB_2U_LIB.S9S_MB_2U(SCH_1):PAGE241
 R4707    1      A Q_RES_0402LF-560,1%,1/16W,CHIPA    I63 @S9S_MB_2U_LIB.S9S_MB_2U(SCH_1):PAGE241

LED_P12V_SCM_FAULT @S9S_MB_2U_LIB.S9S_MB_2U(SCH_1):LED_P12V_SCM_FAULT
  D144    A      A Q_LED_SMLF-LED_YELLOW,LTST-C19A    I67 @S9S_MB_2U_LIB.S9S_MB_2U(SCH_1):PAGE241
 R4711    1      A Q_RES_0402LF-249,1%,1/16W,CHIPA    I68 @S9S_MB_2U_LIB.S9S_MB_2U(SCH_1):PAGE241

LED_P12V_SCM_FAULT_D1 @S9S_MB_2U_LIB.S9S_MB_2U(SCH_1):LED_P12V_SCM_FAULT_D1
  Q150    6     D1 MOSFET_NCH_DUAL-PJT138K,SMLF,IA    I69 @S9S_MB_2U_LIB.S9S_MB_2U(SCH_1):PAGE241
  Q150    5     G2 MOSFET_NCH_DUAL-PJT138K,SMLF,IA    I72 @S9S_MB_2U_LIB.S9S_MB_2U(SCH_1):PAGE241
 R4710    2      B Q_RES_0402LF-4.7K,5%,1/16W,CHIA    I74 @S9S_MB_2U_LIB.S9S_MB_2U(SCH_1):PAGE241

LED_P12V_SCM_FAULT_D2 @S9S_MB_2U_LIB.S9S_MB_2U(SCH_1):LED_P12V_SCM_FAULT_D2
  D144    C      C Q_LED_SMLF-LED_YELLOW,LTST-C19A    I67 @S9S_MB_2U_LIB.S9S_MB_2U(SCH_1):PAGE241
  Q150    3     D2 MOSFET_NCH_DUAL-PJT138K,SMLF,IA    I72 @S9S_MB_2U_LIB.S9S_MB_2U(SCH_1):PAGE241

LED_P3V3 @S9S_MB_2U_LIB.S9S_MB_2U(SCH_1):LED_P3V3
   D99    A      A Q_LED_SMLF-LED_BLUE,LTST-C281TA    I60 @S9S_MB_2U_LIB.S9S_MB_2U(SCH_1):PAGE242
 R3100    1      A Q_RES_0402LF-130,1%,1/16W,CHIPA    I64 @S9S_MB_2U_LIB.S9S_MB_2U(SCH_1):PAGE242

LED_P5V @S9S_MB_2U_LIB.S9S_MB_2U(SCH_1):LED_P5V
   D98    A      A Q_LED_SMLF-LED_BLUE,LTST-C281TA    I53 @S9S_MB_2U_LIB.S9S_MB_2U(SCH_1):PAGE242
 R3102    1      A Q_RES_0402LF-470,1%,1/16W,CHIPA    I61 @S9S_MB_2U_LIB.S9S_MB_2U(SCH_1):PAGE242

LED_P5V_AUX @S9S_MB_2U_LIB.S9S_MB_2U(SCH_1):LED_P5V_AUX
   D97    A      A Q_LED_SMLF-LED_BLUE,LTST-C281TA    I52 @S9S_MB_2U_LIB.S9S_MB_2U(SCH_1):PAGE242
 R3101    1      A Q_RES_0402LF-470,1%,1/16W,CHIPA    I62 @S9S_MB_2U_LIB.S9S_MB_2U(SCH_1):PAGE242

LED_PWRGD_CPUPWRGD_GTL @S9S_MB_2U_LIB.S9S_MB_2U(SCH_1):LED_PWRGD_CPUPWRGD_GTL
   D89    A      A Q_LED_SMLF-LED_BLUE,LTST-C281TA    I11 @S9S_MB_2U_LIB.S9S_MB_2U(SCH_1):PAGE241
 R1044    1      A Q_RES_0402LF-130,1%,1/16W,CHIPA    I40 @S9S_MB_2U_LIB.S9S_MB_2U(SCH_1):PAGE241

LED_PWRGD_CPUPWRGD_GTL_D @S9S_MB_2U_LIB.S9S_MB_2U(SCH_1):LED_PWRGD_CPUPWRGD_GTL_D
   Q88    6     D1 MOSFET_NCH_DUAL-PJT138K,SMLF,IA     I8 @S9S_MB_2U_LIB.S9S_MB_2U(SCH_1):PAGE241
   D89    C      C Q_LED_SMLF-LED_BLUE,LTST-C281TA    I11 @S9S_MB_2U_LIB.S9S_MB_2U(SCH_1):PAGE241

LED_PWRGD_P1V05_PCH_AUX @S9S_MB_2U_LIB.S9S_MB_2U(SCH_1):LED_PWRGD_P1V05_PCH_AUX
 R3072    1      A Q_RES_0402LF-130,1%,1/16W,CHIPA    I15 @S9S_MB_2U_LIB.S9S_MB_2U(SCH_1):PAGE242
   D92    A      A Q_LED_SMLF-LED_BLUE,LTST-C281TA    I42 @S9S_MB_2U_LIB.S9S_MB_2U(SCH_1):PAGE242

LED_PWRGD_P1V05_PCH_AUX_D @S9S_MB_2U_LIB.S9S_MB_2U(SCH_1):LED_PWRGD_P1V05_PCH_AUX_D
   Q76    3     D2 MOSFET_NCH_DUAL-PJT138K,SMLF,IA     I8 @S9S_MB_2U_LIB.S9S_MB_2U(SCH_1):PAGE242
   D92    C      C Q_LED_SMLF-LED_BLUE,LTST-C281TA    I42 @S9S_MB_2U_LIB.S9S_MB_2U(SCH_1):PAGE242

LED_PWRGD_P1V8_PCH_AUX @S9S_MB_2U_LIB.S9S_MB_2U(SCH_1):LED_PWRGD_P1V8_PCH_AUX
   D91    A      A Q_LED_SMLF-LED_BLUE,LTST-C281TA    I18 @S9S_MB_2U_LIB.S9S_MB_2U(SCH_1):PAGE242
 R3071    1      A Q_RES_0402LF-130,1%,1/16W,CHIPA    I19 @S9S_MB_2U_LIB.S9S_MB_2U(SCH_1):PAGE242

LED_PWRGD_P1V8_PCH_AUX_D @S9S_MB_2U_LIB.S9S_MB_2U(SCH_1):LED_PWRGD_P1V8_PCH_AUX_D
   Q76    6     D1 MOSFET_NCH_DUAL-PJT138K,SMLF,IA    I17 @S9S_MB_2U_LIB.S9S_MB_2U(SCH_1):PAGE242
   D91    C      C Q_LED_SMLF-LED_BLUE,LTST-C281TA    I18 @S9S_MB_2U_LIB.S9S_MB_2U(SCH_1):PAGE242

LED_PWRGD_PCH_PWROK_R @S9S_MB_2U_LIB.S9S_MB_2U(SCH_1):LED_PWRGD_PCH_PWROK_R
   D87    A      A Q_LED_SMLF-LED_BLUE,LTST-C281TA    I20 @S9S_MB_2U_LIB.S9S_MB_2U(SCH_1):PAGE241
 R3068    1      A Q_RES_0402LF-130,1%,1/16W,CHIPA    I38 @S9S_MB_2U_LIB.S9S_MB_2U(SCH_1):PAGE241

LED_PWRGD_PCH_PWROK_R_D @S9S_MB_2U_LIB.S9S_MB_2U(SCH_1):LED_PWRGD_PCH_PWROK_R_D
   Q87    6     D1 MOSFET_NCH_DUAL-PJT138K,SMLF,IA    I17 @S9S_MB_2U_LIB.S9S_MB_2U(SCH_1):PAGE241
   D87    C      C Q_LED_SMLF-LED_BLUE,LTST-C281TA    I20 @S9S_MB_2U_LIB.S9S_MB_2U(SCH_1):PAGE241

LED_PWRGD_PS_PWROK_PLD @S9S_MB_2U_LIB.S9S_MB_2U(SCH_1):LED_PWRGD_PS_PWROK_PLD
   D96    A      A Q_LED_SMLF-LED_BLUE,LTST-C281TA    I31 @S9S_MB_2U_LIB.S9S_MB_2U(SCH_1):PAGE242
 R3075    1      A Q_RES_0402LF-130,1%,1/16W,CHIPA    I37 @S9S_MB_2U_LIB.S9S_MB_2U(SCH_1):PAGE242

LED_PWRGD_PS_PWROK_PLD_D @S9S_MB_2U_LIB.S9S_MB_2U(SCH_1):LED_PWRGD_PS_PWROK_PLD_D
   Q78    3     D2 MOSFET_NCH_DUAL-PJT138K,SMLF,IA    I26 @S9S_MB_2U_LIB.S9S_MB_2U(SCH_1):PAGE242
   D96    C      C Q_LED_SMLF-LED_BLUE,LTST-C281TA    I31 @S9S_MB_2U_LIB.S9S_MB_2U(SCH_1):PAGE242

LED_PWRGD_PVCCD_HV_CPU0 @S9S_MB_2U_LIB.S9S_MB_2U(SCH_1):LED_PWRGD_PVCCD_HV_CPU0
   D73    A      A Q_LED_SMLF-LED_BLUE,LTST-C281TA    I22 @S9S_MB_2U_LIB.S9S_MB_2U(SCH_1):PAGE305
 R3086    1      A Q_RES_0402LF-130,1%,1/16W,CHIPA    I49 @S9S_MB_2U_LIB.S9S_MB_2U(SCH_1):PAGE305

LED_PWRGD_PVCCD_HV_CPU0_D @S9S_MB_2U_LIB.S9S_MB_2U(SCH_1):LED_PWRGD_PVCCD_HV_CPU0_D
   Q79    6     D1 MOSFET_NCH_DUAL-PJT138K,SMLF,IA     I8 @S9S_MB_2U_LIB.S9S_MB_2U(SCH_1):PAGE305
   D73    C      C Q_LED_SMLF-LED_BLUE,LTST-C281TA    I22 @S9S_MB_2U_LIB.S9S_MB_2U(SCH_1):PAGE305

LED_PWRGD_PVCCD_HV_CPU1 @S9S_MB_2U_LIB.S9S_MB_2U(SCH_1):LED_PWRGD_PVCCD_HV_CPU1
   D80    A      A Q_LED_SMLF-LED_BLUE,LTST-C281TA    I19 @S9S_MB_2U_LIB.S9S_MB_2U(SCH_1):PAGE306
 R3093    1      A Q_RES_0402LF-130,1%,1/16W,CHIPA    I20 @S9S_MB_2U_LIB.S9S_MB_2U(SCH_1):PAGE306

LED_PWRGD_PVCCD_HV_CPU1_D @S9S_MB_2U_LIB.S9S_MB_2U(SCH_1):LED_PWRGD_PVCCD_HV_CPU1_D
   Q84    6     D1 MOSFET_NCH_DUAL-PJT138K,SMLF,IA    I18 @S9S_MB_2U_LIB.S9S_MB_2U(SCH_1):PAGE306
   D80    C      C Q_LED_SMLF-LED_BLUE,LTST-C281TA    I19 @S9S_MB_2U_LIB.S9S_MB_2U(SCH_1):PAGE306

LED_PWRGD_PVCCFA_EHV_CPU0 @S9S_MB_2U_LIB.S9S_MB_2U(SCH_1):LED_PWRGD_PVCCFA_EHV_CPU0
   D75    A      A Q_LED_SMLF-LED_BLUE,LTST-C281TA    I13 @S9S_MB_2U_LIB.S9S_MB_2U(SCH_1):PAGE305
 R3089    1      A Q_RES_0402LF-130,1%,1/16W,CHIPA    I51 @S9S_MB_2U_LIB.S9S_MB_2U(SCH_1):PAGE305

LED_PWRGD_PVCCFA_EHV_CPU0_D @S9S_MB_2U_LIB.S9S_MB_2U(SCH_1):LED_PWRGD_PVCCFA_EHV_CPU0_D
   Q80    6     D1 MOSFET_NCH_DUAL-PJT138K,SMLF,IA     I4 @S9S_MB_2U_LIB.S9S_MB_2U(SCH_1):PAGE305
   D75    C      C Q_LED_SMLF-LED_BLUE,LTST-C281TA    I13 @S9S_MB_2U_LIB.S9S_MB_2U(SCH_1):PAGE305

LED_PWRGD_PVCCFA_EHV_CPU1 @S9S_MB_2U_LIB.S9S_MB_2U(SCH_1):LED_PWRGD_PVCCFA_EHV_CPU1
   D82    A      A Q_LED_SMLF-LED_BLUE,LTST-C281TA    I13 @S9S_MB_2U_LIB.S9S_MB_2U(SCH_1):PAGE306
 R3096    1      A Q_RES_0402LF-130,1%,1/16W,CHIPA    I15 @S9S_MB_2U_LIB.S9S_MB_2U(SCH_1):PAGE306

LED_PWRGD_PVCCFA_EHV_CPU1_D @S9S_MB_2U_LIB.S9S_MB_2U(SCH_1):LED_PWRGD_PVCCFA_EHV_CPU1_D
   Q85    6     D1 MOSFET_NCH_DUAL-PJT138K,SMLF,IA     I6 @S9S_MB_2U_LIB.S9S_MB_2U(SCH_1):PAGE306
   D82    C      C Q_LED_SMLF-LED_BLUE,LTST-C281TA    I13 @S9S_MB_2U_LIB.S9S_MB_2U(SCH_1):PAGE306

LED_PWRGD_PVCCFA_EHV_FIVRA_CPU0 @S9S_MB_2U_LIB.S9S_MB_2U(SCH_1):LED_PWRGD_PVCCFA_EHV_FIVRA_CPU0
   D76    A      A Q_LED_SMLF-LED_BLUE,LTST-C281TA    I10 @S9S_MB_2U_LIB.S9S_MB_2U(SCH_1):PAGE305
 R3088    1      A Q_RES_0402LF-130,1%,1/16W,CHIPA    I52 @S9S_MB_2U_LIB.S9S_MB_2U(SCH_1):PAGE305

LED_PWRGD_PVCCFA_EHV_FIVRA_CPU1 @S9S_MB_2U_LIB.S9S_MB_2U(SCH_1):LED_PWRGD_PVCCFA_EHV_FIVRA_CPU1
   D83    A      A Q_LED_SMLF-LED_BLUE,LTST-C281TA    I11 @S9S_MB_2U_LIB.S9S_MB_2U(SCH_1):PAGE306
 R3095    1      A Q_RES_0402LF-130,1%,1/16W,CHIPA    I12 @S9S_MB_2U_LIB.S9S_MB_2U(SCH_1):PAGE306

LED_PWRGD_PVCCFA_EHV_FIVRA_CP_1 @S9S_MB_2U_LIB.S9S_MB_2U(SCH_1):LED_PWRGD_PVCCFA_EHV_FIVRA_CPU0_D
   Q80    3     D2 MOSFET_NCH_DUAL-PJT138K,SMLF,IA     I2 @S9S_MB_2U_LIB.S9S_MB_2U(SCH_1):PAGE305
   D76    C      C Q_LED_SMLF-LED_BLUE,LTST-C281TA    I10 @S9S_MB_2U_LIB.S9S_MB_2U(SCH_1):PAGE305

LED_PWRGD_PVCCFA_EHV_FIVRA_CP_2 @S9S_MB_2U_LIB.S9S_MB_2U(SCH_1):LED_PWRGD_PVCCFA_EHV_FIVRA_CPU1_D
   Q85    3     D2 MOSFET_NCH_DUAL-PJT138K,SMLF,IA     I3 @S9S_MB_2U_LIB.S9S_MB_2U(SCH_1):PAGE306
   D83    C      C Q_LED_SMLF-LED_BLUE,LTST-C281TA    I11 @S9S_MB_2U_LIB.S9S_MB_2U(SCH_1):PAGE306

LED_PWRGD_PVCCINFAON_CPU0 @S9S_MB_2U_LIB.S9S_MB_2U(SCH_1):LED_PWRGD_PVCCINFAON_CPU0
   D77    A      A Q_LED_SMLF-LED_BLUE,LTST-C281TA    I44 @S9S_MB_2U_LIB.S9S_MB_2U(SCH_1):PAGE305
 R3092    1      A Q_RES_0402LF-130,1%,1/16W,CHIPA    I55 @S9S_MB_2U_LIB.S9S_MB_2U(SCH_1):PAGE305

LED_PWRGD_PVCCINFAON_CPU0_D @S9S_MB_2U_LIB.S9S_MB_2U(SCH_1):LED_PWRGD_PVCCINFAON_CPU0_D
   Q81    6     D1 MOSFET_NCH_DUAL-PJT138K,SMLF,IA    I41 @S9S_MB_2U_LIB.S9S_MB_2U(SCH_1):PAGE305
   D77    C      C Q_LED_SMLF-LED_BLUE,LTST-C281TA    I44 @S9S_MB_2U_LIB.S9S_MB_2U(SCH_1):PAGE305

LED_PWRGD_PVCCINFAON_CPU1 @S9S_MB_2U_LIB.S9S_MB_2U(SCH_1):LED_PWRGD_PVCCINFAON_CPU1
   D84    A      A Q_LED_SMLF-LED_BLUE,LTST-C281TA    I36 @S9S_MB_2U_LIB.S9S_MB_2U(SCH_1):PAGE306
 R3099    1      A Q_RES_0402LF-130,1%,1/16W,CHIPA    I41 @S9S_MB_2U_LIB.S9S_MB_2U(SCH_1):PAGE306

LED_PWRGD_PVCCINFAON_CPU1_D @S9S_MB_2U_LIB.S9S_MB_2U(SCH_1):LED_PWRGD_PVCCINFAON_CPU1_D
   Q86    6     D1 MOSFET_NCH_DUAL-PJT138K,SMLF,IA    I35 @S9S_MB_2U_LIB.S9S_MB_2U(SCH_1):PAGE306
   D84    C      C Q_LED_SMLF-LED_BLUE,LTST-C281TA    I36 @S9S_MB_2U_LIB.S9S_MB_2U(SCH_1):PAGE306

LED_PWRGD_PVCCIN_CPU0 @S9S_MB_2U_LIB.S9S_MB_2U(SCH_1):LED_PWRGD_PVCCIN_CPU0
   D79    A      A Q_LED_SMLF-LED_BLUE,LTST-C281TA    I35 @S9S_MB_2U_LIB.S9S_MB_2U(SCH_1):PAGE305
 R3091    1      A Q_RES_0402LF-130,1%,1/16W,CHIPA    I53 @S9S_MB_2U_LIB.S9S_MB_2U(SCH_1):PAGE305

LED_PWRGD_PVCCIN_CPU0_D @S9S_MB_2U_LIB.S9S_MB_2U(SCH_1):LED_PWRGD_PVCCIN_CPU0_D
   Q83    6     D1 MOSFET_NCH_DUAL-PJT138K,SMLF,IA    I32 @S9S_MB_2U_LIB.S9S_MB_2U(SCH_1):PAGE305
   D79    C      C Q_LED_SMLF-LED_BLUE,LTST-C281TA    I35 @S9S_MB_2U_LIB.S9S_MB_2U(SCH_1):PAGE305

LED_PWRGD_PVCCIN_CPU1 @S9S_MB_2U_LIB.S9S_MB_2U(SCH_1):LED_PWRGD_PVCCIN_CPU1
   D86    A      A Q_LED_SMLF-LED_BLUE,LTST-C281TA    I30 @S9S_MB_2U_LIB.S9S_MB_2U(SCH_1):PAGE306
 R3098    1      A Q_RES_0402LF-130,1%,1/16W,CHIPA    I37 @S9S_MB_2U_LIB.S9S_MB_2U(SCH_1):PAGE306

LED_PWRGD_PVCCIN_CPU1_D @S9S_MB_2U_LIB.S9S_MB_2U(SCH_1):LED_PWRGD_PVCCIN_CPU1_D
   D86    C      C Q_LED_SMLF-LED_BLUE,LTST-C281TA    I30 @S9S_MB_2U_LIB.S9S_MB_2U(SCH_1):PAGE306
   Q83    3     D2 MOSFET_NCH_DUAL-PJT138K,SMLF,IA    I43 @S9S_MB_2U_LIB.S9S_MB_2U(SCH_1):PAGE306

LED_PWRGD_PVNN_MAIN_CPU0 @S9S_MB_2U_LIB.S9S_MB_2U(SCH_1):LED_PWRGD_PVNN_MAIN_CPU0
   D78    A      A Q_LED_SMLF-LED_BLUE,LTST-C281TA    I43 @S9S_MB_2U_LIB.S9S_MB_2U(SCH_1):PAGE305
 R3090    1      A Q_RES_0402LF-130,1%,1/16W,CHIPA    I54 @S9S_MB_2U_LIB.S9S_MB_2U(SCH_1):PAGE305

LED_PWRGD_PVNN_MAIN_CPU0_D @S9S_MB_2U_LIB.S9S_MB_2U(SCH_1):LED_PWRGD_PVNN_MAIN_CPU0_D
   Q81    3     D2 MOSFET_NCH_DUAL-PJT138K,SMLF,IA    I40 @S9S_MB_2U_LIB.S9S_MB_2U(SCH_1):PAGE305
   D78    C      C Q_LED_SMLF-LED_BLUE,LTST-C281TA    I43 @S9S_MB_2U_LIB.S9S_MB_2U(SCH_1):PAGE305

LED_PWRGD_PVNN_MAIN_CPU1 @S9S_MB_2U_LIB.S9S_MB_2U(SCH_1):LED_PWRGD_PVNN_MAIN_CPU1
   D85    A      A Q_LED_SMLF-LED_BLUE,LTST-C281TA    I32 @S9S_MB_2U_LIB.S9S_MB_2U(SCH_1):PAGE306
 R3097    1      A Q_RES_0402LF-130,1%,1/16W,CHIPA    I38 @S9S_MB_2U_LIB.S9S_MB_2U(SCH_1):PAGE306

LED_PWRGD_PVNN_MAIN_CPU1_D @S9S_MB_2U_LIB.S9S_MB_2U(SCH_1):LED_PWRGD_PVNN_MAIN_CPU1_D
   Q86    3     D2 MOSFET_NCH_DUAL-PJT138K,SMLF,IA    I27 @S9S_MB_2U_LIB.S9S_MB_2U(SCH_1):PAGE306
   D85    C      C Q_LED_SMLF-LED_BLUE,LTST-C281TA    I32 @S9S_MB_2U_LIB.S9S_MB_2U(SCH_1):PAGE306

LED_PWRGD_PVPP_HBM_CPU0 @S9S_MB_2U_LIB.S9S_MB_2U(SCH_1):LED_PWRGD_PVPP_HBM_CPU0
   D74    A      A Q_LED_SMLF-LED_BLUE,LTST-C281TA    I21 @S9S_MB_2U_LIB.S9S_MB_2U(SCH_1):PAGE305
 R3087    1      A Q_RES_0402LF-130,1%,1/16W,CHIPA    I50 @S9S_MB_2U_LIB.S9S_MB_2U(SCH_1):PAGE305

LED_PWRGD_PVPP_HBM_CPU0_D @S9S_MB_2U_LIB.S9S_MB_2U(SCH_1):LED_PWRGD_PVPP_HBM_CPU0_D
   Q79    3     D2 MOSFET_NCH_DUAL-PJT138K,SMLF,IA     I7 @S9S_MB_2U_LIB.S9S_MB_2U(SCH_1):PAGE305
   D74    C      C Q_LED_SMLF-LED_BLUE,LTST-C281TA    I21 @S9S_MB_2U_LIB.S9S_MB_2U(SCH_1):PAGE305

LED_PWRGD_PVPP_HBM_CPU1 @S9S_MB_2U_LIB.S9S_MB_2U(SCH_1):LED_PWRGD_PVPP_HBM_CPU1
   D81    A      A Q_LED_SMLF-LED_BLUE,LTST-C281TA    I14 @S9S_MB_2U_LIB.S9S_MB_2U(SCH_1):PAGE306
 R3094    1      A Q_RES_0402LF-130,1%,1/16W,CHIPA    I16 @S9S_MB_2U_LIB.S9S_MB_2U(SCH_1):PAGE306

LED_PWRGD_PVPP_HBM_CPU1_D @S9S_MB_2U_LIB.S9S_MB_2U(SCH_1):LED_PWRGD_PVPP_HBM_CPU1_D
   Q84    3     D2 MOSFET_NCH_DUAL-PJT138K,SMLF,IA     I8 @S9S_MB_2U_LIB.S9S_MB_2U(SCH_1):PAGE306
   D81    C      C Q_LED_SMLF-LED_BLUE,LTST-C281TA    I14 @S9S_MB_2U_LIB.S9S_MB_2U(SCH_1):PAGE306

LED_PWRGD_SYS_PWROK_R @S9S_MB_2U_LIB.S9S_MB_2U(SCH_1):LED_PWRGD_SYS_PWROK_R
   D88    A      A Q_LED_SMLF-LED_BLUE,LTST-C281TA    I19 @S9S_MB_2U_LIB.S9S_MB_2U(SCH_1):PAGE241
 R3069    1      A Q_RES_0402LF-130,1%,1/16W,CHIPA    I39 @S9S_MB_2U_LIB.S9S_MB_2U(SCH_1):PAGE241

LED_PWRGD_SYS_PWROK_R_D @S9S_MB_2U_LIB.S9S_MB_2U(SCH_1):LED_PWRGD_SYS_PWROK_R_D
   Q87    3     D2 MOSFET_NCH_DUAL-PJT138K,SMLF,IA    I16 @S9S_MB_2U_LIB.S9S_MB_2U(SCH_1):PAGE241
   D88    C      C Q_LED_SMLF-LED_BLUE,LTST-C281TA    I19 @S9S_MB_2U_LIB.S9S_MB_2U(SCH_1):PAGE241

LED_RST_PLD_CPU0_DRAM_AB_N @S9S_MB_2U_LIB.S9S_MB_2U(SCH_1):LED_RST_PLD_CPU0_DRAM_AB_N
   D65    A      A Q_LED_SMLF-LED_BLUE,LTST-C281TA    I21 @S9S_MB_2U_LIB.S9S_MB_2U(SCH_1):PAGE304
 R1371    1      A Q_RES_0402LF-130,1%,1/16W,CHIPA    I49 @S9S_MB_2U_LIB.S9S_MB_2U(SCH_1):PAGE304

LED_RST_PLD_CPU0_DRAM_AB_N_D @S9S_MB_2U_LIB.S9S_MB_2U(SCH_1):LED_RST_PLD_CPU0_DRAM_AB_N_D
   D65    C      C Q_LED_SMLF-LED_BLUE,LTST-C281TA    I21 @S9S_MB_2U_LIB.S9S_MB_2U(SCH_1):PAGE304
   Q98    6     D1 MOSFET_NCH_DUAL-NX6008NBKS,SMLA    I68 @S9S_MB_2U_LIB.S9S_MB_2U(SCH_1):PAGE304

LED_RST_PLD_CPU0_DRAM_CD_N @S9S_MB_2U_LIB.S9S_MB_2U(SCH_1):LED_RST_PLD_CPU0_DRAM_CD_N
   D66    A      A Q_LED_SMLF-LED_BLUE,LTST-C281TA    I20 @S9S_MB_2U_LIB.S9S_MB_2U(SCH_1):PAGE304
 R3080    1      A Q_RES_0402LF-130,1%,1/16W,CHIPA    I50 @S9S_MB_2U_LIB.S9S_MB_2U(SCH_1):PAGE304

LED_RST_PLD_CPU0_DRAM_CD_N_D @S9S_MB_2U_LIB.S9S_MB_2U(SCH_1):LED_RST_PLD_CPU0_DRAM_CD_N_D
   D66    C      C Q_LED_SMLF-LED_BLUE,LTST-C281TA    I20 @S9S_MB_2U_LIB.S9S_MB_2U(SCH_1):PAGE304
   Q98    3     D2 MOSFET_NCH_DUAL-NX6008NBKS,SMLA    I69 @S9S_MB_2U_LIB.S9S_MB_2U(SCH_1):PAGE304

LED_RST_PLD_CPU0_DRAM_EF_N @S9S_MB_2U_LIB.S9S_MB_2U(SCH_1):LED_RST_PLD_CPU0_DRAM_EF_N
   D67    A      A Q_LED_SMLF-LED_BLUE,LTST-C281TA    I12 @S9S_MB_2U_LIB.S9S_MB_2U(SCH_1):PAGE304
 R3079    1      A Q_RES_0402LF-130,1%,1/16W,CHIPA    I51 @S9S_MB_2U_LIB.S9S_MB_2U(SCH_1):PAGE304

LED_RST_PLD_CPU0_DRAM_EF_N_D @S9S_MB_2U_LIB.S9S_MB_2U(SCH_1):LED_RST_PLD_CPU0_DRAM_EF_N_D
   D67    C      C Q_LED_SMLF-LED_BLUE,LTST-C281TA    I12 @S9S_MB_2U_LIB.S9S_MB_2U(SCH_1):PAGE304
   Q97    6     D1 MOSFET_NCH_DUAL-NX6008NBKS,SMLA    I71 @S9S_MB_2U_LIB.S9S_MB_2U(SCH_1):PAGE304

LED_RST_PLD_CPU0_DRAM_GH_N @S9S_MB_2U_LIB.S9S_MB_2U(SCH_1):LED_RST_PLD_CPU0_DRAM_GH_N
   D68    A      A Q_LED_SMLF-LED_BLUE,LTST-C281TA     I9 @S9S_MB_2U_LIB.S9S_MB_2U(SCH_1):PAGE304
 R3081    1      A Q_RES_0402LF-130,1%,1/16W,CHIPA    I52 @S9S_MB_2U_LIB.S9S_MB_2U(SCH_1):PAGE304

LED_RST_PLD_CPU0_DRAM_GH_N_D @S9S_MB_2U_LIB.S9S_MB_2U(SCH_1):LED_RST_PLD_CPU0_DRAM_GH_N_D
   D68    C      C Q_LED_SMLF-LED_BLUE,LTST-C281TA     I9 @S9S_MB_2U_LIB.S9S_MB_2U(SCH_1):PAGE304
   Q97    3     D2 MOSFET_NCH_DUAL-NX6008NBKS,SMLA    I70 @S9S_MB_2U_LIB.S9S_MB_2U(SCH_1):PAGE304

LED_RST_PLD_CPU1_DRAM_AB_N @S9S_MB_2U_LIB.S9S_MB_2U(SCH_1):LED_RST_PLD_CPU1_DRAM_AB_N
   D69    A      A Q_LED_SMLF-LED_BLUE,LTST-C281TA    I32 @S9S_MB_2U_LIB.S9S_MB_2U(SCH_1):PAGE304
 R3082    1      A Q_RES_0402LF-130,1%,1/16W,CHIPA    I54 @S9S_MB_2U_LIB.S9S_MB_2U(SCH_1):PAGE304

LED_RST_PLD_CPU1_DRAM_AB_N_D @S9S_MB_2U_LIB.S9S_MB_2U(SCH_1):LED_RST_PLD_CPU1_DRAM_AB_N_D
   D69    C      C Q_LED_SMLF-LED_BLUE,LTST-C281TA    I32 @S9S_MB_2U_LIB.S9S_MB_2U(SCH_1):PAGE304
  Q105    6     D1 MOSFET_NCH_DUAL-NX6008NBKS,SMLA    I76 @S9S_MB_2U_LIB.S9S_MB_2U(SCH_1):PAGE304

LED_RST_PLD_CPU1_DRAM_CD_N @S9S_MB_2U_LIB.S9S_MB_2U(SCH_1):LED_RST_PLD_CPU1_DRAM_CD_N
   D70    A      A Q_LED_SMLF-LED_BLUE,LTST-C281TA    I31 @S9S_MB_2U_LIB.S9S_MB_2U(SCH_1):PAGE304
 R3084    1      A Q_RES_0402LF-130,1%,1/16W,CHIPA    I53 @S9S_MB_2U_LIB.S9S_MB_2U(SCH_1):PAGE304

LED_RST_PLD_CPU1_DRAM_CD_N_D @S9S_MB_2U_LIB.S9S_MB_2U(SCH_1):LED_RST_PLD_CPU1_DRAM_CD_N_D
   D70    C      C Q_LED_SMLF-LED_BLUE,LTST-C281TA    I31 @S9S_MB_2U_LIB.S9S_MB_2U(SCH_1):PAGE304
   Q99    6     D1 MOSFET_NCH_DUAL-NX6008NBKS,SMLA    I72 @S9S_MB_2U_LIB.S9S_MB_2U(SCH_1):PAGE304

LED_RST_PLD_CPU1_DRAM_EF_N @S9S_MB_2U_LIB.S9S_MB_2U(SCH_1):LED_RST_PLD_CPU1_DRAM_EF_N
 R3083    1      A Q_RES_0402LF-130,1%,1/16W,CHIPA    I57 @S9S_MB_2U_LIB.S9S_MB_2U(SCH_1):PAGE304
   D71    A      A Q_LED_SMLF-LED_BLUE,LTST-C281TA    I58 @S9S_MB_2U_LIB.S9S_MB_2U(SCH_1):PAGE304

LED_RST_PLD_CPU1_DRAM_EF_N_D @S9S_MB_2U_LIB.S9S_MB_2U(SCH_1):LED_RST_PLD_CPU1_DRAM_EF_N_D
   D71    C      C Q_LED_SMLF-LED_BLUE,LTST-C281TA    I58 @S9S_MB_2U_LIB.S9S_MB_2U(SCH_1):PAGE304
  Q100    6     D1 MOSFET_NCH_DUAL-NX6008NBKS,SMLA    I74 @S9S_MB_2U_LIB.S9S_MB_2U(SCH_1):PAGE304

LED_RST_PLD_CPU1_DRAM_GH_N @S9S_MB_2U_LIB.S9S_MB_2U(SCH_1):LED_RST_PLD_CPU1_DRAM_GH_N
 R3085    1      A Q_RES_0402LF-130,1%,1/16W,CHIPA    I62 @S9S_MB_2U_LIB.S9S_MB_2U(SCH_1):PAGE304
   D72    A      A Q_LED_SMLF-LED_BLUE,LTST-C281TA    I63 @S9S_MB_2U_LIB.S9S_MB_2U(SCH_1):PAGE304

LED_RST_PLD_CPU1_DRAM_GH_N_D @S9S_MB_2U_LIB.S9S_MB_2U(SCH_1):LED_RST_PLD_CPU1_DRAM_GH_N_D
   D72    C      C Q_LED_SMLF-LED_BLUE,LTST-C281TA    I63 @S9S_MB_2U_LIB.S9S_MB_2U(SCH_1):PAGE304
  Q100    3     D2 MOSFET_NCH_DUAL-NX6008NBKS,SMLA    I75 @S9S_MB_2U_LIB.S9S_MB_2U(SCH_1):PAGE304

LED_RST_PLTRST_N @S9S_MB_2U_LIB.S9S_MB_2U(SCH_1):LED_RST_PLTRST_N
   D90    A      A Q_LED_SMLF-LED_BLUE,LTST-C281TA    I33 @S9S_MB_2U_LIB.S9S_MB_2U(SCH_1):PAGE241
 R3070    1      A Q_RES_0402LF-130,1%,1/16W,CHIPA    I41 @S9S_MB_2U_LIB.S9S_MB_2U(SCH_1):PAGE241

LED_RST_PLTRST_N_D @S9S_MB_2U_LIB.S9S_MB_2U(SCH_1):LED_RST_PLTRST_N_D
   D90    C      C Q_LED_SMLF-LED_BLUE,LTST-C281TA    I33 @S9S_MB_2U_LIB.S9S_MB_2U(SCH_1):PAGE241
   Q88    3     D2 MOSFET_NCH_DUAL-PJT138K,SMLF,IA    I42 @S9S_MB_2U_LIB.S9S_MB_2U(SCH_1):PAGE241

LED_RST_RSMRST_PLD_R_N @S9S_MB_2U_LIB.S9S_MB_2U(SCH_1):LED_RST_RSMRST_PLD_R_N
   D93    A      A Q_LED_SMLF-LED_BLUE,LTST-C281TA    I13 @S9S_MB_2U_LIB.S9S_MB_2U(SCH_1):PAGE242
 R3074    1      A Q_RES_0402LF-130,1%,1/16W,CHIPA    I14 @S9S_MB_2U_LIB.S9S_MB_2U(SCH_1):PAGE242

LED_RST_RSMRST_PLD_R_N_D @S9S_MB_2U_LIB.S9S_MB_2U(SCH_1):LED_RST_RSMRST_PLD_R_N_D
   Q77    6     D1 MOSFET_NCH_DUAL-PJT138K,SMLF,IA     I6 @S9S_MB_2U_LIB.S9S_MB_2U(SCH_1):PAGE242
   D93    C      C Q_LED_SMLF-LED_BLUE,LTST-C281TA    I13 @S9S_MB_2U_LIB.S9S_MB_2U(SCH_1):PAGE242

M2_0_P3V3_ADC_ALERT @S9S_MB_2U_LIB.S9S_MB_2U(SCH_1):M2_0_P3V3_ADC_ALERT
  U249  K17  PR13C LCMXO3LF9400C5BG484C-LCMXO3LF-A     I1 @S9S_MB_2U_LIB.S9S_MB_2U(SCH_1):PAGE313
 R3560    2      B Q_RES_0402LF-0,5%,1/16W,CHIP,CA    I41 @S9S_MB_2U_LIB.S9S_MB_2U(SCH_1):PAGE163

M2_0_P3V3_ADC_ALERT_R @S9S_MB_2U_LIB.S9S_MB_2U(SCH_1):M2_0_P3V3_ADC_ALERT_R
 R3560    1      A Q_RES_0402LF-0,5%,1/16W,CHIP,CA    I41 @S9S_MB_2U_LIB.S9S_MB_2U(SCH_1):PAGE163
  U264    3  ALERT INA230AIRGTR-INA230AIRGTR,SMLFB    I46 @S9S_MB_2U_LIB.S9S_MB_2U(SCH_1):PAGE163
 R4090    2      B Q_RES_0402LF-4.7K,1%,1/16W,CHIA   I124 @S9S_MB_2U_LIB.S9S_MB_2U(SCH_1):PAGE163

M2_0_PEWAKE_N @S9S_MB_2U_LIB.S9S_MB_2U(SCH_1):M2_0_PEWAKE_N
   J59   54 PEWAKE# SCONN75K_APCI0155P004A-SCONN75A   I178 @S9S_MB_2U_LIB.S9S_MB_2U(SCH_1):PAGE182
 R3301    2      B Q_RES_0402LF-33.2,1%,1/16W,CHIA   I299 @S9S_MB_2U_LIB.S9S_MB_2U(SCH_1):PAGE182

M2_SSD0_CLKREQ_EN_N @S9S_MB_2U_LIB.S9S_MB_2U(SCH_1):M2_SSD0_CLKREQ_EN_N
    U4 BG16 GPPC_A_12_SRCCLKREQ_N_2 EMMITSBURG_REV0P9-GFNOCPU04302A    I93 @S9S_MB_2U_LIB.S9S_MB_2U(SCH_1):PAGE175
  R486    1      A Q_RES_0402LF-0,5%,1/16W,CHIP,CA   I162 @S9S_MB_2U_LIB.S9S_MB_2U(SCH_1):PAGE182
  R491    1      A Q_RES_0402LF-4.7K,1%,1/16W,EMPA   I164 @S9S_MB_2U_LIB.S9S_MB_2U(SCH_1):PAGE182
  U259    1     1A SN74LVC2G07DCKR_SMLF-SN74LVC2GA   I327 @S9S_MB_2U_LIB.S9S_MB_2U(SCH_1):PAGE182

M2_SSD0_CLKREQ_EN_N_BUF @S9S_MB_2U_LIB.S9S_MB_2U(SCH_1):M2_SSD0_CLKREQ_EN_N_BUF
  R486    2      B Q_RES_0402LF-0,5%,1/16W,CHIP,CA   I162 @S9S_MB_2U_LIB.S9S_MB_2U(SCH_1):PAGE182
  R487    2      B Q_RES_0402LF-1K,1%,1/16W,CHIP,A   I173 @S9S_MB_2U_LIB.S9S_MB_2U(SCH_1):PAGE182
   J59   52 CLKREQ# SCONN75K_APCI0155P004A-SCONN75A   I178 @S9S_MB_2U_LIB.S9S_MB_2U(SCH_1):PAGE182

MAX11617_VREF @S9S_MB_2U_LIB.S9S_MB_2U(SCH_1):MAX11617_VREF
 C1767    1      A Q_CAP_C0805-10UF,16V,10%,EMPTYA    I68 @S9S_MB_2U_LIB.S9S_MB_2U(SCH_1):PAGE239
 C1347    1      A Q_CAP_0402-0.1UF,25V,10%,EMPTYA    I70 @S9S_MB_2U_LIB.S9S_MB_2U(SCH_1):PAGE239
 R2900    1      A Q_RES_0402LF-2K,1%,1/16W,EMPTYA    I72 @S9S_MB_2U_LIB.S9S_MB_2U(SCH_1):PAGE239

MAX11617_VREF_R @S9S_MB_2U_LIB.S9S_MB_2U(SCH_1):MAX11617_VREF_R
  U193    1 AIN11||REF MAX11617EEET-MAX11617EEE+T,SMLA    I57 @S9S_MB_2U_LIB.S9S_MB_2U(SCH_1):PAGE239
 R2900    2      B Q_RES_0402LF-2K,1%,1/16W,EMPTYA    I72 @S9S_MB_2U_LIB.S9S_MB_2U(SCH_1):PAGE239

MB0_CM_GATE_G0 @S9S_MB_2U_LIB.S9S_MB_2U(SCH_1):MB0_CM_GATE_G0
PR2538    1      A Q_RES_0402LF-10,1%,1/16W,EMPTYA    I76 @S9S_MB_2U_LIB.S9S_MB_2U(SCH_1):PAGE328
  PPQ9    4      4 MOSFET_NCH_1D3S-PSMNR58-30YLH,B    I77 @S9S_MB_2U_LIB.S9S_MB_2U(SCH_1):PAGE328

MB0_P12V_STBY_PWRGD @S9S_MB_2U_LIB.S9S_MB_2U(SCH_1):MB0_P12V_STBY_PWRGD
 R2531    1      A Q_RES_0402LF-0,5%,1/16W,CHIP,CA     I3 @S9S_MB_2U_LIB.S9S_MB_2U(SCH_1):PAGE234
 R3047    1      A Q_RES_0402LF-0,5%,1/16W,CHIP,CA    I85 @S9S_MB_2U_LIB.S9S_MB_2U(SCH_1):PAGE313
 R3048    1      A Q_RES_0402LF-0,5%,1/16W,CHIP,CA    I86 @S9S_MB_2U_LIB.S9S_MB_2U(SCH_1):PAGE313
 PU289   13 PG||OCW# MP5990GMA1111Z-MP5990GMA-1111-A    I56 @S9S_MB_2U_LIB.S9S_MB_2U(SCH_1):PAGE303
 R1117    1      A Q_RES_0402LF-6.19K,1%,1/16W,CHA    I61 @S9S_MB_2U_LIB.S9S_MB_2U(SCH_1):PAGE303
  PJ42   15     15 SCONN21_9193031121LF-SCONN21_9A    I34 @S9S_MB_2U_LIB.S9S_MB_2U(SCH_1):PAGE327
 R3933    2      B Q_RES_0402LF-16.9K,1%,1/16W,CHA    I62 @S9S_MB_2U_LIB.S9S_MB_2U(SCH_1):PAGE303
  D145    1      1 Q_DIODE_SMLF-SDMK0340L-7-F,IC,A    I71 @S9S_MB_2U_LIB.S9S_MB_2U(SCH_1):PAGE245
 R1571    1      A Q_RES_0402LF-100K,1%,1/16W,CHIA    I72 @S9S_MB_2U_LIB.S9S_MB_2U(SCH_1):PAGE245

MB_FRU_ADDR0 @S9S_MB_2U_LIB.S9S_MB_2U(SCH_1):MB_FRU_ADDR0
   U64    1     E0 M24128BWMN6TP-M24128-BWMN6TP,SA    I35 @S9S_MB_2U_LIB.S9S_MB_2U(SCH_1):PAGE231
  R722    1      A Q_RES_0402LF-1K,1%,1/16W,EMPTYA    I61 @S9S_MB_2U_LIB.S9S_MB_2U(SCH_1):PAGE231
  R721    2      B Q_RES_0402LF-10K,1%,1/16W,CHIPA    I62 @S9S_MB_2U_LIB.S9S_MB_2U(SCH_1):PAGE231

MB_FRU_ADDR1 @S9S_MB_2U_LIB.S9S_MB_2U(SCH_1):MB_FRU_ADDR1
   U64    2     E1 M24128BWMN6TP-M24128-BWMN6TP,SA    I35 @S9S_MB_2U_LIB.S9S_MB_2U(SCH_1):PAGE231
  R717    2      B Q_RES_0402LF-10K,1%,1/16W,EMPTA    I45 @S9S_MB_2U_LIB.S9S_MB_2U(SCH_1):PAGE231
  R718    1      A Q_RES_0402LF-1K,1%,1/16W,CHIP,A    I50 @S9S_MB_2U_LIB.S9S_MB_2U(SCH_1):PAGE231

MB_FRU_ADDR2 @S9S_MB_2U_LIB.S9S_MB_2U(SCH_1):MB_FRU_ADDR2
   U64    3     E2 M24128BWMN6TP-M24128-BWMN6TP,SA    I35 @S9S_MB_2U_LIB.S9S_MB_2U(SCH_1):PAGE231
  R713    2      B Q_RES_0402LF-10K,1%,1/16W,EMPTA    I47 @S9S_MB_2U_LIB.S9S_MB_2U(SCH_1):PAGE231
  R714    1      A Q_RES_0402LF-1K,1%,1/16W,CHIP,A    I52 @S9S_MB_2U_LIB.S9S_MB_2U(SCH_1):PAGE231

M_A_CPU0_ALERT_N @S9S_MB_2U_LIB.S9S_MB_2U(SCH_1):M_A_CPU0_ALERT_N
    U2 AT49 DDR0_ALERT_N SOCKET4677_AZIF0045P001C01CS-SA     I1 @S9S_MB_2U_LIB.S9S_MB_2U(SCH_1):PAGE20
    J1   62 ALERT_N SCONN288_ADR50017P130CC-SCONN2A   I198 @S9S_MB_2U_LIB.S9S_MB_2U(SCH_1):PAGE82
    J2   62 ALERT_N SCONN288_ADR50017P087CC-SCONN2A   I177 @S9S_MB_2U_LIB.S9S_MB_2U(SCH_1):PAGE83

M_A_CPU0_CLK_DN<0> @S9S_MB_2U_LIB.S9S_MB_2U(SCH_1):M_A_CPU0_CLK_DN(0)
    U2  B44 DDR0_CLK_DN0 SOCKET4677_AZIF0045P001C01CS-SA     I1 @S9S_MB_2U_LIB.S9S_MB_2U(SCH_1):PAGE20
    J1  218   CK_C SCONN288_ADR50017P130CC-SCONN2A   I198 @S9S_MB_2U_LIB.S9S_MB_2U(SCH_1):PAGE82

M_A_CPU0_CLK_DN<1> @S9S_MB_2U_LIB.S9S_MB_2U(SCH_1):M_A_CPU0_CLK_DN(1)
    U2  G45 DDR0_CLK_DN1 SOCKET4677_AZIF0045P001C01CS-SA     I1 @S9S_MB_2U_LIB.S9S_MB_2U(SCH_1):PAGE20
    J2  218   CK_C SCONN288_ADR50017P087CC-SCONN2A   I177 @S9S_MB_2U_LIB.S9S_MB_2U(SCH_1):PAGE83

M_A_CPU0_CLK_DP<0> @S9S_MB_2U_LIB.S9S_MB_2U(SCH_1):M_A_CPU0_CLK_DP(0)
    U2  C43 DDR0_CLK_DP0 SOCKET4677_AZIF0045P001C01CS-SA     I1 @S9S_MB_2U_LIB.S9S_MB_2U(SCH_1):PAGE20
    J1  217   CK_T SCONN288_ADR50017P130CC-SCONN2A   I198 @S9S_MB_2U_LIB.S9S_MB_2U(SCH_1):PAGE82

M_A_CPU0_CLK_DP<1> @S9S_MB_2U_LIB.S9S_MB_2U(SCH_1):M_A_CPU0_CLK_DP(1)
    U2  E45 DDR0_CLK_DP1 SOCKET4677_AZIF0045P001C01CS-SA     I1 @S9S_MB_2U_LIB.S9S_MB_2U(SCH_1):PAGE20
    J2  217   CK_T SCONN288_ADR50017P087CC-SCONN2A   I177 @S9S_MB_2U_LIB.S9S_MB_2U(SCH_1):PAGE83

M_A_CPU0_SA_CA<0> @S9S_MB_2U_LIB.S9S_MB_2U(SCH_1):M_A_CPU0_SA_CA(0)
    U2  A52 DDR0_SA_CA0 SOCKET4677_AZIF0045P001C01CS-SA     I1 @S9S_MB_2U_LIB.S9S_MB_2U(SCH_1):PAGE20
    J1   66  CA0_A SCONN288_ADR50017P130CC-SCONN2A   I198 @S9S_MB_2U_LIB.S9S_MB_2U(SCH_1):PAGE82
    J2   66  CA0_A SCONN288_ADR50017P087CC-SCONN2A   I177 @S9S_MB_2U_LIB.S9S_MB_2U(SCH_1):PAGE83

M_A_CPU0_SA_CA<1> @S9S_MB_2U_LIB.S9S_MB_2U(SCH_1):M_A_CPU0_SA_CA(1)
    U2  G52 DDR0_SA_CA1 SOCKET4677_AZIF0045P001C01CS-SA     I1 @S9S_MB_2U_LIB.S9S_MB_2U(SCH_1):PAGE20
    J1  211  CA1_A SCONN288_ADR50017P130CC-SCONN2A   I198 @S9S_MB_2U_LIB.S9S_MB_2U(SCH_1):PAGE82
    J2  211  CA1_A SCONN288_ADR50017P087CC-SCONN2A   I177 @S9S_MB_2U_LIB.S9S_MB_2U(SCH_1):PAGE83

M_A_CPU0_SA_CA<2> @S9S_MB_2U_LIB.S9S_MB_2U(SCH_1):M_A_CPU0_SA_CA(2)
    U2  B51 DDR0_SA_CA2 SOCKET4677_AZIF0045P001C01CS-SA     I1 @S9S_MB_2U_LIB.S9S_MB_2U(SCH_1):PAGE20
    J1   68  CA2_A SCONN288_ADR50017P130CC-SCONN2A   I198 @S9S_MB_2U_LIB.S9S_MB_2U(SCH_1):PAGE82
    J2   68  CA2_A SCONN288_ADR50017P087CC-SCONN2A   I177 @S9S_MB_2U_LIB.S9S_MB_2U(SCH_1):PAGE83

M_A_CPU0_SA_CA<3> @S9S_MB_2U_LIB.S9S_MB_2U(SCH_1):M_A_CPU0_SA_CA(3)
    U2  F51 DDR0_SA_CA3 SOCKET4677_AZIF0045P001C01CS-SA     I1 @S9S_MB_2U_LIB.S9S_MB_2U(SCH_1):PAGE20
    J1  213  CA3_A SCONN288_ADR50017P130CC-SCONN2A   I198 @S9S_MB_2U_LIB.S9S_MB_2U(SCH_1):PAGE82
    J2  213  CA3_A SCONN288_ADR50017P087CC-SCONN2A   I177 @S9S_MB_2U_LIB.S9S_MB_2U(SCH_1):PAGE83

M_A_CPU0_SA_CA<4> @S9S_MB_2U_LIB.S9S_MB_2U(SCH_1):M_A_CPU0_SA_CA(4)
    U2  C50 DDR0_SA_CA4 SOCKET4677_AZIF0045P001C01CS-SA     I1 @S9S_MB_2U_LIB.S9S_MB_2U(SCH_1):PAGE20
    J1   70  CA4_A SCONN288_ADR50017P130CC-SCONN2A   I198 @S9S_MB_2U_LIB.S9S_MB_2U(SCH_1):PAGE82
    J2   70  CA4_A SCONN288_ADR50017P087CC-SCONN2A   I177 @S9S_MB_2U_LIB.S9S_MB_2U(SCH_1):PAGE83

M_A_CPU0_SA_CA<5> @S9S_MB_2U_LIB.S9S_MB_2U(SCH_1):M_A_CPU0_SA_CA(5)
    U2  E50 DDR0_SA_CA5 SOCKET4677_AZIF0045P001C01CS-SA     I1 @S9S_MB_2U_LIB.S9S_MB_2U(SCH_1):PAGE20
    J1  215  CA5_A SCONN288_ADR50017P130CC-SCONN2A   I198 @S9S_MB_2U_LIB.S9S_MB_2U(SCH_1):PAGE82
    J2  215  CA5_A SCONN288_ADR50017P087CC-SCONN2A   I177 @S9S_MB_2U_LIB.S9S_MB_2U(SCH_1):PAGE83

M_A_CPU0_SA_CA<6> @S9S_MB_2U_LIB.S9S_MB_2U(SCH_1):M_A_CPU0_SA_CA(6)
    U2  C48 DDR0_SA_CA6 SOCKET4677_AZIF0045P001C01CS-SA     I1 @S9S_MB_2U_LIB.S9S_MB_2U(SCH_1):PAGE20
    J1   72  CA6_A SCONN288_ADR50017P130CC-SCONN2A   I198 @S9S_MB_2U_LIB.S9S_MB_2U(SCH_1):PAGE82
    J2   72  CA6_A SCONN288_ADR50017P087CC-SCONN2A   I177 @S9S_MB_2U_LIB.S9S_MB_2U(SCH_1):PAGE83

M_A_CPU0_SA_CB<0> @S9S_MB_2U_LIB.S9S_MB_2U(SCH_1):M_A_CPU0_SA_CB(0)
    U2  C60 DDR0_SA_ECC0 SOCKET4677_AZIF0045P001C01CS-SA     I1 @S9S_MB_2U_LIB.S9S_MB_2U(SCH_1):PAGE20
    J1   51  CB0_A SCONN288_ADR50017P130CC-SCONN2A   I198 @S9S_MB_2U_LIB.S9S_MB_2U(SCH_1):PAGE82
    J2   51  CB0_A SCONN288_ADR50017P087CC-SCONN2A   I177 @S9S_MB_2U_LIB.S9S_MB_2U(SCH_1):PAGE83

M_A_CPU0_SA_CB<1> @S9S_MB_2U_LIB.S9S_MB_2U(SCH_1):M_A_CPU0_SA_CB(1)
    U2  B59 DDR0_SA_ECC1 SOCKET4677_AZIF0045P001C01CS-SA     I1 @S9S_MB_2U_LIB.S9S_MB_2U(SCH_1):PAGE20
    J1   53  CB1_A SCONN288_ADR50017P130CC-SCONN2A   I198 @S9S_MB_2U_LIB.S9S_MB_2U(SCH_1):PAGE82
    J2   53  CB1_A SCONN288_ADR50017P087CC-SCONN2A   I177 @S9S_MB_2U_LIB.S9S_MB_2U(SCH_1):PAGE83

M_A_CPU0_SA_CB<2> @S9S_MB_2U_LIB.S9S_MB_2U(SCH_1):M_A_CPU0_SA_CB(2)
    U2  E60 DDR0_SA_ECC2 SOCKET4677_AZIF0045P001C01CS-SA     I1 @S9S_MB_2U_LIB.S9S_MB_2U(SCH_1):PAGE20
    J1  196  CB2_A SCONN288_ADR50017P130CC-SCONN2A   I198 @S9S_MB_2U_LIB.S9S_MB_2U(SCH_1):PAGE82
    J2  196  CB2_A SCONN288_ADR50017P087CC-SCONN2A   I177 @S9S_MB_2U_LIB.S9S_MB_2U(SCH_1):PAGE83

M_A_CPU0_SA_CB<3> @S9S_MB_2U_LIB.S9S_MB_2U(SCH_1):M_A_CPU0_SA_CB(3)
    U2  F59 DDR0_SA_ECC3 SOCKET4677_AZIF0045P001C01CS-SA     I1 @S9S_MB_2U_LIB.S9S_MB_2U(SCH_1):PAGE20
    J1  198  CB3_A SCONN288_ADR50017P130CC-SCONN2A   I198 @S9S_MB_2U_LIB.S9S_MB_2U(SCH_1):PAGE82
    J2  198  CB3_A SCONN288_ADR50017P087CC-SCONN2A   I177 @S9S_MB_2U_LIB.S9S_MB_2U(SCH_1):PAGE83

M_A_CPU0_SA_CB<4> @S9S_MB_2U_LIB.S9S_MB_2U(SCH_1):M_A_CPU0_SA_CB(4)
    U2  B57 DDR0_SA_ECC4 SOCKET4677_AZIF0045P001C01CS-SA     I1 @S9S_MB_2U_LIB.S9S_MB_2U(SCH_1):PAGE20
    J1   58  CB4_A SCONN288_ADR50017P130CC-SCONN2A   I198 @S9S_MB_2U_LIB.S9S_MB_2U(SCH_1):PAGE82
    J2   58  CB4_A SCONN288_ADR50017P087CC-SCONN2A   I177 @S9S_MB_2U_LIB.S9S_MB_2U(SCH_1):PAGE83

M_A_CPU0_SA_CB<5> @S9S_MB_2U_LIB.S9S_MB_2U(SCH_1):M_A_CPU0_SA_CB(5)
    U2  C56 DDR0_SA_ECC5 SOCKET4677_AZIF0045P001C01CS-SA     I1 @S9S_MB_2U_LIB.S9S_MB_2U(SCH_1):PAGE20
    J1   60  CB5_A SCONN288_ADR50017P130CC-SCONN2A   I198 @S9S_MB_2U_LIB.S9S_MB_2U(SCH_1):PAGE82
    J2   60  CB5_A SCONN288_ADR50017P087CC-SCONN2A   I177 @S9S_MB_2U_LIB.S9S_MB_2U(SCH_1):PAGE83

M_A_CPU0_SA_CB<6> @S9S_MB_2U_LIB.S9S_MB_2U(SCH_1):M_A_CPU0_SA_CB(6)
    U2  F57 DDR0_SA_ECC6 SOCKET4677_AZIF0045P001C01CS-SA     I1 @S9S_MB_2U_LIB.S9S_MB_2U(SCH_1):PAGE20
    J1  203  CB6_A SCONN288_ADR50017P130CC-SCONN2A   I198 @S9S_MB_2U_LIB.S9S_MB_2U(SCH_1):PAGE82
    J2  203  CB6_A SCONN288_ADR50017P087CC-SCONN2A   I177 @S9S_MB_2U_LIB.S9S_MB_2U(SCH_1):PAGE83

M_A_CPU0_SA_CB<7> @S9S_MB_2U_LIB.S9S_MB_2U(SCH_1):M_A_CPU0_SA_CB(7)
    U2  E56 DDR0_SA_ECC7 SOCKET4677_AZIF0045P001C01CS-SA     I1 @S9S_MB_2U_LIB.S9S_MB_2U(SCH_1):PAGE20
    J1  205  CB7_A SCONN288_ADR50017P130CC-SCONN2A   I198 @S9S_MB_2U_LIB.S9S_MB_2U(SCH_1):PAGE82
    J2  205  CB7_A SCONN288_ADR50017P087CC-SCONN2A   I177 @S9S_MB_2U_LIB.S9S_MB_2U(SCH_1):PAGE83

M_A_CPU0_SA_CS_N<0> @S9S_MB_2U_LIB.S9S_MB_2U(SCH_1):M_A_CPU0_SA_CS_N(0)
    U2  C54 DDR0_SA_CS_N0 SOCKET4677_AZIF0045P001C01CS-SA     I1 @S9S_MB_2U_LIB.S9S_MB_2U(SCH_1):PAGE20
    J1   64 CS0_A_N SCONN288_ADR50017P130CC-SCONN2A   I198 @S9S_MB_2U_LIB.S9S_MB_2U(SCH_1):PAGE82

M_A_CPU0_SA_CS_N<1> @S9S_MB_2U_LIB.S9S_MB_2U(SCH_1):M_A_CPU0_SA_CS_N(1)
    U2  B53 DDR0_SA_CS_N1 SOCKET4677_AZIF0045P001C01CS-SA     I1 @S9S_MB_2U_LIB.S9S_MB_2U(SCH_1):PAGE20
    J1  209 CS1_A_N SCONN288_ADR50017P130CC-SCONN2A   I198 @S9S_MB_2U_LIB.S9S_MB_2U(SCH_1):PAGE82

M_A_CPU0_SA_CS_N<2> @S9S_MB_2U_LIB.S9S_MB_2U(SCH_1):M_A_CPU0_SA_CS_N(2)
    U2  E54 DDR0_SA_CS_N2 SOCKET4677_AZIF0045P001C01CS-SA     I1 @S9S_MB_2U_LIB.S9S_MB_2U(SCH_1):PAGE20
    J2   64 CS0_A_N SCONN288_ADR50017P087CC-SCONN2A   I177 @S9S_MB_2U_LIB.S9S_MB_2U(SCH_1):PAGE83

M_A_CPU0_SA_CS_N<3> @S9S_MB_2U_LIB.S9S_MB_2U(SCH_1):M_A_CPU0_SA_CS_N(3)
    U2  F53 DDR0_SA_CS_N3 SOCKET4677_AZIF0045P001C01CS-SA     I1 @S9S_MB_2U_LIB.S9S_MB_2U(SCH_1):PAGE20
    J2  209 CS1_A_N SCONN288_ADR50017P087CC-SCONN2A   I177 @S9S_MB_2U_LIB.S9S_MB_2U(SCH_1):PAGE83

M_A_CPU0_SA_DQ<0> @S9S_MB_2U_LIB.S9S_MB_2U(SCH_1):M_A_CPU0_SA_DQ(0)
    U2  B81 DDR0_SA_DQ0 SOCKET4677_AZIF0045P001C01CS-SA     I1 @S9S_MB_2U_LIB.S9S_MB_2U(SCH_1):PAGE20
    J1    7  DQ0_A SCONN288_ADR50017P130CC-SCONN2A   I198 @S9S_MB_2U_LIB.S9S_MB_2U(SCH_1):PAGE82
    J2    7  DQ0_A SCONN288_ADR50017P087CC-SCONN2A   I177 @S9S_MB_2U_LIB.S9S_MB_2U(SCH_1):PAGE83

M_A_CPU0_SA_DQ<10> @S9S_MB_2U_LIB.S9S_MB_2U(SCH_1):M_A_CPU0_SA_DQ(10)
    U2  M69 DDR0_SA_DQ10 SOCKET4677_AZIF0045P001C01CS-SA     I1 @S9S_MB_2U_LIB.S9S_MB_2U(SCH_1):PAGE20
    J1  163 DQ10_A SCONN288_ADR50017P130CC-SCONN2A   I198 @S9S_MB_2U_LIB.S9S_MB_2U(SCH_1):PAGE82
    J2  163 DQ10_A SCONN288_ADR50017P087CC-SCONN2A   I177 @S9S_MB_2U_LIB.S9S_MB_2U(SCH_1):PAGE83

M_A_CPU0_SA_DQ<11> @S9S_MB_2U_LIB.S9S_MB_2U(SCH_1):M_A_CPU0_SA_DQ(11)
    U2  N68 DDR0_SA_DQ11 SOCKET4677_AZIF0045P001C01CS-SA     I1 @S9S_MB_2U_LIB.S9S_MB_2U(SCH_1):PAGE20
    J1  165 DQ11_A SCONN288_ADR50017P130CC-SCONN2A   I198 @S9S_MB_2U_LIB.S9S_MB_2U(SCH_1):PAGE82
    J2  165 DQ11_A SCONN288_ADR50017P087CC-SCONN2A   I177 @S9S_MB_2U_LIB.S9S_MB_2U(SCH_1):PAGE83

M_A_CPU0_SA_DQ<12> @S9S_MB_2U_LIB.S9S_MB_2U(SCH_1):M_A_CPU0_SA_DQ(12)
    U2  J66 DDR0_SA_DQ12 SOCKET4677_AZIF0045P001C01CS-SA     I1 @S9S_MB_2U_LIB.S9S_MB_2U(SCH_1):PAGE20
    J1   25 DQ12_A SCONN288_ADR50017P130CC-SCONN2A   I198 @S9S_MB_2U_LIB.S9S_MB_2U(SCH_1):PAGE82
    J2   25 DQ12_A SCONN288_ADR50017P087CC-SCONN2A   I177 @S9S_MB_2U_LIB.S9S_MB_2U(SCH_1):PAGE83

M_A_CPU0_SA_DQ<13> @S9S_MB_2U_LIB.S9S_MB_2U(SCH_1):M_A_CPU0_SA_DQ(13)
    U2  K65 DDR0_SA_DQ13 SOCKET4677_AZIF0045P001C01CS-SA     I1 @S9S_MB_2U_LIB.S9S_MB_2U(SCH_1):PAGE20
    J1   27 DQ13_A SCONN288_ADR50017P130CC-SCONN2A   I198 @S9S_MB_2U_LIB.S9S_MB_2U(SCH_1):PAGE82
    J2   27 DQ13_A SCONN288_ADR50017P087CC-SCONN2A   I177 @S9S_MB_2U_LIB.S9S_MB_2U(SCH_1):PAGE83

M_A_CPU0_SA_DQ<14> @S9S_MB_2U_LIB.S9S_MB_2U(SCH_1):M_A_CPU0_SA_DQ(14)
    U2  N66 DDR0_SA_DQ14 SOCKET4677_AZIF0045P001C01CS-SA     I1 @S9S_MB_2U_LIB.S9S_MB_2U(SCH_1):PAGE20
    J1  170 DQ14_A SCONN288_ADR50017P130CC-SCONN2A   I198 @S9S_MB_2U_LIB.S9S_MB_2U(SCH_1):PAGE82
    J2  170 DQ14_A SCONN288_ADR50017P087CC-SCONN2A   I177 @S9S_MB_2U_LIB.S9S_MB_2U(SCH_1):PAGE83

M_A_CPU0_SA_DQ<15> @S9S_MB_2U_LIB.S9S_MB_2U(SCH_1):M_A_CPU0_SA_DQ(15)
    U2  M65 DDR0_SA_DQ15 SOCKET4677_AZIF0045P001C01CS-SA     I1 @S9S_MB_2U_LIB.S9S_MB_2U(SCH_1):PAGE20
    J1  172 DQ15_A SCONN288_ADR50017P130CC-SCONN2A   I198 @S9S_MB_2U_LIB.S9S_MB_2U(SCH_1):PAGE82
    J2  172 DQ15_A SCONN288_ADR50017P087CC-SCONN2A   I177 @S9S_MB_2U_LIB.S9S_MB_2U(SCH_1):PAGE83

M_A_CPU0_SA_DQ<16> @S9S_MB_2U_LIB.S9S_MB_2U(SCH_1):M_A_CPU0_SA_DQ(16)
    U2  B73 DDR0_SA_DQ16 SOCKET4677_AZIF0045P001C01CS-SA     I1 @S9S_MB_2U_LIB.S9S_MB_2U(SCH_1):PAGE20
    J1   29 DQ16_A SCONN288_ADR50017P130CC-SCONN2A   I198 @S9S_MB_2U_LIB.S9S_MB_2U(SCH_1):PAGE82
    J2   29 DQ16_A SCONN288_ADR50017P087CC-SCONN2A   I177 @S9S_MB_2U_LIB.S9S_MB_2U(SCH_1):PAGE83

M_A_CPU0_SA_DQ<17> @S9S_MB_2U_LIB.S9S_MB_2U(SCH_1):M_A_CPU0_SA_DQ(17)
    U2  E72 DDR0_SA_DQ17 SOCKET4677_AZIF0045P001C01CS-SA     I1 @S9S_MB_2U_LIB.S9S_MB_2U(SCH_1):PAGE20
    J1   31 DQ17_A SCONN288_ADR50017P130CC-SCONN2A   I198 @S9S_MB_2U_LIB.S9S_MB_2U(SCH_1):PAGE82
    J2   31 DQ17_A SCONN288_ADR50017P087CC-SCONN2A   I177 @S9S_MB_2U_LIB.S9S_MB_2U(SCH_1):PAGE83

M_A_CPU0_SA_DQ<18> @S9S_MB_2U_LIB.S9S_MB_2U(SCH_1):M_A_CPU0_SA_DQ(18)
    U2  D73 DDR0_SA_DQ18 SOCKET4677_AZIF0045P001C01CS-SA     I1 @S9S_MB_2U_LIB.S9S_MB_2U(SCH_1):PAGE20
    J1  174 DQ18_A SCONN288_ADR50017P130CC-SCONN2A   I198 @S9S_MB_2U_LIB.S9S_MB_2U(SCH_1):PAGE82
    J2  174 DQ18_A SCONN288_ADR50017P087CC-SCONN2A   I177 @S9S_MB_2U_LIB.S9S_MB_2U(SCH_1):PAGE83

M_A_CPU0_SA_DQ<19> @S9S_MB_2U_LIB.S9S_MB_2U(SCH_1):M_A_CPU0_SA_DQ(19)
    U2  F71 DDR0_SA_DQ19 SOCKET4677_AZIF0045P001C01CS-SA     I1 @S9S_MB_2U_LIB.S9S_MB_2U(SCH_1):PAGE20
    J1  176 DQ19_A SCONN288_ADR50017P130CC-SCONN2A   I198 @S9S_MB_2U_LIB.S9S_MB_2U(SCH_1):PAGE82
    J2  176 DQ19_A SCONN288_ADR50017P087CC-SCONN2A   I177 @S9S_MB_2U_LIB.S9S_MB_2U(SCH_1):PAGE83

M_A_CPU0_SA_DQ<1> @S9S_MB_2U_LIB.S9S_MB_2U(SCH_1):M_A_CPU0_SA_DQ(1)
    U2  B79 DDR0_SA_DQ1 SOCKET4677_AZIF0045P001C01CS-SA     I1 @S9S_MB_2U_LIB.S9S_MB_2U(SCH_1):PAGE20
    J1    9  DQ1_A SCONN288_ADR50017P130CC-SCONN2A   I198 @S9S_MB_2U_LIB.S9S_MB_2U(SCH_1):PAGE82
    J2    9  DQ1_A SCONN288_ADR50017P087CC-SCONN2A   I177 @S9S_MB_2U_LIB.S9S_MB_2U(SCH_1):PAGE83

M_A_CPU0_SA_DQ<20> @S9S_MB_2U_LIB.S9S_MB_2U(SCH_1):M_A_CPU0_SA_DQ(20)
    U2  B69 DDR0_SA_DQ20 SOCKET4677_AZIF0045P001C01CS-SA     I1 @S9S_MB_2U_LIB.S9S_MB_2U(SCH_1):PAGE20
    J1   36 DQ20_A SCONN288_ADR50017P130CC-SCONN2A   I198 @S9S_MB_2U_LIB.S9S_MB_2U(SCH_1):PAGE82
    J2   36 DQ20_A SCONN288_ADR50017P087CC-SCONN2A   I177 @S9S_MB_2U_LIB.S9S_MB_2U(SCH_1):PAGE83

M_A_CPU0_SA_DQ<21> @S9S_MB_2U_LIB.S9S_MB_2U(SCH_1):M_A_CPU0_SA_DQ(21)
    U2  C68 DDR0_SA_DQ21 SOCKET4677_AZIF0045P001C01CS-SA     I1 @S9S_MB_2U_LIB.S9S_MB_2U(SCH_1):PAGE20
    J1   38 DQ21_A SCONN288_ADR50017P130CC-SCONN2A   I198 @S9S_MB_2U_LIB.S9S_MB_2U(SCH_1):PAGE82
    J2   38 DQ21_A SCONN288_ADR50017P087CC-SCONN2A   I177 @S9S_MB_2U_LIB.S9S_MB_2U(SCH_1):PAGE83

M_A_CPU0_SA_DQ<22> @S9S_MB_2U_LIB.S9S_MB_2U(SCH_1):M_A_CPU0_SA_DQ(22)
    U2  F69 DDR0_SA_DQ22 SOCKET4677_AZIF0045P001C01CS-SA     I1 @S9S_MB_2U_LIB.S9S_MB_2U(SCH_1):PAGE20
    J1  181 DQ22_A SCONN288_ADR50017P130CC-SCONN2A   I198 @S9S_MB_2U_LIB.S9S_MB_2U(SCH_1):PAGE82
    J2  181 DQ22_A SCONN288_ADR50017P087CC-SCONN2A   I177 @S9S_MB_2U_LIB.S9S_MB_2U(SCH_1):PAGE83

M_A_CPU0_SA_DQ<23> @S9S_MB_2U_LIB.S9S_MB_2U(SCH_1):M_A_CPU0_SA_DQ(23)
    U2  E68 DDR0_SA_DQ23 SOCKET4677_AZIF0045P001C01CS-SA     I1 @S9S_MB_2U_LIB.S9S_MB_2U(SCH_1):PAGE20
    J1  183 DQ23_A SCONN288_ADR50017P130CC-SCONN2A   I198 @S9S_MB_2U_LIB.S9S_MB_2U(SCH_1):PAGE82
    J2  183 DQ23_A SCONN288_ADR50017P087CC-SCONN2A   I177 @S9S_MB_2U_LIB.S9S_MB_2U(SCH_1):PAGE83

M_A_CPU0_SA_DQ<24> @S9S_MB_2U_LIB.S9S_MB_2U(SCH_1):M_A_CPU0_SA_DQ(24)
    U2  C66 DDR0_SA_DQ24 SOCKET4677_AZIF0045P001C01CS-SA     I1 @S9S_MB_2U_LIB.S9S_MB_2U(SCH_1):PAGE20
    J1   40 DQ24_A SCONN288_ADR50017P130CC-SCONN2A   I198 @S9S_MB_2U_LIB.S9S_MB_2U(SCH_1):PAGE82
    J2   40 DQ24_A SCONN288_ADR50017P087CC-SCONN2A   I177 @S9S_MB_2U_LIB.S9S_MB_2U(SCH_1):PAGE83

M_A_CPU0_SA_DQ<25> @S9S_MB_2U_LIB.S9S_MB_2U(SCH_1):M_A_CPU0_SA_DQ(25)
    U2  B65 DDR0_SA_DQ25 SOCKET4677_AZIF0045P001C01CS-SA     I1 @S9S_MB_2U_LIB.S9S_MB_2U(SCH_1):PAGE20
    J1   42 DQ25_A SCONN288_ADR50017P130CC-SCONN2A   I198 @S9S_MB_2U_LIB.S9S_MB_2U(SCH_1):PAGE82
    J2   42 DQ25_A SCONN288_ADR50017P087CC-SCONN2A   I177 @S9S_MB_2U_LIB.S9S_MB_2U(SCH_1):PAGE83

M_A_CPU0_SA_DQ<26> @S9S_MB_2U_LIB.S9S_MB_2U(SCH_1):M_A_CPU0_SA_DQ(26)
    U2  E66 DDR0_SA_DQ26 SOCKET4677_AZIF0045P001C01CS-SA     I1 @S9S_MB_2U_LIB.S9S_MB_2U(SCH_1):PAGE20
    J1  185 DQ26_A SCONN288_ADR50017P130CC-SCONN2A   I198 @S9S_MB_2U_LIB.S9S_MB_2U(SCH_1):PAGE82
    J2  185 DQ26_A SCONN288_ADR50017P087CC-SCONN2A   I177 @S9S_MB_2U_LIB.S9S_MB_2U(SCH_1):PAGE83

M_A_CPU0_SA_DQ<27> @S9S_MB_2U_LIB.S9S_MB_2U(SCH_1):M_A_CPU0_SA_DQ(27)
    U2  F65 DDR0_SA_DQ27 SOCKET4677_AZIF0045P001C01CS-SA     I1 @S9S_MB_2U_LIB.S9S_MB_2U(SCH_1):PAGE20
    J1  187 DQ27_A SCONN288_ADR50017P130CC-SCONN2A   I198 @S9S_MB_2U_LIB.S9S_MB_2U(SCH_1):PAGE82
    J2  187 DQ27_A SCONN288_ADR50017P087CC-SCONN2A   I177 @S9S_MB_2U_LIB.S9S_MB_2U(SCH_1):PAGE83

M_A_CPU0_SA_DQ<28> @S9S_MB_2U_LIB.S9S_MB_2U(SCH_1):M_A_CPU0_SA_DQ(28)
    U2  B63 DDR0_SA_DQ28 SOCKET4677_AZIF0045P001C01CS-SA     I1 @S9S_MB_2U_LIB.S9S_MB_2U(SCH_1):PAGE20
    J1   47 DQ28_A SCONN288_ADR50017P130CC-SCONN2A   I198 @S9S_MB_2U_LIB.S9S_MB_2U(SCH_1):PAGE82
    J2   47 DQ28_A SCONN288_ADR50017P087CC-SCONN2A   I177 @S9S_MB_2U_LIB.S9S_MB_2U(SCH_1):PAGE83

M_A_CPU0_SA_DQ<29> @S9S_MB_2U_LIB.S9S_MB_2U(SCH_1):M_A_CPU0_SA_DQ(29)
    U2  C62 DDR0_SA_DQ29 SOCKET4677_AZIF0045P001C01CS-SA     I1 @S9S_MB_2U_LIB.S9S_MB_2U(SCH_1):PAGE20
    J1   49 DQ29_A SCONN288_ADR50017P130CC-SCONN2A   I198 @S9S_MB_2U_LIB.S9S_MB_2U(SCH_1):PAGE82
    J2   49 DQ29_A SCONN288_ADR50017P087CC-SCONN2A   I177 @S9S_MB_2U_LIB.S9S_MB_2U(SCH_1):PAGE83

M_A_CPU0_SA_DQ<2> @S9S_MB_2U_LIB.S9S_MB_2U(SCH_1):M_A_CPU0_SA_DQ(2)
    U2  M77 DDR0_SA_DQ2 SOCKET4677_AZIF0045P001C01CS-SA     I1 @S9S_MB_2U_LIB.S9S_MB_2U(SCH_1):PAGE20
    J1  152  DQ2_A SCONN288_ADR50017P130CC-SCONN2A   I198 @S9S_MB_2U_LIB.S9S_MB_2U(SCH_1):PAGE82
    J2  152  DQ2_A SCONN288_ADR50017P087CC-SCONN2A   I177 @S9S_MB_2U_LIB.S9S_MB_2U(SCH_1):PAGE83

M_A_CPU0_SA_DQ<30> @S9S_MB_2U_LIB.S9S_MB_2U(SCH_1):M_A_CPU0_SA_DQ(30)
    U2  F63 DDR0_SA_DQ30 SOCKET4677_AZIF0045P001C01CS-SA     I1 @S9S_MB_2U_LIB.S9S_MB_2U(SCH_1):PAGE20
    J1  192 DQ30_A SCONN288_ADR50017P130CC-SCONN2A   I198 @S9S_MB_2U_LIB.S9S_MB_2U(SCH_1):PAGE82
    J2  192 DQ30_A SCONN288_ADR50017P087CC-SCONN2A   I177 @S9S_MB_2U_LIB.S9S_MB_2U(SCH_1):PAGE83

M_A_CPU0_SA_DQ<31> @S9S_MB_2U_LIB.S9S_MB_2U(SCH_1):M_A_CPU0_SA_DQ(31)
    U2  E62 DDR0_SA_DQ31 SOCKET4677_AZIF0045P001C01CS-SA     I1 @S9S_MB_2U_LIB.S9S_MB_2U(SCH_1):PAGE20
    J1  194 DQ31_A SCONN288_ADR50017P130CC-SCONN2A   I198 @S9S_MB_2U_LIB.S9S_MB_2U(SCH_1):PAGE82
    J2  194 DQ31_A SCONN288_ADR50017P087CC-SCONN2A   I177 @S9S_MB_2U_LIB.S9S_MB_2U(SCH_1):PAGE83

M_A_CPU0_SA_DQ<3> @S9S_MB_2U_LIB.S9S_MB_2U(SCH_1):M_A_CPU0_SA_DQ(3)
    U2  G78 DDR0_SA_DQ3 SOCKET4677_AZIF0045P001C01CS-SA     I1 @S9S_MB_2U_LIB.S9S_MB_2U(SCH_1):PAGE20
    J1  154  DQ3_A SCONN288_ADR50017P130CC-SCONN2A   I198 @S9S_MB_2U_LIB.S9S_MB_2U(SCH_1):PAGE82
    J2  154  DQ3_A SCONN288_ADR50017P087CC-SCONN2A   I177 @S9S_MB_2U_LIB.S9S_MB_2U(SCH_1):PAGE83

M_A_CPU0_SA_DQ<4> @S9S_MB_2U_LIB.S9S_MB_2U(SCH_1):M_A_CPU0_SA_DQ(4)
    U2  C76 DDR0_SA_DQ4 SOCKET4677_AZIF0045P001C01CS-SA     I1 @S9S_MB_2U_LIB.S9S_MB_2U(SCH_1):PAGE20
    J1   14  DQ4_A SCONN288_ADR50017P130CC-SCONN2A   I198 @S9S_MB_2U_LIB.S9S_MB_2U(SCH_1):PAGE82
    J2   14  DQ4_A SCONN288_ADR50017P087CC-SCONN2A   I177 @S9S_MB_2U_LIB.S9S_MB_2U(SCH_1):PAGE83

M_A_CPU0_SA_DQ<5> @S9S_MB_2U_LIB.S9S_MB_2U(SCH_1):M_A_CPU0_SA_DQ(5)
    U2  D75 DDR0_SA_DQ5 SOCKET4677_AZIF0045P001C01CS-SA     I1 @S9S_MB_2U_LIB.S9S_MB_2U(SCH_1):PAGE20
    J1   16  DQ5_A SCONN288_ADR50017P130CC-SCONN2A   I198 @S9S_MB_2U_LIB.S9S_MB_2U(SCH_1):PAGE82
    J2   16  DQ5_A SCONN288_ADR50017P087CC-SCONN2A   I177 @S9S_MB_2U_LIB.S9S_MB_2U(SCH_1):PAGE83

M_A_CPU0_SA_DQ<6> @S9S_MB_2U_LIB.S9S_MB_2U(SCH_1):M_A_CPU0_SA_DQ(6)
    U2  G76 DDR0_SA_DQ6 SOCKET4677_AZIF0045P001C01CS-SA     I1 @S9S_MB_2U_LIB.S9S_MB_2U(SCH_1):PAGE20
    J1  159  DQ6_A SCONN288_ADR50017P130CC-SCONN2A   I198 @S9S_MB_2U_LIB.S9S_MB_2U(SCH_1):PAGE82
    J2  159  DQ6_A SCONN288_ADR50017P087CC-SCONN2A   I177 @S9S_MB_2U_LIB.S9S_MB_2U(SCH_1):PAGE83

M_A_CPU0_SA_DQ<7> @S9S_MB_2U_LIB.S9S_MB_2U(SCH_1):M_A_CPU0_SA_DQ(7)
    U2  F75 DDR0_SA_DQ7 SOCKET4677_AZIF0045P001C01CS-SA     I1 @S9S_MB_2U_LIB.S9S_MB_2U(SCH_1):PAGE20
    J1  161  DQ7_A SCONN288_ADR50017P130CC-SCONN2A   I198 @S9S_MB_2U_LIB.S9S_MB_2U(SCH_1):PAGE82
    J2  161  DQ7_A SCONN288_ADR50017P087CC-SCONN2A   I177 @S9S_MB_2U_LIB.S9S_MB_2U(SCH_1):PAGE83

M_A_CPU0_SA_DQ<8> @S9S_MB_2U_LIB.S9S_MB_2U(SCH_1):M_A_CPU0_SA_DQ(8)
    U2  K69 DDR0_SA_DQ8 SOCKET4677_AZIF0045P001C01CS-SA     I1 @S9S_MB_2U_LIB.S9S_MB_2U(SCH_1):PAGE20
    J1   18  DQ8_A SCONN288_ADR50017P130CC-SCONN2A   I198 @S9S_MB_2U_LIB.S9S_MB_2U(SCH_1):PAGE82
    J2   18  DQ8_A SCONN288_ADR50017P087CC-SCONN2A   I177 @S9S_MB_2U_LIB.S9S_MB_2U(SCH_1):PAGE83

M_A_CPU0_SA_DQ<9> @S9S_MB_2U_LIB.S9S_MB_2U(SCH_1):M_A_CPU0_SA_DQ(9)
    U2  J68 DDR0_SA_DQ9 SOCKET4677_AZIF0045P001C01CS-SA     I1 @S9S_MB_2U_LIB.S9S_MB_2U(SCH_1):PAGE20
    J1   20  DQ9_A SCONN288_ADR50017P130CC-SCONN2A   I198 @S9S_MB_2U_LIB.S9S_MB_2U(SCH_1):PAGE82
    J2   20  DQ9_A SCONN288_ADR50017P087CC-SCONN2A   I177 @S9S_MB_2U_LIB.S9S_MB_2U(SCH_1):PAGE83

M_A_CPU0_SA_DQS_DN<0> @S9S_MB_2U_LIB.S9S_MB_2U(SCH_1):M_A_CPU0_SA_DQS_DN(0)
    U2  B77 DDR0_SA_DQS_DN0 SOCKET4677_AZIF0045P001C01CS-SA     I1 @S9S_MB_2U_LIB.S9S_MB_2U(SCH_1):PAGE20
    J1   12 DQS0_A_C SCONN288_ADR50017P130CC-SCONN2A   I202 @S9S_MB_2U_LIB.S9S_MB_2U(SCH_1):PAGE82
    J2   12 DQS0_A_C SCONN288_ADR50017P087CC-SCONN2A   I181 @S9S_MB_2U_LIB.S9S_MB_2U(SCH_1):PAGE83

M_A_CPU0_SA_DQS_DN<1> @S9S_MB_2U_LIB.S9S_MB_2U(SCH_1):M_A_CPU0_SA_DQS_DN(1)
    U2  H67 DDR0_SA_DQS_DN1 SOCKET4677_AZIF0045P001C01CS-SA     I1 @S9S_MB_2U_LIB.S9S_MB_2U(SCH_1):PAGE20
    J1   23 DQS1_A_C SCONN288_ADR50017P130CC-SCONN2A   I202 @S9S_MB_2U_LIB.S9S_MB_2U(SCH_1):PAGE82
    J2   23 DQS1_A_C SCONN288_ADR50017P087CC-SCONN2A   I181 @S9S_MB_2U_LIB.S9S_MB_2U(SCH_1):PAGE83

M_A_CPU0_SA_DQS_DN<2> @S9S_MB_2U_LIB.S9S_MB_2U(SCH_1):M_A_CPU0_SA_DQS_DN(2)
    U2  B71 DDR0_SA_DQS_DN2 SOCKET4677_AZIF0045P001C01CS-SA     I1 @S9S_MB_2U_LIB.S9S_MB_2U(SCH_1):PAGE20
    J1   34 DQS2_A_C SCONN288_ADR50017P130CC-SCONN2A   I202 @S9S_MB_2U_LIB.S9S_MB_2U(SCH_1):PAGE82
    J2   34 DQS2_A_C SCONN288_ADR50017P087CC-SCONN2A   I181 @S9S_MB_2U_LIB.S9S_MB_2U(SCH_1):PAGE83

M_A_CPU0_SA_DQS_DN<3> @S9S_MB_2U_LIB.S9S_MB_2U(SCH_1):M_A_CPU0_SA_DQS_DN(3)
    U2  A64 DDR0_SA_DQS_DN3 SOCKET4677_AZIF0045P001C01CS-SA     I1 @S9S_MB_2U_LIB.S9S_MB_2U(SCH_1):PAGE20
    J1   45 DQS3_A_C SCONN288_ADR50017P130CC-SCONN2A   I202 @S9S_MB_2U_LIB.S9S_MB_2U(SCH_1):PAGE82
    J2   45 DQS3_A_C SCONN288_ADR50017P087CC-SCONN2A   I181 @S9S_MB_2U_LIB.S9S_MB_2U(SCH_1):PAGE83

M_A_CPU0_SA_DQS_DN<4> @S9S_MB_2U_LIB.S9S_MB_2U(SCH_1):M_A_CPU0_SA_DQS_DN(4)
    U2  A58 DDR0_SA_DQS_DN4 SOCKET4677_AZIF0045P001C01CS-SA     I1 @S9S_MB_2U_LIB.S9S_MB_2U(SCH_1):PAGE20
    J1   56 DQS4_A_C SCONN288_ADR50017P130CC-SCONN2A   I202 @S9S_MB_2U_LIB.S9S_MB_2U(SCH_1):PAGE82
    J2   56 DQS4_A_C SCONN288_ADR50017P087CC-SCONN2A   I181 @S9S_MB_2U_LIB.S9S_MB_2U(SCH_1):PAGE83

M_A_CPU0_SA_DQS_DN<5> @S9S_MB_2U_LIB.S9S_MB_2U(SCH_1):M_A_CPU0_SA_DQS_DN(5)
    U2  H77 DDR0_SA_DQS_DN5 SOCKET4677_AZIF0045P001C01CS-SA     I1 @S9S_MB_2U_LIB.S9S_MB_2U(SCH_1):PAGE20
    J1  156 DQS5_A_C||TDQS5_A_C||DQS5_A_T||TDQS5_A_T SCONN288_ADR50017P130CC-SCONN2A   I202 @S9S_MB_2U_LIB.S9S_MB_2U(SCH_1):PAGE82
    J2  156 DQS5_A_C||TDQS5_A_C||DQS5_A_T||TDQS5_A_T SCONN288_ADR50017P087CC-SCONN2A   I181 @S9S_MB_2U_LIB.S9S_MB_2U(SCH_1):PAGE83

M_A_CPU0_SA_DQS_DN<6> @S9S_MB_2U_LIB.S9S_MB_2U(SCH_1):M_A_CPU0_SA_DQS_DN(6)
    U2  P67 DDR0_SA_DQS_DN6 SOCKET4677_AZIF0045P001C01CS-SA     I1 @S9S_MB_2U_LIB.S9S_MB_2U(SCH_1):PAGE20
    J1  167 DQS6_A_C||TDQS6_A_C||DQS6_A_T||TDQS6_A_T SCONN288_ADR50017P130CC-SCONN2A   I202 @S9S_MB_2U_LIB.S9S_MB_2U(SCH_1):PAGE82
    J2  167 DQS6_A_C||TDQS6_A_C||DQS6_A_T||TDQS6_A_T SCONN288_ADR50017P087CC-SCONN2A   I181 @S9S_MB_2U_LIB.S9S_MB_2U(SCH_1):PAGE83

M_A_CPU0_SA_DQS_DN<7> @S9S_MB_2U_LIB.S9S_MB_2U(SCH_1):M_A_CPU0_SA_DQS_DN(7)
    U2  G70 DDR0_SA_DQS_DN7 SOCKET4677_AZIF0045P001C01CS-SA     I1 @S9S_MB_2U_LIB.S9S_MB_2U(SCH_1):PAGE20
    J1  178 DQS7_A_C||TDQS7_A_C SCONN288_ADR50017P130CC-SCONN2A   I202 @S9S_MB_2U_LIB.S9S_MB_2U(SCH_1):PAGE82
    J2  178 DQS7_A_C||TDQS7_A_C SCONN288_ADR50017P087CC-SCONN2A   I181 @S9S_MB_2U_LIB.S9S_MB_2U(SCH_1):PAGE83

M_A_CPU0_SA_DQS_DN<8> @S9S_MB_2U_LIB.S9S_MB_2U(SCH_1):M_A_CPU0_SA_DQS_DN(8)
    U2  G64 DDR0_SA_DQS_DN8 SOCKET4677_AZIF0045P001C01CS-SA     I1 @S9S_MB_2U_LIB.S9S_MB_2U(SCH_1):PAGE20
    J1  189 DQS8_A_C||TDQS8_A_C SCONN288_ADR50017P130CC-SCONN2A   I202 @S9S_MB_2U_LIB.S9S_MB_2U(SCH_1):PAGE82
    J2  189 DQS8_A_C||TDQS8_A_C SCONN288_ADR50017P087CC-SCONN2A   I181 @S9S_MB_2U_LIB.S9S_MB_2U(SCH_1):PAGE83

M_A_CPU0_SA_DQS_DN<9> @S9S_MB_2U_LIB.S9S_MB_2U(SCH_1):M_A_CPU0_SA_DQS_DN(9)
    U2  G58 DDR0_SA_DQS_DN9 SOCKET4677_AZIF0045P001C01CS-SA     I1 @S9S_MB_2U_LIB.S9S_MB_2U(SCH_1):PAGE20
    J1  200 DQS9_A_C||TDQS9_A_C SCONN288_ADR50017P130CC-SCONN2A   I202 @S9S_MB_2U_LIB.S9S_MB_2U(SCH_1):PAGE82
    J2  200 DQS9_A_C||TDQS9_A_C SCONN288_ADR50017P087CC-SCONN2A   I181 @S9S_MB_2U_LIB.S9S_MB_2U(SCH_1):PAGE83

M_A_CPU0_SA_DQS_DP<0> @S9S_MB_2U_LIB.S9S_MB_2U(SCH_1):M_A_CPU0_SA_DQS_DP(0)
    U2  D77 DDR0_SA_DQS_DP0 SOCKET4677_AZIF0045P001C01CS-SA     I1 @S9S_MB_2U_LIB.S9S_MB_2U(SCH_1):PAGE20
    J1   11 DQS0_A_T SCONN288_ADR50017P130CC-SCONN2A   I202 @S9S_MB_2U_LIB.S9S_MB_2U(SCH_1):PAGE82
    J2   11 DQS0_A_T SCONN288_ADR50017P087CC-SCONN2A   I181 @S9S_MB_2U_LIB.S9S_MB_2U(SCH_1):PAGE83

M_A_CPU0_SA_DQS_DP<1> @S9S_MB_2U_LIB.S9S_MB_2U(SCH_1):M_A_CPU0_SA_DQS_DP(1)
    U2  K67 DDR0_SA_DQS_DP1 SOCKET4677_AZIF0045P001C01CS-SA     I1 @S9S_MB_2U_LIB.S9S_MB_2U(SCH_1):PAGE20
    J1   22 DQS1_A_T SCONN288_ADR50017P130CC-SCONN2A   I202 @S9S_MB_2U_LIB.S9S_MB_2U(SCH_1):PAGE82
    J2   22 DQS1_A_T SCONN288_ADR50017P087CC-SCONN2A   I181 @S9S_MB_2U_LIB.S9S_MB_2U(SCH_1):PAGE83

M_A_CPU0_SA_DQS_DP<2> @S9S_MB_2U_LIB.S9S_MB_2U(SCH_1):M_A_CPU0_SA_DQS_DP(2)
    U2  C70 DDR0_SA_DQS_DP2 SOCKET4677_AZIF0045P001C01CS-SA     I1 @S9S_MB_2U_LIB.S9S_MB_2U(SCH_1):PAGE20
    J1   33 DQS2_A_T SCONN288_ADR50017P130CC-SCONN2A   I202 @S9S_MB_2U_LIB.S9S_MB_2U(SCH_1):PAGE82
    J2   33 DQS2_A_T SCONN288_ADR50017P087CC-SCONN2A   I181 @S9S_MB_2U_LIB.S9S_MB_2U(SCH_1):PAGE83

M_A_CPU0_SA_DQS_DP<3> @S9S_MB_2U_LIB.S9S_MB_2U(SCH_1):M_A_CPU0_SA_DQS_DP(3)
    U2  C64 DDR0_SA_DQS_DP3 SOCKET4677_AZIF0045P001C01CS-SA     I1 @S9S_MB_2U_LIB.S9S_MB_2U(SCH_1):PAGE20
    J1   44 DQS3_A_T SCONN288_ADR50017P130CC-SCONN2A   I202 @S9S_MB_2U_LIB.S9S_MB_2U(SCH_1):PAGE82
    J2   44 DQS3_A_T SCONN288_ADR50017P087CC-SCONN2A   I181 @S9S_MB_2U_LIB.S9S_MB_2U(SCH_1):PAGE83

M_A_CPU0_SA_DQS_DP<4> @S9S_MB_2U_LIB.S9S_MB_2U(SCH_1):M_A_CPU0_SA_DQS_DP(4)
    U2  C58 DDR0_SA_DQS_DP4 SOCKET4677_AZIF0045P001C01CS-SA     I1 @S9S_MB_2U_LIB.S9S_MB_2U(SCH_1):PAGE20
    J1   55 DQS4_A_T SCONN288_ADR50017P130CC-SCONN2A   I202 @S9S_MB_2U_LIB.S9S_MB_2U(SCH_1):PAGE82
    J2   55 DQS4_A_T SCONN288_ADR50017P087CC-SCONN2A   I181 @S9S_MB_2U_LIB.S9S_MB_2U(SCH_1):PAGE83

M_A_CPU0_SA_DQS_DP<5> @S9S_MB_2U_LIB.S9S_MB_2U(SCH_1):M_A_CPU0_SA_DQS_DP(5)
    U2  F77 DDR0_SA_DQS_DP5 SOCKET4677_AZIF0045P001C01CS-SA     I1 @S9S_MB_2U_LIB.S9S_MB_2U(SCH_1):PAGE20
    J1  157 DQS5_A_T||TDQS5_A_T SCONN288_ADR50017P130CC-SCONN2A   I202 @S9S_MB_2U_LIB.S9S_MB_2U(SCH_1):PAGE82
    J2  157 DQS5_A_T||TDQS5_A_T SCONN288_ADR50017P087CC-SCONN2A   I181 @S9S_MB_2U_LIB.S9S_MB_2U(SCH_1):PAGE83

M_A_CPU0_SA_DQS_DP<6> @S9S_MB_2U_LIB.S9S_MB_2U(SCH_1):M_A_CPU0_SA_DQS_DP(6)
    U2  M67 DDR0_SA_DQS_DP6 SOCKET4677_AZIF0045P001C01CS-SA     I1 @S9S_MB_2U_LIB.S9S_MB_2U(SCH_1):PAGE20
    J1  168 DQS6_A_T||TDQS6_A_T SCONN288_ADR50017P130CC-SCONN2A   I202 @S9S_MB_2U_LIB.S9S_MB_2U(SCH_1):PAGE82
    J2  168 DQS6_A_T||TDQS6_A_T SCONN288_ADR50017P087CC-SCONN2A   I181 @S9S_MB_2U_LIB.S9S_MB_2U(SCH_1):PAGE83

M_A_CPU0_SA_DQS_DP<7> @S9S_MB_2U_LIB.S9S_MB_2U(SCH_1):M_A_CPU0_SA_DQS_DP(7)
    U2  E70 DDR0_SA_DQS_DP7 SOCKET4677_AZIF0045P001C01CS-SA     I1 @S9S_MB_2U_LIB.S9S_MB_2U(SCH_1):PAGE20
    J1  179 DQS7_A_T||TDQS7_A_T SCONN288_ADR50017P130CC-SCONN2A   I202 @S9S_MB_2U_LIB.S9S_MB_2U(SCH_1):PAGE82
    J2  179 DQS7_A_T||TDQS7_A_T SCONN288_ADR50017P087CC-SCONN2A   I181 @S9S_MB_2U_LIB.S9S_MB_2U(SCH_1):PAGE83

M_A_CPU0_SA_DQS_DP<8> @S9S_MB_2U_LIB.S9S_MB_2U(SCH_1):M_A_CPU0_SA_DQS_DP(8)
    U2  E64 DDR0_SA_DQS_DP8 SOCKET4677_AZIF0045P001C01CS-SA     I1 @S9S_MB_2U_LIB.S9S_MB_2U(SCH_1):PAGE20
    J1  190 DQS8_A_T||TDQS8_A_T SCONN288_ADR50017P130CC-SCONN2A   I202 @S9S_MB_2U_LIB.S9S_MB_2U(SCH_1):PAGE82
    J2  190 DQS8_A_T||TDQS8_A_T SCONN288_ADR50017P087CC-SCONN2A   I181 @S9S_MB_2U_LIB.S9S_MB_2U(SCH_1):PAGE83

M_A_CPU0_SA_DQS_DP<9> @S9S_MB_2U_LIB.S9S_MB_2U(SCH_1):M_A_CPU0_SA_DQS_DP(9)
    U2  E58 DDR0_SA_DQS_DP9 SOCKET4677_AZIF0045P001C01CS-SA     I1 @S9S_MB_2U_LIB.S9S_MB_2U(SCH_1):PAGE20
    J1  201 DQS9_A_T||TDQS9_A_T SCONN288_ADR50017P130CC-SCONN2A   I202 @S9S_MB_2U_LIB.S9S_MB_2U(SCH_1):PAGE82
    J2  201 DQS9_A_T||TDQS9_A_T SCONN288_ADR50017P087CC-SCONN2A   I181 @S9S_MB_2U_LIB.S9S_MB_2U(SCH_1):PAGE83

M_A_CPU0_SA_PAR @S9S_MB_2U_LIB.S9S_MB_2U(SCH_1):M_A_CPU0_SA_PAR
    U2  E48 DDR0_SA_PAR SOCKET4677_AZIF0045P001C01CS-SA     I1 @S9S_MB_2U_LIB.S9S_MB_2U(SCH_1):PAGE20
    J1   74  PAR_A SCONN288_ADR50017P130CC-SCONN2A   I198 @S9S_MB_2U_LIB.S9S_MB_2U(SCH_1):PAGE82
    J2   74  PAR_A SCONN288_ADR50017P087CC-SCONN2A   I177 @S9S_MB_2U_LIB.S9S_MB_2U(SCH_1):PAGE83

M_A_CPU0_SA_RSP<0> @S9S_MB_2U_LIB.S9S_MB_2U(SCH_1):M_A_CPU0_SA_RSP(0)
    U2 AT42 DDR0_A_RSP0 SOCKET4677_AZIF0045P001C01CS-SA     I1 @S9S_MB_2U_LIB.S9S_MB_2U(SCH_1):PAGE20
    J1   86 LBD||RSP_A_N SCONN288_ADR50017P130CC-SCONN2A   I198 @S9S_MB_2U_LIB.S9S_MB_2U(SCH_1):PAGE82

M_A_CPU0_SA_RSP<1> @S9S_MB_2U_LIB.S9S_MB_2U(SCH_1):M_A_CPU0_SA_RSP(1)
    U2 AU43 DDR0_A_RSP1 SOCKET4677_AZIF0045P001C01CS-SA     I1 @S9S_MB_2U_LIB.S9S_MB_2U(SCH_1):PAGE20
    J2   86 LBD||RSP_A_N SCONN288_ADR50017P087CC-SCONN2A   I177 @S9S_MB_2U_LIB.S9S_MB_2U(SCH_1):PAGE83

M_A_CPU0_SB_CA<0> @S9S_MB_2U_LIB.S9S_MB_2U(SCH_1):M_A_CPU0_SB_CA(0)
    U2  E43 DDR0_SB_CA0 SOCKET4677_AZIF0045P001C01CS-SA     I1 @S9S_MB_2U_LIB.S9S_MB_2U(SCH_1):PAGE20
    J1   76  CA0_B SCONN288_ADR50017P130CC-SCONN2A   I198 @S9S_MB_2U_LIB.S9S_MB_2U(SCH_1):PAGE82
    J2   76  CA0_B SCONN288_ADR50017P087CC-SCONN2A   I177 @S9S_MB_2U_LIB.S9S_MB_2U(SCH_1):PAGE83

M_A_CPU0_SB_CA<1> @S9S_MB_2U_LIB.S9S_MB_2U(SCH_1):M_A_CPU0_SB_CA(1)
    U2  F44 DDR0_SB_CA1 SOCKET4677_AZIF0045P001C01CS-SA     I1 @S9S_MB_2U_LIB.S9S_MB_2U(SCH_1):PAGE20
    J1  221  CA1_B SCONN288_ADR50017P130CC-SCONN2A   I198 @S9S_MB_2U_LIB.S9S_MB_2U(SCH_1):PAGE82
    J2  221  CA1_B SCONN288_ADR50017P087CC-SCONN2A   I177 @S9S_MB_2U_LIB.S9S_MB_2U(SCH_1):PAGE83

M_A_CPU0_SB_CA<2> @S9S_MB_2U_LIB.S9S_MB_2U(SCH_1):M_A_CPU0_SB_CA(2)
    U2  C41 DDR0_SB_CA2 SOCKET4677_AZIF0045P001C01CS-SA     I1 @S9S_MB_2U_LIB.S9S_MB_2U(SCH_1):PAGE20
    J1   78  CA2_B SCONN288_ADR50017P130CC-SCONN2A   I198 @S9S_MB_2U_LIB.S9S_MB_2U(SCH_1):PAGE82
    J2   78  CA2_B SCONN288_ADR50017P087CC-SCONN2A   I177 @S9S_MB_2U_LIB.S9S_MB_2U(SCH_1):PAGE83

M_A_CPU0_SB_CA<3> @S9S_MB_2U_LIB.S9S_MB_2U(SCH_1):M_A_CPU0_SB_CA(3)
    U2  E41 DDR0_SB_CA3 SOCKET4677_AZIF0045P001C01CS-SA     I1 @S9S_MB_2U_LIB.S9S_MB_2U(SCH_1):PAGE20
    J1  223  CA3_B SCONN288_ADR50017P130CC-SCONN2A   I198 @S9S_MB_2U_LIB.S9S_MB_2U(SCH_1):PAGE82
    J2  223  CA3_B SCONN288_ADR50017P087CC-SCONN2A   I177 @S9S_MB_2U_LIB.S9S_MB_2U(SCH_1):PAGE83

M_A_CPU0_SB_CA<4> @S9S_MB_2U_LIB.S9S_MB_2U(SCH_1):M_A_CPU0_SB_CA(4)
    U2  B40 DDR0_SB_CA4 SOCKET4677_AZIF0045P001C01CS-SA     I1 @S9S_MB_2U_LIB.S9S_MB_2U(SCH_1):PAGE20
    J1   80  CA4_B SCONN288_ADR50017P130CC-SCONN2A   I198 @S9S_MB_2U_LIB.S9S_MB_2U(SCH_1):PAGE82
    J2   80  CA4_B SCONN288_ADR50017P087CC-SCONN2A   I177 @S9S_MB_2U_LIB.S9S_MB_2U(SCH_1):PAGE83

M_A_CPU0_SB_CA<5> @S9S_MB_2U_LIB.S9S_MB_2U(SCH_1):M_A_CPU0_SB_CA(5)
    U2  F40 DDR0_SB_CA5 SOCKET4677_AZIF0045P001C01CS-SA     I1 @S9S_MB_2U_LIB.S9S_MB_2U(SCH_1):PAGE20
    J1  225  CA5_B SCONN288_ADR50017P130CC-SCONN2A   I198 @S9S_MB_2U_LIB.S9S_MB_2U(SCH_1):PAGE82
    J2  225  CA5_B SCONN288_ADR50017P087CC-SCONN2A   I177 @S9S_MB_2U_LIB.S9S_MB_2U(SCH_1):PAGE83

M_A_CPU0_SB_CA<6> @S9S_MB_2U_LIB.S9S_MB_2U(SCH_1):M_A_CPU0_SB_CA(6)
    U2  A39 DDR0_SB_CA6 SOCKET4677_AZIF0045P001C01CS-SA     I1 @S9S_MB_2U_LIB.S9S_MB_2U(SCH_1):PAGE20
    J1   82  CA6_B SCONN288_ADR50017P130CC-SCONN2A   I198 @S9S_MB_2U_LIB.S9S_MB_2U(SCH_1):PAGE82
    J2   82  CA6_B SCONN288_ADR50017P087CC-SCONN2A   I177 @S9S_MB_2U_LIB.S9S_MB_2U(SCH_1):PAGE83

M_A_CPU0_SB_CB<0> @S9S_MB_2U_LIB.S9S_MB_2U(SCH_1):M_A_CPU0_SB_CB(0)
    U2  B32 DDR0_SB_ECC0 SOCKET4677_AZIF0045P001C01CS-SA     I1 @S9S_MB_2U_LIB.S9S_MB_2U(SCH_1):PAGE20
    J1   96  CB0_B SCONN288_ADR50017P130CC-SCONN2A   I198 @S9S_MB_2U_LIB.S9S_MB_2U(SCH_1):PAGE82
    J2   96  CB0_B SCONN288_ADR50017P087CC-SCONN2A   I177 @S9S_MB_2U_LIB.S9S_MB_2U(SCH_1):PAGE83

M_A_CPU0_SB_CB<1> @S9S_MB_2U_LIB.S9S_MB_2U(SCH_1):M_A_CPU0_SB_CB(1)
    U2  C31 DDR0_SB_ECC1 SOCKET4677_AZIF0045P001C01CS-SA     I1 @S9S_MB_2U_LIB.S9S_MB_2U(SCH_1):PAGE20
    J1   98  CB1_B SCONN288_ADR50017P130CC-SCONN2A   I198 @S9S_MB_2U_LIB.S9S_MB_2U(SCH_1):PAGE82
    J2   98  CB1_B SCONN288_ADR50017P087CC-SCONN2A   I177 @S9S_MB_2U_LIB.S9S_MB_2U(SCH_1):PAGE83

M_A_CPU0_SB_CB<2> @S9S_MB_2U_LIB.S9S_MB_2U(SCH_1):M_A_CPU0_SB_CB(2)
    U2  F32 DDR0_SB_ECC2 SOCKET4677_AZIF0045P001C01CS-SA     I1 @S9S_MB_2U_LIB.S9S_MB_2U(SCH_1):PAGE20
    J1  241  CB2_B SCONN288_ADR50017P130CC-SCONN2A   I198 @S9S_MB_2U_LIB.S9S_MB_2U(SCH_1):PAGE82
    J2  241  CB2_B SCONN288_ADR50017P087CC-SCONN2A   I177 @S9S_MB_2U_LIB.S9S_MB_2U(SCH_1):PAGE83

M_A_CPU0_SB_CB<3> @S9S_MB_2U_LIB.S9S_MB_2U(SCH_1):M_A_CPU0_SB_CB(3)
    U2  E31 DDR0_SB_ECC3 SOCKET4677_AZIF0045P001C01CS-SA     I1 @S9S_MB_2U_LIB.S9S_MB_2U(SCH_1):PAGE20
    J1  243  CB3_B SCONN288_ADR50017P130CC-SCONN2A   I198 @S9S_MB_2U_LIB.S9S_MB_2U(SCH_1):PAGE82
    J2  243  CB3_B SCONN288_ADR50017P087CC-SCONN2A   I177 @S9S_MB_2U_LIB.S9S_MB_2U(SCH_1):PAGE83

M_A_CPU0_SB_CB<4> @S9S_MB_2U_LIB.S9S_MB_2U(SCH_1):M_A_CPU0_SB_CB(4)
    U2  C35 DDR0_SB_ECC4 SOCKET4677_AZIF0045P001C01CS-SA     I1 @S9S_MB_2U_LIB.S9S_MB_2U(SCH_1):PAGE20
    J1   89  CB4_B SCONN288_ADR50017P130CC-SCONN2A   I198 @S9S_MB_2U_LIB.S9S_MB_2U(SCH_1):PAGE82
    J2   89  CB4_B SCONN288_ADR50017P087CC-SCONN2A   I177 @S9S_MB_2U_LIB.S9S_MB_2U(SCH_1):PAGE83

M_A_CPU0_SB_CB<5> @S9S_MB_2U_LIB.S9S_MB_2U(SCH_1):M_A_CPU0_SB_CB(5)
    U2  B34 DDR0_SB_ECC5 SOCKET4677_AZIF0045P001C01CS-SA     I1 @S9S_MB_2U_LIB.S9S_MB_2U(SCH_1):PAGE20
    J1   91  CB5_B SCONN288_ADR50017P130CC-SCONN2A   I198 @S9S_MB_2U_LIB.S9S_MB_2U(SCH_1):PAGE82
    J2   91  CB5_B SCONN288_ADR50017P087CC-SCONN2A   I177 @S9S_MB_2U_LIB.S9S_MB_2U(SCH_1):PAGE83

M_A_CPU0_SB_CB<6> @S9S_MB_2U_LIB.S9S_MB_2U(SCH_1):M_A_CPU0_SB_CB(6)
    U2  E35 DDR0_SB_ECC6 SOCKET4677_AZIF0045P001C01CS-SA     I1 @S9S_MB_2U_LIB.S9S_MB_2U(SCH_1):PAGE20
    J1  234  CB6_B SCONN288_ADR50017P130CC-SCONN2A   I198 @S9S_MB_2U_LIB.S9S_MB_2U(SCH_1):PAGE82
    J2  234  CB6_B SCONN288_ADR50017P087CC-SCONN2A   I177 @S9S_MB_2U_LIB.S9S_MB_2U(SCH_1):PAGE83

M_A_CPU0_SB_CB<7> @S9S_MB_2U_LIB.S9S_MB_2U(SCH_1):M_A_CPU0_SB_CB(7)
    U2  F34 DDR0_SB_ECC7 SOCKET4677_AZIF0045P001C01CS-SA     I1 @S9S_MB_2U_LIB.S9S_MB_2U(SCH_1):PAGE20
    J1  236  CB7_B SCONN288_ADR50017P130CC-SCONN2A   I198 @S9S_MB_2U_LIB.S9S_MB_2U(SCH_1):PAGE82
    J2  236  CB7_B SCONN288_ADR50017P087CC-SCONN2A   I177 @S9S_MB_2U_LIB.S9S_MB_2U(SCH_1):PAGE83

M_A_CPU0_SB_CS_N<0> @S9S_MB_2U_LIB.S9S_MB_2U(SCH_1):M_A_CPU0_SB_CS_N(0)
    U2  B38 DDR0_SB_CS_N0 SOCKET4677_AZIF0045P001C01CS-SA     I1 @S9S_MB_2U_LIB.S9S_MB_2U(SCH_1):PAGE20
    J1   84 CS0_B_N SCONN288_ADR50017P130CC-SCONN2A   I198 @S9S_MB_2U_LIB.S9S_MB_2U(SCH_1):PAGE82

M_A_CPU0_SB_CS_N<1> @S9S_MB_2U_LIB.S9S_MB_2U(SCH_1):M_A_CPU0_SB_CS_N(1)
    U2  C37 DDR0_SB_CS_N1 SOCKET4677_AZIF0045P001C01CS-SA     I1 @S9S_MB_2U_LIB.S9S_MB_2U(SCH_1):PAGE20
    J1  229 CS1_B_N SCONN288_ADR50017P130CC-SCONN2A   I198 @S9S_MB_2U_LIB.S9S_MB_2U(SCH_1):PAGE82

M_A_CPU0_SB_CS_N<2> @S9S_MB_2U_LIB.S9S_MB_2U(SCH_1):M_A_CPU0_SB_CS_N(2)
    U2  F38 DDR0_SB_CS_N2 SOCKET4677_AZIF0045P001C01CS-SA     I1 @S9S_MB_2U_LIB.S9S_MB_2U(SCH_1):PAGE20
    J2   84 CS0_B_N SCONN288_ADR50017P087CC-SCONN2A   I177 @S9S_MB_2U_LIB.S9S_MB_2U(SCH_1):PAGE83

M_A_CPU0_SB_CS_N<3> @S9S_MB_2U_LIB.S9S_MB_2U(SCH_1):M_A_CPU0_SB_CS_N(3)
    U2  E37 DDR0_SB_CS_N3 SOCKET4677_AZIF0045P001C01CS-SA     I1 @S9S_MB_2U_LIB.S9S_MB_2U(SCH_1):PAGE20
    J2  229 CS1_B_N SCONN288_ADR50017P087CC-SCONN2A   I177 @S9S_MB_2U_LIB.S9S_MB_2U(SCH_1):PAGE83

M_A_CPU0_SB_DQ<0> @S9S_MB_2U_LIB.S9S_MB_2U(SCH_1):M_A_CPU0_SB_DQ(0)
    U2  K32 DDR0_SB_DQ0 SOCKET4677_AZIF0045P001C01CS-SA     I1 @S9S_MB_2U_LIB.S9S_MB_2U(SCH_1):PAGE20
    J1  100  DQ0_B SCONN288_ADR50017P130CC-SCONN2A   I198 @S9S_MB_2U_LIB.S9S_MB_2U(SCH_1):PAGE82
    J2  100  DQ0_B SCONN288_ADR50017P087CC-SCONN2A   I177 @S9S_MB_2U_LIB.S9S_MB_2U(SCH_1):PAGE83

M_A_CPU0_SB_DQ<10> @S9S_MB_2U_LIB.S9S_MB_2U(SCH_1):M_A_CPU0_SB_DQ(10)
    U2  E29 DDR0_SB_DQ10 SOCKET4677_AZIF0045P001C01CS-SA     I1 @S9S_MB_2U_LIB.S9S_MB_2U(SCH_1):PAGE20
    J1  256 DQ10_B SCONN288_ADR50017P130CC-SCONN2A   I198 @S9S_MB_2U_LIB.S9S_MB_2U(SCH_1):PAGE82
    J2  256 DQ10_B SCONN288_ADR50017P087CC-SCONN2A   I177 @S9S_MB_2U_LIB.S9S_MB_2U(SCH_1):PAGE83

M_A_CPU0_SB_DQ<11> @S9S_MB_2U_LIB.S9S_MB_2U(SCH_1):M_A_CPU0_SB_DQ(11)
    U2  F28 DDR0_SB_DQ11 SOCKET4677_AZIF0045P001C01CS-SA     I1 @S9S_MB_2U_LIB.S9S_MB_2U(SCH_1):PAGE20
    J1  258 DQ11_B SCONN288_ADR50017P130CC-SCONN2A   I198 @S9S_MB_2U_LIB.S9S_MB_2U(SCH_1):PAGE82
    J2  258 DQ11_B SCONN288_ADR50017P087CC-SCONN2A   I177 @S9S_MB_2U_LIB.S9S_MB_2U(SCH_1):PAGE83

M_A_CPU0_SB_DQ<12> @S9S_MB_2U_LIB.S9S_MB_2U(SCH_1):M_A_CPU0_SB_DQ(12)
    U2  B26 DDR0_SB_DQ12 SOCKET4677_AZIF0045P001C01CS-SA     I1 @S9S_MB_2U_LIB.S9S_MB_2U(SCH_1):PAGE20
    J1  118 DQ12_B SCONN288_ADR50017P130CC-SCONN2A   I198 @S9S_MB_2U_LIB.S9S_MB_2U(SCH_1):PAGE82
    J2  118 DQ12_B SCONN288_ADR50017P087CC-SCONN2A   I177 @S9S_MB_2U_LIB.S9S_MB_2U(SCH_1):PAGE83

M_A_CPU0_SB_DQ<13> @S9S_MB_2U_LIB.S9S_MB_2U(SCH_1):M_A_CPU0_SB_DQ(13)
    U2  C25 DDR0_SB_DQ13 SOCKET4677_AZIF0045P001C01CS-SA     I1 @S9S_MB_2U_LIB.S9S_MB_2U(SCH_1):PAGE20
    J1  120 DQ13_B SCONN288_ADR50017P130CC-SCONN2A   I198 @S9S_MB_2U_LIB.S9S_MB_2U(SCH_1):PAGE82
    J2  120 DQ13_B SCONN288_ADR50017P087CC-SCONN2A   I177 @S9S_MB_2U_LIB.S9S_MB_2U(SCH_1):PAGE83

M_A_CPU0_SB_DQ<14> @S9S_MB_2U_LIB.S9S_MB_2U(SCH_1):M_A_CPU0_SB_DQ(14)
    U2  F26 DDR0_SB_DQ14 SOCKET4677_AZIF0045P001C01CS-SA     I1 @S9S_MB_2U_LIB.S9S_MB_2U(SCH_1):PAGE20
    J1  263 DQ14_B SCONN288_ADR50017P130CC-SCONN2A   I198 @S9S_MB_2U_LIB.S9S_MB_2U(SCH_1):PAGE82
    J2  263 DQ14_B SCONN288_ADR50017P087CC-SCONN2A   I177 @S9S_MB_2U_LIB.S9S_MB_2U(SCH_1):PAGE83

M_A_CPU0_SB_DQ<15> @S9S_MB_2U_LIB.S9S_MB_2U(SCH_1):M_A_CPU0_SB_DQ(15)
    U2  E25 DDR0_SB_DQ15 SOCKET4677_AZIF0045P001C01CS-SA     I1 @S9S_MB_2U_LIB.S9S_MB_2U(SCH_1):PAGE20
    J1  265 DQ15_B SCONN288_ADR50017P130CC-SCONN2A   I198 @S9S_MB_2U_LIB.S9S_MB_2U(SCH_1):PAGE82
    J2  265 DQ15_B SCONN288_ADR50017P087CC-SCONN2A   I177 @S9S_MB_2U_LIB.S9S_MB_2U(SCH_1):PAGE83

M_A_CPU0_SB_DQ<16> @S9S_MB_2U_LIB.S9S_MB_2U(SCH_1):M_A_CPU0_SB_DQ(16)
    U2  C23 DDR0_SB_DQ16 SOCKET4677_AZIF0045P001C01CS-SA     I1 @S9S_MB_2U_LIB.S9S_MB_2U(SCH_1):PAGE20
    J1  122 DQ16_B SCONN288_ADR50017P130CC-SCONN2A   I198 @S9S_MB_2U_LIB.S9S_MB_2U(SCH_1):PAGE82
    J2  122 DQ16_B SCONN288_ADR50017P087CC-SCONN2A   I177 @S9S_MB_2U_LIB.S9S_MB_2U(SCH_1):PAGE83

M_A_CPU0_SB_DQ<17> @S9S_MB_2U_LIB.S9S_MB_2U(SCH_1):M_A_CPU0_SB_DQ(17)
    U2  B22 DDR0_SB_DQ17 SOCKET4677_AZIF0045P001C01CS-SA     I1 @S9S_MB_2U_LIB.S9S_MB_2U(SCH_1):PAGE20
    J1  124 DQ17_B SCONN288_ADR50017P130CC-SCONN2A   I198 @S9S_MB_2U_LIB.S9S_MB_2U(SCH_1):PAGE82
    J2  124 DQ17_B SCONN288_ADR50017P087CC-SCONN2A   I177 @S9S_MB_2U_LIB.S9S_MB_2U(SCH_1):PAGE83

M_A_CPU0_SB_DQ<18> @S9S_MB_2U_LIB.S9S_MB_2U(SCH_1):M_A_CPU0_SB_DQ(18)
    U2  E23 DDR0_SB_DQ18 SOCKET4677_AZIF0045P001C01CS-SA     I1 @S9S_MB_2U_LIB.S9S_MB_2U(SCH_1):PAGE20
    J1  267 DQ18_B SCONN288_ADR50017P130CC-SCONN2A   I198 @S9S_MB_2U_LIB.S9S_MB_2U(SCH_1):PAGE82
    J2  267 DQ18_B SCONN288_ADR50017P087CC-SCONN2A   I177 @S9S_MB_2U_LIB.S9S_MB_2U(SCH_1):PAGE83

M_A_CPU0_SB_DQ<19> @S9S_MB_2U_LIB.S9S_MB_2U(SCH_1):M_A_CPU0_SB_DQ(19)
    U2  F22 DDR0_SB_DQ19 SOCKET4677_AZIF0045P001C01CS-SA     I1 @S9S_MB_2U_LIB.S9S_MB_2U(SCH_1):PAGE20
    J1  269 DQ19_B SCONN288_ADR50017P130CC-SCONN2A   I198 @S9S_MB_2U_LIB.S9S_MB_2U(SCH_1):PAGE82
    J2  269 DQ19_B SCONN288_ADR50017P087CC-SCONN2A   I177 @S9S_MB_2U_LIB.S9S_MB_2U(SCH_1):PAGE83

M_A_CPU0_SB_DQ<1> @S9S_MB_2U_LIB.S9S_MB_2U(SCH_1):M_A_CPU0_SB_DQ(1)
    U2  J31 DDR0_SB_DQ1 SOCKET4677_AZIF0045P001C01CS-SA     I1 @S9S_MB_2U_LIB.S9S_MB_2U(SCH_1):PAGE20
    J1  102  DQ1_B SCONN288_ADR50017P130CC-SCONN2A   I198 @S9S_MB_2U_LIB.S9S_MB_2U(SCH_1):PAGE82
    J2  102  DQ1_B SCONN288_ADR50017P087CC-SCONN2A   I177 @S9S_MB_2U_LIB.S9S_MB_2U(SCH_1):PAGE83

M_A_CPU0_SB_DQ<20> @S9S_MB_2U_LIB.S9S_MB_2U(SCH_1):M_A_CPU0_SB_DQ(20)
    U2  B20 DDR0_SB_DQ20 SOCKET4677_AZIF0045P001C01CS-SA     I1 @S9S_MB_2U_LIB.S9S_MB_2U(SCH_1):PAGE20
    J1  129 DQ20_B SCONN288_ADR50017P130CC-SCONN2A   I198 @S9S_MB_2U_LIB.S9S_MB_2U(SCH_1):PAGE82
    J2  129 DQ20_B SCONN288_ADR50017P087CC-SCONN2A   I177 @S9S_MB_2U_LIB.S9S_MB_2U(SCH_1):PAGE83

M_A_CPU0_SB_DQ<21> @S9S_MB_2U_LIB.S9S_MB_2U(SCH_1):M_A_CPU0_SB_DQ(21)
    U2  C19 DDR0_SB_DQ21 SOCKET4677_AZIF0045P001C01CS-SA     I1 @S9S_MB_2U_LIB.S9S_MB_2U(SCH_1):PAGE20
    J1  131 DQ21_B SCONN288_ADR50017P130CC-SCONN2A   I198 @S9S_MB_2U_LIB.S9S_MB_2U(SCH_1):PAGE82
    J2  131 DQ21_B SCONN288_ADR50017P087CC-SCONN2A   I177 @S9S_MB_2U_LIB.S9S_MB_2U(SCH_1):PAGE83

M_A_CPU0_SB_DQ<22> @S9S_MB_2U_LIB.S9S_MB_2U(SCH_1):M_A_CPU0_SB_DQ(22)
    U2  F20 DDR0_SB_DQ22 SOCKET4677_AZIF0045P001C01CS-SA     I1 @S9S_MB_2U_LIB.S9S_MB_2U(SCH_1):PAGE20
    J1  274 DQ22_B SCONN288_ADR50017P130CC-SCONN2A   I198 @S9S_MB_2U_LIB.S9S_MB_2U(SCH_1):PAGE82
    J2  274 DQ22_B SCONN288_ADR50017P087CC-SCONN2A   I177 @S9S_MB_2U_LIB.S9S_MB_2U(SCH_1):PAGE83

M_A_CPU0_SB_DQ<23> @S9S_MB_2U_LIB.S9S_MB_2U(SCH_1):M_A_CPU0_SB_DQ(23)
    U2  E19 DDR0_SB_DQ23 SOCKET4677_AZIF0045P001C01CS-SA     I1 @S9S_MB_2U_LIB.S9S_MB_2U(SCH_1):PAGE20
    J1  276 DQ23_B SCONN288_ADR50017P130CC-SCONN2A   I198 @S9S_MB_2U_LIB.S9S_MB_2U(SCH_1):PAGE82
    J2  276 DQ23_B SCONN288_ADR50017P087CC-SCONN2A   I177 @S9S_MB_2U_LIB.S9S_MB_2U(SCH_1):PAGE83

M_A_CPU0_SB_DQ<24> @S9S_MB_2U_LIB.S9S_MB_2U(SCH_1):M_A_CPU0_SB_DQ(24)
    U2  C11 DDR0_SB_DQ24 SOCKET4677_AZIF0045P001C01CS-SA     I1 @S9S_MB_2U_LIB.S9S_MB_2U(SCH_1):PAGE20
    J1  133 DQ24_B SCONN288_ADR50017P130CC-SCONN2A   I198 @S9S_MB_2U_LIB.S9S_MB_2U(SCH_1):PAGE82
    J2  133 DQ24_B SCONN288_ADR50017P087CC-SCONN2A   I177 @S9S_MB_2U_LIB.S9S_MB_2U(SCH_1):PAGE83

M_A_CPU0_SB_DQ<25> @S9S_MB_2U_LIB.S9S_MB_2U(SCH_1):M_A_CPU0_SB_DQ(25)
    U2  B10 DDR0_SB_DQ25 SOCKET4677_AZIF0045P001C01CS-SA     I1 @S9S_MB_2U_LIB.S9S_MB_2U(SCH_1):PAGE20
    J1  135 DQ25_B SCONN288_ADR50017P130CC-SCONN2A   I198 @S9S_MB_2U_LIB.S9S_MB_2U(SCH_1):PAGE82
    J2  135 DQ25_B SCONN288_ADR50017P087CC-SCONN2A   I177 @S9S_MB_2U_LIB.S9S_MB_2U(SCH_1):PAGE83

M_A_CPU0_SB_DQ<26> @S9S_MB_2U_LIB.S9S_MB_2U(SCH_1):M_A_CPU0_SB_DQ(26)
    U2  E11 DDR0_SB_DQ26 SOCKET4677_AZIF0045P001C01CS-SA     I1 @S9S_MB_2U_LIB.S9S_MB_2U(SCH_1):PAGE20
    J1  278 DQ26_B SCONN288_ADR50017P130CC-SCONN2A   I198 @S9S_MB_2U_LIB.S9S_MB_2U(SCH_1):PAGE82
    J2  278 DQ26_B SCONN288_ADR50017P087CC-SCONN2A   I177 @S9S_MB_2U_LIB.S9S_MB_2U(SCH_1):PAGE83

M_A_CPU0_SB_DQ<27> @S9S_MB_2U_LIB.S9S_MB_2U(SCH_1):M_A_CPU0_SB_DQ(27)
    U2  F10 DDR0_SB_DQ27 SOCKET4677_AZIF0045P001C01CS-SA     I1 @S9S_MB_2U_LIB.S9S_MB_2U(SCH_1):PAGE20
    J1  280 DQ27_B SCONN288_ADR50017P130CC-SCONN2A   I198 @S9S_MB_2U_LIB.S9S_MB_2U(SCH_1):PAGE82
    J2  280 DQ27_B SCONN288_ADR50017P087CC-SCONN2A   I177 @S9S_MB_2U_LIB.S9S_MB_2U(SCH_1):PAGE83

M_A_CPU0_SB_DQ<28> @S9S_MB_2U_LIB.S9S_MB_2U(SCH_1):M_A_CPU0_SB_DQ(28)
    U2   B8 DDR0_SB_DQ28 SOCKET4677_AZIF0045P001C01CS-SA     I1 @S9S_MB_2U_LIB.S9S_MB_2U(SCH_1):PAGE20
    J1  140 DQ28_B SCONN288_ADR50017P130CC-SCONN2A   I198 @S9S_MB_2U_LIB.S9S_MB_2U(SCH_1):PAGE82
    J2  140 DQ28_B SCONN288_ADR50017P087CC-SCONN2A   I177 @S9S_MB_2U_LIB.S9S_MB_2U(SCH_1):PAGE83

M_A_CPU0_SB_DQ<29> @S9S_MB_2U_LIB.S9S_MB_2U(SCH_1):M_A_CPU0_SB_DQ(29)
    U2   C7 DDR0_SB_DQ29 SOCKET4677_AZIF0045P001C01CS-SA     I1 @S9S_MB_2U_LIB.S9S_MB_2U(SCH_1):PAGE20
    J1  142 DQ29_B SCONN288_ADR50017P130CC-SCONN2A   I198 @S9S_MB_2U_LIB.S9S_MB_2U(SCH_1):PAGE82
    J2  142 DQ29_B SCONN288_ADR50017P087CC-SCONN2A   I177 @S9S_MB_2U_LIB.S9S_MB_2U(SCH_1):PAGE83

M_A_CPU0_SB_DQ<2> @S9S_MB_2U_LIB.S9S_MB_2U(SCH_1):M_A_CPU0_SB_DQ(2)
    U2  M32 DDR0_SB_DQ2 SOCKET4677_AZIF0045P001C01CS-SA     I1 @S9S_MB_2U_LIB.S9S_MB_2U(SCH_1):PAGE20
    J1  245  DQ2_B SCONN288_ADR50017P130CC-SCONN2A   I198 @S9S_MB_2U_LIB.S9S_MB_2U(SCH_1):PAGE82
    J2  245  DQ2_B SCONN288_ADR50017P087CC-SCONN2A   I177 @S9S_MB_2U_LIB.S9S_MB_2U(SCH_1):PAGE83

M_A_CPU0_SB_DQ<30> @S9S_MB_2U_LIB.S9S_MB_2U(SCH_1):M_A_CPU0_SB_DQ(30)
    U2   F8 DDR0_SB_DQ30 SOCKET4677_AZIF0045P001C01CS-SA     I1 @S9S_MB_2U_LIB.S9S_MB_2U(SCH_1):PAGE20
    J1  285 DQ30_B SCONN288_ADR50017P130CC-SCONN2A   I198 @S9S_MB_2U_LIB.S9S_MB_2U(SCH_1):PAGE82
    J2  285 DQ30_B SCONN288_ADR50017P087CC-SCONN2A   I177 @S9S_MB_2U_LIB.S9S_MB_2U(SCH_1):PAGE83

M_A_CPU0_SB_DQ<31> @S9S_MB_2U_LIB.S9S_MB_2U(SCH_1):M_A_CPU0_SB_DQ(31)
    U2   E7 DDR0_SB_DQ31 SOCKET4677_AZIF0045P001C01CS-SA     I1 @S9S_MB_2U_LIB.S9S_MB_2U(SCH_1):PAGE20
    J1  287 DQ31_B SCONN288_ADR50017P130CC-SCONN2A   I198 @S9S_MB_2U_LIB.S9S_MB_2U(SCH_1):PAGE82
    J2  287 DQ31_B SCONN288_ADR50017P087CC-SCONN2A   I177 @S9S_MB_2U_LIB.S9S_MB_2U(SCH_1):PAGE83

M_A_CPU0_SB_DQ<3> @S9S_MB_2U_LIB.S9S_MB_2U(SCH_1):M_A_CPU0_SB_DQ(3)
    U2  N31 DDR0_SB_DQ3 SOCKET4677_AZIF0045P001C01CS-SA     I1 @S9S_MB_2U_LIB.S9S_MB_2U(SCH_1):PAGE20
    J1  247  DQ3_B SCONN288_ADR50017P130CC-SCONN2A   I198 @S9S_MB_2U_LIB.S9S_MB_2U(SCH_1):PAGE82
    J2  247  DQ3_B SCONN288_ADR50017P087CC-SCONN2A   I177 @S9S_MB_2U_LIB.S9S_MB_2U(SCH_1):PAGE83

M_A_CPU0_SB_DQ<4> @S9S_MB_2U_LIB.S9S_MB_2U(SCH_1):M_A_CPU0_SB_DQ(4)
    U2  J29 DDR0_SB_DQ4 SOCKET4677_AZIF0045P001C01CS-SA     I1 @S9S_MB_2U_LIB.S9S_MB_2U(SCH_1):PAGE20
    J1  107  DQ4_B SCONN288_ADR50017P130CC-SCONN2A   I198 @S9S_MB_2U_LIB.S9S_MB_2U(SCH_1):PAGE82
    J2  107  DQ4_B SCONN288_ADR50017P087CC-SCONN2A   I177 @S9S_MB_2U_LIB.S9S_MB_2U(SCH_1):PAGE83

M_A_CPU0_SB_DQ<5> @S9S_MB_2U_LIB.S9S_MB_2U(SCH_1):M_A_CPU0_SB_DQ(5)
    U2  K28 DDR0_SB_DQ5 SOCKET4677_AZIF0045P001C01CS-SA     I1 @S9S_MB_2U_LIB.S9S_MB_2U(SCH_1):PAGE20
    J1  109  DQ5_B SCONN288_ADR50017P130CC-SCONN2A   I198 @S9S_MB_2U_LIB.S9S_MB_2U(SCH_1):PAGE82
    J2  109  DQ5_B SCONN288_ADR50017P087CC-SCONN2A   I177 @S9S_MB_2U_LIB.S9S_MB_2U(SCH_1):PAGE83

M_A_CPU0_SB_DQ<6> @S9S_MB_2U_LIB.S9S_MB_2U(SCH_1):M_A_CPU0_SB_DQ(6)
    U2  N29 DDR0_SB_DQ6 SOCKET4677_AZIF0045P001C01CS-SA     I1 @S9S_MB_2U_LIB.S9S_MB_2U(SCH_1):PAGE20
    J1  252  DQ6_B SCONN288_ADR50017P130CC-SCONN2A   I198 @S9S_MB_2U_LIB.S9S_MB_2U(SCH_1):PAGE82
    J2  252  DQ6_B SCONN288_ADR50017P087CC-SCONN2A   I177 @S9S_MB_2U_LIB.S9S_MB_2U(SCH_1):PAGE83

M_A_CPU0_SB_DQ<7> @S9S_MB_2U_LIB.S9S_MB_2U(SCH_1):M_A_CPU0_SB_DQ(7)
    U2  M28 DDR0_SB_DQ7 SOCKET4677_AZIF0045P001C01CS-SA     I1 @S9S_MB_2U_LIB.S9S_MB_2U(SCH_1):PAGE20
    J1  254  DQ7_B SCONN288_ADR50017P130CC-SCONN2A   I198 @S9S_MB_2U_LIB.S9S_MB_2U(SCH_1):PAGE82
    J2  254  DQ7_B SCONN288_ADR50017P087CC-SCONN2A   I177 @S9S_MB_2U_LIB.S9S_MB_2U(SCH_1):PAGE83

M_A_CPU0_SB_DQ<8> @S9S_MB_2U_LIB.S9S_MB_2U(SCH_1):M_A_CPU0_SB_DQ(8)
    U2  C29 DDR0_SB_DQ8 SOCKET4677_AZIF0045P001C01CS-SA     I1 @S9S_MB_2U_LIB.S9S_MB_2U(SCH_1):PAGE20
    J1  111  DQ8_B SCONN288_ADR50017P130CC-SCONN2A   I198 @S9S_MB_2U_LIB.S9S_MB_2U(SCH_1):PAGE82
    J2  111  DQ8_B SCONN288_ADR50017P087CC-SCONN2A   I177 @S9S_MB_2U_LIB.S9S_MB_2U(SCH_1):PAGE83

M_A_CPU0_SB_DQ<9> @S9S_MB_2U_LIB.S9S_MB_2U(SCH_1):M_A_CPU0_SB_DQ(9)
    U2  B28 DDR0_SB_DQ9 SOCKET4677_AZIF0045P001C01CS-SA     I1 @S9S_MB_2U_LIB.S9S_MB_2U(SCH_1):PAGE20
    J1  113  DQ9_B SCONN288_ADR50017P130CC-SCONN2A   I198 @S9S_MB_2U_LIB.S9S_MB_2U(SCH_1):PAGE82
    J2  113  DQ9_B SCONN288_ADR50017P087CC-SCONN2A   I177 @S9S_MB_2U_LIB.S9S_MB_2U(SCH_1):PAGE83

M_A_CPU0_SB_DQS_DN<0> @S9S_MB_2U_LIB.S9S_MB_2U(SCH_1):M_A_CPU0_SB_DQS_DN(0)
    U2  H30 DDR0_SB_DQS_DN0 SOCKET4677_AZIF0045P001C01CS-SA     I1 @S9S_MB_2U_LIB.S9S_MB_2U(SCH_1):PAGE20
    J1  105 DQS0_B_C SCONN288_ADR50017P130CC-SCONN2A   I202 @S9S_MB_2U_LIB.S9S_MB_2U(SCH_1):PAGE82
    J2  105 DQS0_B_C SCONN288_ADR50017P087CC-SCONN2A   I181 @S9S_MB_2U_LIB.S9S_MB_2U(SCH_1):PAGE83

M_A_CPU0_SB_DQS_DN<1> @S9S_MB_2U_LIB.S9S_MB_2U(SCH_1):M_A_CPU0_SB_DQS_DN(1)
    U2  A27 DDR0_SB_DQS_DN1 SOCKET4677_AZIF0045P001C01CS-SA     I1 @S9S_MB_2U_LIB.S9S_MB_2U(SCH_1):PAGE20
    J1  116 DQS1_B_C SCONN288_ADR50017P130CC-SCONN2A   I202 @S9S_MB_2U_LIB.S9S_MB_2U(SCH_1):PAGE82
    J2  116 DQS1_B_C SCONN288_ADR50017P087CC-SCONN2A   I181 @S9S_MB_2U_LIB.S9S_MB_2U(SCH_1):PAGE83

M_A_CPU0_SB_DQS_DN<2> @S9S_MB_2U_LIB.S9S_MB_2U(SCH_1):M_A_CPU0_SB_DQS_DN(2)
    U2  A21 DDR0_SB_DQS_DN2 SOCKET4677_AZIF0045P001C01CS-SA     I1 @S9S_MB_2U_LIB.S9S_MB_2U(SCH_1):PAGE20
    J1  127 DQS2_B_C SCONN288_ADR50017P130CC-SCONN2A   I202 @S9S_MB_2U_LIB.S9S_MB_2U(SCH_1):PAGE82
    J2  127 DQS2_B_C SCONN288_ADR50017P087CC-SCONN2A   I181 @S9S_MB_2U_LIB.S9S_MB_2U(SCH_1):PAGE83

M_A_CPU0_SB_DQS_DN<3> @S9S_MB_2U_LIB.S9S_MB_2U(SCH_1):M_A_CPU0_SB_DQS_DN(3)
    U2   A9 DDR0_SB_DQS_DN3 SOCKET4677_AZIF0045P001C01CS-SA     I1 @S9S_MB_2U_LIB.S9S_MB_2U(SCH_1):PAGE20
    J1  138 DQS3_B_C SCONN288_ADR50017P130CC-SCONN2A   I202 @S9S_MB_2U_LIB.S9S_MB_2U(SCH_1):PAGE82
    J2  138 DQS3_B_C SCONN288_ADR50017P087CC-SCONN2A   I181 @S9S_MB_2U_LIB.S9S_MB_2U(SCH_1):PAGE83

M_A_CPU0_SB_DQS_DN<4> @S9S_MB_2U_LIB.S9S_MB_2U(SCH_1):M_A_CPU0_SB_DQS_DN(4)
    U2  G33 DDR0_SB_DQS_DN4 SOCKET4677_AZIF0045P001C01CS-SA     I1 @S9S_MB_2U_LIB.S9S_MB_2U(SCH_1):PAGE20
    J1  238 DQS4_B_C SCONN288_ADR50017P130CC-SCONN2A   I202 @S9S_MB_2U_LIB.S9S_MB_2U(SCH_1):PAGE82
    J2  238 DQS4_B_C SCONN288_ADR50017P087CC-SCONN2A   I181 @S9S_MB_2U_LIB.S9S_MB_2U(SCH_1):PAGE83

M_A_CPU0_SB_DQS_DN<5> @S9S_MB_2U_LIB.S9S_MB_2U(SCH_1):M_A_CPU0_SB_DQS_DN(5)
    U2  M30 DDR0_SB_DQS_DN5 SOCKET4677_AZIF0045P001C01CS-SA     I1 @S9S_MB_2U_LIB.S9S_MB_2U(SCH_1):PAGE20
    J1  249 DQS5_B_C||TDQS5_B_C SCONN288_ADR50017P130CC-SCONN2A   I202 @S9S_MB_2U_LIB.S9S_MB_2U(SCH_1):PAGE82
    J2  249 DQS5_B_C||TDQS5_B_C SCONN288_ADR50017P087CC-SCONN2A   I181 @S9S_MB_2U_LIB.S9S_MB_2U(SCH_1):PAGE83

M_A_CPU0_SB_DQS_DN<6> @S9S_MB_2U_LIB.S9S_MB_2U(SCH_1):M_A_CPU0_SB_DQS_DN(6)
    U2  G27 DDR0_SB_DQS_DN6 SOCKET4677_AZIF0045P001C01CS-SA     I1 @S9S_MB_2U_LIB.S9S_MB_2U(SCH_1):PAGE20
    J1  260 DQS6_B_C||TDQS6_B_C SCONN288_ADR50017P130CC-SCONN2A   I202 @S9S_MB_2U_LIB.S9S_MB_2U(SCH_1):PAGE82
    J2  260 DQS6_B_C||TDQS6_B_C SCONN288_ADR50017P087CC-SCONN2A   I181 @S9S_MB_2U_LIB.S9S_MB_2U(SCH_1):PAGE83

M_A_CPU0_SB_DQS_DN<7> @S9S_MB_2U_LIB.S9S_MB_2U(SCH_1):M_A_CPU0_SB_DQS_DN(7)
    U2  G21 DDR0_SB_DQS_DN7 SOCKET4677_AZIF0045P001C01CS-SA     I1 @S9S_MB_2U_LIB.S9S_MB_2U(SCH_1):PAGE20
    J1  271 DQS7_B_C||TDQS7_B_C SCONN288_ADR50017P130CC-SCONN2A   I202 @S9S_MB_2U_LIB.S9S_MB_2U(SCH_1):PAGE82
    J2  271 DQS7_B_C||TDQS7_B_C SCONN288_ADR50017P087CC-SCONN2A   I181 @S9S_MB_2U_LIB.S9S_MB_2U(SCH_1):PAGE83

M_A_CPU0_SB_DQS_DN<8> @S9S_MB_2U_LIB.S9S_MB_2U(SCH_1):M_A_CPU0_SB_DQS_DN(8)
    U2   G9 DDR0_SB_DQS_DN8 SOCKET4677_AZIF0045P001C01CS-SA     I1 @S9S_MB_2U_LIB.S9S_MB_2U(SCH_1):PAGE20
    J1  282 DQS8_B_C||TDQS8_B_C SCONN288_ADR50017P130CC-SCONN2A   I202 @S9S_MB_2U_LIB.S9S_MB_2U(SCH_1):PAGE82
    J2  282 DQS8_B_C||TDQS8_B_C SCONN288_ADR50017P087CC-SCONN2A   I181 @S9S_MB_2U_LIB.S9S_MB_2U(SCH_1):PAGE83

M_A_CPU0_SB_DQS_DN<9> @S9S_MB_2U_LIB.S9S_MB_2U(SCH_1):M_A_CPU0_SB_DQS_DN(9)
    U2  A33 DDR0_SB_DQS_DN9 SOCKET4677_AZIF0045P001C01CS-SA     I1 @S9S_MB_2U_LIB.S9S_MB_2U(SCH_1):PAGE20
    J1   94 DQS9_B_C||TDQS9_B_C SCONN288_ADR50017P130CC-SCONN2A   I202 @S9S_MB_2U_LIB.S9S_MB_2U(SCH_1):PAGE82
    J2   94 DQS9_B_C||TDQS9_B_C SCONN288_ADR50017P087CC-SCONN2A   I181 @S9S_MB_2U_LIB.S9S_MB_2U(SCH_1):PAGE83

M_A_CPU0_SB_DQS_DP<0> @S9S_MB_2U_LIB.S9S_MB_2U(SCH_1):M_A_CPU0_SB_DQS_DP(0)
    U2  K30 DDR0_SB_DQS_DP0 SOCKET4677_AZIF0045P001C01CS-SA     I1 @S9S_MB_2U_LIB.S9S_MB_2U(SCH_1):PAGE20
    J1  104 DQS0_B_T SCONN288_ADR50017P130CC-SCONN2A   I202 @S9S_MB_2U_LIB.S9S_MB_2U(SCH_1):PAGE82
    J2  104 DQS0_B_T SCONN288_ADR50017P087CC-SCONN2A   I181 @S9S_MB_2U_LIB.S9S_MB_2U(SCH_1):PAGE83

M_A_CPU0_SB_DQS_DP<1> @S9S_MB_2U_LIB.S9S_MB_2U(SCH_1):M_A_CPU0_SB_DQS_DP(1)
    U2  C27 DDR0_SB_DQS_DP1 SOCKET4677_AZIF0045P001C01CS-SA     I1 @S9S_MB_2U_LIB.S9S_MB_2U(SCH_1):PAGE20
    J1  115 DQS1_B_T SCONN288_ADR50017P130CC-SCONN2A   I202 @S9S_MB_2U_LIB.S9S_MB_2U(SCH_1):PAGE82
    J2  115 DQS1_B_T SCONN288_ADR50017P087CC-SCONN2A   I181 @S9S_MB_2U_LIB.S9S_MB_2U(SCH_1):PAGE83

M_A_CPU0_SB_DQS_DP<2> @S9S_MB_2U_LIB.S9S_MB_2U(SCH_1):M_A_CPU0_SB_DQS_DP(2)
    U2  C21 DDR0_SB_DQS_DP2 SOCKET4677_AZIF0045P001C01CS-SA     I1 @S9S_MB_2U_LIB.S9S_MB_2U(SCH_1):PAGE20
    J1  126 DQS2_B_T SCONN288_ADR50017P130CC-SCONN2A   I202 @S9S_MB_2U_LIB.S9S_MB_2U(SCH_1):PAGE82
    J2  126 DQS2_B_T SCONN288_ADR50017P087CC-SCONN2A   I181 @S9S_MB_2U_LIB.S9S_MB_2U(SCH_1):PAGE83

M_A_CPU0_SB_DQS_DP<3> @S9S_MB_2U_LIB.S9S_MB_2U(SCH_1):M_A_CPU0_SB_DQS_DP(3)
    U2   C9 DDR0_SB_DQS_DP3 SOCKET4677_AZIF0045P001C01CS-SA     I1 @S9S_MB_2U_LIB.S9S_MB_2U(SCH_1):PAGE20
    J1  137 DQS3_B_T SCONN288_ADR50017P130CC-SCONN2A   I202 @S9S_MB_2U_LIB.S9S_MB_2U(SCH_1):PAGE82
    J2  137 DQS3_B_T SCONN288_ADR50017P087CC-SCONN2A   I181 @S9S_MB_2U_LIB.S9S_MB_2U(SCH_1):PAGE83

M_A_CPU0_SB_DQS_DP<4> @S9S_MB_2U_LIB.S9S_MB_2U(SCH_1):M_A_CPU0_SB_DQS_DP(4)
    U2  E33 DDR0_SB_DQS_DP4 SOCKET4677_AZIF0045P001C01CS-SA     I1 @S9S_MB_2U_LIB.S9S_MB_2U(SCH_1):PAGE20
    J1  239 DQS4_B_T SCONN288_ADR50017P130CC-SCONN2A   I202 @S9S_MB_2U_LIB.S9S_MB_2U(SCH_1):PAGE82
    J2  239 DQS4_B_T SCONN288_ADR50017P087CC-SCONN2A   I181 @S9S_MB_2U_LIB.S9S_MB_2U(SCH_1):PAGE83

M_A_CPU0_SB_DQS_DP<5> @S9S_MB_2U_LIB.S9S_MB_2U(SCH_1):M_A_CPU0_SB_DQS_DP(5)
    U2  P30 DDR0_SB_DQS_DP5 SOCKET4677_AZIF0045P001C01CS-SA     I1 @S9S_MB_2U_LIB.S9S_MB_2U(SCH_1):PAGE20
    J1  250 DQS5_B_T||TDQS5_B_T SCONN288_ADR50017P130CC-SCONN2A   I202 @S9S_MB_2U_LIB.S9S_MB_2U(SCH_1):PAGE82
    J2  250 DQS5_B_T||TDQS5_B_T SCONN288_ADR50017P087CC-SCONN2A   I181 @S9S_MB_2U_LIB.S9S_MB_2U(SCH_1):PAGE83

M_A_CPU0_SB_DQS_DP<6> @S9S_MB_2U_LIB.S9S_MB_2U(SCH_1):M_A_CPU0_SB_DQS_DP(6)
    U2  E27 DDR0_SB_DQS_DP6 SOCKET4677_AZIF0045P001C01CS-SA     I1 @S9S_MB_2U_LIB.S9S_MB_2U(SCH_1):PAGE20
    J1  261 DQS6_B_T||TDQS6_B_T SCONN288_ADR50017P130CC-SCONN2A   I202 @S9S_MB_2U_LIB.S9S_MB_2U(SCH_1):PAGE82
    J2  261 DQS6_B_T||TDQS6_B_T SCONN288_ADR50017P087CC-SCONN2A   I181 @S9S_MB_2U_LIB.S9S_MB_2U(SCH_1):PAGE83

M_A_CPU0_SB_DQS_DP<7> @S9S_MB_2U_LIB.S9S_MB_2U(SCH_1):M_A_CPU0_SB_DQS_DP(7)
    U2  E21 DDR0_SB_DQS_DP7 SOCKET4677_AZIF0045P001C01CS-SA     I1 @S9S_MB_2U_LIB.S9S_MB_2U(SCH_1):PAGE20
    J1  272 DQS7_B_T||TDQS7_B_T SCONN288_ADR50017P130CC-SCONN2A   I202 @S9S_MB_2U_LIB.S9S_MB_2U(SCH_1):PAGE82
    J2  272 DQS7_B_T||TDQS7_B_T SCONN288_ADR50017P087CC-SCONN2A   I181 @S9S_MB_2U_LIB.S9S_MB_2U(SCH_1):PAGE83

M_A_CPU0_SB_DQS_DP<8> @S9S_MB_2U_LIB.S9S_MB_2U(SCH_1):M_A_CPU0_SB_DQS_DP(8)
    U2   E9 DDR0_SB_DQS_DP8 SOCKET4677_AZIF0045P001C01CS-SA     I1 @S9S_MB_2U_LIB.S9S_MB_2U(SCH_1):PAGE20
    J1  283 DQS8_B_T||TDQS8_B_T SCONN288_ADR50017P130CC-SCONN2A   I202 @S9S_MB_2U_LIB.S9S_MB_2U(SCH_1):PAGE82
    J2  283 DQS8_B_T||TDQS8_B_T SCONN288_ADR50017P087CC-SCONN2A   I181 @S9S_MB_2U_LIB.S9S_MB_2U(SCH_1):PAGE83

M_A_CPU0_SB_DQS_DP<9> @S9S_MB_2U_LIB.S9S_MB_2U(SCH_1):M_A_CPU0_SB_DQS_DP(9)
    U2  C33 DDR0_SB_DQS_DP9 SOCKET4677_AZIF0045P001C01CS-SA     I1 @S9S_MB_2U_LIB.S9S_MB_2U(SCH_1):PAGE20
    J1   93 DQS9_B_T||TDQS9_B_T||DBI4_B_N SCONN288_ADR50017P130CC-SCONN2A   I202 @S9S_MB_2U_LIB.S9S_MB_2U(SCH_1):PAGE82
    J2   93 DQS9_B_T||TDQS9_B_T||DBI4_B_N SCONN288_ADR50017P087CC-SCONN2A   I181 @S9S_MB_2U_LIB.S9S_MB_2U(SCH_1):PAGE83

M_A_CPU0_SB_PAR @S9S_MB_2U_LIB.S9S_MB_2U(SCH_1):M_A_CPU0_SB_PAR
    U2  G39 DDR0_SB_PAR SOCKET4677_AZIF0045P001C01CS-SA     I1 @S9S_MB_2U_LIB.S9S_MB_2U(SCH_1):PAGE20
    J1  227  PAR_B SCONN288_ADR50017P130CC-SCONN2A   I198 @S9S_MB_2U_LIB.S9S_MB_2U(SCH_1):PAGE82
    J2  227  PAR_B SCONN288_ADR50017P087CC-SCONN2A   I177 @S9S_MB_2U_LIB.S9S_MB_2U(SCH_1):PAGE83

M_A_CPU0_SB_RSP<0> @S9S_MB_2U_LIB.S9S_MB_2U(SCH_1):M_A_CPU0_SB_RSP(0)
    U2 AV44 DDR0_B_RSP0 SOCKET4677_AZIF0045P001C01CS-SA     I1 @S9S_MB_2U_LIB.S9S_MB_2U(SCH_1):PAGE20
    J1   87 LBS||RSP_B_N SCONN288_ADR50017P130CC-SCONN2A   I198 @S9S_MB_2U_LIB.S9S_MB_2U(SCH_1):PAGE82

M_A_CPU0_SB_RSP<1> @S9S_MB_2U_LIB.S9S_MB_2U(SCH_1):M_A_CPU0_SB_RSP(1)
    U2 AV42 DDR0_B_RSP1 SOCKET4677_AZIF0045P001C01CS-SA     I1 @S9S_MB_2U_LIB.S9S_MB_2U(SCH_1):PAGE20
    J2   87 LBS||RSP_B_N SCONN288_ADR50017P087CC-SCONN2A   I177 @S9S_MB_2U_LIB.S9S_MB_2U(SCH_1):PAGE83

M_A_CPU1_ALERT_N @S9S_MB_2U_LIB.S9S_MB_2U(SCH_1):M_A_CPU1_ALERT_N
    U1 AT49 DDR0_ALERT_N SOCKET4677_AZIF0045P001C01CS-SA     I2 @S9S_MB_2U_LIB.S9S_MB_2U(SCH_1):PAGE51
   J17   62 ALERT_N SCONN288_ADR50017P130CC-SCONN2A    I12 @S9S_MB_2U_LIB.S9S_MB_2U(SCH_1):PAGE98
   J18   62 ALERT_N SCONN288_ADR50017P087CC-SCONN2A    I24 @S9S_MB_2U_LIB.S9S_MB_2U(SCH_1):PAGE99

M_A_CPU1_CLK_DN<0> @S9S_MB_2U_LIB.S9S_MB_2U(SCH_1):M_A_CPU1_CLK_DN(0)
    U1  B44 DDR0_CLK_DN0 SOCKET4677_AZIF0045P001C01CS-SA     I2 @S9S_MB_2U_LIB.S9S_MB_2U(SCH_1):PAGE51
   J17  218   CK_C SCONN288_ADR50017P130CC-SCONN2A    I12 @S9S_MB_2U_LIB.S9S_MB_2U(SCH_1):PAGE98

M_A_CPU1_CLK_DN<1> @S9S_MB_2U_LIB.S9S_MB_2U(SCH_1):M_A_CPU1_CLK_DN(1)
    U1  G45 DDR0_CLK_DN1 SOCKET4677_AZIF0045P001C01CS-SA     I2 @S9S_MB_2U_LIB.S9S_MB_2U(SCH_1):PAGE51
   J18  218   CK_C SCONN288_ADR50017P087CC-SCONN2A    I24 @S9S_MB_2U_LIB.S9S_MB_2U(SCH_1):PAGE99

M_A_CPU1_CLK_DP<0> @S9S_MB_2U_LIB.S9S_MB_2U(SCH_1):M_A_CPU1_CLK_DP(0)
    U1  C43 DDR0_CLK_DP0 SOCKET4677_AZIF0045P001C01CS-SA     I2 @S9S_MB_2U_LIB.S9S_MB_2U(SCH_1):PAGE51
   J17  217   CK_T SCONN288_ADR50017P130CC-SCONN2A    I12 @S9S_MB_2U_LIB.S9S_MB_2U(SCH_1):PAGE98

M_A_CPU1_CLK_DP<1> @S9S_MB_2U_LIB.S9S_MB_2U(SCH_1):M_A_CPU1_CLK_DP(1)
    U1  E45 DDR0_CLK_DP1 SOCKET4677_AZIF0045P001C01CS-SA     I2 @S9S_MB_2U_LIB.S9S_MB_2U(SCH_1):PAGE51
   J18  217   CK_T SCONN288_ADR50017P087CC-SCONN2A    I24 @S9S_MB_2U_LIB.S9S_MB_2U(SCH_1):PAGE99

M_A_CPU1_SA_CA<0> @S9S_MB_2U_LIB.S9S_MB_2U(SCH_1):M_A_CPU1_SA_CA(0)
    U1  A52 DDR0_SA_CA0 SOCKET4677_AZIF0045P001C01CS-SA     I2 @S9S_MB_2U_LIB.S9S_MB_2U(SCH_1):PAGE51
   J17   66  CA0_A SCONN288_ADR50017P130CC-SCONN2A    I12 @S9S_MB_2U_LIB.S9S_MB_2U(SCH_1):PAGE98
   J18   66  CA0_A SCONN288_ADR50017P087CC-SCONN2A    I24 @S9S_MB_2U_LIB.S9S_MB_2U(SCH_1):PAGE99

M_A_CPU1_SA_CA<1> @S9S_MB_2U_LIB.S9S_MB_2U(SCH_1):M_A_CPU1_SA_CA(1)
    U1  G52 DDR0_SA_CA1 SOCKET4677_AZIF0045P001C01CS-SA     I2 @S9S_MB_2U_LIB.S9S_MB_2U(SCH_1):PAGE51
   J17  211  CA1_A SCONN288_ADR50017P130CC-SCONN2A    I12 @S9S_MB_2U_LIB.S9S_MB_2U(SCH_1):PAGE98
   J18  211  CA1_A SCONN288_ADR50017P087CC-SCONN2A    I24 @S9S_MB_2U_LIB.S9S_MB_2U(SCH_1):PAGE99

M_A_CPU1_SA_CA<2> @S9S_MB_2U_LIB.S9S_MB_2U(SCH_1):M_A_CPU1_SA_CA(2)
    U1  B51 DDR0_SA_CA2 SOCKET4677_AZIF0045P001C01CS-SA     I2 @S9S_MB_2U_LIB.S9S_MB_2U(SCH_1):PAGE51
   J17   68  CA2_A SCONN288_ADR50017P130CC-SCONN2A    I12 @S9S_MB_2U_LIB.S9S_MB_2U(SCH_1):PAGE98
   J18   68  CA2_A SCONN288_ADR50017P087CC-SCONN2A    I24 @S9S_MB_2U_LIB.S9S_MB_2U(SCH_1):PAGE99

M_A_CPU1_SA_CA<3> @S9S_MB_2U_LIB.S9S_MB_2U(SCH_1):M_A_CPU1_SA_CA(3)
    U1  F51 DDR0_SA_CA3 SOCKET4677_AZIF0045P001C01CS-SA     I2 @S9S_MB_2U_LIB.S9S_MB_2U(SCH_1):PAGE51
   J17  213  CA3_A SCONN288_ADR50017P130CC-SCONN2A    I12 @S9S_MB_2U_LIB.S9S_MB_2U(SCH_1):PAGE98
   J18  213  CA3_A SCONN288_ADR50017P087CC-SCONN2A    I24 @S9S_MB_2U_LIB.S9S_MB_2U(SCH_1):PAGE99

M_A_CPU1_SA_CA<4> @S9S_MB_2U_LIB.S9S_MB_2U(SCH_1):M_A_CPU1_SA_CA(4)
    U1  C50 DDR0_SA_CA4 SOCKET4677_AZIF0045P001C01CS-SA     I2 @S9S_MB_2U_LIB.S9S_MB_2U(SCH_1):PAGE51
   J17   70  CA4_A SCONN288_ADR50017P130CC-SCONN2A    I12 @S9S_MB_2U_LIB.S9S_MB_2U(SCH_1):PAGE98
   J18   70  CA4_A SCONN288_ADR50017P087CC-SCONN2A    I24 @S9S_MB_2U_LIB.S9S_MB_2U(SCH_1):PAGE99

M_A_CPU1_SA_CA<5> @S9S_MB_2U_LIB.S9S_MB_2U(SCH_1):M_A_CPU1_SA_CA(5)
    U1  E50 DDR0_SA_CA5 SOCKET4677_AZIF0045P001C01CS-SA     I2 @S9S_MB_2U_LIB.S9S_MB_2U(SCH_1):PAGE51
   J17  215  CA5_A SCONN288_ADR50017P130CC-SCONN2A    I12 @S9S_MB_2U_LIB.S9S_MB_2U(SCH_1):PAGE98
   J18  215  CA5_A SCONN288_ADR50017P087CC-SCONN2A    I24 @S9S_MB_2U_LIB.S9S_MB_2U(SCH_1):PAGE99

M_A_CPU1_SA_CA<6> @S9S_MB_2U_LIB.S9S_MB_2U(SCH_1):M_A_CPU1_SA_CA(6)
    U1  C48 DDR0_SA_CA6 SOCKET4677_AZIF0045P001C01CS-SA     I2 @S9S_MB_2U_LIB.S9S_MB_2U(SCH_1):PAGE51
   J17   72  CA6_A SCONN288_ADR50017P130CC-SCONN2A    I12 @S9S_MB_2U_LIB.S9S_MB_2U(SCH_1):PAGE98
   J18   72  CA6_A SCONN288_ADR50017P087CC-SCONN2A    I24 @S9S_MB_2U_LIB.S9S_MB_2U(SCH_1):PAGE99

M_A_CPU1_SA_CB<0> @S9S_MB_2U_LIB.S9S_MB_2U(SCH_1):M_A_CPU1_SA_CB(0)
    U1  C60 DDR0_SA_ECC0 SOCKET4677_AZIF0045P001C01CS-SA     I2 @S9S_MB_2U_LIB.S9S_MB_2U(SCH_1):PAGE51
   J17   51  CB0_A SCONN288_ADR50017P130CC-SCONN2A    I12 @S9S_MB_2U_LIB.S9S_MB_2U(SCH_1):PAGE98
   J18   51  CB0_A SCONN288_ADR50017P087CC-SCONN2A    I24 @S9S_MB_2U_LIB.S9S_MB_2U(SCH_1):PAGE99

M_A_CPU1_SA_CB<1> @S9S_MB_2U_LIB.S9S_MB_2U(SCH_1):M_A_CPU1_SA_CB(1)
    U1  B59 DDR0_SA_ECC1 SOCKET4677_AZIF0045P001C01CS-SA     I2 @S9S_MB_2U_LIB.S9S_MB_2U(SCH_1):PAGE51
   J17   53  CB1_A SCONN288_ADR50017P130CC-SCONN2A    I12 @S9S_MB_2U_LIB.S9S_MB_2U(SCH_1):PAGE98
   J18   53  CB1_A SCONN288_ADR50017P087CC-SCONN2A    I24 @S9S_MB_2U_LIB.S9S_MB_2U(SCH_1):PAGE99

M_A_CPU1_SA_CB<2> @S9S_MB_2U_LIB.S9S_MB_2U(SCH_1):M_A_CPU1_SA_CB(2)
    U1  E60 DDR0_SA_ECC2 SOCKET4677_AZIF0045P001C01CS-SA     I2 @S9S_MB_2U_LIB.S9S_MB_2U(SCH_1):PAGE51
   J17  196  CB2_A SCONN288_ADR50017P130CC-SCONN2A    I12 @S9S_MB_2U_LIB.S9S_MB_2U(SCH_1):PAGE98
   J18  196  CB2_A SCONN288_ADR50017P087CC-SCONN2A    I24 @S9S_MB_2U_LIB.S9S_MB_2U(SCH_1):PAGE99

M_A_CPU1_SA_CB<3> @S9S_MB_2U_LIB.S9S_MB_2U(SCH_1):M_A_CPU1_SA_CB(3)
    U1  F59 DDR0_SA_ECC3 SOCKET4677_AZIF0045P001C01CS-SA     I2 @S9S_MB_2U_LIB.S9S_MB_2U(SCH_1):PAGE51
   J17  198  CB3_A SCONN288_ADR50017P130CC-SCONN2A    I12 @S9S_MB_2U_LIB.S9S_MB_2U(SCH_1):PAGE98
   J18  198  CB3_A SCONN288_ADR50017P087CC-SCONN2A    I24 @S9S_MB_2U_LIB.S9S_MB_2U(SCH_1):PAGE99

M_A_CPU1_SA_CB<4> @S9S_MB_2U_LIB.S9S_MB_2U(SCH_1):M_A_CPU1_SA_CB(4)
    U1  B57 DDR0_SA_ECC4 SOCKET4677_AZIF0045P001C01CS-SA     I2 @S9S_MB_2U_LIB.S9S_MB_2U(SCH_1):PAGE51
   J17   58  CB4_A SCONN288_ADR50017P130CC-SCONN2A    I12 @S9S_MB_2U_LIB.S9S_MB_2U(SCH_1):PAGE98
   J18   58  CB4_A SCONN288_ADR50017P087CC-SCONN2A    I24 @S9S_MB_2U_LIB.S9S_MB_2U(SCH_1):PAGE99

M_A_CPU1_SA_CB<5> @S9S_MB_2U_LIB.S9S_MB_2U(SCH_1):M_A_CPU1_SA_CB(5)
    U1  C56 DDR0_SA_ECC5 SOCKET4677_AZIF0045P001C01CS-SA     I2 @S9S_MB_2U_LIB.S9S_MB_2U(SCH_1):PAGE51
   J17   60  CB5_A SCONN288_ADR50017P130CC-SCONN2A    I12 @S9S_MB_2U_LIB.S9S_MB_2U(SCH_1):PAGE98
   J18   60  CB5_A SCONN288_ADR50017P087CC-SCONN2A    I24 @S9S_MB_2U_LIB.S9S_MB_2U(SCH_1):PAGE99

M_A_CPU1_SA_CB<6> @S9S_MB_2U_LIB.S9S_MB_2U(SCH_1):M_A_CPU1_SA_CB(6)
    U1  F57 DDR0_SA_ECC6 SOCKET4677_AZIF0045P001C01CS-SA     I2 @S9S_MB_2U_LIB.S9S_MB_2U(SCH_1):PAGE51
   J17  203  CB6_A SCONN288_ADR50017P130CC-SCONN2A    I12 @S9S_MB_2U_LIB.S9S_MB_2U(SCH_1):PAGE98
   J18  203  CB6_A SCONN288_ADR50017P087CC-SCONN2A    I24 @S9S_MB_2U_LIB.S9S_MB_2U(SCH_1):PAGE99

M_A_CPU1_SA_CB<7> @S9S_MB_2U_LIB.S9S_MB_2U(SCH_1):M_A_CPU1_SA_CB(7)
    U1  E56 DDR0_SA_ECC7 SOCKET4677_AZIF0045P001C01CS-SA     I2 @S9S_MB_2U_LIB.S9S_MB_2U(SCH_1):PAGE51
   J17  205  CB7_A SCONN288_ADR50017P130CC-SCONN2A    I12 @S9S_MB_2U_LIB.S9S_MB_2U(SCH_1):PAGE98
   J18  205  CB7_A SCONN288_ADR50017P087CC-SCONN2A    I24 @S9S_MB_2U_LIB.S9S_MB_2U(SCH_1):PAGE99

M_A_CPU1_SA_CS_N<0> @S9S_MB_2U_LIB.S9S_MB_2U(SCH_1):M_A_CPU1_SA_CS_N(0)
    U1  C54 DDR0_SA_CS_N0 SOCKET4677_AZIF0045P001C01CS-SA     I2 @S9S_MB_2U_LIB.S9S_MB_2U(SCH_1):PAGE51
   J17   64 CS0_A_N SCONN288_ADR50017P130CC-SCONN2A    I12 @S9S_MB_2U_LIB.S9S_MB_2U(SCH_1):PAGE98

M_A_CPU1_SA_CS_N<1> @S9S_MB_2U_LIB.S9S_MB_2U(SCH_1):M_A_CPU1_SA_CS_N(1)
    U1  B53 DDR0_SA_CS_N1 SOCKET4677_AZIF0045P001C01CS-SA     I2 @S9S_MB_2U_LIB.S9S_MB_2U(SCH_1):PAGE51
   J17  209 CS1_A_N SCONN288_ADR50017P130CC-SCONN2A    I12 @S9S_MB_2U_LIB.S9S_MB_2U(SCH_1):PAGE98

M_A_CPU1_SA_CS_N<2> @S9S_MB_2U_LIB.S9S_MB_2U(SCH_1):M_A_CPU1_SA_CS_N(2)
    U1  E54 DDR0_SA_CS_N2 SOCKET4677_AZIF0045P001C01CS-SA     I2 @S9S_MB_2U_LIB.S9S_MB_2U(SCH_1):PAGE51
   J18   64 CS0_A_N SCONN288_ADR50017P087CC-SCONN2A    I24 @S9S_MB_2U_LIB.S9S_MB_2U(SCH_1):PAGE99

M_A_CPU1_SA_CS_N<3> @S9S_MB_2U_LIB.S9S_MB_2U(SCH_1):M_A_CPU1_SA_CS_N(3)
    U1  F53 DDR0_SA_CS_N3 SOCKET4677_AZIF0045P001C01CS-SA     I2 @S9S_MB_2U_LIB.S9S_MB_2U(SCH_1):PAGE51
   J18  209 CS1_A_N SCONN288_ADR50017P087CC-SCONN2A    I24 @S9S_MB_2U_LIB.S9S_MB_2U(SCH_1):PAGE99

M_A_CPU1_SA_DQ<0> @S9S_MB_2U_LIB.S9S_MB_2U(SCH_1):M_A_CPU1_SA_DQ(0)
    U1  B81 DDR0_SA_DQ0 SOCKET4677_AZIF0045P001C01CS-SA     I2 @S9S_MB_2U_LIB.S9S_MB_2U(SCH_1):PAGE51
   J17    7  DQ0_A SCONN288_ADR50017P130CC-SCONN2A    I12 @S9S_MB_2U_LIB.S9S_MB_2U(SCH_1):PAGE98
   J18    7  DQ0_A SCONN288_ADR50017P087CC-SCONN2A    I24 @S9S_MB_2U_LIB.S9S_MB_2U(SCH_1):PAGE99

M_A_CPU1_SA_DQ<10> @S9S_MB_2U_LIB.S9S_MB_2U(SCH_1):M_A_CPU1_SA_DQ(10)
    U1  M69 DDR0_SA_DQ10 SOCKET4677_AZIF0045P001C01CS-SA     I2 @S9S_MB_2U_LIB.S9S_MB_2U(SCH_1):PAGE51
   J17  163 DQ10_A SCONN288_ADR50017P130CC-SCONN2A    I12 @S9S_MB_2U_LIB.S9S_MB_2U(SCH_1):PAGE98
   J18  163 DQ10_A SCONN288_ADR50017P087CC-SCONN2A    I24 @S9S_MB_2U_LIB.S9S_MB_2U(SCH_1):PAGE99

M_A_CPU1_SA_DQ<11> @S9S_MB_2U_LIB.S9S_MB_2U(SCH_1):M_A_CPU1_SA_DQ(11)
    U1  N68 DDR0_SA_DQ11 SOCKET4677_AZIF0045P001C01CS-SA     I2 @S9S_MB_2U_LIB.S9S_MB_2U(SCH_1):PAGE51
   J17  165 DQ11_A SCONN288_ADR50017P130CC-SCONN2A    I12 @S9S_MB_2U_LIB.S9S_MB_2U(SCH_1):PAGE98
   J18  165 DQ11_A SCONN288_ADR50017P087CC-SCONN2A    I24 @S9S_MB_2U_LIB.S9S_MB_2U(SCH_1):PAGE99

M_A_CPU1_SA_DQ<12> @S9S_MB_2U_LIB.S9S_MB_2U(SCH_1):M_A_CPU1_SA_DQ(12)
    U1  J66 DDR0_SA_DQ12 SOCKET4677_AZIF0045P001C01CS-SA     I2 @S9S_MB_2U_LIB.S9S_MB_2U(SCH_1):PAGE51
   J17   25 DQ12_A SCONN288_ADR50017P130CC-SCONN2A    I12 @S9S_MB_2U_LIB.S9S_MB_2U(SCH_1):PAGE98
   J18   25 DQ12_A SCONN288_ADR50017P087CC-SCONN2A    I24 @S9S_MB_2U_LIB.S9S_MB_2U(SCH_1):PAGE99

M_A_CPU1_SA_DQ<13> @S9S_MB_2U_LIB.S9S_MB_2U(SCH_1):M_A_CPU1_SA_DQ(13)
    U1  K65 DDR0_SA_DQ13 SOCKET4677_AZIF0045P001C01CS-SA     I2 @S9S_MB_2U_LIB.S9S_MB_2U(SCH_1):PAGE51
   J17   27 DQ13_A SCONN288_ADR50017P130CC-SCONN2A    I12 @S9S_MB_2U_LIB.S9S_MB_2U(SCH_1):PAGE98
   J18   27 DQ13_A SCONN288_ADR50017P087CC-SCONN2A    I24 @S9S_MB_2U_LIB.S9S_MB_2U(SCH_1):PAGE99

M_A_CPU1_SA_DQ<14> @S9S_MB_2U_LIB.S9S_MB_2U(SCH_1):M_A_CPU1_SA_DQ(14)
    U1  N66 DDR0_SA_DQ14 SOCKET4677_AZIF0045P001C01CS-SA     I2 @S9S_MB_2U_LIB.S9S_MB_2U(SCH_1):PAGE51
   J17  170 DQ14_A SCONN288_ADR50017P130CC-SCONN2A    I12 @S9S_MB_2U_LIB.S9S_MB_2U(SCH_1):PAGE98
   J18  170 DQ14_A SCONN288_ADR50017P087CC-SCONN2A    I24 @S9S_MB_2U_LIB.S9S_MB_2U(SCH_1):PAGE99

M_A_CPU1_SA_DQ<15> @S9S_MB_2U_LIB.S9S_MB_2U(SCH_1):M_A_CPU1_SA_DQ(15)
    U1  M65 DDR0_SA_DQ15 SOCKET4677_AZIF0045P001C01CS-SA     I2 @S9S_MB_2U_LIB.S9S_MB_2U(SCH_1):PAGE51
   J17  172 DQ15_A SCONN288_ADR50017P130CC-SCONN2A    I12 @S9S_MB_2U_LIB.S9S_MB_2U(SCH_1):PAGE98
   J18  172 DQ15_A SCONN288_ADR50017P087CC-SCONN2A    I24 @S9S_MB_2U_LIB.S9S_MB_2U(SCH_1):PAGE99

M_A_CPU1_SA_DQ<16> @S9S_MB_2U_LIB.S9S_MB_2U(SCH_1):M_A_CPU1_SA_DQ(16)
    U1  B73 DDR0_SA_DQ16 SOCKET4677_AZIF0045P001C01CS-SA     I2 @S9S_MB_2U_LIB.S9S_MB_2U(SCH_1):PAGE51
   J17   29 DQ16_A SCONN288_ADR50017P130CC-SCONN2A    I12 @S9S_MB_2U_LIB.S9S_MB_2U(SCH_1):PAGE98
   J18   29 DQ16_A SCONN288_ADR50017P087CC-SCONN2A    I24 @S9S_MB_2U_LIB.S9S_MB_2U(SCH_1):PAGE99

M_A_CPU1_SA_DQ<17> @S9S_MB_2U_LIB.S9S_MB_2U(SCH_1):M_A_CPU1_SA_DQ(17)
    U1  E72 DDR0_SA_DQ17 SOCKET4677_AZIF0045P001C01CS-SA     I2 @S9S_MB_2U_LIB.S9S_MB_2U(SCH_1):PAGE51
   J17   31 DQ17_A SCONN288_ADR50017P130CC-SCONN2A    I12 @S9S_MB_2U_LIB.S9S_MB_2U(SCH_1):PAGE98
   J18   31 DQ17_A SCONN288_ADR50017P087CC-SCONN2A    I24 @S9S_MB_2U_LIB.S9S_MB_2U(SCH_1):PAGE99

M_A_CPU1_SA_DQ<18> @S9S_MB_2U_LIB.S9S_MB_2U(SCH_1):M_A_CPU1_SA_DQ(18)
    U1  D73 DDR0_SA_DQ18 SOCKET4677_AZIF0045P001C01CS-SA     I2 @S9S_MB_2U_LIB.S9S_MB_2U(SCH_1):PAGE51
   J17  174 DQ18_A SCONN288_ADR50017P130CC-SCONN2A    I12 @S9S_MB_2U_LIB.S9S_MB_2U(SCH_1):PAGE98
   J18  174 DQ18_A SCONN288_ADR50017P087CC-SCONN2A    I24 @S9S_MB_2U_LIB.S9S_MB_2U(SCH_1):PAGE99

M_A_CPU1_SA_DQ<19> @S9S_MB_2U_LIB.S9S_MB_2U(SCH_1):M_A_CPU1_SA_DQ(19)
    U1  F71 DDR0_SA_DQ19 SOCKET4677_AZIF0045P001C01CS-SA     I2 @S9S_MB_2U_LIB.S9S_MB_2U(SCH_1):PAGE51
   J17  176 DQ19_A SCONN288_ADR50017P130CC-SCONN2A    I12 @S9S_MB_2U_LIB.S9S_MB_2U(SCH_1):PAGE98
   J18  176 DQ19_A SCONN288_ADR50017P087CC-SCONN2A    I24 @S9S_MB_2U_LIB.S9S_MB_2U(SCH_1):PAGE99

M_A_CPU1_SA_DQ<1> @S9S_MB_2U_LIB.S9S_MB_2U(SCH_1):M_A_CPU1_SA_DQ(1)
    U1  B79 DDR0_SA_DQ1 SOCKET4677_AZIF0045P001C01CS-SA     I2 @S9S_MB_2U_LIB.S9S_MB_2U(SCH_1):PAGE51
   J17    9  DQ1_A SCONN288_ADR50017P130CC-SCONN2A    I12 @S9S_MB_2U_LIB.S9S_MB_2U(SCH_1):PAGE98
   J18    9  DQ1_A SCONN288_ADR50017P087CC-SCONN2A    I24 @S9S_MB_2U_LIB.S9S_MB_2U(SCH_1):PAGE99

M_A_CPU1_SA_DQ<20> @S9S_MB_2U_LIB.S9S_MB_2U(SCH_1):M_A_CPU1_SA_DQ(20)
    U1  B69 DDR0_SA_DQ20 SOCKET4677_AZIF0045P001C01CS-SA     I2 @S9S_MB_2U_LIB.S9S_MB_2U(SCH_1):PAGE51
   J17   36 DQ20_A SCONN288_ADR50017P130CC-SCONN2A    I12 @S9S_MB_2U_LIB.S9S_MB_2U(SCH_1):PAGE98
   J18   36 DQ20_A SCONN288_ADR50017P087CC-SCONN2A    I24 @S9S_MB_2U_LIB.S9S_MB_2U(SCH_1):PAGE99

M_A_CPU1_SA_DQ<21> @S9S_MB_2U_LIB.S9S_MB_2U(SCH_1):M_A_CPU1_SA_DQ(21)
    U1  C68 DDR0_SA_DQ21 SOCKET4677_AZIF0045P001C01CS-SA     I2 @S9S_MB_2U_LIB.S9S_MB_2U(SCH_1):PAGE51
   J17   38 DQ21_A SCONN288_ADR50017P130CC-SCONN2A    I12 @S9S_MB_2U_LIB.S9S_MB_2U(SCH_1):PAGE98
   J18   38 DQ21_A SCONN288_ADR50017P087CC-SCONN2A    I24 @S9S_MB_2U_LIB.S9S_MB_2U(SCH_1):PAGE99

M_A_CPU1_SA_DQ<22> @S9S_MB_2U_LIB.S9S_MB_2U(SCH_1):M_A_CPU1_SA_DQ(22)
    U1  F69 DDR0_SA_DQ22 SOCKET4677_AZIF0045P001C01CS-SA     I2 @S9S_MB_2U_LIB.S9S_MB_2U(SCH_1):PAGE51
   J17  181 DQ22_A SCONN288_ADR50017P130CC-SCONN2A    I12 @S9S_MB_2U_LIB.S9S_MB_2U(SCH_1):PAGE98
   J18  181 DQ22_A SCONN288_ADR50017P087CC-SCONN2A    I24 @S9S_MB_2U_LIB.S9S_MB_2U(SCH_1):PAGE99

M_A_CPU1_SA_DQ<23> @S9S_MB_2U_LIB.S9S_MB_2U(SCH_1):M_A_CPU1_SA_DQ(23)
    U1  E68 DDR0_SA_DQ23 SOCKET4677_AZIF0045P001C01CS-SA     I2 @S9S_MB_2U_LIB.S9S_MB_2U(SCH_1):PAGE51
   J17  183 DQ23_A SCONN288_ADR50017P130CC-SCONN2A    I12 @S9S_MB_2U_LIB.S9S_MB_2U(SCH_1):PAGE98
   J18  183 DQ23_A SCONN288_ADR50017P087CC-SCONN2A    I24 @S9S_MB_2U_LIB.S9S_MB_2U(SCH_1):PAGE99

M_A_CPU1_SA_DQ<24> @S9S_MB_2U_LIB.S9S_MB_2U(SCH_1):M_A_CPU1_SA_DQ(24)
    U1  C66 DDR0_SA_DQ24 SOCKET4677_AZIF0045P001C01CS-SA     I2 @S9S_MB_2U_LIB.S9S_MB_2U(SCH_1):PAGE51
   J17   40 DQ24_A SCONN288_ADR50017P130CC-SCONN2A    I12 @S9S_MB_2U_LIB.S9S_MB_2U(SCH_1):PAGE98
   J18   40 DQ24_A SCONN288_ADR50017P087CC-SCONN2A    I24 @S9S_MB_2U_LIB.S9S_MB_2U(SCH_1):PAGE99

M_A_CPU1_SA_DQ<25> @S9S_MB_2U_LIB.S9S_MB_2U(SCH_1):M_A_CPU1_SA_DQ(25)
    U1  B65 DDR0_SA_DQ25 SOCKET4677_AZIF0045P001C01CS-SA     I2 @S9S_MB_2U_LIB.S9S_MB_2U(SCH_1):PAGE51
   J17   42 DQ25_A SCONN288_ADR50017P130CC-SCONN2A    I12 @S9S_MB_2U_LIB.S9S_MB_2U(SCH_1):PAGE98
   J18   42 DQ25_A SCONN288_ADR50017P087CC-SCONN2A    I24 @S9S_MB_2U_LIB.S9S_MB_2U(SCH_1):PAGE99

M_A_CPU1_SA_DQ<26> @S9S_MB_2U_LIB.S9S_MB_2U(SCH_1):M_A_CPU1_SA_DQ(26)
    U1  E66 DDR0_SA_DQ26 SOCKET4677_AZIF0045P001C01CS-SA     I2 @S9S_MB_2U_LIB.S9S_MB_2U(SCH_1):PAGE51
   J17  185 DQ26_A SCONN288_ADR50017P130CC-SCONN2A    I12 @S9S_MB_2U_LIB.S9S_MB_2U(SCH_1):PAGE98
   J18  185 DQ26_A SCONN288_ADR50017P087CC-SCONN2A    I24 @S9S_MB_2U_LIB.S9S_MB_2U(SCH_1):PAGE99

M_A_CPU1_SA_DQ<27> @S9S_MB_2U_LIB.S9S_MB_2U(SCH_1):M_A_CPU1_SA_DQ(27)
    U1  F65 DDR0_SA_DQ27 SOCKET4677_AZIF0045P001C01CS-SA     I2 @S9S_MB_2U_LIB.S9S_MB_2U(SCH_1):PAGE51
   J17  187 DQ27_A SCONN288_ADR50017P130CC-SCONN2A    I12 @S9S_MB_2U_LIB.S9S_MB_2U(SCH_1):PAGE98
   J18  187 DQ27_A SCONN288_ADR50017P087CC-SCONN2A    I24 @S9S_MB_2U_LIB.S9S_MB_2U(SCH_1):PAGE99

M_A_CPU1_SA_DQ<28> @S9S_MB_2U_LIB.S9S_MB_2U(SCH_1):M_A_CPU1_SA_DQ(28)
    U1  B63 DDR0_SA_DQ28 SOCKET4677_AZIF0045P001C01CS-SA     I2 @S9S_MB_2U_LIB.S9S_MB_2U(SCH_1):PAGE51
   J17   47 DQ28_A SCONN288_ADR50017P130CC-SCONN2A    I12 @S9S_MB_2U_LIB.S9S_MB_2U(SCH_1):PAGE98
   J18   47 DQ28_A SCONN288_ADR50017P087CC-SCONN2A    I24 @S9S_MB_2U_LIB.S9S_MB_2U(SCH_1):PAGE99

M_A_CPU1_SA_DQ<29> @S9S_MB_2U_LIB.S9S_MB_2U(SCH_1):M_A_CPU1_SA_DQ(29)
    U1  C62 DDR0_SA_DQ29 SOCKET4677_AZIF0045P001C01CS-SA     I2 @S9S_MB_2U_LIB.S9S_MB_2U(SCH_1):PAGE51
   J17   49 DQ29_A SCONN288_ADR50017P130CC-SCONN2A    I12 @S9S_MB_2U_LIB.S9S_MB_2U(SCH_1):PAGE98
   J18   49 DQ29_A SCONN288_ADR50017P087CC-SCONN2A    I24 @S9S_MB_2U_LIB.S9S_MB_2U(SCH_1):PAGE99

M_A_CPU1_SA_DQ<2> @S9S_MB_2U_LIB.S9S_MB_2U(SCH_1):M_A_CPU1_SA_DQ(2)
    U1  M77 DDR0_SA_DQ2 SOCKET4677_AZIF0045P001C01CS-SA     I2 @S9S_MB_2U_LIB.S9S_MB_2U(SCH_1):PAGE51
   J17  152  DQ2_A SCONN288_ADR50017P130CC-SCONN2A    I12 @S9S_MB_2U_LIB.S9S_MB_2U(SCH_1):PAGE98
   J18  152  DQ2_A SCONN288_ADR50017P087CC-SCONN2A    I24 @S9S_MB_2U_LIB.S9S_MB_2U(SCH_1):PAGE99

M_A_CPU1_SA_DQ<30> @S9S_MB_2U_LIB.S9S_MB_2U(SCH_1):M_A_CPU1_SA_DQ(30)
    U1  F63 DDR0_SA_DQ30 SOCKET4677_AZIF0045P001C01CS-SA     I2 @S9S_MB_2U_LIB.S9S_MB_2U(SCH_1):PAGE51
   J17  192 DQ30_A SCONN288_ADR50017P130CC-SCONN2A    I12 @S9S_MB_2U_LIB.S9S_MB_2U(SCH_1):PAGE98
   J18  192 DQ30_A SCONN288_ADR50017P087CC-SCONN2A    I24 @S9S_MB_2U_LIB.S9S_MB_2U(SCH_1):PAGE99

M_A_CPU1_SA_DQ<31> @S9S_MB_2U_LIB.S9S_MB_2U(SCH_1):M_A_CPU1_SA_DQ(31)
    U1  E62 DDR0_SA_DQ31 SOCKET4677_AZIF0045P001C01CS-SA     I2 @S9S_MB_2U_LIB.S9S_MB_2U(SCH_1):PAGE51
   J17  194 DQ31_A SCONN288_ADR50017P130CC-SCONN2A    I12 @S9S_MB_2U_LIB.S9S_MB_2U(SCH_1):PAGE98
   J18  194 DQ31_A SCONN288_ADR50017P087CC-SCONN2A    I24 @S9S_MB_2U_LIB.S9S_MB_2U(SCH_1):PAGE99

M_A_CPU1_SA_DQ<3> @S9S_MB_2U_LIB.S9S_MB_2U(SCH_1):M_A_CPU1_SA_DQ(3)
    U1  G78 DDR0_SA_DQ3 SOCKET4677_AZIF0045P001C01CS-SA     I2 @S9S_MB_2U_LIB.S9S_MB_2U(SCH_1):PAGE51
   J17  154  DQ3_A SCONN288_ADR50017P130CC-SCONN2A    I12 @S9S_MB_2U_LIB.S9S_MB_2U(SCH_1):PAGE98
   J18  154  DQ3_A SCONN288_ADR50017P087CC-SCONN2A    I24 @S9S_MB_2U_LIB.S9S_MB_2U(SCH_1):PAGE99

M_A_CPU1_SA_DQ<4> @S9S_MB_2U_LIB.S9S_MB_2U(SCH_1):M_A_CPU1_SA_DQ(4)
    U1  C76 DDR0_SA_DQ4 SOCKET4677_AZIF0045P001C01CS-SA     I2 @S9S_MB_2U_LIB.S9S_MB_2U(SCH_1):PAGE51
   J17   14  DQ4_A SCONN288_ADR50017P130CC-SCONN2A    I12 @S9S_MB_2U_LIB.S9S_MB_2U(SCH_1):PAGE98
   J18   14  DQ4_A SCONN288_ADR50017P087CC-SCONN2A    I24 @S9S_MB_2U_LIB.S9S_MB_2U(SCH_1):PAGE99

M_A_CPU1_SA_DQ<5> @S9S_MB_2U_LIB.S9S_MB_2U(SCH_1):M_A_CPU1_SA_DQ(5)
    U1  D75 DDR0_SA_DQ5 SOCKET4677_AZIF0045P001C01CS-SA     I2 @S9S_MB_2U_LIB.S9S_MB_2U(SCH_1):PAGE51
   J17   16  DQ5_A SCONN288_ADR50017P130CC-SCONN2A    I12 @S9S_MB_2U_LIB.S9S_MB_2U(SCH_1):PAGE98
   J18   16  DQ5_A SCONN288_ADR50017P087CC-SCONN2A    I24 @S9S_MB_2U_LIB.S9S_MB_2U(SCH_1):PAGE99

M_A_CPU1_SA_DQ<6> @S9S_MB_2U_LIB.S9S_MB_2U(SCH_1):M_A_CPU1_SA_DQ(6)
    U1  G76 DDR0_SA_DQ6 SOCKET4677_AZIF0045P001C01CS-SA     I2 @S9S_MB_2U_LIB.S9S_MB_2U(SCH_1):PAGE51
   J17  159  DQ6_A SCONN288_ADR50017P130CC-SCONN2A    I12 @S9S_MB_2U_LIB.S9S_MB_2U(SCH_1):PAGE98
   J18  159  DQ6_A SCONN288_ADR50017P087CC-SCONN2A    I24 @S9S_MB_2U_LIB.S9S_MB_2U(SCH_1):PAGE99

M_A_CPU1_SA_DQ<7> @S9S_MB_2U_LIB.S9S_MB_2U(SCH_1):M_A_CPU1_SA_DQ(7)
    U1  F75 DDR0_SA_DQ7 SOCKET4677_AZIF0045P001C01CS-SA     I2 @S9S_MB_2U_LIB.S9S_MB_2U(SCH_1):PAGE51
   J17  161  DQ7_A SCONN288_ADR50017P130CC-SCONN2A    I12 @S9S_MB_2U_LIB.S9S_MB_2U(SCH_1):PAGE98
   J18  161  DQ7_A SCONN288_ADR50017P087CC-SCONN2A    I24 @S9S_MB_2U_LIB.S9S_MB_2U(SCH_1):PAGE99

M_A_CPU1_SA_DQ<8> @S9S_MB_2U_LIB.S9S_MB_2U(SCH_1):M_A_CPU1_SA_DQ(8)
    U1  K69 DDR0_SA_DQ8 SOCKET4677_AZIF0045P001C01CS-SA     I2 @S9S_MB_2U_LIB.S9S_MB_2U(SCH_1):PAGE51
   J17   18  DQ8_A SCONN288_ADR50017P130CC-SCONN2A    I12 @S9S_MB_2U_LIB.S9S_MB_2U(SCH_1):PAGE98
   J18   18  DQ8_A SCONN288_ADR50017P087CC-SCONN2A    I24 @S9S_MB_2U_LIB.S9S_MB_2U(SCH_1):PAGE99

M_A_CPU1_SA_DQ<9> @S9S_MB_2U_LIB.S9S_MB_2U(SCH_1):M_A_CPU1_SA_DQ(9)
    U1  J68 DDR0_SA_DQ9 SOCKET4677_AZIF0045P001C01CS-SA     I2 @S9S_MB_2U_LIB.S9S_MB_2U(SCH_1):PAGE51
   J17   20  DQ9_A SCONN288_ADR50017P130CC-SCONN2A    I12 @S9S_MB_2U_LIB.S9S_MB_2U(SCH_1):PAGE98
   J18   20  DQ9_A SCONN288_ADR50017P087CC-SCONN2A    I24 @S9S_MB_2U_LIB.S9S_MB_2U(SCH_1):PAGE99

M_A_CPU1_SA_DQS_DN<0> @S9S_MB_2U_LIB.S9S_MB_2U(SCH_1):M_A_CPU1_SA_DQS_DN(0)
    U1  B77 DDR0_SA_DQS_DN0 SOCKET4677_AZIF0045P001C01CS-SA     I2 @S9S_MB_2U_LIB.S9S_MB_2U(SCH_1):PAGE51
   J17   12 DQS0_A_C SCONN288_ADR50017P130CC-SCONN2A   I178 @S9S_MB_2U_LIB.S9S_MB_2U(SCH_1):PAGE98
   J18   12 DQS0_A_C SCONN288_ADR50017P087CC-SCONN2A   I178 @S9S_MB_2U_LIB.S9S_MB_2U(SCH_1):PAGE99

M_A_CPU1_SA_DQS_DN<1> @S9S_MB_2U_LIB.S9S_MB_2U(SCH_1):M_A_CPU1_SA_DQS_DN(1)
    U1  H67 DDR0_SA_DQS_DN1 SOCKET4677_AZIF0045P001C01CS-SA     I2 @S9S_MB_2U_LIB.S9S_MB_2U(SCH_1):PAGE51
   J17   23 DQS1_A_C SCONN288_ADR50017P130CC-SCONN2A   I178 @S9S_MB_2U_LIB.S9S_MB_2U(SCH_1):PAGE98
   J18   23 DQS1_A_C SCONN288_ADR50017P087CC-SCONN2A   I178 @S9S_MB_2U_LIB.S9S_MB_2U(SCH_1):PAGE99

M_A_CPU1_SA_DQS_DN<2> @S9S_MB_2U_LIB.S9S_MB_2U(SCH_1):M_A_CPU1_SA_DQS_DN(2)
    U1  B71 DDR0_SA_DQS_DN2 SOCKET4677_AZIF0045P001C01CS-SA     I2 @S9S_MB_2U_LIB.S9S_MB_2U(SCH_1):PAGE51
   J17   34 DQS2_A_C SCONN288_ADR50017P130CC-SCONN2A   I178 @S9S_MB_2U_LIB.S9S_MB_2U(SCH_1):PAGE98
   J18   34 DQS2_A_C SCONN288_ADR50017P087CC-SCONN2A   I178 @S9S_MB_2U_LIB.S9S_MB_2U(SCH_1):PAGE99

M_A_CPU1_SA_DQS_DN<3> @S9S_MB_2U_LIB.S9S_MB_2U(SCH_1):M_A_CPU1_SA_DQS_DN(3)
    U1  A64 DDR0_SA_DQS_DN3 SOCKET4677_AZIF0045P001C01CS-SA     I2 @S9S_MB_2U_LIB.S9S_MB_2U(SCH_1):PAGE51
   J17   45 DQS3_A_C SCONN288_ADR50017P130CC-SCONN2A   I178 @S9S_MB_2U_LIB.S9S_MB_2U(SCH_1):PAGE98
   J18   45 DQS3_A_C SCONN288_ADR50017P087CC-SCONN2A   I178 @S9S_MB_2U_LIB.S9S_MB_2U(SCH_1):PAGE99

M_A_CPU1_SA_DQS_DN<4> @S9S_MB_2U_LIB.S9S_MB_2U(SCH_1):M_A_CPU1_SA_DQS_DN(4)
    U1  A58 DDR0_SA_DQS_DN4 SOCKET4677_AZIF0045P001C01CS-SA     I2 @S9S_MB_2U_LIB.S9S_MB_2U(SCH_1):PAGE51
   J17   56 DQS4_A_C SCONN288_ADR50017P130CC-SCONN2A   I178 @S9S_MB_2U_LIB.S9S_MB_2U(SCH_1):PAGE98
   J18   56 DQS4_A_C SCONN288_ADR50017P087CC-SCONN2A   I178 @S9S_MB_2U_LIB.S9S_MB_2U(SCH_1):PAGE99

M_A_CPU1_SA_DQS_DN<5> @S9S_MB_2U_LIB.S9S_MB_2U(SCH_1):M_A_CPU1_SA_DQS_DN(5)
    U1  H77 DDR0_SA_DQS_DN5 SOCKET4677_AZIF0045P001C01CS-SA     I2 @S9S_MB_2U_LIB.S9S_MB_2U(SCH_1):PAGE51
   J17  156 DQS5_A_C||TDQS5_A_C||DQS5_A_T||TDQS5_A_T SCONN288_ADR50017P130CC-SCONN2A   I178 @S9S_MB_2U_LIB.S9S_MB_2U(SCH_1):PAGE98
   J18  156 DQS5_A_C||TDQS5_A_C||DQS5_A_T||TDQS5_A_T SCONN288_ADR50017P087CC-SCONN2A   I178 @S9S_MB_2U_LIB.S9S_MB_2U(SCH_1):PAGE99

M_A_CPU1_SA_DQS_DN<6> @S9S_MB_2U_LIB.S9S_MB_2U(SCH_1):M_A_CPU1_SA_DQS_DN(6)
    U1  P67 DDR0_SA_DQS_DN6 SOCKET4677_AZIF0045P001C01CS-SA     I2 @S9S_MB_2U_LIB.S9S_MB_2U(SCH_1):PAGE51
   J17  167 DQS6_A_C||TDQS6_A_C||DQS6_A_T||TDQS6_A_T SCONN288_ADR50017P130CC-SCONN2A   I178 @S9S_MB_2U_LIB.S9S_MB_2U(SCH_1):PAGE98
   J18  167 DQS6_A_C||TDQS6_A_C||DQS6_A_T||TDQS6_A_T SCONN288_ADR50017P087CC-SCONN2A   I178 @S9S_MB_2U_LIB.S9S_MB_2U(SCH_1):PAGE99

M_A_CPU1_SA_DQS_DN<7> @S9S_MB_2U_LIB.S9S_MB_2U(SCH_1):M_A_CPU1_SA_DQS_DN(7)
    U1  G70 DDR0_SA_DQS_DN7 SOCKET4677_AZIF0045P001C01CS-SA     I2 @S9S_MB_2U_LIB.S9S_MB_2U(SCH_1):PAGE51
   J17  178 DQS7_A_C||TDQS7_A_C SCONN288_ADR50017P130CC-SCONN2A   I178 @S9S_MB_2U_LIB.S9S_MB_2U(SCH_1):PAGE98
   J18  178 DQS7_A_C||TDQS7_A_C SCONN288_ADR50017P087CC-SCONN2A   I178 @S9S_MB_2U_LIB.S9S_MB_2U(SCH_1):PAGE99

M_A_CPU1_SA_DQS_DN<8> @S9S_MB_2U_LIB.S9S_MB_2U(SCH_1):M_A_CPU1_SA_DQS_DN(8)
    U1  G64 DDR0_SA_DQS_DN8 SOCKET4677_AZIF0045P001C01CS-SA     I2 @S9S_MB_2U_LIB.S9S_MB_2U(SCH_1):PAGE51
   J17  189 DQS8_A_C||TDQS8_A_C SCONN288_ADR50017P130CC-SCONN2A   I178 @S9S_MB_2U_LIB.S9S_MB_2U(SCH_1):PAGE98
   J18  189 DQS8_A_C||TDQS8_A_C SCONN288_ADR50017P087CC-SCONN2A   I178 @S9S_MB_2U_LIB.S9S_MB_2U(SCH_1):PAGE99

M_A_CPU1_SA_DQS_DN<9> @S9S_MB_2U_LIB.S9S_MB_2U(SCH_1):M_A_CPU1_SA_DQS_DN(9)
    U1  G58 DDR0_SA_DQS_DN9 SOCKET4677_AZIF0045P001C01CS-SA     I2 @S9S_MB_2U_LIB.S9S_MB_2U(SCH_1):PAGE51
   J17  200 DQS9_A_C||TDQS9_A_C SCONN288_ADR50017P130CC-SCONN2A   I178 @S9S_MB_2U_LIB.S9S_MB_2U(SCH_1):PAGE98
   J18  200 DQS9_A_C||TDQS9_A_C SCONN288_ADR50017P087CC-SCONN2A   I178 @S9S_MB_2U_LIB.S9S_MB_2U(SCH_1):PAGE99

M_A_CPU1_SA_DQS_DP<0> @S9S_MB_2U_LIB.S9S_MB_2U(SCH_1):M_A_CPU1_SA_DQS_DP(0)
    U1  D77 DDR0_SA_DQS_DP0 SOCKET4677_AZIF0045P001C01CS-SA     I2 @S9S_MB_2U_LIB.S9S_MB_2U(SCH_1):PAGE51
   J17   11 DQS0_A_T SCONN288_ADR50017P130CC-SCONN2A   I178 @S9S_MB_2U_LIB.S9S_MB_2U(SCH_1):PAGE98
   J18   11 DQS0_A_T SCONN288_ADR50017P087CC-SCONN2A   I178 @S9S_MB_2U_LIB.S9S_MB_2U(SCH_1):PAGE99

M_A_CPU1_SA_DQS_DP<1> @S9S_MB_2U_LIB.S9S_MB_2U(SCH_1):M_A_CPU1_SA_DQS_DP(1)
    U1  K67 DDR0_SA_DQS_DP1 SOCKET4677_AZIF0045P001C01CS-SA     I2 @S9S_MB_2U_LIB.S9S_MB_2U(SCH_1):PAGE51
   J17   22 DQS1_A_T SCONN288_ADR50017P130CC-SCONN2A   I178 @S9S_MB_2U_LIB.S9S_MB_2U(SCH_1):PAGE98
   J18   22 DQS1_A_T SCONN288_ADR50017P087CC-SCONN2A   I178 @S9S_MB_2U_LIB.S9S_MB_2U(SCH_1):PAGE99

M_A_CPU1_SA_DQS_DP<2> @S9S_MB_2U_LIB.S9S_MB_2U(SCH_1):M_A_CPU1_SA_DQS_DP(2)
    U1  C70 DDR0_SA_DQS_DP2 SOCKET4677_AZIF0045P001C01CS-SA     I2 @S9S_MB_2U_LIB.S9S_MB_2U(SCH_1):PAGE51
   J17   33 DQS2_A_T SCONN288_ADR50017P130CC-SCONN2A   I178 @S9S_MB_2U_LIB.S9S_MB_2U(SCH_1):PAGE98
   J18   33 DQS2_A_T SCONN288_ADR50017P087CC-SCONN2A   I178 @S9S_MB_2U_LIB.S9S_MB_2U(SCH_1):PAGE99

M_A_CPU1_SA_DQS_DP<3> @S9S_MB_2U_LIB.S9S_MB_2U(SCH_1):M_A_CPU1_SA_DQS_DP(3)
    U1  C64 DDR0_SA_DQS_DP3 SOCKET4677_AZIF0045P001C01CS-SA     I2 @S9S_MB_2U_LIB.S9S_MB_2U(SCH_1):PAGE51
   J17   44 DQS3_A_T SCONN288_ADR50017P130CC-SCONN2A   I178 @S9S_MB_2U_LIB.S9S_MB_2U(SCH_1):PAGE98
   J18   44 DQS3_A_T SCONN288_ADR50017P087CC-SCONN2A   I178 @S9S_MB_2U_LIB.S9S_MB_2U(SCH_1):PAGE99

M_A_CPU1_SA_DQS_DP<4> @S9S_MB_2U_LIB.S9S_MB_2U(SCH_1):M_A_CPU1_SA_DQS_DP(4)
    U1  C58 DDR0_SA_DQS_DP4 SOCKET4677_AZIF0045P001C01CS-SA     I2 @S9S_MB_2U_LIB.S9S_MB_2U(SCH_1):PAGE51
   J17   55 DQS4_A_T SCONN288_ADR50017P130CC-SCONN2A   I178 @S9S_MB_2U_LIB.S9S_MB_2U(SCH_1):PAGE98
   J18   55 DQS4_A_T SCONN288_ADR50017P087CC-SCONN2A   I178 @S9S_MB_2U_LIB.S9S_MB_2U(SCH_1):PAGE99

M_A_CPU1_SA_DQS_DP<5> @S9S_MB_2U_LIB.S9S_MB_2U(SCH_1):M_A_CPU1_SA_DQS_DP(5)
    U1  F77 DDR0_SA_DQS_DP5 SOCKET4677_AZIF0045P001C01CS-SA     I2 @S9S_MB_2U_LIB.S9S_MB_2U(SCH_1):PAGE51
   J17  157 DQS5_A_T||TDQS5_A_T SCONN288_ADR50017P130CC-SCONN2A   I178 @S9S_MB_2U_LIB.S9S_MB_2U(SCH_1):PAGE98
   J18  157 DQS5_A_T||TDQS5_A_T SCONN288_ADR50017P087CC-SCONN2A   I178 @S9S_MB_2U_LIB.S9S_MB_2U(SCH_1):PAGE99

M_A_CPU1_SA_DQS_DP<6> @S9S_MB_2U_LIB.S9S_MB_2U(SCH_1):M_A_CPU1_SA_DQS_DP(6)
    U1  M67 DDR0_SA_DQS_DP6 SOCKET4677_AZIF0045P001C01CS-SA     I2 @S9S_MB_2U_LIB.S9S_MB_2U(SCH_1):PAGE51
   J17  168 DQS6_A_T||TDQS6_A_T SCONN288_ADR50017P130CC-SCONN2A   I178 @S9S_MB_2U_LIB.S9S_MB_2U(SCH_1):PAGE98
   J18  168 DQS6_A_T||TDQS6_A_T SCONN288_ADR50017P087CC-SCONN2A   I178 @S9S_MB_2U_LIB.S9S_MB_2U(SCH_1):PAGE99

M_A_CPU1_SA_DQS_DP<7> @S9S_MB_2U_LIB.S9S_MB_2U(SCH_1):M_A_CPU1_SA_DQS_DP(7)
    U1  E70 DDR0_SA_DQS_DP7 SOCKET4677_AZIF0045P001C01CS-SA     I2 @S9S_MB_2U_LIB.S9S_MB_2U(SCH_1):PAGE51
   J17  179 DQS7_A_T||TDQS7_A_T SCONN288_ADR50017P130CC-SCONN2A   I178 @S9S_MB_2U_LIB.S9S_MB_2U(SCH_1):PAGE98
   J18  179 DQS7_A_T||TDQS7_A_T SCONN288_ADR50017P087CC-SCONN2A   I178 @S9S_MB_2U_LIB.S9S_MB_2U(SCH_1):PAGE99

M_A_CPU1_SA_DQS_DP<8> @S9S_MB_2U_LIB.S9S_MB_2U(SCH_1):M_A_CPU1_SA_DQS_DP(8)
    U1  E64 DDR0_SA_DQS_DP8 SOCKET4677_AZIF0045P001C01CS-SA     I2 @S9S_MB_2U_LIB.S9S_MB_2U(SCH_1):PAGE51
   J17  190 DQS8_A_T||TDQS8_A_T SCONN288_ADR50017P130CC-SCONN2A   I178 @S9S_MB_2U_LIB.S9S_MB_2U(SCH_1):PAGE98
   J18  190 DQS8_A_T||TDQS8_A_T SCONN288_ADR50017P087CC-SCONN2A   I178 @S9S_MB_2U_LIB.S9S_MB_2U(SCH_1):PAGE99

M_A_CPU1_SA_DQS_DP<9> @S9S_MB_2U_LIB.S9S_MB_2U(SCH_1):M_A_CPU1_SA_DQS_DP(9)
    U1  E58 DDR0_SA_DQS_DP9 SOCKET4677_AZIF0045P001C01CS-SA     I2 @S9S_MB_2U_LIB.S9S_MB_2U(SCH_1):PAGE51
   J17  201 DQS9_A_T||TDQS9_A_T SCONN288_ADR50017P130CC-SCONN2A   I178 @S9S_MB_2U_LIB.S9S_MB_2U(SCH_1):PAGE98
   J18  201 DQS9_A_T||TDQS9_A_T SCONN288_ADR50017P087CC-SCONN2A   I178 @S9S_MB_2U_LIB.S9S_MB_2U(SCH_1):PAGE99

M_A_CPU1_SA_PAR @S9S_MB_2U_LIB.S9S_MB_2U(SCH_1):M_A_CPU1_SA_PAR
    U1  E48 DDR0_SA_PAR SOCKET4677_AZIF0045P001C01CS-SA     I2 @S9S_MB_2U_LIB.S9S_MB_2U(SCH_1):PAGE51
   J17   74  PAR_A SCONN288_ADR50017P130CC-SCONN2A    I12 @S9S_MB_2U_LIB.S9S_MB_2U(SCH_1):PAGE98
   J18   74  PAR_A SCONN288_ADR50017P087CC-SCONN2A    I24 @S9S_MB_2U_LIB.S9S_MB_2U(SCH_1):PAGE99

M_A_CPU1_SA_RSP<0> @S9S_MB_2U_LIB.S9S_MB_2U(SCH_1):M_A_CPU1_SA_RSP(0)
    U1 AT42 DDR0_A_RSP0 SOCKET4677_AZIF0045P001C01CS-SA     I2 @S9S_MB_2U_LIB.S9S_MB_2U(SCH_1):PAGE51
   J17   86 LBD||RSP_A_N SCONN288_ADR50017P130CC-SCONN2A    I12 @S9S_MB_2U_LIB.S9S_MB_2U(SCH_1):PAGE98

M_A_CPU1_SA_RSP<1> @S9S_MB_2U_LIB.S9S_MB_2U(SCH_1):M_A_CPU1_SA_RSP(1)
    U1 AU43 DDR0_A_RSP1 SOCKET4677_AZIF0045P001C01CS-SA     I2 @S9S_MB_2U_LIB.S9S_MB_2U(SCH_1):PAGE51
   J18   86 LBD||RSP_A_N SCONN288_ADR50017P087CC-SCONN2A    I24 @S9S_MB_2U_LIB.S9S_MB_2U(SCH_1):PAGE99

M_A_CPU1_SB_CA<0> @S9S_MB_2U_LIB.S9S_MB_2U(SCH_1):M_A_CPU1_SB_CA(0)
    U1  E43 DDR0_SB_CA0 SOCKET4677_AZIF0045P001C01CS-SA     I2 @S9S_MB_2U_LIB.S9S_MB_2U(SCH_1):PAGE51
   J17   76  CA0_B SCONN288_ADR50017P130CC-SCONN2A    I12 @S9S_MB_2U_LIB.S9S_MB_2U(SCH_1):PAGE98
   J18   76  CA0_B SCONN288_ADR50017P087CC-SCONN2A    I24 @S9S_MB_2U_LIB.S9S_MB_2U(SCH_1):PAGE99

M_A_CPU1_SB_CA<1> @S9S_MB_2U_LIB.S9S_MB_2U(SCH_1):M_A_CPU1_SB_CA(1)
    U1  F44 DDR0_SB_CA1 SOCKET4677_AZIF0045P001C01CS-SA     I2 @S9S_MB_2U_LIB.S9S_MB_2U(SCH_1):PAGE51
   J17  221  CA1_B SCONN288_ADR50017P130CC-SCONN2A    I12 @S9S_MB_2U_LIB.S9S_MB_2U(SCH_1):PAGE98
   J18  221  CA1_B SCONN288_ADR50017P087CC-SCONN2A    I24 @S9S_MB_2U_LIB.S9S_MB_2U(SCH_1):PAGE99

M_A_CPU1_SB_CA<2> @S9S_MB_2U_LIB.S9S_MB_2U(SCH_1):M_A_CPU1_SB_CA(2)
    U1  C41 DDR0_SB_CA2 SOCKET4677_AZIF0045P001C01CS-SA     I2 @S9S_MB_2U_LIB.S9S_MB_2U(SCH_1):PAGE51
   J17   78  CA2_B SCONN288_ADR50017P130CC-SCONN2A    I12 @S9S_MB_2U_LIB.S9S_MB_2U(SCH_1):PAGE98
   J18   78  CA2_B SCONN288_ADR50017P087CC-SCONN2A    I24 @S9S_MB_2U_LIB.S9S_MB_2U(SCH_1):PAGE99

M_A_CPU1_SB_CA<3> @S9S_MB_2U_LIB.S9S_MB_2U(SCH_1):M_A_CPU1_SB_CA(3)
    U1  E41 DDR0_SB_CA3 SOCKET4677_AZIF0045P001C01CS-SA     I2 @S9S_MB_2U_LIB.S9S_MB_2U(SCH_1):PAGE51
   J17  223  CA3_B SCONN288_ADR50017P130CC-SCONN2A    I12 @S9S_MB_2U_LIB.S9S_MB_2U(SCH_1):PAGE98
   J18  223  CA3_B SCONN288_ADR50017P087CC-SCONN2A    I24 @S9S_MB_2U_LIB.S9S_MB_2U(SCH_1):PAGE99

M_A_CPU1_SB_CA<4> @S9S_MB_2U_LIB.S9S_MB_2U(SCH_1):M_A_CPU1_SB_CA(4)
    U1  B40 DDR0_SB_CA4 SOCKET4677_AZIF0045P001C01CS-SA     I2 @S9S_MB_2U_LIB.S9S_MB_2U(SCH_1):PAGE51
   J17   80  CA4_B SCONN288_ADR50017P130CC-SCONN2A    I12 @S9S_MB_2U_LIB.S9S_MB_2U(SCH_1):PAGE98
   J18   80  CA4_B SCONN288_ADR50017P087CC-SCONN2A    I24 @S9S_MB_2U_LIB.S9S_MB_2U(SCH_1):PAGE99

M_A_CPU1_SB_CA<5> @S9S_MB_2U_LIB.S9S_MB_2U(SCH_1):M_A_CPU1_SB_CA(5)
    U1  F40 DDR0_SB_CA5 SOCKET4677_AZIF0045P001C01CS-SA     I2 @S9S_MB_2U_LIB.S9S_MB_2U(SCH_1):PAGE51
   J17  225  CA5_B SCONN288_ADR50017P130CC-SCONN2A    I12 @S9S_MB_2U_LIB.S9S_MB_2U(SCH_1):PAGE98
   J18  225  CA5_B SCONN288_ADR50017P087CC-SCONN2A    I24 @S9S_MB_2U_LIB.S9S_MB_2U(SCH_1):PAGE99

M_A_CPU1_SB_CA<6> @S9S_MB_2U_LIB.S9S_MB_2U(SCH_1):M_A_CPU1_SB_CA(6)
    U1  A39 DDR0_SB_CA6 SOCKET4677_AZIF0045P001C01CS-SA     I2 @S9S_MB_2U_LIB.S9S_MB_2U(SCH_1):PAGE51
   J17   82  CA6_B SCONN288_ADR50017P130CC-SCONN2A    I12 @S9S_MB_2U_LIB.S9S_MB_2U(SCH_1):PAGE98
   J18   82  CA6_B SCONN288_ADR50017P087CC-SCONN2A    I24 @S9S_MB_2U_LIB.S9S_MB_2U(SCH_1):PAGE99

M_A_CPU1_SB_CB<0> @S9S_MB_2U_LIB.S9S_MB_2U(SCH_1):M_A_CPU1_SB_CB(0)
    U1  B32 DDR0_SB_ECC0 SOCKET4677_AZIF0045P001C01CS-SA     I2 @S9S_MB_2U_LIB.S9S_MB_2U(SCH_1):PAGE51
   J17   96  CB0_B SCONN288_ADR50017P130CC-SCONN2A    I12 @S9S_MB_2U_LIB.S9S_MB_2U(SCH_1):PAGE98
   J18   96  CB0_B SCONN288_ADR50017P087CC-SCONN2A    I24 @S9S_MB_2U_LIB.S9S_MB_2U(SCH_1):PAGE99

M_A_CPU1_SB_CB<1> @S9S_MB_2U_LIB.S9S_MB_2U(SCH_1):M_A_CPU1_SB_CB(1)
    U1  C31 DDR0_SB_ECC1 SOCKET4677_AZIF0045P001C01CS-SA     I2 @S9S_MB_2U_LIB.S9S_MB_2U(SCH_1):PAGE51
   J17   98  CB1_B SCONN288_ADR50017P130CC-SCONN2A    I12 @S9S_MB_2U_LIB.S9S_MB_2U(SCH_1):PAGE98
   J18   98  CB1_B SCONN288_ADR50017P087CC-SCONN2A    I24 @S9S_MB_2U_LIB.S9S_MB_2U(SCH_1):PAGE99

M_A_CPU1_SB_CB<2> @S9S_MB_2U_LIB.S9S_MB_2U(SCH_1):M_A_CPU1_SB_CB(2)
    U1  F32 DDR0_SB_ECC2 SOCKET4677_AZIF0045P001C01CS-SA     I2 @S9S_MB_2U_LIB.S9S_MB_2U(SCH_1):PAGE51
   J17  241  CB2_B SCONN288_ADR50017P130CC-SCONN2A    I12 @S9S_MB_2U_LIB.S9S_MB_2U(SCH_1):PAGE98
   J18  241  CB2_B SCONN288_ADR50017P087CC-SCONN2A    I24 @S9S_MB_2U_LIB.S9S_MB_2U(SCH_1):PAGE99

M_A_CPU1_SB_CB<3> @S9S_MB_2U_LIB.S9S_MB_2U(SCH_1):M_A_CPU1_SB_CB(3)
    U1  E31 DDR0_SB_ECC3 SOCKET4677_AZIF0045P001C01CS-SA     I2 @S9S_MB_2U_LIB.S9S_MB_2U(SCH_1):PAGE51
   J17  243  CB3_B SCONN288_ADR50017P130CC-SCONN2A    I12 @S9S_MB_2U_LIB.S9S_MB_2U(SCH_1):PAGE98
   J18  243  CB3_B SCONN288_ADR50017P087CC-SCONN2A    I24 @S9S_MB_2U_LIB.S9S_MB_2U(SCH_1):PAGE99

M_A_CPU1_SB_CB<4> @S9S_MB_2U_LIB.S9S_MB_2U(SCH_1):M_A_CPU1_SB_CB(4)
    U1  C35 DDR0_SB_ECC4 SOCKET4677_AZIF0045P001C01CS-SA     I2 @S9S_MB_2U_LIB.S9S_MB_2U(SCH_1):PAGE51
   J17   89  CB4_B SCONN288_ADR50017P130CC-SCONN2A    I12 @S9S_MB_2U_LIB.S9S_MB_2U(SCH_1):PAGE98
   J18   89  CB4_B SCONN288_ADR50017P087CC-SCONN2A    I24 @S9S_MB_2U_LIB.S9S_MB_2U(SCH_1):PAGE99

M_A_CPU1_SB_CB<5> @S9S_MB_2U_LIB.S9S_MB_2U(SCH_1):M_A_CPU1_SB_CB(5)
    U1  B34 DDR0_SB_ECC5 SOCKET4677_AZIF0045P001C01CS-SA     I2 @S9S_MB_2U_LIB.S9S_MB_2U(SCH_1):PAGE51
   J17   91  CB5_B SCONN288_ADR50017P130CC-SCONN2A    I12 @S9S_MB_2U_LIB.S9S_MB_2U(SCH_1):PAGE98
   J18   91  CB5_B SCONN288_ADR50017P087CC-SCONN2A    I24 @S9S_MB_2U_LIB.S9S_MB_2U(SCH_1):PAGE99

M_A_CPU1_SB_CB<6> @S9S_MB_2U_LIB.S9S_MB_2U(SCH_1):M_A_CPU1_SB_CB(6)
    U1  E35 DDR0_SB_ECC6 SOCKET4677_AZIF0045P001C01CS-SA     I2 @S9S_MB_2U_LIB.S9S_MB_2U(SCH_1):PAGE51
   J17  234  CB6_B SCONN288_ADR50017P130CC-SCONN2A    I12 @S9S_MB_2U_LIB.S9S_MB_2U(SCH_1):PAGE98
   J18  234  CB6_B SCONN288_ADR50017P087CC-SCONN2A    I24 @S9S_MB_2U_LIB.S9S_MB_2U(SCH_1):PAGE99

M_A_CPU1_SB_CB<7> @S9S_MB_2U_LIB.S9S_MB_2U(SCH_1):M_A_CPU1_SB_CB(7)
    U1  F34 DDR0_SB_ECC7 SOCKET4677_AZIF0045P001C01CS-SA     I2 @S9S_MB_2U_LIB.S9S_MB_2U(SCH_1):PAGE51
   J17  236  CB7_B SCONN288_ADR50017P130CC-SCONN2A    I12 @S9S_MB_2U_LIB.S9S_MB_2U(SCH_1):PAGE98
   J18  236  CB7_B SCONN288_ADR50017P087CC-SCONN2A    I24 @S9S_MB_2U_LIB.S9S_MB_2U(SCH_1):PAGE99

M_A_CPU1_SB_CS_N<0> @S9S_MB_2U_LIB.S9S_MB_2U(SCH_1):M_A_CPU1_SB_CS_N(0)
    U1  B38 DDR0_SB_CS_N0 SOCKET4677_AZIF0045P001C01CS-SA     I2 @S9S_MB_2U_LIB.S9S_MB_2U(SCH_1):PAGE51
   J17   84 CS0_B_N SCONN288_ADR50017P130CC-SCONN2A    I12 @S9S_MB_2U_LIB.S9S_MB_2U(SCH_1):PAGE98

M_A_CPU1_SB_CS_N<1> @S9S_MB_2U_LIB.S9S_MB_2U(SCH_1):M_A_CPU1_SB_CS_N(1)
    U1  C37 DDR0_SB_CS_N1 SOCKET4677_AZIF0045P001C01CS-SA     I2 @S9S_MB_2U_LIB.S9S_MB_2U(SCH_1):PAGE51
   J17  229 CS1_B_N SCONN288_ADR50017P130CC-SCONN2A    I12 @S9S_MB_2U_LIB.S9S_MB_2U(SCH_1):PAGE98

M_A_CPU1_SB_CS_N<2> @S9S_MB_2U_LIB.S9S_MB_2U(SCH_1):M_A_CPU1_SB_CS_N(2)
    U1  F38 DDR0_SB_CS_N2 SOCKET4677_AZIF0045P001C01CS-SA     I2 @S9S_MB_2U_LIB.S9S_MB_2U(SCH_1):PAGE51
   J18   84 CS0_B_N SCONN288_ADR50017P087CC-SCONN2A    I24 @S9S_MB_2U_LIB.S9S_MB_2U(SCH_1):PAGE99

M_A_CPU1_SB_CS_N<3> @S9S_MB_2U_LIB.S9S_MB_2U(SCH_1):M_A_CPU1_SB_CS_N(3)
    U1  E37 DDR0_SB_CS_N3 SOCKET4677_AZIF0045P001C01CS-SA     I2 @S9S_MB_2U_LIB.S9S_MB_2U(SCH_1):PAGE51
   J18  229 CS1_B_N SCONN288_ADR50017P087CC-SCONN2A    I24 @S9S_MB_2U_LIB.S9S_MB_2U(SCH_1):PAGE99

M_A_CPU1_SB_DQ<0> @S9S_MB_2U_LIB.S9S_MB_2U(SCH_1):M_A_CPU1_SB_DQ(0)
    U1  K32 DDR0_SB_DQ0 SOCKET4677_AZIF0045P001C01CS-SA     I2 @S9S_MB_2U_LIB.S9S_MB_2U(SCH_1):PAGE51
   J17  100  DQ0_B SCONN288_ADR50017P130CC-SCONN2A    I12 @S9S_MB_2U_LIB.S9S_MB_2U(SCH_1):PAGE98
   J18  100  DQ0_B SCONN288_ADR50017P087CC-SCONN2A    I24 @S9S_MB_2U_LIB.S9S_MB_2U(SCH_1):PAGE99

M_A_CPU1_SB_DQ<10> @S9S_MB_2U_LIB.S9S_MB_2U(SCH_1):M_A_CPU1_SB_DQ(10)
    U1  E29 DDR0_SB_DQ10 SOCKET4677_AZIF0045P001C01CS-SA     I2 @S9S_MB_2U_LIB.S9S_MB_2U(SCH_1):PAGE51
   J17  256 DQ10_B SCONN288_ADR50017P130CC-SCONN2A    I12 @S9S_MB_2U_LIB.S9S_MB_2U(SCH_1):PAGE98
   J18  256 DQ10_B SCONN288_ADR50017P087CC-SCONN2A    I24 @S9S_MB_2U_LIB.S9S_MB_2U(SCH_1):PAGE99

M_A_CPU1_SB_DQ<11> @S9S_MB_2U_LIB.S9S_MB_2U(SCH_1):M_A_CPU1_SB_DQ(11)
    U1  F28 DDR0_SB_DQ11 SOCKET4677_AZIF0045P001C01CS-SA     I2 @S9S_MB_2U_LIB.S9S_MB_2U(SCH_1):PAGE51
   J17  258 DQ11_B SCONN288_ADR50017P130CC-SCONN2A    I12 @S9S_MB_2U_LIB.S9S_MB_2U(SCH_1):PAGE98
   J18  258 DQ11_B SCONN288_ADR50017P087CC-SCONN2A    I24 @S9S_MB_2U_LIB.S9S_MB_2U(SCH_1):PAGE99

M_A_CPU1_SB_DQ<12> @S9S_MB_2U_LIB.S9S_MB_2U(SCH_1):M_A_CPU1_SB_DQ(12)
    U1  B26 DDR0_SB_DQ12 SOCKET4677_AZIF0045P001C01CS-SA     I2 @S9S_MB_2U_LIB.S9S_MB_2U(SCH_1):PAGE51
   J17  118 DQ12_B SCONN288_ADR50017P130CC-SCONN2A    I12 @S9S_MB_2U_LIB.S9S_MB_2U(SCH_1):PAGE98
   J18  118 DQ12_B SCONN288_ADR50017P087CC-SCONN2A    I24 @S9S_MB_2U_LIB.S9S_MB_2U(SCH_1):PAGE99

M_A_CPU1_SB_DQ<13> @S9S_MB_2U_LIB.S9S_MB_2U(SCH_1):M_A_CPU1_SB_DQ(13)
    U1  C25 DDR0_SB_DQ13 SOCKET4677_AZIF0045P001C01CS-SA     I2 @S9S_MB_2U_LIB.S9S_MB_2U(SCH_1):PAGE51
   J17  120 DQ13_B SCONN288_ADR50017P130CC-SCONN2A    I12 @S9S_MB_2U_LIB.S9S_MB_2U(SCH_1):PAGE98
   J18  120 DQ13_B SCONN288_ADR50017P087CC-SCONN2A    I24 @S9S_MB_2U_LIB.S9S_MB_2U(SCH_1):PAGE99

M_A_CPU1_SB_DQ<14> @S9S_MB_2U_LIB.S9S_MB_2U(SCH_1):M_A_CPU1_SB_DQ(14)
    U1  F26 DDR0_SB_DQ14 SOCKET4677_AZIF0045P001C01CS-SA     I2 @S9S_MB_2U_LIB.S9S_MB_2U(SCH_1):PAGE51
   J17  263 DQ14_B SCONN288_ADR50017P130CC-SCONN2A    I12 @S9S_MB_2U_LIB.S9S_MB_2U(SCH_1):PAGE98
   J18  263 DQ14_B SCONN288_ADR50017P087CC-SCONN2A    I24 @S9S_MB_2U_LIB.S9S_MB_2U(SCH_1):PAGE99

M_A_CPU1_SB_DQ<15> @S9S_MB_2U_LIB.S9S_MB_2U(SCH_1):M_A_CPU1_SB_DQ(15)
    U1  E25 DDR0_SB_DQ15 SOCKET4677_AZIF0045P001C01CS-SA     I2 @S9S_MB_2U_LIB.S9S_MB_2U(SCH_1):PAGE51
   J17  265 DQ15_B SCONN288_ADR50017P130CC-SCONN2A    I12 @S9S_MB_2U_LIB.S9S_MB_2U(SCH_1):PAGE98
   J18  265 DQ15_B SCONN288_ADR50017P087CC-SCONN2A    I24 @S9S_MB_2U_LIB.S9S_MB_2U(SCH_1):PAGE99

M_A_CPU1_SB_DQ<16> @S9S_MB_2U_LIB.S9S_MB_2U(SCH_1):M_A_CPU1_SB_DQ(16)
    U1  C23 DDR0_SB_DQ16 SOCKET4677_AZIF0045P001C01CS-SA     I2 @S9S_MB_2U_LIB.S9S_MB_2U(SCH_1):PAGE51
   J17  122 DQ16_B SCONN288_ADR50017P130CC-SCONN2A    I12 @S9S_MB_2U_LIB.S9S_MB_2U(SCH_1):PAGE98
   J18  122 DQ16_B SCONN288_ADR50017P087CC-SCONN2A    I24 @S9S_MB_2U_LIB.S9S_MB_2U(SCH_1):PAGE99

M_A_CPU1_SB_DQ<17> @S9S_MB_2U_LIB.S9S_MB_2U(SCH_1):M_A_CPU1_SB_DQ(17)
    U1  B22 DDR0_SB_DQ17 SOCKET4677_AZIF0045P001C01CS-SA     I2 @S9S_MB_2U_LIB.S9S_MB_2U(SCH_1):PAGE51
   J17  124 DQ17_B SCONN288_ADR50017P130CC-SCONN2A    I12 @S9S_MB_2U_LIB.S9S_MB_2U(SCH_1):PAGE98
   J18  124 DQ17_B SCONN288_ADR50017P087CC-SCONN2A    I24 @S9S_MB_2U_LIB.S9S_MB_2U(SCH_1):PAGE99

M_A_CPU1_SB_DQ<18> @S9S_MB_2U_LIB.S9S_MB_2U(SCH_1):M_A_CPU1_SB_DQ(18)
    U1  E23 DDR0_SB_DQ18 SOCKET4677_AZIF0045P001C01CS-SA     I2 @S9S_MB_2U_LIB.S9S_MB_2U(SCH_1):PAGE51
   J17  267 DQ18_B SCONN288_ADR50017P130CC-SCONN2A    I12 @S9S_MB_2U_LIB.S9S_MB_2U(SCH_1):PAGE98
   J18  267 DQ18_B SCONN288_ADR50017P087CC-SCONN2A    I24 @S9S_MB_2U_LIB.S9S_MB_2U(SCH_1):PAGE99

M_A_CPU1_SB_DQ<19> @S9S_MB_2U_LIB.S9S_MB_2U(SCH_1):M_A_CPU1_SB_DQ(19)
    U1  F22 DDR0_SB_DQ19 SOCKET4677_AZIF0045P001C01CS-SA     I2 @S9S_MB_2U_LIB.S9S_MB_2U(SCH_1):PAGE51
   J17  269 DQ19_B SCONN288_ADR50017P130CC-SCONN2A    I12 @S9S_MB_2U_LIB.S9S_MB_2U(SCH_1):PAGE98
   J18  269 DQ19_B SCONN288_ADR50017P087CC-SCONN2A    I24 @S9S_MB_2U_LIB.S9S_MB_2U(SCH_1):PAGE99

M_A_CPU1_SB_DQ<1> @S9S_MB_2U_LIB.S9S_MB_2U(SCH_1):M_A_CPU1_SB_DQ(1)
    U1  J31 DDR0_SB_DQ1 SOCKET4677_AZIF0045P001C01CS-SA     I2 @S9S_MB_2U_LIB.S9S_MB_2U(SCH_1):PAGE51
   J17  102  DQ1_B SCONN288_ADR50017P130CC-SCONN2A    I12 @S9S_MB_2U_LIB.S9S_MB_2U(SCH_1):PAGE98
   J18  102  DQ1_B SCONN288_ADR50017P087CC-SCONN2A    I24 @S9S_MB_2U_LIB.S9S_MB_2U(SCH_1):PAGE99

M_A_CPU1_SB_DQ<20> @S9S_MB_2U_LIB.S9S_MB_2U(SCH_1):M_A_CPU1_SB_DQ(20)
    U1  B20 DDR0_SB_DQ20 SOCKET4677_AZIF0045P001C01CS-SA     I2 @S9S_MB_2U_LIB.S9S_MB_2U(SCH_1):PAGE51
   J17  129 DQ20_B SCONN288_ADR50017P130CC-SCONN2A    I12 @S9S_MB_2U_LIB.S9S_MB_2U(SCH_1):PAGE98
   J18  129 DQ20_B SCONN288_ADR50017P087CC-SCONN2A    I24 @S9S_MB_2U_LIB.S9S_MB_2U(SCH_1):PAGE99

M_A_CPU1_SB_DQ<21> @S9S_MB_2U_LIB.S9S_MB_2U(SCH_1):M_A_CPU1_SB_DQ(21)
    U1  C19 DDR0_SB_DQ21 SOCKET4677_AZIF0045P001C01CS-SA     I2 @S9S_MB_2U_LIB.S9S_MB_2U(SCH_1):PAGE51
   J17  131 DQ21_B SCONN288_ADR50017P130CC-SCONN2A    I12 @S9S_MB_2U_LIB.S9S_MB_2U(SCH_1):PAGE98
   J18  131 DQ21_B SCONN288_ADR50017P087CC-SCONN2A    I24 @S9S_MB_2U_LIB.S9S_MB_2U(SCH_1):PAGE99

M_A_CPU1_SB_DQ<22> @S9S_MB_2U_LIB.S9S_MB_2U(SCH_1):M_A_CPU1_SB_DQ(22)
    U1  F20 DDR0_SB_DQ22 SOCKET4677_AZIF0045P001C01CS-SA     I2 @S9S_MB_2U_LIB.S9S_MB_2U(SCH_1):PAGE51
   J17  274 DQ22_B SCONN288_ADR50017P130CC-SCONN2A    I12 @S9S_MB_2U_LIB.S9S_MB_2U(SCH_1):PAGE98
   J18  274 DQ22_B SCONN288_ADR50017P087CC-SCONN2A    I24 @S9S_MB_2U_LIB.S9S_MB_2U(SCH_1):PAGE99

M_A_CPU1_SB_DQ<23> @S9S_MB_2U_LIB.S9S_MB_2U(SCH_1):M_A_CPU1_SB_DQ(23)
    U1  E19 DDR0_SB_DQ23 SOCKET4677_AZIF0045P001C01CS-SA     I2 @S9S_MB_2U_LIB.S9S_MB_2U(SCH_1):PAGE51
   J17  276 DQ23_B SCONN288_ADR50017P130CC-SCONN2A    I12 @S9S_MB_2U_LIB.S9S_MB_2U(SCH_1):PAGE98
   J18  276 DQ23_B SCONN288_ADR50017P087CC-SCONN2A    I24 @S9S_MB_2U_LIB.S9S_MB_2U(SCH_1):PAGE99

M_A_CPU1_SB_DQ<24> @S9S_MB_2U_LIB.S9S_MB_2U(SCH_1):M_A_CPU1_SB_DQ(24)
    U1  C11 DDR0_SB_DQ24 SOCKET4677_AZIF0045P001C01CS-SA     I2 @S9S_MB_2U_LIB.S9S_MB_2U(SCH_1):PAGE51
   J17  133 DQ24_B SCONN288_ADR50017P130CC-SCONN2A    I12 @S9S_MB_2U_LIB.S9S_MB_2U(SCH_1):PAGE98
   J18  133 DQ24_B SCONN288_ADR50017P087CC-SCONN2A    I24 @S9S_MB_2U_LIB.S9S_MB_2U(SCH_1):PAGE99

M_A_CPU1_SB_DQ<25> @S9S_MB_2U_LIB.S9S_MB_2U(SCH_1):M_A_CPU1_SB_DQ(25)
    U1  B10 DDR0_SB_DQ25 SOCKET4677_AZIF0045P001C01CS-SA     I2 @S9S_MB_2U_LIB.S9S_MB_2U(SCH_1):PAGE51
   J17  135 DQ25_B SCONN288_ADR50017P130CC-SCONN2A    I12 @S9S_MB_2U_LIB.S9S_MB_2U(SCH_1):PAGE98
   J18  135 DQ25_B SCONN288_ADR50017P087CC-SCONN2A    I24 @S9S_MB_2U_LIB.S9S_MB_2U(SCH_1):PAGE99

M_A_CPU1_SB_DQ<26> @S9S_MB_2U_LIB.S9S_MB_2U(SCH_1):M_A_CPU1_SB_DQ(26)
    U1  E11 DDR0_SB_DQ26 SOCKET4677_AZIF0045P001C01CS-SA     I2 @S9S_MB_2U_LIB.S9S_MB_2U(SCH_1):PAGE51
   J17  278 DQ26_B SCONN288_ADR50017P130CC-SCONN2A    I12 @S9S_MB_2U_LIB.S9S_MB_2U(SCH_1):PAGE98
   J18  278 DQ26_B SCONN288_ADR50017P087CC-SCONN2A    I24 @S9S_MB_2U_LIB.S9S_MB_2U(SCH_1):PAGE99

M_A_CPU1_SB_DQ<27> @S9S_MB_2U_LIB.S9S_MB_2U(SCH_1):M_A_CPU1_SB_DQ(27)
    U1  F10 DDR0_SB_DQ27 SOCKET4677_AZIF0045P001C01CS-SA     I2 @S9S_MB_2U_LIB.S9S_MB_2U(SCH_1):PAGE51
   J17  280 DQ27_B SCONN288_ADR50017P130CC-SCONN2A    I12 @S9S_MB_2U_LIB.S9S_MB_2U(SCH_1):PAGE98
   J18  280 DQ27_B SCONN288_ADR50017P087CC-SCONN2A    I24 @S9S_MB_2U_LIB.S9S_MB_2U(SCH_1):PAGE99

M_A_CPU1_SB_DQ<28> @S9S_MB_2U_LIB.S9S_MB_2U(SCH_1):M_A_CPU1_SB_DQ(28)
    U1   B8 DDR0_SB_DQ28 SOCKET4677_AZIF0045P001C01CS-SA     I2 @S9S_MB_2U_LIB.S9S_MB_2U(SCH_1):PAGE51
   J17  140 DQ28_B SCONN288_ADR50017P130CC-SCONN2A    I12 @S9S_MB_2U_LIB.S9S_MB_2U(SCH_1):PAGE98
   J18  140 DQ28_B SCONN288_ADR50017P087CC-SCONN2A    I24 @S9S_MB_2U_LIB.S9S_MB_2U(SCH_1):PAGE99

M_A_CPU1_SB_DQ<29> @S9S_MB_2U_LIB.S9S_MB_2U(SCH_1):M_A_CPU1_SB_DQ(29)
    U1   C7 DDR0_SB_DQ29 SOCKET4677_AZIF0045P001C01CS-SA     I2 @S9S_MB_2U_LIB.S9S_MB_2U(SCH_1):PAGE51
   J17  142 DQ29_B SCONN288_ADR50017P130CC-SCONN2A    I12 @S9S_MB_2U_LIB.S9S_MB_2U(SCH_1):PAGE98
   J18  142 DQ29_B SCONN288_ADR50017P087CC-SCONN2A    I24 @S9S_MB_2U_LIB.S9S_MB_2U(SCH_1):PAGE99

M_A_CPU1_SB_DQ<2> @S9S_MB_2U_LIB.S9S_MB_2U(SCH_1):M_A_CPU1_SB_DQ(2)
    U1  M32 DDR0_SB_DQ2 SOCKET4677_AZIF0045P001C01CS-SA     I2 @S9S_MB_2U_LIB.S9S_MB_2U(SCH_1):PAGE51
   J17  245  DQ2_B SCONN288_ADR50017P130CC-SCONN2A    I12 @S9S_MB_2U_LIB.S9S_MB_2U(SCH_1):PAGE98
   J18  245  DQ2_B SCONN288_ADR50017P087CC-SCONN2A    I24 @S9S_MB_2U_LIB.S9S_MB_2U(SCH_1):PAGE99

M_A_CPU1_SB_DQ<30> @S9S_MB_2U_LIB.S9S_MB_2U(SCH_1):M_A_CPU1_SB_DQ(30)
    U1   F8 DDR0_SB_DQ30 SOCKET4677_AZIF0045P001C01CS-SA     I2 @S9S_MB_2U_LIB.S9S_MB_2U(SCH_1):PAGE51
   J17  285 DQ30_B SCONN288_ADR50017P130CC-SCONN2A    I12 @S9S_MB_2U_LIB.S9S_MB_2U(SCH_1):PAGE98
   J18  285 DQ30_B SCONN288_ADR50017P087CC-SCONN2A    I24 @S9S_MB_2U_LIB.S9S_MB_2U(SCH_1):PAGE99

M_A_CPU1_SB_DQ<31> @S9S_MB_2U_LIB.S9S_MB_2U(SCH_1):M_A_CPU1_SB_DQ(31)
    U1   E7 DDR0_SB_DQ31 SOCKET4677_AZIF0045P001C01CS-SA     I2 @S9S_MB_2U_LIB.S9S_MB_2U(SCH_1):PAGE51
   J17  287 DQ31_B SCONN288_ADR50017P130CC-SCONN2A    I12 @S9S_MB_2U_LIB.S9S_MB_2U(SCH_1):PAGE98
   J18  287 DQ31_B SCONN288_ADR50017P087CC-SCONN2A    I24 @S9S_MB_2U_LIB.S9S_MB_2U(SCH_1):PAGE99

M_A_CPU1_SB_DQ<3> @S9S_MB_2U_LIB.S9S_MB_2U(SCH_1):M_A_CPU1_SB_DQ(3)
    U1  N31 DDR0_SB_DQ3 SOCKET4677_AZIF0045P001C01CS-SA     I2 @S9S_MB_2U_LIB.S9S_MB_2U(SCH_1):PAGE51
   J17  247  DQ3_B SCONN288_ADR50017P130CC-SCONN2A    I12 @S9S_MB_2U_LIB.S9S_MB_2U(SCH_1):PAGE98
   J18  247  DQ3_B SCONN288_ADR50017P087CC-SCONN2A    I24 @S9S_MB_2U_LIB.S9S_MB_2U(SCH_1):PAGE99

M_A_CPU1_SB_DQ<4> @S9S_MB_2U_LIB.S9S_MB_2U(SCH_1):M_A_CPU1_SB_DQ(4)
    U1  J29 DDR0_SB_DQ4 SOCKET4677_AZIF0045P001C01CS-SA     I2 @S9S_MB_2U_LIB.S9S_MB_2U(SCH_1):PAGE51
   J17  107  DQ4_B SCONN288_ADR50017P130CC-SCONN2A    I12 @S9S_MB_2U_LIB.S9S_MB_2U(SCH_1):PAGE98
   J18  107  DQ4_B SCONN288_ADR50017P087CC-SCONN2A    I24 @S9S_MB_2U_LIB.S9S_MB_2U(SCH_1):PAGE99

M_A_CPU1_SB_DQ<5> @S9S_MB_2U_LIB.S9S_MB_2U(SCH_1):M_A_CPU1_SB_DQ(5)
    U1  K28 DDR0_SB_DQ5 SOCKET4677_AZIF0045P001C01CS-SA     I2 @S9S_MB_2U_LIB.S9S_MB_2U(SCH_1):PAGE51
   J17  109  DQ5_B SCONN288_ADR50017P130CC-SCONN2A    I12 @S9S_MB_2U_LIB.S9S_MB_2U(SCH_1):PAGE98
   J18  109  DQ5_B SCONN288_ADR50017P087CC-SCONN2A    I24 @S9S_MB_2U_LIB.S9S_MB_2U(SCH_1):PAGE99

M_A_CPU1_SB_DQ<6> @S9S_MB_2U_LIB.S9S_MB_2U(SCH_1):M_A_CPU1_SB_DQ(6)
    U1  N29 DDR0_SB_DQ6 SOCKET4677_AZIF0045P001C01CS-SA     I2 @S9S_MB_2U_LIB.S9S_MB_2U(SCH_1):PAGE51
   J17  252  DQ6_B SCONN288_ADR50017P130CC-SCONN2A    I12 @S9S_MB_2U_LIB.S9S_MB_2U(SCH_1):PAGE98
   J18  252  DQ6_B SCONN288_ADR50017P087CC-SCONN2A    I24 @S9S_MB_2U_LIB.S9S_MB_2U(SCH_1):PAGE99

M_A_CPU1_SB_DQ<7> @S9S_MB_2U_LIB.S9S_MB_2U(SCH_1):M_A_CPU1_SB_DQ(7)
    U1  M28 DDR0_SB_DQ7 SOCKET4677_AZIF0045P001C01CS-SA     I2 @S9S_MB_2U_LIB.S9S_MB_2U(SCH_1):PAGE51
   J17  254  DQ7_B SCONN288_ADR50017P130CC-SCONN2A    I12 @S9S_MB_2U_LIB.S9S_MB_2U(SCH_1):PAGE98
   J18  254  DQ7_B SCONN288_ADR50017P087CC-SCONN2A    I24 @S9S_MB_2U_LIB.S9S_MB_2U(SCH_1):PAGE99

M_A_CPU1_SB_DQ<8> @S9S_MB_2U_LIB.S9S_MB_2U(SCH_1):M_A_CPU1_SB_DQ(8)
    U1  C29 DDR0_SB_DQ8 SOCKET4677_AZIF0045P001C01CS-SA     I2 @S9S_MB_2U_LIB.S9S_MB_2U(SCH_1):PAGE51
   J17  111  DQ8_B SCONN288_ADR50017P130CC-SCONN2A    I12 @S9S_MB_2U_LIB.S9S_MB_2U(SCH_1):PAGE98
   J18  111  DQ8_B SCONN288_ADR50017P087CC-SCONN2A    I24 @S9S_MB_2U_LIB.S9S_MB_2U(SCH_1):PAGE99

M_A_CPU1_SB_DQ<9> @S9S_MB_2U_LIB.S9S_MB_2U(SCH_1):M_A_CPU1_SB_DQ(9)
    U1  B28 DDR0_SB_DQ9 SOCKET4677_AZIF0045P001C01CS-SA     I2 @S9S_MB_2U_LIB.S9S_MB_2U(SCH_1):PAGE51
   J17  113  DQ9_B SCONN288_ADR50017P130CC-SCONN2A    I12 @S9S_MB_2U_LIB.S9S_MB_2U(SCH_1):PAGE98
   J18  113  DQ9_B SCONN288_ADR50017P087CC-SCONN2A    I24 @S9S_MB_2U_LIB.S9S_MB_2U(SCH_1):PAGE99

M_A_CPU1_SB_DQS_DN<0> @S9S_MB_2U_LIB.S9S_MB_2U(SCH_1):M_A_CPU1_SB_DQS_DN(0)
    U1  H30 DDR0_SB_DQS_DN0 SOCKET4677_AZIF0045P001C01CS-SA     I2 @S9S_MB_2U_LIB.S9S_MB_2U(SCH_1):PAGE51
   J17  105 DQS0_B_C SCONN288_ADR50017P130CC-SCONN2A   I178 @S9S_MB_2U_LIB.S9S_MB_2U(SCH_1):PAGE98
   J18  105 DQS0_B_C SCONN288_ADR50017P087CC-SCONN2A   I178 @S9S_MB_2U_LIB.S9S_MB_2U(SCH_1):PAGE99

M_A_CPU1_SB_DQS_DN<1> @S9S_MB_2U_LIB.S9S_MB_2U(SCH_1):M_A_CPU1_SB_DQS_DN(1)
    U1  A27 DDR0_SB_DQS_DN1 SOCKET4677_AZIF0045P001C01CS-SA     I2 @S9S_MB_2U_LIB.S9S_MB_2U(SCH_1):PAGE51
   J17  116 DQS1_B_C SCONN288_ADR50017P130CC-SCONN2A   I178 @S9S_MB_2U_LIB.S9S_MB_2U(SCH_1):PAGE98
   J18  116 DQS1_B_C SCONN288_ADR50017P087CC-SCONN2A   I178 @S9S_MB_2U_LIB.S9S_MB_2U(SCH_1):PAGE99

M_A_CPU1_SB_DQS_DN<2> @S9S_MB_2U_LIB.S9S_MB_2U(SCH_1):M_A_CPU1_SB_DQS_DN(2)
    U1  A21 DDR0_SB_DQS_DN2 SOCKET4677_AZIF0045P001C01CS-SA     I2 @S9S_MB_2U_LIB.S9S_MB_2U(SCH_1):PAGE51
   J17  127 DQS2_B_C SCONN288_ADR50017P130CC-SCONN2A   I178 @S9S_MB_2U_LIB.S9S_MB_2U(SCH_1):PAGE98
   J18  127 DQS2_B_C SCONN288_ADR50017P087CC-SCONN2A   I178 @S9S_MB_2U_LIB.S9S_MB_2U(SCH_1):PAGE99

M_A_CPU1_SB_DQS_DN<3> @S9S_MB_2U_LIB.S9S_MB_2U(SCH_1):M_A_CPU1_SB_DQS_DN(3)
    U1   A9 DDR0_SB_DQS_DN3 SOCKET4677_AZIF0045P001C01CS-SA     I2 @S9S_MB_2U_LIB.S9S_MB_2U(SCH_1):PAGE51
   J17  138 DQS3_B_C SCONN288_ADR50017P130CC-SCONN2A   I178 @S9S_MB_2U_LIB.S9S_MB_2U(SCH_1):PAGE98
   J18  138 DQS3_B_C SCONN288_ADR50017P087CC-SCONN2A   I178 @S9S_MB_2U_LIB.S9S_MB_2U(SCH_1):PAGE99

M_A_CPU1_SB_DQS_DN<4> @S9S_MB_2U_LIB.S9S_MB_2U(SCH_1):M_A_CPU1_SB_DQS_DN(4)
    U1  G33 DDR0_SB_DQS_DN4 SOCKET4677_AZIF0045P001C01CS-SA     I2 @S9S_MB_2U_LIB.S9S_MB_2U(SCH_1):PAGE51
   J17  238 DQS4_B_C SCONN288_ADR50017P130CC-SCONN2A   I178 @S9S_MB_2U_LIB.S9S_MB_2U(SCH_1):PAGE98
   J18  238 DQS4_B_C SCONN288_ADR50017P087CC-SCONN2A   I178 @S9S_MB_2U_LIB.S9S_MB_2U(SCH_1):PAGE99

M_A_CPU1_SB_DQS_DN<5> @S9S_MB_2U_LIB.S9S_MB_2U(SCH_1):M_A_CPU1_SB_DQS_DN(5)
    U1  M30 DDR0_SB_DQS_DN5 SOCKET4677_AZIF0045P001C01CS-SA     I2 @S9S_MB_2U_LIB.S9S_MB_2U(SCH_1):PAGE51
   J17  249 DQS5_B_C||TDQS5_B_C SCONN288_ADR50017P130CC-SCONN2A   I178 @S9S_MB_2U_LIB.S9S_MB_2U(SCH_1):PAGE98
   J18  249 DQS5_B_C||TDQS5_B_C SCONN288_ADR50017P087CC-SCONN2A   I178 @S9S_MB_2U_LIB.S9S_MB_2U(SCH_1):PAGE99

M_A_CPU1_SB_DQS_DN<6> @S9S_MB_2U_LIB.S9S_MB_2U(SCH_1):M_A_CPU1_SB_DQS_DN(6)
    U1  G27 DDR0_SB_DQS_DN6 SOCKET4677_AZIF0045P001C01CS-SA     I2 @S9S_MB_2U_LIB.S9S_MB_2U(SCH_1):PAGE51
   J17  260 DQS6_B_C||TDQS6_B_C SCONN288_ADR50017P130CC-SCONN2A   I178 @S9S_MB_2U_LIB.S9S_MB_2U(SCH_1):PAGE98
   J18  260 DQS6_B_C||TDQS6_B_C SCONN288_ADR50017P087CC-SCONN2A   I178 @S9S_MB_2U_LIB.S9S_MB_2U(SCH_1):PAGE99

M_A_CPU1_SB_DQS_DN<7> @S9S_MB_2U_LIB.S9S_MB_2U(SCH_1):M_A_CPU1_SB_DQS_DN(7)
    U1  G21 DDR0_SB_DQS_DN7 SOCKET4677_AZIF0045P001C01CS-SA     I2 @S9S_MB_2U_LIB.S9S_MB_2U(SCH_1):PAGE51
   J17  271 DQS7_B_C||TDQS7_B_C SCONN288_ADR50017P130CC-SCONN2A   I178 @S9S_MB_2U_LIB.S9S_MB_2U(SCH_1):PAGE98
   J18  271 DQS7_B_C||TDQS7_B_C SCONN288_ADR50017P087CC-SCONN2A   I178 @S9S_MB_2U_LIB.S9S_MB_2U(SCH_1):PAGE99

M_A_CPU1_SB_DQS_DN<8> @S9S_MB_2U_LIB.S9S_MB_2U(SCH_1):M_A_CPU1_SB_DQS_DN(8)
    U1   G9 DDR0_SB_DQS_DN8 SOCKET4677_AZIF0045P001C01CS-SA     I2 @S9S_MB_2U_LIB.S9S_MB_2U(SCH_1):PAGE51
   J17  282 DQS8_B_C||TDQS8_B_C SCONN288_ADR50017P130CC-SCONN2A   I178 @S9S_MB_2U_LIB.S9S_MB_2U(SCH_1):PAGE98
   J18  282 DQS8_B_C||TDQS8_B_C SCONN288_ADR50017P087CC-SCONN2A   I178 @S9S_MB_2U_LIB.S9S_MB_2U(SCH_1):PAGE99

M_A_CPU1_SB_DQS_DN<9> @S9S_MB_2U_LIB.S9S_MB_2U(SCH_1):M_A_CPU1_SB_DQS_DN(9)
    U1  A33 DDR0_SB_DQS_DN9 SOCKET4677_AZIF0045P001C01CS-SA     I2 @S9S_MB_2U_LIB.S9S_MB_2U(SCH_1):PAGE51
   J17   94 DQS9_B_C||TDQS9_B_C SCONN288_ADR50017P130CC-SCONN2A   I178 @S9S_MB_2U_LIB.S9S_MB_2U(SCH_1):PAGE98
   J18   94 DQS9_B_C||TDQS9_B_C SCONN288_ADR50017P087CC-SCONN2A   I178 @S9S_MB_2U_LIB.S9S_MB_2U(SCH_1):PAGE99

M_A_CPU1_SB_DQS_DP<0> @S9S_MB_2U_LIB.S9S_MB_2U(SCH_1):M_A_CPU1_SB_DQS_DP(0)
    U1  K30 DDR0_SB_DQS_DP0 SOCKET4677_AZIF0045P001C01CS-SA     I2 @S9S_MB_2U_LIB.S9S_MB_2U(SCH_1):PAGE51
   J17  104 DQS0_B_T SCONN288_ADR50017P130CC-SCONN2A   I178 @S9S_MB_2U_LIB.S9S_MB_2U(SCH_1):PAGE98
   J18  104 DQS0_B_T SCONN288_ADR50017P087CC-SCONN2A   I178 @S9S_MB_2U_LIB.S9S_MB_2U(SCH_1):PAGE99

M_A_CPU1_SB_DQS_DP<1> @S9S_MB_2U_LIB.S9S_MB_2U(SCH_1):M_A_CPU1_SB_DQS_DP(1)
    U1  C27 DDR0_SB_DQS_DP1 SOCKET4677_AZIF0045P001C01CS-SA     I2 @S9S_MB_2U_LIB.S9S_MB_2U(SCH_1):PAGE51
   J17  115 DQS1_B_T SCONN288_ADR50017P130CC-SCONN2A   I178 @S9S_MB_2U_LIB.S9S_MB_2U(SCH_1):PAGE98
   J18  115 DQS1_B_T SCONN288_ADR50017P087CC-SCONN2A   I178 @S9S_MB_2U_LIB.S9S_MB_2U(SCH_1):PAGE99

M_A_CPU1_SB_DQS_DP<2> @S9S_MB_2U_LIB.S9S_MB_2U(SCH_1):M_A_CPU1_SB_DQS_DP(2)
    U1  C21 DDR0_SB_DQS_DP2 SOCKET4677_AZIF0045P001C01CS-SA     I2 @S9S_MB_2U_LIB.S9S_MB_2U(SCH_1):PAGE51
   J17  126 DQS2_B_T SCONN288_ADR50017P130CC-SCONN2A   I178 @S9S_MB_2U_LIB.S9S_MB_2U(SCH_1):PAGE98
   J18  126 DQS2_B_T SCONN288_ADR50017P087CC-SCONN2A   I178 @S9S_MB_2U_LIB.S9S_MB_2U(SCH_1):PAGE99

M_A_CPU1_SB_DQS_DP<3> @S9S_MB_2U_LIB.S9S_MB_2U(SCH_1):M_A_CPU1_SB_DQS_DP(3)
    U1   C9 DDR0_SB_DQS_DP3 SOCKET4677_AZIF0045P001C01CS-SA     I2 @S9S_MB_2U_LIB.S9S_MB_2U(SCH_1):PAGE51
   J17  137 DQS3_B_T SCONN288_ADR50017P130CC-SCONN2A   I178 @S9S_MB_2U_LIB.S9S_MB_2U(SCH_1):PAGE98
   J18  137 DQS3_B_T SCONN288_ADR50017P087CC-SCONN2A   I178 @S9S_MB_2U_LIB.S9S_MB_2U(SCH_1):PAGE99

M_A_CPU1_SB_DQS_DP<4> @S9S_MB_2U_LIB.S9S_MB_2U(SCH_1):M_A_CPU1_SB_DQS_DP(4)
    U1  E33 DDR0_SB_DQS_DP4 SOCKET4677_AZIF0045P001C01CS-SA     I2 @S9S_MB_2U_LIB.S9S_MB_2U(SCH_1):PAGE51
   J17  239 DQS4_B_T SCONN288_ADR50017P130CC-SCONN2A   I178 @S9S_MB_2U_LIB.S9S_MB_2U(SCH_1):PAGE98
   J18  239 DQS4_B_T SCONN288_ADR50017P087CC-SCONN2A   I178 @S9S_MB_2U_LIB.S9S_MB_2U(SCH_1):PAGE99

M_A_CPU1_SB_DQS_DP<5> @S9S_MB_2U_LIB.S9S_MB_2U(SCH_1):M_A_CPU1_SB_DQS_DP(5)
    U1  P30 DDR0_SB_DQS_DP5 SOCKET4677_AZIF0045P001C01CS-SA     I2 @S9S_MB_2U_LIB.S9S_MB_2U(SCH_1):PAGE51
   J17  250 DQS5_B_T||TDQS5_B_T SCONN288_ADR50017P130CC-SCONN2A   I178 @S9S_MB_2U_LIB.S9S_MB_2U(SCH_1):PAGE98
   J18  250 DQS5_B_T||TDQS5_B_T SCONN288_ADR50017P087CC-SCONN2A   I178 @S9S_MB_2U_LIB.S9S_MB_2U(SCH_1):PAGE99

M_A_CPU1_SB_DQS_DP<6> @S9S_MB_2U_LIB.S9S_MB_2U(SCH_1):M_A_CPU1_SB_DQS_DP(6)
    U1  E27 DDR0_SB_DQS_DP6 SOCKET4677_AZIF0045P001C01CS-SA     I2 @S9S_MB_2U_LIB.S9S_MB_2U(SCH_1):PAGE51
   J17  261 DQS6_B_T||TDQS6_B_T SCONN288_ADR50017P130CC-SCONN2A   I178 @S9S_MB_2U_LIB.S9S_MB_2U(SCH_1):PAGE98
   J18  261 DQS6_B_T||TDQS6_B_T SCONN288_ADR50017P087CC-SCONN2A   I178 @S9S_MB_2U_LIB.S9S_MB_2U(SCH_1):PAGE99

M_A_CPU1_SB_DQS_DP<7> @S9S_MB_2U_LIB.S9S_MB_2U(SCH_1):M_A_CPU1_SB_DQS_DP(7)
    U1  E21 DDR0_SB_DQS_DP7 SOCKET4677_AZIF0045P001C01CS-SA     I2 @S9S_MB_2U_LIB.S9S_MB_2U(SCH_1):PAGE51
   J17  272 DQS7_B_T||TDQS7_B_T SCONN288_ADR50017P130CC-SCONN2A   I178 @S9S_MB_2U_LIB.S9S_MB_2U(SCH_1):PAGE98
   J18  272 DQS7_B_T||TDQS7_B_T SCONN288_ADR50017P087CC-SCONN2A   I178 @S9S_MB_2U_LIB.S9S_MB_2U(SCH_1):PAGE99

M_A_CPU1_SB_DQS_DP<8> @S9S_MB_2U_LIB.S9S_MB_2U(SCH_1):M_A_CPU1_SB_DQS_DP(8)
    U1   E9 DDR0_SB_DQS_DP8 SOCKET4677_AZIF0045P001C01CS-SA     I2 @S9S_MB_2U_LIB.S9S_MB_2U(SCH_1):PAGE51
   J17  283 DQS8_B_T||TDQS8_B_T SCONN288_ADR50017P130CC-SCONN2A   I178 @S9S_MB_2U_LIB.S9S_MB_2U(SCH_1):PAGE98
   J18  283 DQS8_B_T||TDQS8_B_T SCONN288_ADR50017P087CC-SCONN2A   I178 @S9S_MB_2U_LIB.S9S_MB_2U(SCH_1):PAGE99

M_A_CPU1_SB_DQS_DP<9> @S9S_MB_2U_LIB.S9S_MB_2U(SCH_1):M_A_CPU1_SB_DQS_DP(9)
    U1  C33 DDR0_SB_DQS_DP9 SOCKET4677_AZIF0045P001C01CS-SA     I2 @S9S_MB_2U_LIB.S9S_MB_2U(SCH_1):PAGE51
   J17   93 DQS9_B_T||TDQS9_B_T||DBI4_B_N SCONN288_ADR50017P130CC-SCONN2A   I178 @S9S_MB_2U_LIB.S9S_MB_2U(SCH_1):PAGE98
   J18   93 DQS9_B_T||TDQS9_B_T||DBI4_B_N SCONN288_ADR50017P087CC-SCONN2A   I178 @S9S_MB_2U_LIB.S9S_MB_2U(SCH_1):PAGE99

M_A_CPU1_SB_PAR @S9S_MB_2U_LIB.S9S_MB_2U(SCH_1):M_A_CPU1_SB_PAR
    U1  G39 DDR0_SB_PAR SOCKET4677_AZIF0045P001C01CS-SA     I2 @S9S_MB_2U_LIB.S9S_MB_2U(SCH_1):PAGE51
   J17  227  PAR_B SCONN288_ADR50017P130CC-SCONN2A    I12 @S9S_MB_2U_LIB.S9S_MB_2U(SCH_1):PAGE98
   J18  227  PAR_B SCONN288_ADR50017P087CC-SCONN2A    I24 @S9S_MB_2U_LIB.S9S_MB_2U(SCH_1):PAGE99

M_A_CPU1_SB_RSP<0> @S9S_MB_2U_LIB.S9S_MB_2U(SCH_1):M_A_CPU1_SB_RSP(0)
    U1 AV44 DDR0_B_RSP0 SOCKET4677_AZIF0045P001C01CS-SA     I2 @S9S_MB_2U_LIB.S9S_MB_2U(SCH_1):PAGE51
   J17   87 LBS||RSP_B_N SCONN288_ADR50017P130CC-SCONN2A    I12 @S9S_MB_2U_LIB.S9S_MB_2U(SCH_1):PAGE98

M_A_CPU1_SB_RSP<1> @S9S_MB_2U_LIB.S9S_MB_2U(SCH_1):M_A_CPU1_SB_RSP(1)
    U1 AV42 DDR0_B_RSP1 SOCKET4677_AZIF0045P001C01CS-SA     I2 @S9S_MB_2U_LIB.S9S_MB_2U(SCH_1):PAGE51
   J18   87 LBS||RSP_B_N SCONN288_ADR50017P087CC-SCONN2A    I24 @S9S_MB_2U_LIB.S9S_MB_2U(SCH_1):PAGE99

M_B_CPU0_ALERT_N @S9S_MB_2U_LIB.S9S_MB_2U(SCH_1):M_B_CPU0_ALERT_N
    U2 AV49 DDR1_ALERT_N SOCKET4677_AZIF0045P001C01CS-SA   I169 @S9S_MB_2U_LIB.S9S_MB_2U(SCH_1):PAGE21
    J4   62 ALERT_N SCONN288_ADR50017P087CC-SCONN2A    I23 @S9S_MB_2U_LIB.S9S_MB_2U(SCH_1):PAGE85
    J3   62 ALERT_N SCONN288_ADR50017P130CC-SCONN2A   I180 @S9S_MB_2U_LIB.S9S_MB_2U(SCH_1):PAGE84

M_B_CPU0_CLK_DN<0> @S9S_MB_2U_LIB.S9S_MB_2U(SCH_1):M_B_CPU0_CLK_DN(0)
    U2  R45 DDR1_CLK_DN0 SOCKET4677_AZIF0045P001C01CS-SA   I169 @S9S_MB_2U_LIB.S9S_MB_2U(SCH_1):PAGE21
    J3  218   CK_C SCONN288_ADR50017P130CC-SCONN2A   I180 @S9S_MB_2U_LIB.S9S_MB_2U(SCH_1):PAGE84

M_B_CPU0_CLK_DN<1> @S9S_MB_2U_LIB.S9S_MB_2U(SCH_1):M_B_CPU0_CLK_DN(1)
    U2  W45 DDR1_CLK_DN1 SOCKET4677_AZIF0045P001C01CS-SA   I169 @S9S_MB_2U_LIB.S9S_MB_2U(SCH_1):PAGE21
    J4  218   CK_C SCONN288_ADR50017P087CC-SCONN2A    I23 @S9S_MB_2U_LIB.S9S_MB_2U(SCH_1):PAGE85

M_B_CPU0_CLK_DP<0> @S9S_MB_2U_LIB.S9S_MB_2U(SCH_1):M_B_CPU0_CLK_DP(0)
    U2  U45 DDR1_CLK_DP0 SOCKET4677_AZIF0045P001C01CS-SA   I169 @S9S_MB_2U_LIB.S9S_MB_2U(SCH_1):PAGE21
    J3  217   CK_T SCONN288_ADR50017P130CC-SCONN2A   I180 @S9S_MB_2U_LIB.S9S_MB_2U(SCH_1):PAGE84

M_B_CPU0_CLK_DP<1> @S9S_MB_2U_LIB.S9S_MB_2U(SCH_1):M_B_CPU0_CLK_DP(1)
    U2 AA45 DDR1_CLK_DP1 SOCKET4677_AZIF0045P001C01CS-SA   I169 @S9S_MB_2U_LIB.S9S_MB_2U(SCH_1):PAGE21
    J4  217   CK_T SCONN288_ADR50017P087CC-SCONN2A    I23 @S9S_MB_2U_LIB.S9S_MB_2U(SCH_1):PAGE85

M_B_CPU0_SA_CA<0> @S9S_MB_2U_LIB.S9S_MB_2U(SCH_1):M_B_CPU0_SA_CA(0)
    U2  H49 DDR1_SA_CA0 SOCKET4677_AZIF0045P001C01CS-SA   I169 @S9S_MB_2U_LIB.S9S_MB_2U(SCH_1):PAGE21
    J4   66  CA0_A SCONN288_ADR50017P087CC-SCONN2A    I23 @S9S_MB_2U_LIB.S9S_MB_2U(SCH_1):PAGE85
    J3   66  CA0_A SCONN288_ADR50017P130CC-SCONN2A   I180 @S9S_MB_2U_LIB.S9S_MB_2U(SCH_1):PAGE84

M_B_CPU0_SA_CA<1> @S9S_MB_2U_LIB.S9S_MB_2U(SCH_1):M_B_CPU0_SA_CA(1)
    U2  P49 DDR1_SA_CA1 SOCKET4677_AZIF0045P001C01CS-SA   I169 @S9S_MB_2U_LIB.S9S_MB_2U(SCH_1):PAGE21
    J4  211  CA1_A SCONN288_ADR50017P087CC-SCONN2A    I23 @S9S_MB_2U_LIB.S9S_MB_2U(SCH_1):PAGE85
    J3  211  CA1_A SCONN288_ADR50017P130CC-SCONN2A   I180 @S9S_MB_2U_LIB.S9S_MB_2U(SCH_1):PAGE84

M_B_CPU0_SA_CA<2> @S9S_MB_2U_LIB.S9S_MB_2U(SCH_1):M_B_CPU0_SA_CA(2)
    U2  J48 DDR1_SA_CA2 SOCKET4677_AZIF0045P001C01CS-SA   I169 @S9S_MB_2U_LIB.S9S_MB_2U(SCH_1):PAGE21
    J4   68  CA2_A SCONN288_ADR50017P087CC-SCONN2A    I23 @S9S_MB_2U_LIB.S9S_MB_2U(SCH_1):PAGE85
    J3   68  CA2_A SCONN288_ADR50017P130CC-SCONN2A   I180 @S9S_MB_2U_LIB.S9S_MB_2U(SCH_1):PAGE84

M_B_CPU0_SA_CA<3> @S9S_MB_2U_LIB.S9S_MB_2U(SCH_1):M_B_CPU0_SA_CA(3)
    U2  N48 DDR1_SA_CA3 SOCKET4677_AZIF0045P001C01CS-SA   I169 @S9S_MB_2U_LIB.S9S_MB_2U(SCH_1):PAGE21
    J4  213  CA3_A SCONN288_ADR50017P087CC-SCONN2A    I23 @S9S_MB_2U_LIB.S9S_MB_2U(SCH_1):PAGE85
    J3  213  CA3_A SCONN288_ADR50017P130CC-SCONN2A   I180 @S9S_MB_2U_LIB.S9S_MB_2U(SCH_1):PAGE84

M_B_CPU0_SA_CA<4> @S9S_MB_2U_LIB.S9S_MB_2U(SCH_1):M_B_CPU0_SA_CA(4)
    U2  K47 DDR1_SA_CA4 SOCKET4677_AZIF0045P001C01CS-SA   I169 @S9S_MB_2U_LIB.S9S_MB_2U(SCH_1):PAGE21
    J4   70  CA4_A SCONN288_ADR50017P087CC-SCONN2A    I23 @S9S_MB_2U_LIB.S9S_MB_2U(SCH_1):PAGE85
    J3   70  CA4_A SCONN288_ADR50017P130CC-SCONN2A   I180 @S9S_MB_2U_LIB.S9S_MB_2U(SCH_1):PAGE84

M_B_CPU0_SA_CA<5> @S9S_MB_2U_LIB.S9S_MB_2U(SCH_1):M_B_CPU0_SA_CA(5)
    U2  M47 DDR1_SA_CA5 SOCKET4677_AZIF0045P001C01CS-SA   I169 @S9S_MB_2U_LIB.S9S_MB_2U(SCH_1):PAGE21
    J4  215  CA5_A SCONN288_ADR50017P087CC-SCONN2A    I23 @S9S_MB_2U_LIB.S9S_MB_2U(SCH_1):PAGE85
    J3  215  CA5_A SCONN288_ADR50017P130CC-SCONN2A   I180 @S9S_MB_2U_LIB.S9S_MB_2U(SCH_1):PAGE84

M_B_CPU0_SA_CA<6> @S9S_MB_2U_LIB.S9S_MB_2U(SCH_1):M_B_CPU0_SA_CA(6)
    U2  Y44 DDR1_SA_CA6 SOCKET4677_AZIF0045P001C01CS-SA   I169 @S9S_MB_2U_LIB.S9S_MB_2U(SCH_1):PAGE21
    J4   72  CA6_A SCONN288_ADR50017P087CC-SCONN2A    I23 @S9S_MB_2U_LIB.S9S_MB_2U(SCH_1):PAGE85
    J3   72  CA6_A SCONN288_ADR50017P130CC-SCONN2A   I180 @S9S_MB_2U_LIB.S9S_MB_2U(SCH_1):PAGE84

M_B_CPU0_SA_CB<0> @S9S_MB_2U_LIB.S9S_MB_2U(SCH_1):M_B_CPU0_SA_CB(0)
    U2  K57 DDR1_SA_ECC0 SOCKET4677_AZIF0045P001C01CS-SA   I169 @S9S_MB_2U_LIB.S9S_MB_2U(SCH_1):PAGE21
    J4   51  CB0_A SCONN288_ADR50017P087CC-SCONN2A    I23 @S9S_MB_2U_LIB.S9S_MB_2U(SCH_1):PAGE85
    J3   51  CB0_A SCONN288_ADR50017P130CC-SCONN2A   I180 @S9S_MB_2U_LIB.S9S_MB_2U(SCH_1):PAGE84

M_B_CPU0_SA_CB<1> @S9S_MB_2U_LIB.S9S_MB_2U(SCH_1):M_B_CPU0_SA_CB(1)
    U2  J56 DDR1_SA_ECC1 SOCKET4677_AZIF0045P001C01CS-SA   I169 @S9S_MB_2U_LIB.S9S_MB_2U(SCH_1):PAGE21
    J4   53  CB1_A SCONN288_ADR50017P087CC-SCONN2A    I23 @S9S_MB_2U_LIB.S9S_MB_2U(SCH_1):PAGE85
    J3   53  CB1_A SCONN288_ADR50017P130CC-SCONN2A   I180 @S9S_MB_2U_LIB.S9S_MB_2U(SCH_1):PAGE84

M_B_CPU0_SA_CB<2> @S9S_MB_2U_LIB.S9S_MB_2U(SCH_1):M_B_CPU0_SA_CB(2)
    U2  M57 DDR1_SA_ECC2 SOCKET4677_AZIF0045P001C01CS-SA   I169 @S9S_MB_2U_LIB.S9S_MB_2U(SCH_1):PAGE21
    J4  196  CB2_A SCONN288_ADR50017P087CC-SCONN2A    I23 @S9S_MB_2U_LIB.S9S_MB_2U(SCH_1):PAGE85
    J3  196  CB2_A SCONN288_ADR50017P130CC-SCONN2A   I180 @S9S_MB_2U_LIB.S9S_MB_2U(SCH_1):PAGE84

M_B_CPU0_SA_CB<3> @S9S_MB_2U_LIB.S9S_MB_2U(SCH_1):M_B_CPU0_SA_CB(3)
    U2  N56 DDR1_SA_ECC3 SOCKET4677_AZIF0045P001C01CS-SA   I169 @S9S_MB_2U_LIB.S9S_MB_2U(SCH_1):PAGE21
    J4  198  CB3_A SCONN288_ADR50017P087CC-SCONN2A    I23 @S9S_MB_2U_LIB.S9S_MB_2U(SCH_1):PAGE85
    J3  198  CB3_A SCONN288_ADR50017P130CC-SCONN2A   I180 @S9S_MB_2U_LIB.S9S_MB_2U(SCH_1):PAGE84

M_B_CPU0_SA_CB<4> @S9S_MB_2U_LIB.S9S_MB_2U(SCH_1):M_B_CPU0_SA_CB(4)
    U2  J54 DDR1_SA_ECC4 SOCKET4677_AZIF0045P001C01CS-SA   I169 @S9S_MB_2U_LIB.S9S_MB_2U(SCH_1):PAGE21
    J4   58  CB4_A SCONN288_ADR50017P087CC-SCONN2A    I23 @S9S_MB_2U_LIB.S9S_MB_2U(SCH_1):PAGE85
    J3   58  CB4_A SCONN288_ADR50017P130CC-SCONN2A   I180 @S9S_MB_2U_LIB.S9S_MB_2U(SCH_1):PAGE84

M_B_CPU0_SA_CB<5> @S9S_MB_2U_LIB.S9S_MB_2U(SCH_1):M_B_CPU0_SA_CB(5)
    U2  K53 DDR1_SA_ECC5 SOCKET4677_AZIF0045P001C01CS-SA   I169 @S9S_MB_2U_LIB.S9S_MB_2U(SCH_1):PAGE21
    J4   60  CB5_A SCONN288_ADR50017P087CC-SCONN2A    I23 @S9S_MB_2U_LIB.S9S_MB_2U(SCH_1):PAGE85
    J3   60  CB5_A SCONN288_ADR50017P130CC-SCONN2A   I180 @S9S_MB_2U_LIB.S9S_MB_2U(SCH_1):PAGE84

M_B_CPU0_SA_CB<6> @S9S_MB_2U_LIB.S9S_MB_2U(SCH_1):M_B_CPU0_SA_CB(6)
    U2  N54 DDR1_SA_ECC6 SOCKET4677_AZIF0045P001C01CS-SA   I169 @S9S_MB_2U_LIB.S9S_MB_2U(SCH_1):PAGE21
    J4  203  CB6_A SCONN288_ADR50017P087CC-SCONN2A    I23 @S9S_MB_2U_LIB.S9S_MB_2U(SCH_1):PAGE85
    J3  203  CB6_A SCONN288_ADR50017P130CC-SCONN2A   I180 @S9S_MB_2U_LIB.S9S_MB_2U(SCH_1):PAGE84

M_B_CPU0_SA_CB<7> @S9S_MB_2U_LIB.S9S_MB_2U(SCH_1):M_B_CPU0_SA_CB(7)
    U2  M53 DDR1_SA_ECC7 SOCKET4677_AZIF0045P001C01CS-SA   I169 @S9S_MB_2U_LIB.S9S_MB_2U(SCH_1):PAGE21
    J4  205  CB7_A SCONN288_ADR50017P087CC-SCONN2A    I23 @S9S_MB_2U_LIB.S9S_MB_2U(SCH_1):PAGE85
    J3  205  CB7_A SCONN288_ADR50017P130CC-SCONN2A   I180 @S9S_MB_2U_LIB.S9S_MB_2U(SCH_1):PAGE84

M_B_CPU0_SA_CS_N<0> @S9S_MB_2U_LIB.S9S_MB_2U(SCH_1):M_B_CPU0_SA_CS_N(0)
    U2  K51 DDR1_SA_CS_N0 SOCKET4677_AZIF0045P001C01CS-SA   I169 @S9S_MB_2U_LIB.S9S_MB_2U(SCH_1):PAGE21
    J3   64 CS0_A_N SCONN288_ADR50017P130CC-SCONN2A   I180 @S9S_MB_2U_LIB.S9S_MB_2U(SCH_1):PAGE84

M_B_CPU0_SA_CS_N<1> @S9S_MB_2U_LIB.S9S_MB_2U(SCH_1):M_B_CPU0_SA_CS_N(1)
    U2  J50 DDR1_SA_CS_N1 SOCKET4677_AZIF0045P001C01CS-SA   I169 @S9S_MB_2U_LIB.S9S_MB_2U(SCH_1):PAGE21
    J3  209 CS1_A_N SCONN288_ADR50017P130CC-SCONN2A   I180 @S9S_MB_2U_LIB.S9S_MB_2U(SCH_1):PAGE84

M_B_CPU0_SA_CS_N<2> @S9S_MB_2U_LIB.S9S_MB_2U(SCH_1):M_B_CPU0_SA_CS_N(2)
    U2  M51 DDR1_SA_CS_N2 SOCKET4677_AZIF0045P001C01CS-SA   I169 @S9S_MB_2U_LIB.S9S_MB_2U(SCH_1):PAGE21
    J4   64 CS0_A_N SCONN288_ADR50017P087CC-SCONN2A    I23 @S9S_MB_2U_LIB.S9S_MB_2U(SCH_1):PAGE85

M_B_CPU0_SA_CS_N<3> @S9S_MB_2U_LIB.S9S_MB_2U(SCH_1):M_B_CPU0_SA_CS_N(3)
    U2  N50 DDR1_SA_CS_N3 SOCKET4677_AZIF0045P001C01CS-SA   I169 @S9S_MB_2U_LIB.S9S_MB_2U(SCH_1):PAGE21
    J4  209 CS1_A_N SCONN288_ADR50017P087CC-SCONN2A    I23 @S9S_MB_2U_LIB.S9S_MB_2U(SCH_1):PAGE85

M_B_CPU0_SA_DQ<0> @S9S_MB_2U_LIB.S9S_MB_2U(SCH_1):M_B_CPU0_SA_DQ(0)
    U2  K75 DDR1_SA_DQ0 SOCKET4677_AZIF0045P001C01CS-SA   I169 @S9S_MB_2U_LIB.S9S_MB_2U(SCH_1):PAGE21
    J4    7  DQ0_A SCONN288_ADR50017P087CC-SCONN2A    I23 @S9S_MB_2U_LIB.S9S_MB_2U(SCH_1):PAGE85
    J3    7  DQ0_A SCONN288_ADR50017P130CC-SCONN2A   I180 @S9S_MB_2U_LIB.S9S_MB_2U(SCH_1):PAGE84

M_B_CPU0_SA_DQ<10> @S9S_MB_2U_LIB.S9S_MB_2U(SCH_1):M_B_CPU0_SA_DQ(10)
    U2  W72 DDR1_SA_DQ10 SOCKET4677_AZIF0045P001C01CS-SA   I169 @S9S_MB_2U_LIB.S9S_MB_2U(SCH_1):PAGE21
    J4  163 DQ10_A SCONN288_ADR50017P087CC-SCONN2A    I23 @S9S_MB_2U_LIB.S9S_MB_2U(SCH_1):PAGE85
    J3  163 DQ10_A SCONN288_ADR50017P130CC-SCONN2A   I180 @S9S_MB_2U_LIB.S9S_MB_2U(SCH_1):PAGE84

M_B_CPU0_SA_DQ<11> @S9S_MB_2U_LIB.S9S_MB_2U(SCH_1):M_B_CPU0_SA_DQ(11)
    U2  Y71 DDR1_SA_DQ11 SOCKET4677_AZIF0045P001C01CS-SA   I169 @S9S_MB_2U_LIB.S9S_MB_2U(SCH_1):PAGE21
    J4  165 DQ11_A SCONN288_ADR50017P087CC-SCONN2A    I23 @S9S_MB_2U_LIB.S9S_MB_2U(SCH_1):PAGE85
    J3  165 DQ11_A SCONN288_ADR50017P130CC-SCONN2A   I180 @S9S_MB_2U_LIB.S9S_MB_2U(SCH_1):PAGE84

M_B_CPU0_SA_DQ<12> @S9S_MB_2U_LIB.S9S_MB_2U(SCH_1):M_B_CPU0_SA_DQ(12)
    U2  T69 DDR1_SA_DQ12 SOCKET4677_AZIF0045P001C01CS-SA   I169 @S9S_MB_2U_LIB.S9S_MB_2U(SCH_1):PAGE21
    J4   25 DQ12_A SCONN288_ADR50017P087CC-SCONN2A    I23 @S9S_MB_2U_LIB.S9S_MB_2U(SCH_1):PAGE85
    J3   25 DQ12_A SCONN288_ADR50017P130CC-SCONN2A   I180 @S9S_MB_2U_LIB.S9S_MB_2U(SCH_1):PAGE84

M_B_CPU0_SA_DQ<13> @S9S_MB_2U_LIB.S9S_MB_2U(SCH_1):M_B_CPU0_SA_DQ(13)
    U2  U68 DDR1_SA_DQ13 SOCKET4677_AZIF0045P001C01CS-SA   I169 @S9S_MB_2U_LIB.S9S_MB_2U(SCH_1):PAGE21
    J4   27 DQ13_A SCONN288_ADR50017P087CC-SCONN2A    I23 @S9S_MB_2U_LIB.S9S_MB_2U(SCH_1):PAGE85
    J3   27 DQ13_A SCONN288_ADR50017P130CC-SCONN2A   I180 @S9S_MB_2U_LIB.S9S_MB_2U(SCH_1):PAGE84

M_B_CPU0_SA_DQ<14> @S9S_MB_2U_LIB.S9S_MB_2U(SCH_1):M_B_CPU0_SA_DQ(14)
    U2  Y69 DDR1_SA_DQ14 SOCKET4677_AZIF0045P001C01CS-SA   I169 @S9S_MB_2U_LIB.S9S_MB_2U(SCH_1):PAGE21
    J4  170 DQ14_A SCONN288_ADR50017P087CC-SCONN2A    I23 @S9S_MB_2U_LIB.S9S_MB_2U(SCH_1):PAGE85
    J3  170 DQ14_A SCONN288_ADR50017P130CC-SCONN2A   I180 @S9S_MB_2U_LIB.S9S_MB_2U(SCH_1):PAGE84

M_B_CPU0_SA_DQ<15> @S9S_MB_2U_LIB.S9S_MB_2U(SCH_1):M_B_CPU0_SA_DQ(15)
    U2  W68 DDR1_SA_DQ15 SOCKET4677_AZIF0045P001C01CS-SA   I169 @S9S_MB_2U_LIB.S9S_MB_2U(SCH_1):PAGE21
    J4  172 DQ15_A SCONN288_ADR50017P087CC-SCONN2A    I23 @S9S_MB_2U_LIB.S9S_MB_2U(SCH_1):PAGE85
    J3  172 DQ15_A SCONN288_ADR50017P130CC-SCONN2A   I180 @S9S_MB_2U_LIB.S9S_MB_2U(SCH_1):PAGE84

M_B_CPU0_SA_DQ<16> @S9S_MB_2U_LIB.S9S_MB_2U(SCH_1):M_B_CPU0_SA_DQ(16)
    U2  K63 DDR1_SA_DQ16 SOCKET4677_AZIF0045P001C01CS-SA   I169 @S9S_MB_2U_LIB.S9S_MB_2U(SCH_1):PAGE21
    J4   29 DQ16_A SCONN288_ADR50017P087CC-SCONN2A    I23 @S9S_MB_2U_LIB.S9S_MB_2U(SCH_1):PAGE85
    J3   29 DQ16_A SCONN288_ADR50017P130CC-SCONN2A   I180 @S9S_MB_2U_LIB.S9S_MB_2U(SCH_1):PAGE84

M_B_CPU0_SA_DQ<17> @S9S_MB_2U_LIB.S9S_MB_2U(SCH_1):M_B_CPU0_SA_DQ(17)
    U2  J62 DDR1_SA_DQ17 SOCKET4677_AZIF0045P001C01CS-SA   I169 @S9S_MB_2U_LIB.S9S_MB_2U(SCH_1):PAGE21
    J4   31 DQ17_A SCONN288_ADR50017P087CC-SCONN2A    I23 @S9S_MB_2U_LIB.S9S_MB_2U(SCH_1):PAGE85
    J3   31 DQ17_A SCONN288_ADR50017P130CC-SCONN2A   I180 @S9S_MB_2U_LIB.S9S_MB_2U(SCH_1):PAGE84

M_B_CPU0_SA_DQ<18> @S9S_MB_2U_LIB.S9S_MB_2U(SCH_1):M_B_CPU0_SA_DQ(18)
    U2  M63 DDR1_SA_DQ18 SOCKET4677_AZIF0045P001C01CS-SA   I169 @S9S_MB_2U_LIB.S9S_MB_2U(SCH_1):PAGE21
    J4  174 DQ18_A SCONN288_ADR50017P087CC-SCONN2A    I23 @S9S_MB_2U_LIB.S9S_MB_2U(SCH_1):PAGE85
    J3  174 DQ18_A SCONN288_ADR50017P130CC-SCONN2A   I180 @S9S_MB_2U_LIB.S9S_MB_2U(SCH_1):PAGE84

M_B_CPU0_SA_DQ<19> @S9S_MB_2U_LIB.S9S_MB_2U(SCH_1):M_B_CPU0_SA_DQ(19)
    U2  N62 DDR1_SA_DQ19 SOCKET4677_AZIF0045P001C01CS-SA   I169 @S9S_MB_2U_LIB.S9S_MB_2U(SCH_1):PAGE21
    J4  176 DQ19_A SCONN288_ADR50017P087CC-SCONN2A    I23 @S9S_MB_2U_LIB.S9S_MB_2U(SCH_1):PAGE85
    J3  176 DQ19_A SCONN288_ADR50017P130CC-SCONN2A   I180 @S9S_MB_2U_LIB.S9S_MB_2U(SCH_1):PAGE84

M_B_CPU0_SA_DQ<1> @S9S_MB_2U_LIB.S9S_MB_2U(SCH_1):M_B_CPU0_SA_DQ(1)
    U2  J74 DDR1_SA_DQ1 SOCKET4677_AZIF0045P001C01CS-SA   I169 @S9S_MB_2U_LIB.S9S_MB_2U(SCH_1):PAGE21
    J4    9  DQ1_A SCONN288_ADR50017P087CC-SCONN2A    I23 @S9S_MB_2U_LIB.S9S_MB_2U(SCH_1):PAGE85
    J3    9  DQ1_A SCONN288_ADR50017P130CC-SCONN2A   I180 @S9S_MB_2U_LIB.S9S_MB_2U(SCH_1):PAGE84

M_B_CPU0_SA_DQ<20> @S9S_MB_2U_LIB.S9S_MB_2U(SCH_1):M_B_CPU0_SA_DQ(20)
    U2  J60 DDR1_SA_DQ20 SOCKET4677_AZIF0045P001C01CS-SA   I169 @S9S_MB_2U_LIB.S9S_MB_2U(SCH_1):PAGE21
    J4   36 DQ20_A SCONN288_ADR50017P087CC-SCONN2A    I23 @S9S_MB_2U_LIB.S9S_MB_2U(SCH_1):PAGE85
    J3   36 DQ20_A SCONN288_ADR50017P130CC-SCONN2A   I180 @S9S_MB_2U_LIB.S9S_MB_2U(SCH_1):PAGE84

M_B_CPU0_SA_DQ<21> @S9S_MB_2U_LIB.S9S_MB_2U(SCH_1):M_B_CPU0_SA_DQ(21)
    U2  K59 DDR1_SA_DQ21 SOCKET4677_AZIF0045P001C01CS-SA   I169 @S9S_MB_2U_LIB.S9S_MB_2U(SCH_1):PAGE21
    J4   38 DQ21_A SCONN288_ADR50017P087CC-SCONN2A    I23 @S9S_MB_2U_LIB.S9S_MB_2U(SCH_1):PAGE85
    J3   38 DQ21_A SCONN288_ADR50017P130CC-SCONN2A   I180 @S9S_MB_2U_LIB.S9S_MB_2U(SCH_1):PAGE84

M_B_CPU0_SA_DQ<22> @S9S_MB_2U_LIB.S9S_MB_2U(SCH_1):M_B_CPU0_SA_DQ(22)
    U2  N60 DDR1_SA_DQ22 SOCKET4677_AZIF0045P001C01CS-SA   I169 @S9S_MB_2U_LIB.S9S_MB_2U(SCH_1):PAGE21
    J4  181 DQ22_A SCONN288_ADR50017P087CC-SCONN2A    I23 @S9S_MB_2U_LIB.S9S_MB_2U(SCH_1):PAGE85
    J3  181 DQ22_A SCONN288_ADR50017P130CC-SCONN2A   I180 @S9S_MB_2U_LIB.S9S_MB_2U(SCH_1):PAGE84

M_B_CPU0_SA_DQ<23> @S9S_MB_2U_LIB.S9S_MB_2U(SCH_1):M_B_CPU0_SA_DQ(23)
    U2  M59 DDR1_SA_DQ23 SOCKET4677_AZIF0045P001C01CS-SA   I169 @S9S_MB_2U_LIB.S9S_MB_2U(SCH_1):PAGE21
    J4  183 DQ23_A SCONN288_ADR50017P087CC-SCONN2A    I23 @S9S_MB_2U_LIB.S9S_MB_2U(SCH_1):PAGE85
    J3  183 DQ23_A SCONN288_ADR50017P130CC-SCONN2A   I180 @S9S_MB_2U_LIB.S9S_MB_2U(SCH_1):PAGE84

M_B_CPU0_SA_DQ<24> @S9S_MB_2U_LIB.S9S_MB_2U(SCH_1):M_B_CPU0_SA_DQ(24)
    U2  U60 DDR1_SA_DQ24 SOCKET4677_AZIF0045P001C01CS-SA   I169 @S9S_MB_2U_LIB.S9S_MB_2U(SCH_1):PAGE21
    J4   40 DQ24_A SCONN288_ADR50017P087CC-SCONN2A    I23 @S9S_MB_2U_LIB.S9S_MB_2U(SCH_1):PAGE85
    J3   40 DQ24_A SCONN288_ADR50017P130CC-SCONN2A   I180 @S9S_MB_2U_LIB.S9S_MB_2U(SCH_1):PAGE84

M_B_CPU0_SA_DQ<25> @S9S_MB_2U_LIB.S9S_MB_2U(SCH_1):M_B_CPU0_SA_DQ(25)
    U2  T59 DDR1_SA_DQ25 SOCKET4677_AZIF0045P001C01CS-SA   I169 @S9S_MB_2U_LIB.S9S_MB_2U(SCH_1):PAGE21
    J4   42 DQ25_A SCONN288_ADR50017P087CC-SCONN2A    I23 @S9S_MB_2U_LIB.S9S_MB_2U(SCH_1):PAGE85
    J3   42 DQ25_A SCONN288_ADR50017P130CC-SCONN2A   I180 @S9S_MB_2U_LIB.S9S_MB_2U(SCH_1):PAGE84

M_B_CPU0_SA_DQ<26> @S9S_MB_2U_LIB.S9S_MB_2U(SCH_1):M_B_CPU0_SA_DQ(26)
    U2  W60 DDR1_SA_DQ26 SOCKET4677_AZIF0045P001C01CS-SA   I169 @S9S_MB_2U_LIB.S9S_MB_2U(SCH_1):PAGE21
    J4  185 DQ26_A SCONN288_ADR50017P087CC-SCONN2A    I23 @S9S_MB_2U_LIB.S9S_MB_2U(SCH_1):PAGE85
    J3  185 DQ26_A SCONN288_ADR50017P130CC-SCONN2A   I180 @S9S_MB_2U_LIB.S9S_MB_2U(SCH_1):PAGE84

M_B_CPU0_SA_DQ<27> @S9S_MB_2U_LIB.S9S_MB_2U(SCH_1):M_B_CPU0_SA_DQ(27)
    U2  Y59 DDR1_SA_DQ27 SOCKET4677_AZIF0045P001C01CS-SA   I169 @S9S_MB_2U_LIB.S9S_MB_2U(SCH_1):PAGE21
    J4  187 DQ27_A SCONN288_ADR50017P087CC-SCONN2A    I23 @S9S_MB_2U_LIB.S9S_MB_2U(SCH_1):PAGE85
    J3  187 DQ27_A SCONN288_ADR50017P130CC-SCONN2A   I180 @S9S_MB_2U_LIB.S9S_MB_2U(SCH_1):PAGE84

M_B_CPU0_SA_DQ<28> @S9S_MB_2U_LIB.S9S_MB_2U(SCH_1):M_B_CPU0_SA_DQ(28)
    U2  T57 DDR1_SA_DQ28 SOCKET4677_AZIF0045P001C01CS-SA   I169 @S9S_MB_2U_LIB.S9S_MB_2U(SCH_1):PAGE21
    J4   47 DQ28_A SCONN288_ADR50017P087CC-SCONN2A    I23 @S9S_MB_2U_LIB.S9S_MB_2U(SCH_1):PAGE85
    J3   47 DQ28_A SCONN288_ADR50017P130CC-SCONN2A   I180 @S9S_MB_2U_LIB.S9S_MB_2U(SCH_1):PAGE84

M_B_CPU0_SA_DQ<29> @S9S_MB_2U_LIB.S9S_MB_2U(SCH_1):M_B_CPU0_SA_DQ(29)
    U2  U56 DDR1_SA_DQ29 SOCKET4677_AZIF0045P001C01CS-SA   I169 @S9S_MB_2U_LIB.S9S_MB_2U(SCH_1):PAGE21
    J4   49 DQ29_A SCONN288_ADR50017P087CC-SCONN2A    I23 @S9S_MB_2U_LIB.S9S_MB_2U(SCH_1):PAGE85
    J3   49 DQ29_A SCONN288_ADR50017P130CC-SCONN2A   I180 @S9S_MB_2U_LIB.S9S_MB_2U(SCH_1):PAGE84

M_B_CPU0_SA_DQ<2> @S9S_MB_2U_LIB.S9S_MB_2U(SCH_1):M_B_CPU0_SA_DQ(2)
    U2  M75 DDR1_SA_DQ2 SOCKET4677_AZIF0045P001C01CS-SA   I169 @S9S_MB_2U_LIB.S9S_MB_2U(SCH_1):PAGE21
    J4  152  DQ2_A SCONN288_ADR50017P087CC-SCONN2A    I23 @S9S_MB_2U_LIB.S9S_MB_2U(SCH_1):PAGE85
    J3  152  DQ2_A SCONN288_ADR50017P130CC-SCONN2A   I180 @S9S_MB_2U_LIB.S9S_MB_2U(SCH_1):PAGE84

M_B_CPU0_SA_DQ<30> @S9S_MB_2U_LIB.S9S_MB_2U(SCH_1):M_B_CPU0_SA_DQ(30)
    U2  Y57 DDR1_SA_DQ30 SOCKET4677_AZIF0045P001C01CS-SA   I169 @S9S_MB_2U_LIB.S9S_MB_2U(SCH_1):PAGE21
    J4  192 DQ30_A SCONN288_ADR50017P087CC-SCONN2A    I23 @S9S_MB_2U_LIB.S9S_MB_2U(SCH_1):PAGE85
    J3  192 DQ30_A SCONN288_ADR50017P130CC-SCONN2A   I180 @S9S_MB_2U_LIB.S9S_MB_2U(SCH_1):PAGE84

M_B_CPU0_SA_DQ<31> @S9S_MB_2U_LIB.S9S_MB_2U(SCH_1):M_B_CPU0_SA_DQ(31)
    U2  W56 DDR1_SA_DQ31 SOCKET4677_AZIF0045P001C01CS-SA   I169 @S9S_MB_2U_LIB.S9S_MB_2U(SCH_1):PAGE21
    J4  194 DQ31_A SCONN288_ADR50017P087CC-SCONN2A    I23 @S9S_MB_2U_LIB.S9S_MB_2U(SCH_1):PAGE85
    J3  194 DQ31_A SCONN288_ADR50017P130CC-SCONN2A   I180 @S9S_MB_2U_LIB.S9S_MB_2U(SCH_1):PAGE84

M_B_CPU0_SA_DQ<3> @S9S_MB_2U_LIB.S9S_MB_2U(SCH_1):M_B_CPU0_SA_DQ(3)
    U2  N74 DDR1_SA_DQ3 SOCKET4677_AZIF0045P001C01CS-SA   I169 @S9S_MB_2U_LIB.S9S_MB_2U(SCH_1):PAGE21
    J4  154  DQ3_A SCONN288_ADR50017P087CC-SCONN2A    I23 @S9S_MB_2U_LIB.S9S_MB_2U(SCH_1):PAGE85
    J3  154  DQ3_A SCONN288_ADR50017P130CC-SCONN2A   I180 @S9S_MB_2U_LIB.S9S_MB_2U(SCH_1):PAGE84

M_B_CPU0_SA_DQ<4> @S9S_MB_2U_LIB.S9S_MB_2U(SCH_1):M_B_CPU0_SA_DQ(4)
    U2  J72 DDR1_SA_DQ4 SOCKET4677_AZIF0045P001C01CS-SA   I169 @S9S_MB_2U_LIB.S9S_MB_2U(SCH_1):PAGE21
    J4   14  DQ4_A SCONN288_ADR50017P087CC-SCONN2A    I23 @S9S_MB_2U_LIB.S9S_MB_2U(SCH_1):PAGE85
    J3   14  DQ4_A SCONN288_ADR50017P130CC-SCONN2A   I180 @S9S_MB_2U_LIB.S9S_MB_2U(SCH_1):PAGE84

M_B_CPU0_SA_DQ<5> @S9S_MB_2U_LIB.S9S_MB_2U(SCH_1):M_B_CPU0_SA_DQ(5)
    U2  K71 DDR1_SA_DQ5 SOCKET4677_AZIF0045P001C01CS-SA   I169 @S9S_MB_2U_LIB.S9S_MB_2U(SCH_1):PAGE21
    J4   16  DQ5_A SCONN288_ADR50017P087CC-SCONN2A    I23 @S9S_MB_2U_LIB.S9S_MB_2U(SCH_1):PAGE85
    J3   16  DQ5_A SCONN288_ADR50017P130CC-SCONN2A   I180 @S9S_MB_2U_LIB.S9S_MB_2U(SCH_1):PAGE84

M_B_CPU0_SA_DQ<6> @S9S_MB_2U_LIB.S9S_MB_2U(SCH_1):M_B_CPU0_SA_DQ(6)
    U2  N72 DDR1_SA_DQ6 SOCKET4677_AZIF0045P001C01CS-SA   I169 @S9S_MB_2U_LIB.S9S_MB_2U(SCH_1):PAGE21
    J4  159  DQ6_A SCONN288_ADR50017P087CC-SCONN2A    I23 @S9S_MB_2U_LIB.S9S_MB_2U(SCH_1):PAGE85
    J3  159  DQ6_A SCONN288_ADR50017P130CC-SCONN2A   I180 @S9S_MB_2U_LIB.S9S_MB_2U(SCH_1):PAGE84

M_B_CPU0_SA_DQ<7> @S9S_MB_2U_LIB.S9S_MB_2U(SCH_1):M_B_CPU0_SA_DQ(7)
    U2  M71 DDR1_SA_DQ7 SOCKET4677_AZIF0045P001C01CS-SA   I169 @S9S_MB_2U_LIB.S9S_MB_2U(SCH_1):PAGE21
    J4  161  DQ7_A SCONN288_ADR50017P087CC-SCONN2A    I23 @S9S_MB_2U_LIB.S9S_MB_2U(SCH_1):PAGE85
    J3  161  DQ7_A SCONN288_ADR50017P130CC-SCONN2A   I180 @S9S_MB_2U_LIB.S9S_MB_2U(SCH_1):PAGE84

M_B_CPU0_SA_DQ<8> @S9S_MB_2U_LIB.S9S_MB_2U(SCH_1):M_B_CPU0_SA_DQ(8)
    U2  U72 DDR1_SA_DQ8 SOCKET4677_AZIF0045P001C01CS-SA   I169 @S9S_MB_2U_LIB.S9S_MB_2U(SCH_1):PAGE21
    J4   18  DQ8_A SCONN288_ADR50017P087CC-SCONN2A    I23 @S9S_MB_2U_LIB.S9S_MB_2U(SCH_1):PAGE85
    J3   18  DQ8_A SCONN288_ADR50017P130CC-SCONN2A   I180 @S9S_MB_2U_LIB.S9S_MB_2U(SCH_1):PAGE84

M_B_CPU0_SA_DQ<9> @S9S_MB_2U_LIB.S9S_MB_2U(SCH_1):M_B_CPU0_SA_DQ(9)
    U2  T71 DDR1_SA_DQ9 SOCKET4677_AZIF0045P001C01CS-SA   I169 @S9S_MB_2U_LIB.S9S_MB_2U(SCH_1):PAGE21
    J4   20  DQ9_A SCONN288_ADR50017P087CC-SCONN2A    I23 @S9S_MB_2U_LIB.S9S_MB_2U(SCH_1):PAGE85
    J3   20  DQ9_A SCONN288_ADR50017P130CC-SCONN2A   I180 @S9S_MB_2U_LIB.S9S_MB_2U(SCH_1):PAGE84

M_B_CPU0_SA_DQS_DN<0> @S9S_MB_2U_LIB.S9S_MB_2U(SCH_1):M_B_CPU0_SA_DQS_DN(0)
    U2  H73 DDR1_SA_DQS_DN0 SOCKET4677_AZIF0045P001C01CS-SA   I169 @S9S_MB_2U_LIB.S9S_MB_2U(SCH_1):PAGE21
    J4   12 DQS0_A_C SCONN288_ADR50017P087CC-SCONN2A   I178 @S9S_MB_2U_LIB.S9S_MB_2U(SCH_1):PAGE85
    J3   12 DQS0_A_C SCONN288_ADR50017P130CC-SCONN2A   I179 @S9S_MB_2U_LIB.S9S_MB_2U(SCH_1):PAGE84

M_B_CPU0_SA_DQS_DN<1> @S9S_MB_2U_LIB.S9S_MB_2U(SCH_1):M_B_CPU0_SA_DQS_DN(1)
    U2  R70 DDR1_SA_DQS_DN1 SOCKET4677_AZIF0045P001C01CS-SA   I169 @S9S_MB_2U_LIB.S9S_MB_2U(SCH_1):PAGE21
    J4   23 DQS1_A_C SCONN288_ADR50017P087CC-SCONN2A   I178 @S9S_MB_2U_LIB.S9S_MB_2U(SCH_1):PAGE85
    J3   23 DQS1_A_C SCONN288_ADR50017P130CC-SCONN2A   I179 @S9S_MB_2U_LIB.S9S_MB_2U(SCH_1):PAGE84

M_B_CPU0_SA_DQS_DN<2> @S9S_MB_2U_LIB.S9S_MB_2U(SCH_1):M_B_CPU0_SA_DQS_DN(2)
    U2  H61 DDR1_SA_DQS_DN2 SOCKET4677_AZIF0045P001C01CS-SA   I169 @S9S_MB_2U_LIB.S9S_MB_2U(SCH_1):PAGE21
    J4   34 DQS2_A_C SCONN288_ADR50017P087CC-SCONN2A   I178 @S9S_MB_2U_LIB.S9S_MB_2U(SCH_1):PAGE85
    J3   34 DQS2_A_C SCONN288_ADR50017P130CC-SCONN2A   I179 @S9S_MB_2U_LIB.S9S_MB_2U(SCH_1):PAGE84

M_B_CPU0_SA_DQS_DN<3> @S9S_MB_2U_LIB.S9S_MB_2U(SCH_1):M_B_CPU0_SA_DQS_DN(3)
    U2  R58 DDR1_SA_DQS_DN3 SOCKET4677_AZIF0045P001C01CS-SA   I169 @S9S_MB_2U_LIB.S9S_MB_2U(SCH_1):PAGE21
    J4   45 DQS3_A_C SCONN288_ADR50017P087CC-SCONN2A   I178 @S9S_MB_2U_LIB.S9S_MB_2U(SCH_1):PAGE85
    J3   45 DQS3_A_C SCONN288_ADR50017P130CC-SCONN2A   I179 @S9S_MB_2U_LIB.S9S_MB_2U(SCH_1):PAGE84

M_B_CPU0_SA_DQS_DN<4> @S9S_MB_2U_LIB.S9S_MB_2U(SCH_1):M_B_CPU0_SA_DQS_DN(4)
    U2  H55 DDR1_SA_DQS_DN4 SOCKET4677_AZIF0045P001C01CS-SA   I169 @S9S_MB_2U_LIB.S9S_MB_2U(SCH_1):PAGE21
    J4   56 DQS4_A_C SCONN288_ADR50017P087CC-SCONN2A   I178 @S9S_MB_2U_LIB.S9S_MB_2U(SCH_1):PAGE85
    J3   56 DQS4_A_C SCONN288_ADR50017P130CC-SCONN2A   I179 @S9S_MB_2U_LIB.S9S_MB_2U(SCH_1):PAGE84

M_B_CPU0_SA_DQS_DN<5> @S9S_MB_2U_LIB.S9S_MB_2U(SCH_1):M_B_CPU0_SA_DQS_DN(5)
    U2  M73 DDR1_SA_DQS_DN5 SOCKET4677_AZIF0045P001C01CS-SA   I169 @S9S_MB_2U_LIB.S9S_MB_2U(SCH_1):PAGE21
    J4  156 DQS5_A_C||TDQS5_A_C||DQS5_A_T||TDQS5_A_T SCONN288_ADR50017P087CC-SCONN2A   I178 @S9S_MB_2U_LIB.S9S_MB_2U(SCH_1):PAGE85
    J3  156 DQS5_A_C||TDQS5_A_C||DQS5_A_T||TDQS5_A_T SCONN288_ADR50017P130CC-SCONN2A   I179 @S9S_MB_2U_LIB.S9S_MB_2U(SCH_1):PAGE84

M_B_CPU0_SA_DQS_DN<6> @S9S_MB_2U_LIB.S9S_MB_2U(SCH_1):M_B_CPU0_SA_DQS_DN(6)
    U2 AA70 DDR1_SA_DQS_DN6 SOCKET4677_AZIF0045P001C01CS-SA   I169 @S9S_MB_2U_LIB.S9S_MB_2U(SCH_1):PAGE21
    J4  167 DQS6_A_C||TDQS6_A_C||DQS6_A_T||TDQS6_A_T SCONN288_ADR50017P087CC-SCONN2A   I178 @S9S_MB_2U_LIB.S9S_MB_2U(SCH_1):PAGE85
    J3  167 DQS6_A_C||TDQS6_A_C||DQS6_A_T||TDQS6_A_T SCONN288_ADR50017P130CC-SCONN2A   I179 @S9S_MB_2U_LIB.S9S_MB_2U(SCH_1):PAGE84

M_B_CPU0_SA_DQS_DN<7> @S9S_MB_2U_LIB.S9S_MB_2U(SCH_1):M_B_CPU0_SA_DQS_DN(7)
    U2  M61 DDR1_SA_DQS_DN7 SOCKET4677_AZIF0045P001C01CS-SA   I169 @S9S_MB_2U_LIB.S9S_MB_2U(SCH_1):PAGE21
    J4  178 DQS7_A_C||TDQS7_A_C SCONN288_ADR50017P087CC-SCONN2A   I178 @S9S_MB_2U_LIB.S9S_MB_2U(SCH_1):PAGE85
    J3  178 DQS7_A_C||TDQS7_A_C SCONN288_ADR50017P130CC-SCONN2A   I179 @S9S_MB_2U_LIB.S9S_MB_2U(SCH_1):PAGE84

M_B_CPU0_SA_DQS_DN<8> @S9S_MB_2U_LIB.S9S_MB_2U(SCH_1):M_B_CPU0_SA_DQS_DN(8)
    U2 AA58 DDR1_SA_DQS_DN8 SOCKET4677_AZIF0045P001C01CS-SA   I169 @S9S_MB_2U_LIB.S9S_MB_2U(SCH_1):PAGE21
    J4  189 DQS8_A_C||TDQS8_A_C SCONN288_ADR50017P087CC-SCONN2A   I178 @S9S_MB_2U_LIB.S9S_MB_2U(SCH_1):PAGE85
    J3  189 DQS8_A_C||TDQS8_A_C SCONN288_ADR50017P130CC-SCONN2A   I179 @S9S_MB_2U_LIB.S9S_MB_2U(SCH_1):PAGE84

M_B_CPU0_SA_DQS_DN<9> @S9S_MB_2U_LIB.S9S_MB_2U(SCH_1):M_B_CPU0_SA_DQS_DN(9)
    U2  M55 DDR1_SA_DQS_DN9 SOCKET4677_AZIF0045P001C01CS-SA   I169 @S9S_MB_2U_LIB.S9S_MB_2U(SCH_1):PAGE21
    J4  200 DQS9_A_C||TDQS9_A_C SCONN288_ADR50017P087CC-SCONN2A   I178 @S9S_MB_2U_LIB.S9S_MB_2U(SCH_1):PAGE85
    J3  200 DQS9_A_C||TDQS9_A_C SCONN288_ADR50017P130CC-SCONN2A   I179 @S9S_MB_2U_LIB.S9S_MB_2U(SCH_1):PAGE84

M_B_CPU0_SA_DQS_DP<0> @S9S_MB_2U_LIB.S9S_MB_2U(SCH_1):M_B_CPU0_SA_DQS_DP(0)
    U2  K73 DDR1_SA_DQS_DP0 SOCKET4677_AZIF0045P001C01CS-SA   I169 @S9S_MB_2U_LIB.S9S_MB_2U(SCH_1):PAGE21
    J4   11 DQS0_A_T SCONN288_ADR50017P087CC-SCONN2A   I178 @S9S_MB_2U_LIB.S9S_MB_2U(SCH_1):PAGE85
    J3   11 DQS0_A_T SCONN288_ADR50017P130CC-SCONN2A   I179 @S9S_MB_2U_LIB.S9S_MB_2U(SCH_1):PAGE84

M_B_CPU0_SA_DQS_DP<1> @S9S_MB_2U_LIB.S9S_MB_2U(SCH_1):M_B_CPU0_SA_DQS_DP(1)
    U2  U70 DDR1_SA_DQS_DP1 SOCKET4677_AZIF0045P001C01CS-SA   I169 @S9S_MB_2U_LIB.S9S_MB_2U(SCH_1):PAGE21
    J4   22 DQS1_A_T SCONN288_ADR50017P087CC-SCONN2A   I178 @S9S_MB_2U_LIB.S9S_MB_2U(SCH_1):PAGE85
    J3   22 DQS1_A_T SCONN288_ADR50017P130CC-SCONN2A   I179 @S9S_MB_2U_LIB.S9S_MB_2U(SCH_1):PAGE84

M_B_CPU0_SA_DQS_DP<2> @S9S_MB_2U_LIB.S9S_MB_2U(SCH_1):M_B_CPU0_SA_DQS_DP(2)
    U2  K61 DDR1_SA_DQS_DP2 SOCKET4677_AZIF0045P001C01CS-SA   I169 @S9S_MB_2U_LIB.S9S_MB_2U(SCH_1):PAGE21
    J4   33 DQS2_A_T SCONN288_ADR50017P087CC-SCONN2A   I178 @S9S_MB_2U_LIB.S9S_MB_2U(SCH_1):PAGE85
    J3   33 DQS2_A_T SCONN288_ADR50017P130CC-SCONN2A   I179 @S9S_MB_2U_LIB.S9S_MB_2U(SCH_1):PAGE84

M_B_CPU0_SA_DQS_DP<3> @S9S_MB_2U_LIB.S9S_MB_2U(SCH_1):M_B_CPU0_SA_DQS_DP(3)
    U2  U58 DDR1_SA_DQS_DP3 SOCKET4677_AZIF0045P001C01CS-SA   I169 @S9S_MB_2U_LIB.S9S_MB_2U(SCH_1):PAGE21
    J4   44 DQS3_A_T SCONN288_ADR50017P087CC-SCONN2A   I178 @S9S_MB_2U_LIB.S9S_MB_2U(SCH_1):PAGE85
    J3   44 DQS3_A_T SCONN288_ADR50017P130CC-SCONN2A   I179 @S9S_MB_2U_LIB.S9S_MB_2U(SCH_1):PAGE84

M_B_CPU0_SA_DQS_DP<4> @S9S_MB_2U_LIB.S9S_MB_2U(SCH_1):M_B_CPU0_SA_DQS_DP(4)
    U2  K55 DDR1_SA_DQS_DP4 SOCKET4677_AZIF0045P001C01CS-SA   I169 @S9S_MB_2U_LIB.S9S_MB_2U(SCH_1):PAGE21
    J4   55 DQS4_A_T SCONN288_ADR50017P087CC-SCONN2A   I178 @S9S_MB_2U_LIB.S9S_MB_2U(SCH_1):PAGE85
    J3   55 DQS4_A_T SCONN288_ADR50017P130CC-SCONN2A   I179 @S9S_MB_2U_LIB.S9S_MB_2U(SCH_1):PAGE84

M_B_CPU0_SA_DQS_DP<5> @S9S_MB_2U_LIB.S9S_MB_2U(SCH_1):M_B_CPU0_SA_DQS_DP(5)
    U2  P73 DDR1_SA_DQS_DP5 SOCKET4677_AZIF0045P001C01CS-SA   I169 @S9S_MB_2U_LIB.S9S_MB_2U(SCH_1):PAGE21
    J4  157 DQS5_A_T||TDQS5_A_T SCONN288_ADR50017P087CC-SCONN2A   I178 @S9S_MB_2U_LIB.S9S_MB_2U(SCH_1):PAGE85
    J3  157 DQS5_A_T||TDQS5_A_T SCONN288_ADR50017P130CC-SCONN2A   I179 @S9S_MB_2U_LIB.S9S_MB_2U(SCH_1):PAGE84

M_B_CPU0_SA_DQS_DP<6> @S9S_MB_2U_LIB.S9S_MB_2U(SCH_1):M_B_CPU0_SA_DQS_DP(6)
    U2  W70 DDR1_SA_DQS_DP6 SOCKET4677_AZIF0045P001C01CS-SA   I169 @S9S_MB_2U_LIB.S9S_MB_2U(SCH_1):PAGE21
    J4  168 DQS6_A_T||TDQS6_A_T SCONN288_ADR50017P087CC-SCONN2A   I178 @S9S_MB_2U_LIB.S9S_MB_2U(SCH_1):PAGE85
    J3  168 DQS6_A_T||TDQS6_A_T SCONN288_ADR50017P130CC-SCONN2A   I179 @S9S_MB_2U_LIB.S9S_MB_2U(SCH_1):PAGE84

M_B_CPU0_SA_DQS_DP<7> @S9S_MB_2U_LIB.S9S_MB_2U(SCH_1):M_B_CPU0_SA_DQS_DP(7)
    U2  P61 DDR1_SA_DQS_DP7 SOCKET4677_AZIF0045P001C01CS-SA   I169 @S9S_MB_2U_LIB.S9S_MB_2U(SCH_1):PAGE21
    J4  179 DQS7_A_T||TDQS7_A_T SCONN288_ADR50017P087CC-SCONN2A   I178 @S9S_MB_2U_LIB.S9S_MB_2U(SCH_1):PAGE85
    J3  179 DQS7_A_T||TDQS7_A_T SCONN288_ADR50017P130CC-SCONN2A   I179 @S9S_MB_2U_LIB.S9S_MB_2U(SCH_1):PAGE84

M_B_CPU0_SA_DQS_DP<8> @S9S_MB_2U_LIB.S9S_MB_2U(SCH_1):M_B_CPU0_SA_DQS_DP(8)
    U2  W58 DDR1_SA_DQS_DP8 SOCKET4677_AZIF0045P001C01CS-SA   I169 @S9S_MB_2U_LIB.S9S_MB_2U(SCH_1):PAGE21
    J4  190 DQS8_A_T||TDQS8_A_T SCONN288_ADR50017P087CC-SCONN2A   I178 @S9S_MB_2U_LIB.S9S_MB_2U(SCH_1):PAGE85
    J3  190 DQS8_A_T||TDQS8_A_T SCONN288_ADR50017P130CC-SCONN2A   I179 @S9S_MB_2U_LIB.S9S_MB_2U(SCH_1):PAGE84

M_B_CPU0_SA_DQS_DP<9> @S9S_MB_2U_LIB.S9S_MB_2U(SCH_1):M_B_CPU0_SA_DQS_DP(9)
    U2  P55 DDR1_SA_DQS_DP9 SOCKET4677_AZIF0045P001C01CS-SA   I169 @S9S_MB_2U_LIB.S9S_MB_2U(SCH_1):PAGE21
    J4  201 DQS9_A_T||TDQS9_A_T SCONN288_ADR50017P087CC-SCONN2A   I178 @S9S_MB_2U_LIB.S9S_MB_2U(SCH_1):PAGE85
    J3  201 DQS9_A_T||TDQS9_A_T SCONN288_ADR50017P130CC-SCONN2A   I179 @S9S_MB_2U_LIB.S9S_MB_2U(SCH_1):PAGE84

M_B_CPU0_SA_PAR @S9S_MB_2U_LIB.S9S_MB_2U(SCH_1):M_B_CPU0_SA_PAR
    U2  W43 DDR1_SA_PAR SOCKET4677_AZIF0045P001C01CS-SA   I169 @S9S_MB_2U_LIB.S9S_MB_2U(SCH_1):PAGE21
    J4   74  PAR_A SCONN288_ADR50017P087CC-SCONN2A    I23 @S9S_MB_2U_LIB.S9S_MB_2U(SCH_1):PAGE85
    J3   74  PAR_A SCONN288_ADR50017P130CC-SCONN2A   I180 @S9S_MB_2U_LIB.S9S_MB_2U(SCH_1):PAGE84

M_B_CPU0_SA_RSP<0> @S9S_MB_2U_LIB.S9S_MB_2U(SCH_1):M_B_CPU0_SA_RSP(0)
    U2 AL48 DDR1_A_RSP0 SOCKET4677_AZIF0045P001C01CS-SA   I169 @S9S_MB_2U_LIB.S9S_MB_2U(SCH_1):PAGE21
    J3   86 LBD||RSP_A_N SCONN288_ADR50017P130CC-SCONN2A   I180 @S9S_MB_2U_LIB.S9S_MB_2U(SCH_1):PAGE84

M_B_CPU0_SA_RSP<1> @S9S_MB_2U_LIB.S9S_MB_2U(SCH_1):M_B_CPU0_SA_RSP(1)
    U2 AK47 DDR1_A_RSP1 SOCKET4677_AZIF0045P001C01CS-SA   I169 @S9S_MB_2U_LIB.S9S_MB_2U(SCH_1):PAGE21
    J4   86 LBD||RSP_A_N SCONN288_ADR50017P087CC-SCONN2A    I23 @S9S_MB_2U_LIB.S9S_MB_2U(SCH_1):PAGE85

M_B_CPU0_SB_CA<0> @S9S_MB_2U_LIB.S9S_MB_2U(SCH_1):M_B_CPU0_SB_CA(0)
    U2  T44 DDR1_SB_CA0 SOCKET4677_AZIF0045P001C01CS-SA   I169 @S9S_MB_2U_LIB.S9S_MB_2U(SCH_1):PAGE21
    J4   76  CA0_B SCONN288_ADR50017P087CC-SCONN2A    I23 @S9S_MB_2U_LIB.S9S_MB_2U(SCH_1):PAGE85
    J3   76  CA0_B SCONN288_ADR50017P130CC-SCONN2A   I180 @S9S_MB_2U_LIB.S9S_MB_2U(SCH_1):PAGE84

M_B_CPU0_SB_CA<1> @S9S_MB_2U_LIB.S9S_MB_2U(SCH_1):M_B_CPU0_SB_CA(1)
    U2  U43 DDR1_SB_CA1 SOCKET4677_AZIF0045P001C01CS-SA   I169 @S9S_MB_2U_LIB.S9S_MB_2U(SCH_1):PAGE21
    J4  221  CA1_B SCONN288_ADR50017P087CC-SCONN2A    I23 @S9S_MB_2U_LIB.S9S_MB_2U(SCH_1):PAGE85
    J3  221  CA1_B SCONN288_ADR50017P130CC-SCONN2A   I180 @S9S_MB_2U_LIB.S9S_MB_2U(SCH_1):PAGE84

M_B_CPU0_SB_CA<2> @S9S_MB_2U_LIB.S9S_MB_2U(SCH_1):M_B_CPU0_SB_CA(2)
    U2  K44 DDR1_SB_CA2 SOCKET4677_AZIF0045P001C01CS-SA   I169 @S9S_MB_2U_LIB.S9S_MB_2U(SCH_1):PAGE21
    J4   78  CA2_B SCONN288_ADR50017P087CC-SCONN2A    I23 @S9S_MB_2U_LIB.S9S_MB_2U(SCH_1):PAGE85
    J3   78  CA2_B SCONN288_ADR50017P130CC-SCONN2A   I180 @S9S_MB_2U_LIB.S9S_MB_2U(SCH_1):PAGE84

M_B_CPU0_SB_CA<3> @S9S_MB_2U_LIB.S9S_MB_2U(SCH_1):M_B_CPU0_SB_CA(3)
    U2  M44 DDR1_SB_CA3 SOCKET4677_AZIF0045P001C01CS-SA   I169 @S9S_MB_2U_LIB.S9S_MB_2U(SCH_1):PAGE21
    J4  223  CA3_B SCONN288_ADR50017P087CC-SCONN2A    I23 @S9S_MB_2U_LIB.S9S_MB_2U(SCH_1):PAGE85
    J3  223  CA3_B SCONN288_ADR50017P130CC-SCONN2A   I180 @S9S_MB_2U_LIB.S9S_MB_2U(SCH_1):PAGE84

M_B_CPU0_SB_CA<4> @S9S_MB_2U_LIB.S9S_MB_2U(SCH_1):M_B_CPU0_SB_CA(4)
    U2  J43 DDR1_SB_CA4 SOCKET4677_AZIF0045P001C01CS-SA   I169 @S9S_MB_2U_LIB.S9S_MB_2U(SCH_1):PAGE21
    J4   80  CA4_B SCONN288_ADR50017P087CC-SCONN2A    I23 @S9S_MB_2U_LIB.S9S_MB_2U(SCH_1):PAGE85
    J3   80  CA4_B SCONN288_ADR50017P130CC-SCONN2A   I180 @S9S_MB_2U_LIB.S9S_MB_2U(SCH_1):PAGE84

M_B_CPU0_SB_CA<5> @S9S_MB_2U_LIB.S9S_MB_2U(SCH_1):M_B_CPU0_SB_CA(5)
    U2  N43 DDR1_SB_CA5 SOCKET4677_AZIF0045P001C01CS-SA   I169 @S9S_MB_2U_LIB.S9S_MB_2U(SCH_1):PAGE21
    J4  225  CA5_B SCONN288_ADR50017P087CC-SCONN2A    I23 @S9S_MB_2U_LIB.S9S_MB_2U(SCH_1):PAGE85
    J3  225  CA5_B SCONN288_ADR50017P130CC-SCONN2A   I180 @S9S_MB_2U_LIB.S9S_MB_2U(SCH_1):PAGE84

M_B_CPU0_SB_CA<6> @S9S_MB_2U_LIB.S9S_MB_2U(SCH_1):M_B_CPU0_SB_CA(6)
    U2  H42 DDR1_SB_CA6 SOCKET4677_AZIF0045P001C01CS-SA   I169 @S9S_MB_2U_LIB.S9S_MB_2U(SCH_1):PAGE21
    J4   82  CA6_B SCONN288_ADR50017P087CC-SCONN2A    I23 @S9S_MB_2U_LIB.S9S_MB_2U(SCH_1):PAGE85
    J3   82  CA6_B SCONN288_ADR50017P130CC-SCONN2A   I180 @S9S_MB_2U_LIB.S9S_MB_2U(SCH_1):PAGE84

M_B_CPU0_SB_CB<0> @S9S_MB_2U_LIB.S9S_MB_2U(SCH_1):M_B_CPU0_SB_CB(0)
    U2  J35 DDR1_SB_ECC0 SOCKET4677_AZIF0045P001C01CS-SA   I169 @S9S_MB_2U_LIB.S9S_MB_2U(SCH_1):PAGE21
    J4   96  CB0_B SCONN288_ADR50017P087CC-SCONN2A    I23 @S9S_MB_2U_LIB.S9S_MB_2U(SCH_1):PAGE85
    J3   96  CB0_B SCONN288_ADR50017P130CC-SCONN2A   I180 @S9S_MB_2U_LIB.S9S_MB_2U(SCH_1):PAGE84

M_B_CPU0_SB_CB<1> @S9S_MB_2U_LIB.S9S_MB_2U(SCH_1):M_B_CPU0_SB_CB(1)
    U2  K34 DDR1_SB_ECC1 SOCKET4677_AZIF0045P001C01CS-SA   I169 @S9S_MB_2U_LIB.S9S_MB_2U(SCH_1):PAGE21
    J4   98  CB1_B SCONN288_ADR50017P087CC-SCONN2A    I23 @S9S_MB_2U_LIB.S9S_MB_2U(SCH_1):PAGE85
    J3   98  CB1_B SCONN288_ADR50017P130CC-SCONN2A   I180 @S9S_MB_2U_LIB.S9S_MB_2U(SCH_1):PAGE84

M_B_CPU0_SB_CB<2> @S9S_MB_2U_LIB.S9S_MB_2U(SCH_1):M_B_CPU0_SB_CB(2)
    U2  N35 DDR1_SB_ECC2 SOCKET4677_AZIF0045P001C01CS-SA   I169 @S9S_MB_2U_LIB.S9S_MB_2U(SCH_1):PAGE21
    J4  241  CB2_B SCONN288_ADR50017P087CC-SCONN2A    I23 @S9S_MB_2U_LIB.S9S_MB_2U(SCH_1):PAGE85
    J3  241  CB2_B SCONN288_ADR50017P130CC-SCONN2A   I180 @S9S_MB_2U_LIB.S9S_MB_2U(SCH_1):PAGE84

M_B_CPU0_SB_CB<3> @S9S_MB_2U_LIB.S9S_MB_2U(SCH_1):M_B_CPU0_SB_CB(3)
    U2  M34 DDR1_SB_ECC3 SOCKET4677_AZIF0045P001C01CS-SA   I169 @S9S_MB_2U_LIB.S9S_MB_2U(SCH_1):PAGE21
    J4  243  CB3_B SCONN288_ADR50017P087CC-SCONN2A    I23 @S9S_MB_2U_LIB.S9S_MB_2U(SCH_1):PAGE85
    J3  243  CB3_B SCONN288_ADR50017P130CC-SCONN2A   I180 @S9S_MB_2U_LIB.S9S_MB_2U(SCH_1):PAGE84

M_B_CPU0_SB_CB<4> @S9S_MB_2U_LIB.S9S_MB_2U(SCH_1):M_B_CPU0_SB_CB(4)
    U2  K38 DDR1_SB_ECC4 SOCKET4677_AZIF0045P001C01CS-SA   I169 @S9S_MB_2U_LIB.S9S_MB_2U(SCH_1):PAGE21
    J4   89  CB4_B SCONN288_ADR50017P087CC-SCONN2A    I23 @S9S_MB_2U_LIB.S9S_MB_2U(SCH_1):PAGE85
    J3   89  CB4_B SCONN288_ADR50017P130CC-SCONN2A   I180 @S9S_MB_2U_LIB.S9S_MB_2U(SCH_1):PAGE84

M_B_CPU0_SB_CB<5> @S9S_MB_2U_LIB.S9S_MB_2U(SCH_1):M_B_CPU0_SB_CB(5)
    U2  J37 DDR1_SB_ECC5 SOCKET4677_AZIF0045P001C01CS-SA   I169 @S9S_MB_2U_LIB.S9S_MB_2U(SCH_1):PAGE21
    J4   91  CB5_B SCONN288_ADR50017P087CC-SCONN2A    I23 @S9S_MB_2U_LIB.S9S_MB_2U(SCH_1):PAGE85
    J3   91  CB5_B SCONN288_ADR50017P130CC-SCONN2A   I180 @S9S_MB_2U_LIB.S9S_MB_2U(SCH_1):PAGE84

M_B_CPU0_SB_CB<6> @S9S_MB_2U_LIB.S9S_MB_2U(SCH_1):M_B_CPU0_SB_CB(6)
    U2  M38 DDR1_SB_ECC6 SOCKET4677_AZIF0045P001C01CS-SA   I169 @S9S_MB_2U_LIB.S9S_MB_2U(SCH_1):PAGE21
    J4  234  CB6_B SCONN288_ADR50017P087CC-SCONN2A    I23 @S9S_MB_2U_LIB.S9S_MB_2U(SCH_1):PAGE85
    J3  234  CB6_B SCONN288_ADR50017P130CC-SCONN2A   I180 @S9S_MB_2U_LIB.S9S_MB_2U(SCH_1):PAGE84

M_B_CPU0_SB_CB<7> @S9S_MB_2U_LIB.S9S_MB_2U(SCH_1):M_B_CPU0_SB_CB(7)
    U2  N37 DDR1_SB_ECC7 SOCKET4677_AZIF0045P001C01CS-SA   I169 @S9S_MB_2U_LIB.S9S_MB_2U(SCH_1):PAGE21
    J4  236  CB7_B SCONN288_ADR50017P087CC-SCONN2A    I23 @S9S_MB_2U_LIB.S9S_MB_2U(SCH_1):PAGE85
    J3  236  CB7_B SCONN288_ADR50017P130CC-SCONN2A   I180 @S9S_MB_2U_LIB.S9S_MB_2U(SCH_1):PAGE84

M_B_CPU0_SB_CS_N<0> @S9S_MB_2U_LIB.S9S_MB_2U(SCH_1):M_B_CPU0_SB_CS_N(0)
    U2  J41 DDR1_SB_CS_N0 SOCKET4677_AZIF0045P001C01CS-SA   I169 @S9S_MB_2U_LIB.S9S_MB_2U(SCH_1):PAGE21
    J3   84 CS0_B_N SCONN288_ADR50017P130CC-SCONN2A   I180 @S9S_MB_2U_LIB.S9S_MB_2U(SCH_1):PAGE84

M_B_CPU0_SB_CS_N<1> @S9S_MB_2U_LIB.S9S_MB_2U(SCH_1):M_B_CPU0_SB_CS_N(1)
    U2  K40 DDR1_SB_CS_N1 SOCKET4677_AZIF0045P001C01CS-SA   I169 @S9S_MB_2U_LIB.S9S_MB_2U(SCH_1):PAGE21
    J3  229 CS1_B_N SCONN288_ADR50017P130CC-SCONN2A   I180 @S9S_MB_2U_LIB.S9S_MB_2U(SCH_1):PAGE84

M_B_CPU0_SB_CS_N<2> @S9S_MB_2U_LIB.S9S_MB_2U(SCH_1):M_B_CPU0_SB_CS_N(2)
    U2  N41 DDR1_SB_CS_N2 SOCKET4677_AZIF0045P001C01CS-SA   I169 @S9S_MB_2U_LIB.S9S_MB_2U(SCH_1):PAGE21
    J4   84 CS0_B_N SCONN288_ADR50017P087CC-SCONN2A    I23 @S9S_MB_2U_LIB.S9S_MB_2U(SCH_1):PAGE85

M_B_CPU0_SB_CS_N<3> @S9S_MB_2U_LIB.S9S_MB_2U(SCH_1):M_B_CPU0_SB_CS_N(3)
    U2  M40 DDR1_SB_CS_N3 SOCKET4677_AZIF0045P001C01CS-SA   I169 @S9S_MB_2U_LIB.S9S_MB_2U(SCH_1):PAGE21
    J4  229 CS1_B_N SCONN288_ADR50017P087CC-SCONN2A    I23 @S9S_MB_2U_LIB.S9S_MB_2U(SCH_1):PAGE85

M_B_CPU0_SB_DQ<0> @S9S_MB_2U_LIB.S9S_MB_2U(SCH_1):M_B_CPU0_SB_DQ(0)
    U2  U29 DDR1_SB_DQ0 SOCKET4677_AZIF0045P001C01CS-SA   I169 @S9S_MB_2U_LIB.S9S_MB_2U(SCH_1):PAGE21
    J4  100  DQ0_B SCONN288_ADR50017P087CC-SCONN2A    I23 @S9S_MB_2U_LIB.S9S_MB_2U(SCH_1):PAGE85
    J3  100  DQ0_B SCONN288_ADR50017P130CC-SCONN2A   I180 @S9S_MB_2U_LIB.S9S_MB_2U(SCH_1):PAGE84

M_B_CPU0_SB_DQ<10> @S9S_MB_2U_LIB.S9S_MB_2U(SCH_1):M_B_CPU0_SB_DQ(10)
    U2  M26 DDR1_SB_DQ10 SOCKET4677_AZIF0045P001C01CS-SA   I169 @S9S_MB_2U_LIB.S9S_MB_2U(SCH_1):PAGE21
    J4  256 DQ10_B SCONN288_ADR50017P087CC-SCONN2A    I23 @S9S_MB_2U_LIB.S9S_MB_2U(SCH_1):PAGE85
    J3  256 DQ10_B SCONN288_ADR50017P130CC-SCONN2A   I180 @S9S_MB_2U_LIB.S9S_MB_2U(SCH_1):PAGE84

M_B_CPU0_SB_DQ<11> @S9S_MB_2U_LIB.S9S_MB_2U(SCH_1):M_B_CPU0_SB_DQ(11)
    U2  N25 DDR1_SB_DQ11 SOCKET4677_AZIF0045P001C01CS-SA   I169 @S9S_MB_2U_LIB.S9S_MB_2U(SCH_1):PAGE21
    J4  258 DQ11_B SCONN288_ADR50017P087CC-SCONN2A    I23 @S9S_MB_2U_LIB.S9S_MB_2U(SCH_1):PAGE85
    J3  258 DQ11_B SCONN288_ADR50017P130CC-SCONN2A   I180 @S9S_MB_2U_LIB.S9S_MB_2U(SCH_1):PAGE84

M_B_CPU0_SB_DQ<12> @S9S_MB_2U_LIB.S9S_MB_2U(SCH_1):M_B_CPU0_SB_DQ(12)
    U2  J23 DDR1_SB_DQ12 SOCKET4677_AZIF0045P001C01CS-SA   I169 @S9S_MB_2U_LIB.S9S_MB_2U(SCH_1):PAGE21
    J4  118 DQ12_B SCONN288_ADR50017P087CC-SCONN2A    I23 @S9S_MB_2U_LIB.S9S_MB_2U(SCH_1):PAGE85
    J3  118 DQ12_B SCONN288_ADR50017P130CC-SCONN2A   I180 @S9S_MB_2U_LIB.S9S_MB_2U(SCH_1):PAGE84

M_B_CPU0_SB_DQ<13> @S9S_MB_2U_LIB.S9S_MB_2U(SCH_1):M_B_CPU0_SB_DQ(13)
    U2  K22 DDR1_SB_DQ13 SOCKET4677_AZIF0045P001C01CS-SA   I169 @S9S_MB_2U_LIB.S9S_MB_2U(SCH_1):PAGE21
    J4  120 DQ13_B SCONN288_ADR50017P087CC-SCONN2A    I23 @S9S_MB_2U_LIB.S9S_MB_2U(SCH_1):PAGE85
    J3  120 DQ13_B SCONN288_ADR50017P130CC-SCONN2A   I180 @S9S_MB_2U_LIB.S9S_MB_2U(SCH_1):PAGE84

M_B_CPU0_SB_DQ<14> @S9S_MB_2U_LIB.S9S_MB_2U(SCH_1):M_B_CPU0_SB_DQ(14)
    U2  N23 DDR1_SB_DQ14 SOCKET4677_AZIF0045P001C01CS-SA   I169 @S9S_MB_2U_LIB.S9S_MB_2U(SCH_1):PAGE21
    J4  263 DQ14_B SCONN288_ADR50017P087CC-SCONN2A    I23 @S9S_MB_2U_LIB.S9S_MB_2U(SCH_1):PAGE85
    J3  263 DQ14_B SCONN288_ADR50017P130CC-SCONN2A   I180 @S9S_MB_2U_LIB.S9S_MB_2U(SCH_1):PAGE84

M_B_CPU0_SB_DQ<15> @S9S_MB_2U_LIB.S9S_MB_2U(SCH_1):M_B_CPU0_SB_DQ(15)
    U2  M22 DDR1_SB_DQ15 SOCKET4677_AZIF0045P001C01CS-SA   I169 @S9S_MB_2U_LIB.S9S_MB_2U(SCH_1):PAGE21
    J4  265 DQ15_B SCONN288_ADR50017P087CC-SCONN2A    I23 @S9S_MB_2U_LIB.S9S_MB_2U(SCH_1):PAGE85
    J3  265 DQ15_B SCONN288_ADR50017P130CC-SCONN2A   I180 @S9S_MB_2U_LIB.S9S_MB_2U(SCH_1):PAGE84

M_B_CPU0_SB_DQ<16> @S9S_MB_2U_LIB.S9S_MB_2U(SCH_1):M_B_CPU0_SB_DQ(16)
    U2  K20 DDR1_SB_DQ16 SOCKET4677_AZIF0045P001C01CS-SA   I169 @S9S_MB_2U_LIB.S9S_MB_2U(SCH_1):PAGE21
    J4  122 DQ16_B SCONN288_ADR50017P087CC-SCONN2A    I23 @S9S_MB_2U_LIB.S9S_MB_2U(SCH_1):PAGE85
    J3  122 DQ16_B SCONN288_ADR50017P130CC-SCONN2A   I180 @S9S_MB_2U_LIB.S9S_MB_2U(SCH_1):PAGE84

M_B_CPU0_SB_DQ<17> @S9S_MB_2U_LIB.S9S_MB_2U(SCH_1):M_B_CPU0_SB_DQ(17)
    U2  J19 DDR1_SB_DQ17 SOCKET4677_AZIF0045P001C01CS-SA   I169 @S9S_MB_2U_LIB.S9S_MB_2U(SCH_1):PAGE21
    J4  124 DQ17_B SCONN288_ADR50017P087CC-SCONN2A    I23 @S9S_MB_2U_LIB.S9S_MB_2U(SCH_1):PAGE85
    J3  124 DQ17_B SCONN288_ADR50017P130CC-SCONN2A   I180 @S9S_MB_2U_LIB.S9S_MB_2U(SCH_1):PAGE84

M_B_CPU0_SB_DQ<18> @S9S_MB_2U_LIB.S9S_MB_2U(SCH_1):M_B_CPU0_SB_DQ(18)
    U2  M20 DDR1_SB_DQ18 SOCKET4677_AZIF0045P001C01CS-SA   I169 @S9S_MB_2U_LIB.S9S_MB_2U(SCH_1):PAGE21
    J4  267 DQ18_B SCONN288_ADR50017P087CC-SCONN2A    I23 @S9S_MB_2U_LIB.S9S_MB_2U(SCH_1):PAGE85
    J3  267 DQ18_B SCONN288_ADR50017P130CC-SCONN2A   I180 @S9S_MB_2U_LIB.S9S_MB_2U(SCH_1):PAGE84

M_B_CPU0_SB_DQ<19> @S9S_MB_2U_LIB.S9S_MB_2U(SCH_1):M_B_CPU0_SB_DQ(19)
    U2  N19 DDR1_SB_DQ19 SOCKET4677_AZIF0045P001C01CS-SA   I169 @S9S_MB_2U_LIB.S9S_MB_2U(SCH_1):PAGE21
    J4  269 DQ19_B SCONN288_ADR50017P087CC-SCONN2A    I23 @S9S_MB_2U_LIB.S9S_MB_2U(SCH_1):PAGE85
    J3  269 DQ19_B SCONN288_ADR50017P130CC-SCONN2A   I180 @S9S_MB_2U_LIB.S9S_MB_2U(SCH_1):PAGE84

M_B_CPU0_SB_DQ<1> @S9S_MB_2U_LIB.S9S_MB_2U(SCH_1):M_B_CPU0_SB_DQ(1)
    U2  T28 DDR1_SB_DQ1 SOCKET4677_AZIF0045P001C01CS-SA   I169 @S9S_MB_2U_LIB.S9S_MB_2U(SCH_1):PAGE21
    J4  102  DQ1_B SCONN288_ADR50017P087CC-SCONN2A    I23 @S9S_MB_2U_LIB.S9S_MB_2U(SCH_1):PAGE85
    J3  102  DQ1_B SCONN288_ADR50017P130CC-SCONN2A   I180 @S9S_MB_2U_LIB.S9S_MB_2U(SCH_1):PAGE84

M_B_CPU0_SB_DQ<20> @S9S_MB_2U_LIB.S9S_MB_2U(SCH_1):M_B_CPU0_SB_DQ(20)
    U2  J17 DDR1_SB_DQ20 SOCKET4677_AZIF0045P001C01CS-SA   I169 @S9S_MB_2U_LIB.S9S_MB_2U(SCH_1):PAGE21
    J4  129 DQ20_B SCONN288_ADR50017P087CC-SCONN2A    I23 @S9S_MB_2U_LIB.S9S_MB_2U(SCH_1):PAGE85
    J3  129 DQ20_B SCONN288_ADR50017P130CC-SCONN2A   I180 @S9S_MB_2U_LIB.S9S_MB_2U(SCH_1):PAGE84

M_B_CPU0_SB_DQ<21> @S9S_MB_2U_LIB.S9S_MB_2U(SCH_1):M_B_CPU0_SB_DQ(21)
    U2  K16 DDR1_SB_DQ21 SOCKET4677_AZIF0045P001C01CS-SA   I169 @S9S_MB_2U_LIB.S9S_MB_2U(SCH_1):PAGE21
    J4  131 DQ21_B SCONN288_ADR50017P087CC-SCONN2A    I23 @S9S_MB_2U_LIB.S9S_MB_2U(SCH_1):PAGE85
    J3  131 DQ21_B SCONN288_ADR50017P130CC-SCONN2A   I180 @S9S_MB_2U_LIB.S9S_MB_2U(SCH_1):PAGE84

M_B_CPU0_SB_DQ<22> @S9S_MB_2U_LIB.S9S_MB_2U(SCH_1):M_B_CPU0_SB_DQ(22)
    U2  N17 DDR1_SB_DQ22 SOCKET4677_AZIF0045P001C01CS-SA   I169 @S9S_MB_2U_LIB.S9S_MB_2U(SCH_1):PAGE21
    J4  274 DQ22_B SCONN288_ADR50017P087CC-SCONN2A    I23 @S9S_MB_2U_LIB.S9S_MB_2U(SCH_1):PAGE85
    J3  274 DQ22_B SCONN288_ADR50017P130CC-SCONN2A   I180 @S9S_MB_2U_LIB.S9S_MB_2U(SCH_1):PAGE84

M_B_CPU0_SB_DQ<23> @S9S_MB_2U_LIB.S9S_MB_2U(SCH_1):M_B_CPU0_SB_DQ(23)
    U2  M16 DDR1_SB_DQ23 SOCKET4677_AZIF0045P001C01CS-SA   I169 @S9S_MB_2U_LIB.S9S_MB_2U(SCH_1):PAGE21
    J4  276 DQ23_B SCONN288_ADR50017P087CC-SCONN2A    I23 @S9S_MB_2U_LIB.S9S_MB_2U(SCH_1):PAGE85
    J3  276 DQ23_B SCONN288_ADR50017P130CC-SCONN2A   I180 @S9S_MB_2U_LIB.S9S_MB_2U(SCH_1):PAGE84

M_B_CPU0_SB_DQ<24> @S9S_MB_2U_LIB.S9S_MB_2U(SCH_1):M_B_CPU0_SB_DQ(24)
    U2  C17 DDR1_SB_DQ24 SOCKET4677_AZIF0045P001C01CS-SA   I169 @S9S_MB_2U_LIB.S9S_MB_2U(SCH_1):PAGE21
    J4  133 DQ24_B SCONN288_ADR50017P087CC-SCONN2A    I23 @S9S_MB_2U_LIB.S9S_MB_2U(SCH_1):PAGE85
    J3  133 DQ24_B SCONN288_ADR50017P130CC-SCONN2A   I180 @S9S_MB_2U_LIB.S9S_MB_2U(SCH_1):PAGE84

M_B_CPU0_SB_DQ<25> @S9S_MB_2U_LIB.S9S_MB_2U(SCH_1):M_B_CPU0_SB_DQ(25)
    U2  B16 DDR1_SB_DQ25 SOCKET4677_AZIF0045P001C01CS-SA   I169 @S9S_MB_2U_LIB.S9S_MB_2U(SCH_1):PAGE21
    J4  135 DQ25_B SCONN288_ADR50017P087CC-SCONN2A    I23 @S9S_MB_2U_LIB.S9S_MB_2U(SCH_1):PAGE85
    J3  135 DQ25_B SCONN288_ADR50017P130CC-SCONN2A   I180 @S9S_MB_2U_LIB.S9S_MB_2U(SCH_1):PAGE84

M_B_CPU0_SB_DQ<26> @S9S_MB_2U_LIB.S9S_MB_2U(SCH_1):M_B_CPU0_SB_DQ(26)
    U2  E17 DDR1_SB_DQ26 SOCKET4677_AZIF0045P001C01CS-SA   I169 @S9S_MB_2U_LIB.S9S_MB_2U(SCH_1):PAGE21
    J4  278 DQ26_B SCONN288_ADR50017P087CC-SCONN2A    I23 @S9S_MB_2U_LIB.S9S_MB_2U(SCH_1):PAGE85
    J3  278 DQ26_B SCONN288_ADR50017P130CC-SCONN2A   I180 @S9S_MB_2U_LIB.S9S_MB_2U(SCH_1):PAGE84

M_B_CPU0_SB_DQ<27> @S9S_MB_2U_LIB.S9S_MB_2U(SCH_1):M_B_CPU0_SB_DQ(27)
    U2  F16 DDR1_SB_DQ27 SOCKET4677_AZIF0045P001C01CS-SA   I169 @S9S_MB_2U_LIB.S9S_MB_2U(SCH_1):PAGE21
    J4  280 DQ27_B SCONN288_ADR50017P087CC-SCONN2A    I23 @S9S_MB_2U_LIB.S9S_MB_2U(SCH_1):PAGE85
    J3  280 DQ27_B SCONN288_ADR50017P130CC-SCONN2A   I180 @S9S_MB_2U_LIB.S9S_MB_2U(SCH_1):PAGE84

M_B_CPU0_SB_DQ<28> @S9S_MB_2U_LIB.S9S_MB_2U(SCH_1):M_B_CPU0_SB_DQ(28)
    U2  C13 DDR1_SB_DQ28 SOCKET4677_AZIF0045P001C01CS-SA   I169 @S9S_MB_2U_LIB.S9S_MB_2U(SCH_1):PAGE21
    J4  140 DQ28_B SCONN288_ADR50017P087CC-SCONN2A    I23 @S9S_MB_2U_LIB.S9S_MB_2U(SCH_1):PAGE85
    J3  140 DQ28_B SCONN288_ADR50017P130CC-SCONN2A   I180 @S9S_MB_2U_LIB.S9S_MB_2U(SCH_1):PAGE84

M_B_CPU0_SB_DQ<29> @S9S_MB_2U_LIB.S9S_MB_2U(SCH_1):M_B_CPU0_SB_DQ(29)
    U2  E13 DDR1_SB_DQ29 SOCKET4677_AZIF0045P001C01CS-SA   I169 @S9S_MB_2U_LIB.S9S_MB_2U(SCH_1):PAGE21
    J4  142 DQ29_B SCONN288_ADR50017P087CC-SCONN2A    I23 @S9S_MB_2U_LIB.S9S_MB_2U(SCH_1):PAGE85
    J3  142 DQ29_B SCONN288_ADR50017P130CC-SCONN2A   I180 @S9S_MB_2U_LIB.S9S_MB_2U(SCH_1):PAGE84

M_B_CPU0_SB_DQ<2> @S9S_MB_2U_LIB.S9S_MB_2U(SCH_1):M_B_CPU0_SB_DQ(2)
    U2  W29 DDR1_SB_DQ2 SOCKET4677_AZIF0045P001C01CS-SA   I169 @S9S_MB_2U_LIB.S9S_MB_2U(SCH_1):PAGE21
    J4  245  DQ2_B SCONN288_ADR50017P087CC-SCONN2A    I23 @S9S_MB_2U_LIB.S9S_MB_2U(SCH_1):PAGE85
    J3  245  DQ2_B SCONN288_ADR50017P130CC-SCONN2A   I180 @S9S_MB_2U_LIB.S9S_MB_2U(SCH_1):PAGE84

M_B_CPU0_SB_DQ<30> @S9S_MB_2U_LIB.S9S_MB_2U(SCH_1):M_B_CPU0_SB_DQ(30)
    U2  B14 DDR1_SB_DQ30 SOCKET4677_AZIF0045P001C01CS-SA   I169 @S9S_MB_2U_LIB.S9S_MB_2U(SCH_1):PAGE21
    J4  285 DQ30_B SCONN288_ADR50017P087CC-SCONN2A    I23 @S9S_MB_2U_LIB.S9S_MB_2U(SCH_1):PAGE85
    J3  285 DQ30_B SCONN288_ADR50017P130CC-SCONN2A   I180 @S9S_MB_2U_LIB.S9S_MB_2U(SCH_1):PAGE84

M_B_CPU0_SB_DQ<31> @S9S_MB_2U_LIB.S9S_MB_2U(SCH_1):M_B_CPU0_SB_DQ(31)
    U2  F14 DDR1_SB_DQ31 SOCKET4677_AZIF0045P001C01CS-SA   I169 @S9S_MB_2U_LIB.S9S_MB_2U(SCH_1):PAGE21
    J4  287 DQ31_B SCONN288_ADR50017P087CC-SCONN2A    I23 @S9S_MB_2U_LIB.S9S_MB_2U(SCH_1):PAGE85
    J3  287 DQ31_B SCONN288_ADR50017P130CC-SCONN2A   I180 @S9S_MB_2U_LIB.S9S_MB_2U(SCH_1):PAGE84

M_B_CPU0_SB_DQ<3> @S9S_MB_2U_LIB.S9S_MB_2U(SCH_1):M_B_CPU0_SB_DQ(3)
    U2  Y28 DDR1_SB_DQ3 SOCKET4677_AZIF0045P001C01CS-SA   I169 @S9S_MB_2U_LIB.S9S_MB_2U(SCH_1):PAGE21
    J4  247  DQ3_B SCONN288_ADR50017P087CC-SCONN2A    I23 @S9S_MB_2U_LIB.S9S_MB_2U(SCH_1):PAGE85
    J3  247  DQ3_B SCONN288_ADR50017P130CC-SCONN2A   I180 @S9S_MB_2U_LIB.S9S_MB_2U(SCH_1):PAGE84

M_B_CPU0_SB_DQ<4> @S9S_MB_2U_LIB.S9S_MB_2U(SCH_1):M_B_CPU0_SB_DQ(4)
    U2  T26 DDR1_SB_DQ4 SOCKET4677_AZIF0045P001C01CS-SA   I169 @S9S_MB_2U_LIB.S9S_MB_2U(SCH_1):PAGE21
    J4  107  DQ4_B SCONN288_ADR50017P087CC-SCONN2A    I23 @S9S_MB_2U_LIB.S9S_MB_2U(SCH_1):PAGE85
    J3  107  DQ4_B SCONN288_ADR50017P130CC-SCONN2A   I180 @S9S_MB_2U_LIB.S9S_MB_2U(SCH_1):PAGE84

M_B_CPU0_SB_DQ<5> @S9S_MB_2U_LIB.S9S_MB_2U(SCH_1):M_B_CPU0_SB_DQ(5)
    U2  U25 DDR1_SB_DQ5 SOCKET4677_AZIF0045P001C01CS-SA   I169 @S9S_MB_2U_LIB.S9S_MB_2U(SCH_1):PAGE21
    J4  109  DQ5_B SCONN288_ADR50017P087CC-SCONN2A    I23 @S9S_MB_2U_LIB.S9S_MB_2U(SCH_1):PAGE85
    J3  109  DQ5_B SCONN288_ADR50017P130CC-SCONN2A   I180 @S9S_MB_2U_LIB.S9S_MB_2U(SCH_1):PAGE84

M_B_CPU0_SB_DQ<6> @S9S_MB_2U_LIB.S9S_MB_2U(SCH_1):M_B_CPU0_SB_DQ(6)
    U2  Y26 DDR1_SB_DQ6 SOCKET4677_AZIF0045P001C01CS-SA   I169 @S9S_MB_2U_LIB.S9S_MB_2U(SCH_1):PAGE21
    J4  252  DQ6_B SCONN288_ADR50017P087CC-SCONN2A    I23 @S9S_MB_2U_LIB.S9S_MB_2U(SCH_1):PAGE85
    J3  252  DQ6_B SCONN288_ADR50017P130CC-SCONN2A   I180 @S9S_MB_2U_LIB.S9S_MB_2U(SCH_1):PAGE84

M_B_CPU0_SB_DQ<7> @S9S_MB_2U_LIB.S9S_MB_2U(SCH_1):M_B_CPU0_SB_DQ(7)
    U2  W25 DDR1_SB_DQ7 SOCKET4677_AZIF0045P001C01CS-SA   I169 @S9S_MB_2U_LIB.S9S_MB_2U(SCH_1):PAGE21
    J4  254  DQ7_B SCONN288_ADR50017P087CC-SCONN2A    I23 @S9S_MB_2U_LIB.S9S_MB_2U(SCH_1):PAGE85
    J3  254  DQ7_B SCONN288_ADR50017P130CC-SCONN2A   I180 @S9S_MB_2U_LIB.S9S_MB_2U(SCH_1):PAGE84

M_B_CPU0_SB_DQ<8> @S9S_MB_2U_LIB.S9S_MB_2U(SCH_1):M_B_CPU0_SB_DQ(8)
    U2  K26 DDR1_SB_DQ8 SOCKET4677_AZIF0045P001C01CS-SA   I169 @S9S_MB_2U_LIB.S9S_MB_2U(SCH_1):PAGE21
    J4  111  DQ8_B SCONN288_ADR50017P087CC-SCONN2A    I23 @S9S_MB_2U_LIB.S9S_MB_2U(SCH_1):PAGE85
    J3  111  DQ8_B SCONN288_ADR50017P130CC-SCONN2A   I180 @S9S_MB_2U_LIB.S9S_MB_2U(SCH_1):PAGE84

M_B_CPU0_SB_DQ<9> @S9S_MB_2U_LIB.S9S_MB_2U(SCH_1):M_B_CPU0_SB_DQ(9)
    U2  J25 DDR1_SB_DQ9 SOCKET4677_AZIF0045P001C01CS-SA   I169 @S9S_MB_2U_LIB.S9S_MB_2U(SCH_1):PAGE21
    J4  113  DQ9_B SCONN288_ADR50017P087CC-SCONN2A    I23 @S9S_MB_2U_LIB.S9S_MB_2U(SCH_1):PAGE85
    J3  113  DQ9_B SCONN288_ADR50017P130CC-SCONN2A   I180 @S9S_MB_2U_LIB.S9S_MB_2U(SCH_1):PAGE84

M_B_CPU0_SB_DQS_DN<0> @S9S_MB_2U_LIB.S9S_MB_2U(SCH_1):M_B_CPU0_SB_DQS_DN(0)
    U2  R27 DDR1_SB_DQS_DN0 SOCKET4677_AZIF0045P001C01CS-SA   I169 @S9S_MB_2U_LIB.S9S_MB_2U(SCH_1):PAGE21
    J4  105 DQS0_B_C SCONN288_ADR50017P087CC-SCONN2A   I178 @S9S_MB_2U_LIB.S9S_MB_2U(SCH_1):PAGE85
    J3  105 DQS0_B_C SCONN288_ADR50017P130CC-SCONN2A   I179 @S9S_MB_2U_LIB.S9S_MB_2U(SCH_1):PAGE84

M_B_CPU0_SB_DQS_DN<1> @S9S_MB_2U_LIB.S9S_MB_2U(SCH_1):M_B_CPU0_SB_DQS_DN(1)
    U2  H24 DDR1_SB_DQS_DN1 SOCKET4677_AZIF0045P001C01CS-SA   I169 @S9S_MB_2U_LIB.S9S_MB_2U(SCH_1):PAGE21
    J4  116 DQS1_B_C SCONN288_ADR50017P087CC-SCONN2A   I178 @S9S_MB_2U_LIB.S9S_MB_2U(SCH_1):PAGE85
    J3  116 DQS1_B_C SCONN288_ADR50017P130CC-SCONN2A   I179 @S9S_MB_2U_LIB.S9S_MB_2U(SCH_1):PAGE84

M_B_CPU0_SB_DQS_DN<2> @S9S_MB_2U_LIB.S9S_MB_2U(SCH_1):M_B_CPU0_SB_DQS_DN(2)
    U2  H18 DDR1_SB_DQS_DN2 SOCKET4677_AZIF0045P001C01CS-SA   I169 @S9S_MB_2U_LIB.S9S_MB_2U(SCH_1):PAGE21
    J4  127 DQS2_B_C SCONN288_ADR50017P087CC-SCONN2A   I178 @S9S_MB_2U_LIB.S9S_MB_2U(SCH_1):PAGE85
    J3  127 DQS2_B_C SCONN288_ADR50017P130CC-SCONN2A   I179 @S9S_MB_2U_LIB.S9S_MB_2U(SCH_1):PAGE84

M_B_CPU0_SB_DQS_DN<3> @S9S_MB_2U_LIB.S9S_MB_2U(SCH_1):M_B_CPU0_SB_DQS_DN(3)
    U2  A15 DDR1_SB_DQS_DN3 SOCKET4677_AZIF0045P001C01CS-SA   I169 @S9S_MB_2U_LIB.S9S_MB_2U(SCH_1):PAGE21
    J4  138 DQS3_B_C SCONN288_ADR50017P087CC-SCONN2A   I178 @S9S_MB_2U_LIB.S9S_MB_2U(SCH_1):PAGE85
    J3  138 DQS3_B_C SCONN288_ADR50017P130CC-SCONN2A   I179 @S9S_MB_2U_LIB.S9S_MB_2U(SCH_1):PAGE84

M_B_CPU0_SB_DQS_DN<4> @S9S_MB_2U_LIB.S9S_MB_2U(SCH_1):M_B_CPU0_SB_DQS_DN(4)
    U2  P36 DDR1_SB_DQS_DN4 SOCKET4677_AZIF0045P001C01CS-SA   I169 @S9S_MB_2U_LIB.S9S_MB_2U(SCH_1):PAGE21
    J4  238 DQS4_B_C SCONN288_ADR50017P087CC-SCONN2A   I178 @S9S_MB_2U_LIB.S9S_MB_2U(SCH_1):PAGE85
    J3  238 DQS4_B_C SCONN288_ADR50017P130CC-SCONN2A   I179 @S9S_MB_2U_LIB.S9S_MB_2U(SCH_1):PAGE84

M_B_CPU0_SB_DQS_DN<5> @S9S_MB_2U_LIB.S9S_MB_2U(SCH_1):M_B_CPU0_SB_DQS_DN(5)
    U2  W27 DDR1_SB_DQS_DN5 SOCKET4677_AZIF0045P001C01CS-SA   I169 @S9S_MB_2U_LIB.S9S_MB_2U(SCH_1):PAGE21
    J4  249 DQS5_B_C||TDQS5_B_C SCONN288_ADR50017P087CC-SCONN2A   I178 @S9S_MB_2U_LIB.S9S_MB_2U(SCH_1):PAGE85
    J3  249 DQS5_B_C||TDQS5_B_C SCONN288_ADR50017P130CC-SCONN2A   I179 @S9S_MB_2U_LIB.S9S_MB_2U(SCH_1):PAGE84

M_B_CPU0_SB_DQS_DN<6> @S9S_MB_2U_LIB.S9S_MB_2U(SCH_1):M_B_CPU0_SB_DQS_DN(6)
    U2  M24 DDR1_SB_DQS_DN6 SOCKET4677_AZIF0045P001C01CS-SA   I169 @S9S_MB_2U_LIB.S9S_MB_2U(SCH_1):PAGE21
    J4  260 DQS6_B_C||TDQS6_B_C SCONN288_ADR50017P087CC-SCONN2A   I178 @S9S_MB_2U_LIB.S9S_MB_2U(SCH_1):PAGE85
    J3  260 DQS6_B_C||TDQS6_B_C SCONN288_ADR50017P130CC-SCONN2A   I179 @S9S_MB_2U_LIB.S9S_MB_2U(SCH_1):PAGE84

M_B_CPU0_SB_DQS_DN<7> @S9S_MB_2U_LIB.S9S_MB_2U(SCH_1):M_B_CPU0_SB_DQS_DN(7)
    U2  M18 DDR1_SB_DQS_DN7 SOCKET4677_AZIF0045P001C01CS-SA   I169 @S9S_MB_2U_LIB.S9S_MB_2U(SCH_1):PAGE21
    J4  271 DQS7_B_C||TDQS7_B_C SCONN288_ADR50017P087CC-SCONN2A   I178 @S9S_MB_2U_LIB.S9S_MB_2U(SCH_1):PAGE85
    J3  271 DQS7_B_C||TDQS7_B_C SCONN288_ADR50017P130CC-SCONN2A   I179 @S9S_MB_2U_LIB.S9S_MB_2U(SCH_1):PAGE84

M_B_CPU0_SB_DQS_DN<8> @S9S_MB_2U_LIB.S9S_MB_2U(SCH_1):M_B_CPU0_SB_DQS_DN(8)
    U2  E15 DDR1_SB_DQS_DN8 SOCKET4677_AZIF0045P001C01CS-SA   I169 @S9S_MB_2U_LIB.S9S_MB_2U(SCH_1):PAGE21
    J4  282 DQS8_B_C||TDQS8_B_C SCONN288_ADR50017P087CC-SCONN2A   I178 @S9S_MB_2U_LIB.S9S_MB_2U(SCH_1):PAGE85
    J3  282 DQS8_B_C||TDQS8_B_C SCONN288_ADR50017P130CC-SCONN2A   I179 @S9S_MB_2U_LIB.S9S_MB_2U(SCH_1):PAGE84

M_B_CPU0_SB_DQS_DN<9> @S9S_MB_2U_LIB.S9S_MB_2U(SCH_1):M_B_CPU0_SB_DQS_DN(9)
    U2  K36 DDR1_SB_DQS_DN9 SOCKET4677_AZIF0045P001C01CS-SA   I169 @S9S_MB_2U_LIB.S9S_MB_2U(SCH_1):PAGE21
    J4   94 DQS9_B_C||TDQS9_B_C SCONN288_ADR50017P087CC-SCONN2A   I178 @S9S_MB_2U_LIB.S9S_MB_2U(SCH_1):PAGE85
    J3   94 DQS9_B_C||TDQS9_B_C SCONN288_ADR50017P130CC-SCONN2A   I179 @S9S_MB_2U_LIB.S9S_MB_2U(SCH_1):PAGE84

M_B_CPU0_SB_DQS_DP<0> @S9S_MB_2U_LIB.S9S_MB_2U(SCH_1):M_B_CPU0_SB_DQS_DP(0)
    U2  U27 DDR1_SB_DQS_DP0 SOCKET4677_AZIF0045P001C01CS-SA   I169 @S9S_MB_2U_LIB.S9S_MB_2U(SCH_1):PAGE21
    J4  104 DQS0_B_T SCONN288_ADR50017P087CC-SCONN2A   I178 @S9S_MB_2U_LIB.S9S_MB_2U(SCH_1):PAGE85
    J3  104 DQS0_B_T SCONN288_ADR50017P130CC-SCONN2A   I179 @S9S_MB_2U_LIB.S9S_MB_2U(SCH_1):PAGE84

M_B_CPU0_SB_DQS_DP<1> @S9S_MB_2U_LIB.S9S_MB_2U(SCH_1):M_B_CPU0_SB_DQS_DP(1)
    U2  K24 DDR1_SB_DQS_DP1 SOCKET4677_AZIF0045P001C01CS-SA   I169 @S9S_MB_2U_LIB.S9S_MB_2U(SCH_1):PAGE21
    J4  115 DQS1_B_T SCONN288_ADR50017P087CC-SCONN2A   I178 @S9S_MB_2U_LIB.S9S_MB_2U(SCH_1):PAGE85
    J3  115 DQS1_B_T SCONN288_ADR50017P130CC-SCONN2A   I179 @S9S_MB_2U_LIB.S9S_MB_2U(SCH_1):PAGE84

M_B_CPU0_SB_DQS_DP<2> @S9S_MB_2U_LIB.S9S_MB_2U(SCH_1):M_B_CPU0_SB_DQS_DP(2)
    U2  K18 DDR1_SB_DQS_DP2 SOCKET4677_AZIF0045P001C01CS-SA   I169 @S9S_MB_2U_LIB.S9S_MB_2U(SCH_1):PAGE21
    J4  126 DQS2_B_T SCONN288_ADR50017P087CC-SCONN2A   I178 @S9S_MB_2U_LIB.S9S_MB_2U(SCH_1):PAGE85
    J3  126 DQS2_B_T SCONN288_ADR50017P130CC-SCONN2A   I179 @S9S_MB_2U_LIB.S9S_MB_2U(SCH_1):PAGE84

M_B_CPU0_SB_DQS_DP<3> @S9S_MB_2U_LIB.S9S_MB_2U(SCH_1):M_B_CPU0_SB_DQS_DP(3)
    U2  C15 DDR1_SB_DQS_DP3 SOCKET4677_AZIF0045P001C01CS-SA   I169 @S9S_MB_2U_LIB.S9S_MB_2U(SCH_1):PAGE21
    J4  137 DQS3_B_T SCONN288_ADR50017P087CC-SCONN2A   I178 @S9S_MB_2U_LIB.S9S_MB_2U(SCH_1):PAGE85
    J3  137 DQS3_B_T SCONN288_ADR50017P130CC-SCONN2A   I179 @S9S_MB_2U_LIB.S9S_MB_2U(SCH_1):PAGE84

M_B_CPU0_SB_DQS_DP<4> @S9S_MB_2U_LIB.S9S_MB_2U(SCH_1):M_B_CPU0_SB_DQS_DP(4)
    U2  M36 DDR1_SB_DQS_DP4 SOCKET4677_AZIF0045P001C01CS-SA   I169 @S9S_MB_2U_LIB.S9S_MB_2U(SCH_1):PAGE21
    J4  239 DQS4_B_T SCONN288_ADR50017P087CC-SCONN2A   I178 @S9S_MB_2U_LIB.S9S_MB_2U(SCH_1):PAGE85
    J3  239 DQS4_B_T SCONN288_ADR50017P130CC-SCONN2A   I179 @S9S_MB_2U_LIB.S9S_MB_2U(SCH_1):PAGE84

M_B_CPU0_SB_DQS_DP<5> @S9S_MB_2U_LIB.S9S_MB_2U(SCH_1):M_B_CPU0_SB_DQS_DP(5)
    U2 AA27 DDR1_SB_DQS_DP5 SOCKET4677_AZIF0045P001C01CS-SA   I169 @S9S_MB_2U_LIB.S9S_MB_2U(SCH_1):PAGE21
    J4  250 DQS5_B_T||TDQS5_B_T SCONN288_ADR50017P087CC-SCONN2A   I178 @S9S_MB_2U_LIB.S9S_MB_2U(SCH_1):PAGE85
    J3  250 DQS5_B_T||TDQS5_B_T SCONN288_ADR50017P130CC-SCONN2A   I179 @S9S_MB_2U_LIB.S9S_MB_2U(SCH_1):PAGE84

M_B_CPU0_SB_DQS_DP<6> @S9S_MB_2U_LIB.S9S_MB_2U(SCH_1):M_B_CPU0_SB_DQS_DP(6)
    U2  P24 DDR1_SB_DQS_DP6 SOCKET4677_AZIF0045P001C01CS-SA   I169 @S9S_MB_2U_LIB.S9S_MB_2U(SCH_1):PAGE21
    J4  261 DQS6_B_T||TDQS6_B_T SCONN288_ADR50017P087CC-SCONN2A   I178 @S9S_MB_2U_LIB.S9S_MB_2U(SCH_1):PAGE85
    J3  261 DQS6_B_T||TDQS6_B_T SCONN288_ADR50017P130CC-SCONN2A   I179 @S9S_MB_2U_LIB.S9S_MB_2U(SCH_1):PAGE84

M_B_CPU0_SB_DQS_DP<7> @S9S_MB_2U_LIB.S9S_MB_2U(SCH_1):M_B_CPU0_SB_DQS_DP(7)
    U2  P18 DDR1_SB_DQS_DP7 SOCKET4677_AZIF0045P001C01CS-SA   I169 @S9S_MB_2U_LIB.S9S_MB_2U(SCH_1):PAGE21
    J4  272 DQS7_B_T||TDQS7_B_T SCONN288_ADR50017P087CC-SCONN2A   I178 @S9S_MB_2U_LIB.S9S_MB_2U(SCH_1):PAGE85
    J3  272 DQS7_B_T||TDQS7_B_T SCONN288_ADR50017P130CC-SCONN2A   I179 @S9S_MB_2U_LIB.S9S_MB_2U(SCH_1):PAGE84

M_B_CPU0_SB_DQS_DP<8> @S9S_MB_2U_LIB.S9S_MB_2U(SCH_1):M_B_CPU0_SB_DQS_DP(8)
    U2  G15 DDR1_SB_DQS_DP8 SOCKET4677_AZIF0045P001C01CS-SA   I169 @S9S_MB_2U_LIB.S9S_MB_2U(SCH_1):PAGE21
    J4  283 DQS8_B_T||TDQS8_B_T SCONN288_ADR50017P087CC-SCONN2A   I178 @S9S_MB_2U_LIB.S9S_MB_2U(SCH_1):PAGE85
    J3  283 DQS8_B_T||TDQS8_B_T SCONN288_ADR50017P130CC-SCONN2A   I179 @S9S_MB_2U_LIB.S9S_MB_2U(SCH_1):PAGE84

M_B_CPU0_SB_DQS_DP<9> @S9S_MB_2U_LIB.S9S_MB_2U(SCH_1):M_B_CPU0_SB_DQS_DP(9)
    U2  H36 DDR1_SB_DQS_DP9 SOCKET4677_AZIF0045P001C01CS-SA   I169 @S9S_MB_2U_LIB.S9S_MB_2U(SCH_1):PAGE21
    J4   93 DQS9_B_T||TDQS9_B_T||DBI4_B_N SCONN288_ADR50017P087CC-SCONN2A   I178 @S9S_MB_2U_LIB.S9S_MB_2U(SCH_1):PAGE85
    J3   93 DQS9_B_T||TDQS9_B_T||DBI4_B_N SCONN288_ADR50017P130CC-SCONN2A   I179 @S9S_MB_2U_LIB.S9S_MB_2U(SCH_1):PAGE84

M_B_CPU0_SB_PAR @S9S_MB_2U_LIB.S9S_MB_2U(SCH_1):M_B_CPU0_SB_PAR
    U2  P42 DDR1_SB_PAR SOCKET4677_AZIF0045P001C01CS-SA   I169 @S9S_MB_2U_LIB.S9S_MB_2U(SCH_1):PAGE21
    J4  227  PAR_B SCONN288_ADR50017P087CC-SCONN2A    I23 @S9S_MB_2U_LIB.S9S_MB_2U(SCH_1):PAGE85
    J3  227  PAR_B SCONN288_ADR50017P130CC-SCONN2A   I180 @S9S_MB_2U_LIB.S9S_MB_2U(SCH_1):PAGE84

M_B_CPU0_SB_RSP<0> @S9S_MB_2U_LIB.S9S_MB_2U(SCH_1):M_B_CPU0_SB_RSP(0)
    U2 AN48 DDR1_B_RSP0 SOCKET4677_AZIF0045P001C01CS-SA   I169 @S9S_MB_2U_LIB.S9S_MB_2U(SCH_1):PAGE21
    J3   87 LBS||RSP_B_N SCONN288_ADR50017P130CC-SCONN2A   I180 @S9S_MB_2U_LIB.S9S_MB_2U(SCH_1):PAGE84

M_B_CPU0_SB_RSP<1> @S9S_MB_2U_LIB.S9S_MB_2U(SCH_1):M_B_CPU0_SB_RSP(1)
    U2 AP47 DDR1_B_RSP1 SOCKET4677_AZIF0045P001C01CS-SA   I169 @S9S_MB_2U_LIB.S9S_MB_2U(SCH_1):PAGE21
    J4   87 LBS||RSP_B_N SCONN288_ADR50017P087CC-SCONN2A    I23 @S9S_MB_2U_LIB.S9S_MB_2U(SCH_1):PAGE85

M_B_CPU1_ALERT_N @S9S_MB_2U_LIB.S9S_MB_2U(SCH_1):M_B_CPU1_ALERT_N
    U1 AV49 DDR1_ALERT_N SOCKET4677_AZIF0045P001C01CS-SA    I91 @S9S_MB_2U_LIB.S9S_MB_2U(SCH_1):PAGE52
   J19   62 ALERT_N SCONN288_ADR50017P130CC-SCONN2A    I25 @S9S_MB_2U_LIB.S9S_MB_2U(SCH_1):PAGE100
   J20   62 ALERT_N SCONN288_ADR50017P087CC-SCONN2A    I47 @S9S_MB_2U_LIB.S9S_MB_2U(SCH_1):PAGE101

M_B_CPU1_CLK_DN<0> @S9S_MB_2U_LIB.S9S_MB_2U(SCH_1):M_B_CPU1_CLK_DN(0)
    U1  R45 DDR1_CLK_DN0 SOCKET4677_AZIF0045P001C01CS-SA    I91 @S9S_MB_2U_LIB.S9S_MB_2U(SCH_1):PAGE52
   J19  218   CK_C SCONN288_ADR50017P130CC-SCONN2A    I25 @S9S_MB_2U_LIB.S9S_MB_2U(SCH_1):PAGE100

M_B_CPU1_CLK_DN<1> @S9S_MB_2U_LIB.S9S_MB_2U(SCH_1):M_B_CPU1_CLK_DN(1)
    U1  W45 DDR1_CLK_DN1 SOCKET4677_AZIF0045P001C01CS-SA    I91 @S9S_MB_2U_LIB.S9S_MB_2U(SCH_1):PAGE52
   J20  218   CK_C SCONN288_ADR50017P087CC-SCONN2A    I47 @S9S_MB_2U_LIB.S9S_MB_2U(SCH_1):PAGE101

M_B_CPU1_CLK_DP<0> @S9S_MB_2U_LIB.S9S_MB_2U(SCH_1):M_B_CPU1_CLK_DP(0)
    U1  U45 DDR1_CLK_DP0 SOCKET4677_AZIF0045P001C01CS-SA    I91 @S9S_MB_2U_LIB.S9S_MB_2U(SCH_1):PAGE52
   J19  217   CK_T SCONN288_ADR50017P130CC-SCONN2A    I25 @S9S_MB_2U_LIB.S9S_MB_2U(SCH_1):PAGE100

M_B_CPU1_CLK_DP<1> @S9S_MB_2U_LIB.S9S_MB_2U(SCH_1):M_B_CPU1_CLK_DP(1)
    U1 AA45 DDR1_CLK_DP1 SOCKET4677_AZIF0045P001C01CS-SA    I91 @S9S_MB_2U_LIB.S9S_MB_2U(SCH_1):PAGE52
   J20  217   CK_T SCONN288_ADR50017P087CC-SCONN2A    I47 @S9S_MB_2U_LIB.S9S_MB_2U(SCH_1):PAGE101

M_B_CPU1_SA_CA<0> @S9S_MB_2U_LIB.S9S_MB_2U(SCH_1):M_B_CPU1_SA_CA(0)
    U1  H49 DDR1_SA_CA0 SOCKET4677_AZIF0045P001C01CS-SA    I91 @S9S_MB_2U_LIB.S9S_MB_2U(SCH_1):PAGE52
   J19   66  CA0_A SCONN288_ADR50017P130CC-SCONN2A    I25 @S9S_MB_2U_LIB.S9S_MB_2U(SCH_1):PAGE100
   J20   66  CA0_A SCONN288_ADR50017P087CC-SCONN2A    I47 @S9S_MB_2U_LIB.S9S_MB_2U(SCH_1):PAGE101

M_B_CPU1_SA_CA<1> @S9S_MB_2U_LIB.S9S_MB_2U(SCH_1):M_B_CPU1_SA_CA(1)
    U1  P49 DDR1_SA_CA1 SOCKET4677_AZIF0045P001C01CS-SA    I91 @S9S_MB_2U_LIB.S9S_MB_2U(SCH_1):PAGE52
   J19  211  CA1_A SCONN288_ADR50017P130CC-SCONN2A    I25 @S9S_MB_2U_LIB.S9S_MB_2U(SCH_1):PAGE100
   J20  211  CA1_A SCONN288_ADR50017P087CC-SCONN2A    I47 @S9S_MB_2U_LIB.S9S_MB_2U(SCH_1):PAGE101

M_B_CPU1_SA_CA<2> @S9S_MB_2U_LIB.S9S_MB_2U(SCH_1):M_B_CPU1_SA_CA(2)
    U1  J48 DDR1_SA_CA2 SOCKET4677_AZIF0045P001C01CS-SA    I91 @S9S_MB_2U_LIB.S9S_MB_2U(SCH_1):PAGE52
   J19   68  CA2_A SCONN288_ADR50017P130CC-SCONN2A    I25 @S9S_MB_2U_LIB.S9S_MB_2U(SCH_1):PAGE100
   J20   68  CA2_A SCONN288_ADR50017P087CC-SCONN2A    I47 @S9S_MB_2U_LIB.S9S_MB_2U(SCH_1):PAGE101

M_B_CPU1_SA_CA<3> @S9S_MB_2U_LIB.S9S_MB_2U(SCH_1):M_B_CPU1_SA_CA(3)
    U1  N48 DDR1_SA_CA3 SOCKET4677_AZIF0045P001C01CS-SA    I91 @S9S_MB_2U_LIB.S9S_MB_2U(SCH_1):PAGE52
   J19  213  CA3_A SCONN288_ADR50017P130CC-SCONN2A    I25 @S9S_MB_2U_LIB.S9S_MB_2U(SCH_1):PAGE100
   J20  213  CA3_A SCONN288_ADR50017P087CC-SCONN2A    I47 @S9S_MB_2U_LIB.S9S_MB_2U(SCH_1):PAGE101

M_B_CPU1_SA_CA<4> @S9S_MB_2U_LIB.S9S_MB_2U(SCH_1):M_B_CPU1_SA_CA(4)
    U1  K47 DDR1_SA_CA4 SOCKET4677_AZIF0045P001C01CS-SA    I91 @S9S_MB_2U_LIB.S9S_MB_2U(SCH_1):PAGE52
   J19   70  CA4_A SCONN288_ADR50017P130CC-SCONN2A    I25 @S9S_MB_2U_LIB.S9S_MB_2U(SCH_1):PAGE100
   J20   70  CA4_A SCONN288_ADR50017P087CC-SCONN2A    I47 @S9S_MB_2U_LIB.S9S_MB_2U(SCH_1):PAGE101

M_B_CPU1_SA_CA<5> @S9S_MB_2U_LIB.S9S_MB_2U(SCH_1):M_B_CPU1_SA_CA(5)
    U1  M47 DDR1_SA_CA5 SOCKET4677_AZIF0045P001C01CS-SA    I91 @S9S_MB_2U_LIB.S9S_MB_2U(SCH_1):PAGE52
   J19  215  CA5_A SCONN288_ADR50017P130CC-SCONN2A    I25 @S9S_MB_2U_LIB.S9S_MB_2U(SCH_1):PAGE100
   J20  215  CA5_A SCONN288_ADR50017P087CC-SCONN2A    I47 @S9S_MB_2U_LIB.S9S_MB_2U(SCH_1):PAGE101

M_B_CPU1_SA_CA<6> @S9S_MB_2U_LIB.S9S_MB_2U(SCH_1):M_B_CPU1_SA_CA(6)
    U1  Y44 DDR1_SA_CA6 SOCKET4677_AZIF0045P001C01CS-SA    I91 @S9S_MB_2U_LIB.S9S_MB_2U(SCH_1):PAGE52
   J19   72  CA6_A SCONN288_ADR50017P130CC-SCONN2A    I25 @S9S_MB_2U_LIB.S9S_MB_2U(SCH_1):PAGE100
   J20   72  CA6_A SCONN288_ADR50017P087CC-SCONN2A    I47 @S9S_MB_2U_LIB.S9S_MB_2U(SCH_1):PAGE101

M_B_CPU1_SA_CB<0> @S9S_MB_2U_LIB.S9S_MB_2U(SCH_1):M_B_CPU1_SA_CB(0)
    U1  K57 DDR1_SA_ECC0 SOCKET4677_AZIF0045P001C01CS-SA    I91 @S9S_MB_2U_LIB.S9S_MB_2U(SCH_1):PAGE52
   J19   51  CB0_A SCONN288_ADR50017P130CC-SCONN2A    I25 @S9S_MB_2U_LIB.S9S_MB_2U(SCH_1):PAGE100
   J20   51  CB0_A SCONN288_ADR50017P087CC-SCONN2A    I47 @S9S_MB_2U_LIB.S9S_MB_2U(SCH_1):PAGE101

M_B_CPU1_SA_CB<1> @S9S_MB_2U_LIB.S9S_MB_2U(SCH_1):M_B_CPU1_SA_CB(1)
    U1  J56 DDR1_SA_ECC1 SOCKET4677_AZIF0045P001C01CS-SA    I91 @S9S_MB_2U_LIB.S9S_MB_2U(SCH_1):PAGE52
   J19   53  CB1_A SCONN288_ADR50017P130CC-SCONN2A    I25 @S9S_MB_2U_LIB.S9S_MB_2U(SCH_1):PAGE100
   J20   53  CB1_A SCONN288_ADR50017P087CC-SCONN2A    I47 @S9S_MB_2U_LIB.S9S_MB_2U(SCH_1):PAGE101

M_B_CPU1_SA_CB<2> @S9S_MB_2U_LIB.S9S_MB_2U(SCH_1):M_B_CPU1_SA_CB(2)
    U1  M57 DDR1_SA_ECC2 SOCKET4677_AZIF0045P001C01CS-SA    I91 @S9S_MB_2U_LIB.S9S_MB_2U(SCH_1):PAGE52
   J19  196  CB2_A SCONN288_ADR50017P130CC-SCONN2A    I25 @S9S_MB_2U_LIB.S9S_MB_2U(SCH_1):PAGE100
   J20  196  CB2_A SCONN288_ADR50017P087CC-SCONN2A    I47 @S9S_MB_2U_LIB.S9S_MB_2U(SCH_1):PAGE101

M_B_CPU1_SA_CB<3> @S9S_MB_2U_LIB.S9S_MB_2U(SCH_1):M_B_CPU1_SA_CB(3)
    U1  N56 DDR1_SA_ECC3 SOCKET4677_AZIF0045P001C01CS-SA    I91 @S9S_MB_2U_LIB.S9S_MB_2U(SCH_1):PAGE52
   J19  198  CB3_A SCONN288_ADR50017P130CC-SCONN2A    I25 @S9S_MB_2U_LIB.S9S_MB_2U(SCH_1):PAGE100
   J20  198  CB3_A SCONN288_ADR50017P087CC-SCONN2A    I47 @S9S_MB_2U_LIB.S9S_MB_2U(SCH_1):PAGE101

M_B_CPU1_SA_CB<4> @S9S_MB_2U_LIB.S9S_MB_2U(SCH_1):M_B_CPU1_SA_CB(4)
    U1  J54 DDR1_SA_ECC4 SOCKET4677_AZIF0045P001C01CS-SA    I91 @S9S_MB_2U_LIB.S9S_MB_2U(SCH_1):PAGE52
   J19   58  CB4_A SCONN288_ADR50017P130CC-SCONN2A    I25 @S9S_MB_2U_LIB.S9S_MB_2U(SCH_1):PAGE100
   J20   58  CB4_A SCONN288_ADR50017P087CC-SCONN2A    I47 @S9S_MB_2U_LIB.S9S_MB_2U(SCH_1):PAGE101

M_B_CPU1_SA_CB<5> @S9S_MB_2U_LIB.S9S_MB_2U(SCH_1):M_B_CPU1_SA_CB(5)
    U1  K53 DDR1_SA_ECC5 SOCKET4677_AZIF0045P001C01CS-SA    I91 @S9S_MB_2U_LIB.S9S_MB_2U(SCH_1):PAGE52
   J19   60  CB5_A SCONN288_ADR50017P130CC-SCONN2A    I25 @S9S_MB_2U_LIB.S9S_MB_2U(SCH_1):PAGE100
   J20   60  CB5_A SCONN288_ADR50017P087CC-SCONN2A    I47 @S9S_MB_2U_LIB.S9S_MB_2U(SCH_1):PAGE101

M_B_CPU1_SA_CB<6> @S9S_MB_2U_LIB.S9S_MB_2U(SCH_1):M_B_CPU1_SA_CB(6)
    U1  N54 DDR1_SA_ECC6 SOCKET4677_AZIF0045P001C01CS-SA    I91 @S9S_MB_2U_LIB.S9S_MB_2U(SCH_1):PAGE52
   J19  203  CB6_A SCONN288_ADR50017P130CC-SCONN2A    I25 @S9S_MB_2U_LIB.S9S_MB_2U(SCH_1):PAGE100
   J20  203  CB6_A SCONN288_ADR50017P087CC-SCONN2A    I47 @S9S_MB_2U_LIB.S9S_MB_2U(SCH_1):PAGE101

M_B_CPU1_SA_CB<7> @S9S_MB_2U_LIB.S9S_MB_2U(SCH_1):M_B_CPU1_SA_CB(7)
    U1  M53 DDR1_SA_ECC7 SOCKET4677_AZIF0045P001C01CS-SA    I91 @S9S_MB_2U_LIB.S9S_MB_2U(SCH_1):PAGE52
   J19  205  CB7_A SCONN288_ADR50017P130CC-SCONN2A    I25 @S9S_MB_2U_LIB.S9S_MB_2U(SCH_1):PAGE100
   J20  205  CB7_A SCONN288_ADR50017P087CC-SCONN2A    I47 @S9S_MB_2U_LIB.S9S_MB_2U(SCH_1):PAGE101

M_B_CPU1_SA_CS_N<0> @S9S_MB_2U_LIB.S9S_MB_2U(SCH_1):M_B_CPU1_SA_CS_N(0)
    U1  K51 DDR1_SA_CS_N0 SOCKET4677_AZIF0045P001C01CS-SA    I91 @S9S_MB_2U_LIB.S9S_MB_2U(SCH_1):PAGE52
   J19   64 CS0_A_N SCONN288_ADR50017P130CC-SCONN2A    I25 @S9S_MB_2U_LIB.S9S_MB_2U(SCH_1):PAGE100

M_B_CPU1_SA_CS_N<1> @S9S_MB_2U_LIB.S9S_MB_2U(SCH_1):M_B_CPU1_SA_CS_N(1)
    U1  J50 DDR1_SA_CS_N1 SOCKET4677_AZIF0045P001C01CS-SA    I91 @S9S_MB_2U_LIB.S9S_MB_2U(SCH_1):PAGE52
   J19  209 CS1_A_N SCONN288_ADR50017P130CC-SCONN2A    I25 @S9S_MB_2U_LIB.S9S_MB_2U(SCH_1):PAGE100

M_B_CPU1_SA_CS_N<2> @S9S_MB_2U_LIB.S9S_MB_2U(SCH_1):M_B_CPU1_SA_CS_N(2)
    U1  M51 DDR1_SA_CS_N2 SOCKET4677_AZIF0045P001C01CS-SA    I91 @S9S_MB_2U_LIB.S9S_MB_2U(SCH_1):PAGE52
   J20   64 CS0_A_N SCONN288_ADR50017P087CC-SCONN2A    I47 @S9S_MB_2U_LIB.S9S_MB_2U(SCH_1):PAGE101

M_B_CPU1_SA_CS_N<3> @S9S_MB_2U_LIB.S9S_MB_2U(SCH_1):M_B_CPU1_SA_CS_N(3)
    U1  N50 DDR1_SA_CS_N3 SOCKET4677_AZIF0045P001C01CS-SA    I91 @S9S_MB_2U_LIB.S9S_MB_2U(SCH_1):PAGE52
   J20  209 CS1_A_N SCONN288_ADR50017P087CC-SCONN2A    I47 @S9S_MB_2U_LIB.S9S_MB_2U(SCH_1):PAGE101

M_B_CPU1_SA_DQ<0> @S9S_MB_2U_LIB.S9S_MB_2U(SCH_1):M_B_CPU1_SA_DQ(0)
    U1  K75 DDR1_SA_DQ0 SOCKET4677_AZIF0045P001C01CS-SA    I91 @S9S_MB_2U_LIB.S9S_MB_2U(SCH_1):PAGE52
   J19    7  DQ0_A SCONN288_ADR50017P130CC-SCONN2A    I25 @S9S_MB_2U_LIB.S9S_MB_2U(SCH_1):PAGE100
   J20    7  DQ0_A SCONN288_ADR50017P087CC-SCONN2A    I47 @S9S_MB_2U_LIB.S9S_MB_2U(SCH_1):PAGE101

M_B_CPU1_SA_DQ<10> @S9S_MB_2U_LIB.S9S_MB_2U(SCH_1):M_B_CPU1_SA_DQ(10)
    U1  W72 DDR1_SA_DQ10 SOCKET4677_AZIF0045P001C01CS-SA    I91 @S9S_MB_2U_LIB.S9S_MB_2U(SCH_1):PAGE52
   J19  163 DQ10_A SCONN288_ADR50017P130CC-SCONN2A    I25 @S9S_MB_2U_LIB.S9S_MB_2U(SCH_1):PAGE100
   J20  163 DQ10_A SCONN288_ADR50017P087CC-SCONN2A    I47 @S9S_MB_2U_LIB.S9S_MB_2U(SCH_1):PAGE101

M_B_CPU1_SA_DQ<11> @S9S_MB_2U_LIB.S9S_MB_2U(SCH_1):M_B_CPU1_SA_DQ(11)
    U1  Y71 DDR1_SA_DQ11 SOCKET4677_AZIF0045P001C01CS-SA    I91 @S9S_MB_2U_LIB.S9S_MB_2U(SCH_1):PAGE52
   J19  165 DQ11_A SCONN288_ADR50017P130CC-SCONN2A    I25 @S9S_MB_2U_LIB.S9S_MB_2U(SCH_1):PAGE100
   J20  165 DQ11_A SCONN288_ADR50017P087CC-SCONN2A    I47 @S9S_MB_2U_LIB.S9S_MB_2U(SCH_1):PAGE101

M_B_CPU1_SA_DQ<12> @S9S_MB_2U_LIB.S9S_MB_2U(SCH_1):M_B_CPU1_SA_DQ(12)
    U1  T69 DDR1_SA_DQ12 SOCKET4677_AZIF0045P001C01CS-SA    I91 @S9S_MB_2U_LIB.S9S_MB_2U(SCH_1):PAGE52
   J19   25 DQ12_A SCONN288_ADR50017P130CC-SCONN2A    I25 @S9S_MB_2U_LIB.S9S_MB_2U(SCH_1):PAGE100
   J20   25 DQ12_A SCONN288_ADR50017P087CC-SCONN2A    I47 @S9S_MB_2U_LIB.S9S_MB_2U(SCH_1):PAGE101

M_B_CPU1_SA_DQ<13> @S9S_MB_2U_LIB.S9S_MB_2U(SCH_1):M_B_CPU1_SA_DQ(13)
    U1  U68 DDR1_SA_DQ13 SOCKET4677_AZIF0045P001C01CS-SA    I91 @S9S_MB_2U_LIB.S9S_MB_2U(SCH_1):PAGE52
   J19   27 DQ13_A SCONN288_ADR50017P130CC-SCONN2A    I25 @S9S_MB_2U_LIB.S9S_MB_2U(SCH_1):PAGE100
   J20   27 DQ13_A SCONN288_ADR50017P087CC-SCONN2A    I47 @S9S_MB_2U_LIB.S9S_MB_2U(SCH_1):PAGE101

M_B_CPU1_SA_DQ<14> @S9S_MB_2U_LIB.S9S_MB_2U(SCH_1):M_B_CPU1_SA_DQ(14)
    U1  Y69 DDR1_SA_DQ14 SOCKET4677_AZIF0045P001C01CS-SA    I91 @S9S_MB_2U_LIB.S9S_MB_2U(SCH_1):PAGE52
   J19  170 DQ14_A SCONN288_ADR50017P130CC-SCONN2A    I25 @S9S_MB_2U_LIB.S9S_MB_2U(SCH_1):PAGE100
   J20  170 DQ14_A SCONN288_ADR50017P087CC-SCONN2A    I47 @S9S_MB_2U_LIB.S9S_MB_2U(SCH_1):PAGE101

M_B_CPU1_SA_DQ<15> @S9S_MB_2U_LIB.S9S_MB_2U(SCH_1):M_B_CPU1_SA_DQ(15)
    U1  W68 DDR1_SA_DQ15 SOCKET4677_AZIF0045P001C01CS-SA    I91 @S9S_MB_2U_LIB.S9S_MB_2U(SCH_1):PAGE52
   J19  172 DQ15_A SCONN288_ADR50017P130CC-SCONN2A    I25 @S9S_MB_2U_LIB.S9S_MB_2U(SCH_1):PAGE100
   J20  172 DQ15_A SCONN288_ADR50017P087CC-SCONN2A    I47 @S9S_MB_2U_LIB.S9S_MB_2U(SCH_1):PAGE101

M_B_CPU1_SA_DQ<16> @S9S_MB_2U_LIB.S9S_MB_2U(SCH_1):M_B_CPU1_SA_DQ(16)
    U1  K63 DDR1_SA_DQ16 SOCKET4677_AZIF0045P001C01CS-SA    I91 @S9S_MB_2U_LIB.S9S_MB_2U(SCH_1):PAGE52
   J19   29 DQ16_A SCONN288_ADR50017P130CC-SCONN2A    I25 @S9S_MB_2U_LIB.S9S_MB_2U(SCH_1):PAGE100
   J20   29 DQ16_A SCONN288_ADR50017P087CC-SCONN2A    I47 @S9S_MB_2U_LIB.S9S_MB_2U(SCH_1):PAGE101

M_B_CPU1_SA_DQ<17> @S9S_MB_2U_LIB.S9S_MB_2U(SCH_1):M_B_CPU1_SA_DQ(17)
    U1  J62 DDR1_SA_DQ17 SOCKET4677_AZIF0045P001C01CS-SA    I91 @S9S_MB_2U_LIB.S9S_MB_2U(SCH_1):PAGE52
   J19   31 DQ17_A SCONN288_ADR50017P130CC-SCONN2A    I25 @S9S_MB_2U_LIB.S9S_MB_2U(SCH_1):PAGE100
   J20   31 DQ17_A SCONN288_ADR50017P087CC-SCONN2A    I47 @S9S_MB_2U_LIB.S9S_MB_2U(SCH_1):PAGE101

M_B_CPU1_SA_DQ<18> @S9S_MB_2U_LIB.S9S_MB_2U(SCH_1):M_B_CPU1_SA_DQ(18)
    U1  M63 DDR1_SA_DQ18 SOCKET4677_AZIF0045P001C01CS-SA    I91 @S9S_MB_2U_LIB.S9S_MB_2U(SCH_1):PAGE52
   J19  174 DQ18_A SCONN288_ADR50017P130CC-SCONN2A    I25 @S9S_MB_2U_LIB.S9S_MB_2U(SCH_1):PAGE100
   J20  174 DQ18_A SCONN288_ADR50017P087CC-SCONN2A    I47 @S9S_MB_2U_LIB.S9S_MB_2U(SCH_1):PAGE101

M_B_CPU1_SA_DQ<19> @S9S_MB_2U_LIB.S9S_MB_2U(SCH_1):M_B_CPU1_SA_DQ(19)
    U1  N62 DDR1_SA_DQ19 SOCKET4677_AZIF0045P001C01CS-SA    I91 @S9S_MB_2U_LIB.S9S_MB_2U(SCH_1):PAGE52
   J19  176 DQ19_A SCONN288_ADR50017P130CC-SCONN2A    I25 @S9S_MB_2U_LIB.S9S_MB_2U(SCH_1):PAGE100
   J20  176 DQ19_A SCONN288_ADR50017P087CC-SCONN2A    I47 @S9S_MB_2U_LIB.S9S_MB_2U(SCH_1):PAGE101

M_B_CPU1_SA_DQ<1> @S9S_MB_2U_LIB.S9S_MB_2U(SCH_1):M_B_CPU1_SA_DQ(1)
    U1  J74 DDR1_SA_DQ1 SOCKET4677_AZIF0045P001C01CS-SA    I91 @S9S_MB_2U_LIB.S9S_MB_2U(SCH_1):PAGE52
   J19    9  DQ1_A SCONN288_ADR50017P130CC-SCONN2A    I25 @S9S_MB_2U_LIB.S9S_MB_2U(SCH_1):PAGE100
   J20    9  DQ1_A SCONN288_ADR50017P087CC-SCONN2A    I47 @S9S_MB_2U_LIB.S9S_MB_2U(SCH_1):PAGE101

M_B_CPU1_SA_DQ<20> @S9S_MB_2U_LIB.S9S_MB_2U(SCH_1):M_B_CPU1_SA_DQ(20)
    U1  J60 DDR1_SA_DQ20 SOCKET4677_AZIF0045P001C01CS-SA    I91 @S9S_MB_2U_LIB.S9S_MB_2U(SCH_1):PAGE52
   J19   36 DQ20_A SCONN288_ADR50017P130CC-SCONN2A    I25 @S9S_MB_2U_LIB.S9S_MB_2U(SCH_1):PAGE100
   J20   36 DQ20_A SCONN288_ADR50017P087CC-SCONN2A    I47 @S9S_MB_2U_LIB.S9S_MB_2U(SCH_1):PAGE101

M_B_CPU1_SA_DQ<21> @S9S_MB_2U_LIB.S9S_MB_2U(SCH_1):M_B_CPU1_SA_DQ(21)
    U1  K59 DDR1_SA_DQ21 SOCKET4677_AZIF0045P001C01CS-SA    I91 @S9S_MB_2U_LIB.S9S_MB_2U(SCH_1):PAGE52
   J19   38 DQ21_A SCONN288_ADR50017P130CC-SCONN2A    I25 @S9S_MB_2U_LIB.S9S_MB_2U(SCH_1):PAGE100
   J20   38 DQ21_A SCONN288_ADR50017P087CC-SCONN2A    I47 @S9S_MB_2U_LIB.S9S_MB_2U(SCH_1):PAGE101

M_B_CPU1_SA_DQ<22> @S9S_MB_2U_LIB.S9S_MB_2U(SCH_1):M_B_CPU1_SA_DQ(22)
    U1  N60 DDR1_SA_DQ22 SOCKET4677_AZIF0045P001C01CS-SA    I91 @S9S_MB_2U_LIB.S9S_MB_2U(SCH_1):PAGE52
   J19  181 DQ22_A SCONN288_ADR50017P130CC-SCONN2A    I25 @S9S_MB_2U_LIB.S9S_MB_2U(SCH_1):PAGE100
   J20  181 DQ22_A SCONN288_ADR50017P087CC-SCONN2A    I47 @S9S_MB_2U_LIB.S9S_MB_2U(SCH_1):PAGE101

M_B_CPU1_SA_DQ<23> @S9S_MB_2U_LIB.S9S_MB_2U(SCH_1):M_B_CPU1_SA_DQ(23)
    U1  M59 DDR1_SA_DQ23 SOCKET4677_AZIF0045P001C01CS-SA    I91 @S9S_MB_2U_LIB.S9S_MB_2U(SCH_1):PAGE52
   J19  183 DQ23_A SCONN288_ADR50017P130CC-SCONN2A    I25 @S9S_MB_2U_LIB.S9S_MB_2U(SCH_1):PAGE100
   J20  183 DQ23_A SCONN288_ADR50017P087CC-SCONN2A    I47 @S9S_MB_2U_LIB.S9S_MB_2U(SCH_1):PAGE101

M_B_CPU1_SA_DQ<24> @S9S_MB_2U_LIB.S9S_MB_2U(SCH_1):M_B_CPU1_SA_DQ(24)
    U1  U60 DDR1_SA_DQ24 SOCKET4677_AZIF0045P001C01CS-SA    I91 @S9S_MB_2U_LIB.S9S_MB_2U(SCH_1):PAGE52
   J19   40 DQ24_A SCONN288_ADR50017P130CC-SCONN2A    I25 @S9S_MB_2U_LIB.S9S_MB_2U(SCH_1):PAGE100
   J20   40 DQ24_A SCONN288_ADR50017P087CC-SCONN2A    I47 @S9S_MB_2U_LIB.S9S_MB_2U(SCH_1):PAGE101

M_B_CPU1_SA_DQ<25> @S9S_MB_2U_LIB.S9S_MB_2U(SCH_1):M_B_CPU1_SA_DQ(25)
    U1  T59 DDR1_SA_DQ25 SOCKET4677_AZIF0045P001C01CS-SA    I91 @S9S_MB_2U_LIB.S9S_MB_2U(SCH_1):PAGE52
   J19   42 DQ25_A SCONN288_ADR50017P130CC-SCONN2A    I25 @S9S_MB_2U_LIB.S9S_MB_2U(SCH_1):PAGE100
   J20   42 DQ25_A SCONN288_ADR50017P087CC-SCONN2A    I47 @S9S_MB_2U_LIB.S9S_MB_2U(SCH_1):PAGE101

M_B_CPU1_SA_DQ<26> @S9S_MB_2U_LIB.S9S_MB_2U(SCH_1):M_B_CPU1_SA_DQ(26)
    U1  W60 DDR1_SA_DQ26 SOCKET4677_AZIF0045P001C01CS-SA    I91 @S9S_MB_2U_LIB.S9S_MB_2U(SCH_1):PAGE52
   J19  185 DQ26_A SCONN288_ADR50017P130CC-SCONN2A    I25 @S9S_MB_2U_LIB.S9S_MB_2U(SCH_1):PAGE100
   J20  185 DQ26_A SCONN288_ADR50017P087CC-SCONN2A    I47 @S9S_MB_2U_LIB.S9S_MB_2U(SCH_1):PAGE101

M_B_CPU1_SA_DQ<27> @S9S_MB_2U_LIB.S9S_MB_2U(SCH_1):M_B_CPU1_SA_DQ(27)
    U1  Y59 DDR1_SA_DQ27 SOCKET4677_AZIF0045P001C01CS-SA    I91 @S9S_MB_2U_LIB.S9S_MB_2U(SCH_1):PAGE52
   J19  187 DQ27_A SCONN288_ADR50017P130CC-SCONN2A    I25 @S9S_MB_2U_LIB.S9S_MB_2U(SCH_1):PAGE100
   J20  187 DQ27_A SCONN288_ADR50017P087CC-SCONN2A    I47 @S9S_MB_2U_LIB.S9S_MB_2U(SCH_1):PAGE101

M_B_CPU1_SA_DQ<28> @S9S_MB_2U_LIB.S9S_MB_2U(SCH_1):M_B_CPU1_SA_DQ(28)
    U1  T57 DDR1_SA_DQ28 SOCKET4677_AZIF0045P001C01CS-SA    I91 @S9S_MB_2U_LIB.S9S_MB_2U(SCH_1):PAGE52
   J19   47 DQ28_A SCONN288_ADR50017P130CC-SCONN2A    I25 @S9S_MB_2U_LIB.S9S_MB_2U(SCH_1):PAGE100
   J20   47 DQ28_A SCONN288_ADR50017P087CC-SCONN2A    I47 @S9S_MB_2U_LIB.S9S_MB_2U(SCH_1):PAGE101

M_B_CPU1_SA_DQ<29> @S9S_MB_2U_LIB.S9S_MB_2U(SCH_1):M_B_CPU1_SA_DQ(29)
    U1  U56 DDR1_SA_DQ29 SOCKET4677_AZIF0045P001C01CS-SA    I91 @S9S_MB_2U_LIB.S9S_MB_2U(SCH_1):PAGE52
   J19   49 DQ29_A SCONN288_ADR50017P130CC-SCONN2A    I25 @S9S_MB_2U_LIB.S9S_MB_2U(SCH_1):PAGE100
   J20   49 DQ29_A SCONN288_ADR50017P087CC-SCONN2A    I47 @S9S_MB_2U_LIB.S9S_MB_2U(SCH_1):PAGE101

M_B_CPU1_SA_DQ<2> @S9S_MB_2U_LIB.S9S_MB_2U(SCH_1):M_B_CPU1_SA_DQ(2)
    U1  M75 DDR1_SA_DQ2 SOCKET4677_AZIF0045P001C01CS-SA    I91 @S9S_MB_2U_LIB.S9S_MB_2U(SCH_1):PAGE52
   J19  152  DQ2_A SCONN288_ADR50017P130CC-SCONN2A    I25 @S9S_MB_2U_LIB.S9S_MB_2U(SCH_1):PAGE100
   J20  152  DQ2_A SCONN288_ADR50017P087CC-SCONN2A    I47 @S9S_MB_2U_LIB.S9S_MB_2U(SCH_1):PAGE101

M_B_CPU1_SA_DQ<30> @S9S_MB_2U_LIB.S9S_MB_2U(SCH_1):M_B_CPU1_SA_DQ(30)
    U1  Y57 DDR1_SA_DQ30 SOCKET4677_AZIF0045P001C01CS-SA    I91 @S9S_MB_2U_LIB.S9S_MB_2U(SCH_1):PAGE52
   J19  192 DQ30_A SCONN288_ADR50017P130CC-SCONN2A    I25 @S9S_MB_2U_LIB.S9S_MB_2U(SCH_1):PAGE100
   J20  192 DQ30_A SCONN288_ADR50017P087CC-SCONN2A    I47 @S9S_MB_2U_LIB.S9S_MB_2U(SCH_1):PAGE101

M_B_CPU1_SA_DQ<31> @S9S_MB_2U_LIB.S9S_MB_2U(SCH_1):M_B_CPU1_SA_DQ(31)
    U1  W56 DDR1_SA_DQ31 SOCKET4677_AZIF0045P001C01CS-SA    I91 @S9S_MB_2U_LIB.S9S_MB_2U(SCH_1):PAGE52
   J19  194 DQ31_A SCONN288_ADR50017P130CC-SCONN2A    I25 @S9S_MB_2U_LIB.S9S_MB_2U(SCH_1):PAGE100
   J20  194 DQ31_A SCONN288_ADR50017P087CC-SCONN2A    I47 @S9S_MB_2U_LIB.S9S_MB_2U(SCH_1):PAGE101

M_B_CPU1_SA_DQ<3> @S9S_MB_2U_LIB.S9S_MB_2U(SCH_1):M_B_CPU1_SA_DQ(3)
    U1  N74 DDR1_SA_DQ3 SOCKET4677_AZIF0045P001C01CS-SA    I91 @S9S_MB_2U_LIB.S9S_MB_2U(SCH_1):PAGE52
   J19  154  DQ3_A SCONN288_ADR50017P130CC-SCONN2A    I25 @S9S_MB_2U_LIB.S9S_MB_2U(SCH_1):PAGE100
   J20  154  DQ3_A SCONN288_ADR50017P087CC-SCONN2A    I47 @S9S_MB_2U_LIB.S9S_MB_2U(SCH_1):PAGE101

M_B_CPU1_SA_DQ<4> @S9S_MB_2U_LIB.S9S_MB_2U(SCH_1):M_B_CPU1_SA_DQ(4)
    U1  J72 DDR1_SA_DQ4 SOCKET4677_AZIF0045P001C01CS-SA    I91 @S9S_MB_2U_LIB.S9S_MB_2U(SCH_1):PAGE52
   J19   14  DQ4_A SCONN288_ADR50017P130CC-SCONN2A    I25 @S9S_MB_2U_LIB.S9S_MB_2U(SCH_1):PAGE100
   J20   14  DQ4_A SCONN288_ADR50017P087CC-SCONN2A    I47 @S9S_MB_2U_LIB.S9S_MB_2U(SCH_1):PAGE101

M_B_CPU1_SA_DQ<5> @S9S_MB_2U_LIB.S9S_MB_2U(SCH_1):M_B_CPU1_SA_DQ(5)
    U1  K71 DDR1_SA_DQ5 SOCKET4677_AZIF0045P001C01CS-SA    I91 @S9S_MB_2U_LIB.S9S_MB_2U(SCH_1):PAGE52
   J19   16  DQ5_A SCONN288_ADR50017P130CC-SCONN2A    I25 @S9S_MB_2U_LIB.S9S_MB_2U(SCH_1):PAGE100
   J20   16  DQ5_A SCONN288_ADR50017P087CC-SCONN2A    I47 @S9S_MB_2U_LIB.S9S_MB_2U(SCH_1):PAGE101

M_B_CPU1_SA_DQ<6> @S9S_MB_2U_LIB.S9S_MB_2U(SCH_1):M_B_CPU1_SA_DQ(6)
    U1  N72 DDR1_SA_DQ6 SOCKET4677_AZIF0045P001C01CS-SA    I91 @S9S_MB_2U_LIB.S9S_MB_2U(SCH_1):PAGE52
   J19  159  DQ6_A SCONN288_ADR50017P130CC-SCONN2A    I25 @S9S_MB_2U_LIB.S9S_MB_2U(SCH_1):PAGE100
   J20  159  DQ6_A SCONN288_ADR50017P087CC-SCONN2A    I47 @S9S_MB_2U_LIB.S9S_MB_2U(SCH_1):PAGE101

M_B_CPU1_SA_DQ<7> @S9S_MB_2U_LIB.S9S_MB_2U(SCH_1):M_B_CPU1_SA_DQ(7)
    U1  M71 DDR1_SA_DQ7 SOCKET4677_AZIF0045P001C01CS-SA    I91 @S9S_MB_2U_LIB.S9S_MB_2U(SCH_1):PAGE52
   J19  161  DQ7_A SCONN288_ADR50017P130CC-SCONN2A    I25 @S9S_MB_2U_LIB.S9S_MB_2U(SCH_1):PAGE100
   J20  161  DQ7_A SCONN288_ADR50017P087CC-SCONN2A    I47 @S9S_MB_2U_LIB.S9S_MB_2U(SCH_1):PAGE101

M_B_CPU1_SA_DQ<8> @S9S_MB_2U_LIB.S9S_MB_2U(SCH_1):M_B_CPU1_SA_DQ(8)
    U1  U72 DDR1_SA_DQ8 SOCKET4677_AZIF0045P001C01CS-SA    I91 @S9S_MB_2U_LIB.S9S_MB_2U(SCH_1):PAGE52
   J19   18  DQ8_A SCONN288_ADR50017P130CC-SCONN2A    I25 @S9S_MB_2U_LIB.S9S_MB_2U(SCH_1):PAGE100
   J20   18  DQ8_A SCONN288_ADR50017P087CC-SCONN2A    I47 @S9S_MB_2U_LIB.S9S_MB_2U(SCH_1):PAGE101

M_B_CPU1_SA_DQ<9> @S9S_MB_2U_LIB.S9S_MB_2U(SCH_1):M_B_CPU1_SA_DQ(9)
    U1  T71 DDR1_SA_DQ9 SOCKET4677_AZIF0045P001C01CS-SA    I91 @S9S_MB_2U_LIB.S9S_MB_2U(SCH_1):PAGE52
   J19   20  DQ9_A SCONN288_ADR50017P130CC-SCONN2A    I25 @S9S_MB_2U_LIB.S9S_MB_2U(SCH_1):PAGE100
   J20   20  DQ9_A SCONN288_ADR50017P087CC-SCONN2A    I47 @S9S_MB_2U_LIB.S9S_MB_2U(SCH_1):PAGE101

M_B_CPU1_SA_DQS_DN<0> @S9S_MB_2U_LIB.S9S_MB_2U(SCH_1):M_B_CPU1_SA_DQS_DN(0)
    U1  H73 DDR1_SA_DQS_DN0 SOCKET4677_AZIF0045P001C01CS-SA    I91 @S9S_MB_2U_LIB.S9S_MB_2U(SCH_1):PAGE52
   J19   12 DQS0_A_C SCONN288_ADR50017P130CC-SCONN2A   I178 @S9S_MB_2U_LIB.S9S_MB_2U(SCH_1):PAGE100
   J20   12 DQS0_A_C SCONN288_ADR50017P087CC-SCONN2A   I178 @S9S_MB_2U_LIB.S9S_MB_2U(SCH_1):PAGE101

M_B_CPU1_SA_DQS_DN<1> @S9S_MB_2U_LIB.S9S_MB_2U(SCH_1):M_B_CPU1_SA_DQS_DN(1)
    U1  R70 DDR1_SA_DQS_DN1 SOCKET4677_AZIF0045P001C01CS-SA    I91 @S9S_MB_2U_LIB.S9S_MB_2U(SCH_1):PAGE52
   J19   23 DQS1_A_C SCONN288_ADR50017P130CC-SCONN2A   I178 @S9S_MB_2U_LIB.S9S_MB_2U(SCH_1):PAGE100
   J20   23 DQS1_A_C SCONN288_ADR50017P087CC-SCONN2A   I178 @S9S_MB_2U_LIB.S9S_MB_2U(SCH_1):PAGE101

M_B_CPU1_SA_DQS_DN<2> @S9S_MB_2U_LIB.S9S_MB_2U(SCH_1):M_B_CPU1_SA_DQS_DN(2)
    U1  H61 DDR1_SA_DQS_DN2 SOCKET4677_AZIF0045P001C01CS-SA    I91 @S9S_MB_2U_LIB.S9S_MB_2U(SCH_1):PAGE52
   J19   34 DQS2_A_C SCONN288_ADR50017P130CC-SCONN2A   I178 @S9S_MB_2U_LIB.S9S_MB_2U(SCH_1):PAGE100
   J20   34 DQS2_A_C SCONN288_ADR50017P087CC-SCONN2A   I178 @S9S_MB_2U_LIB.S9S_MB_2U(SCH_1):PAGE101

M_B_CPU1_SA_DQS_DN<3> @S9S_MB_2U_LIB.S9S_MB_2U(SCH_1):M_B_CPU1_SA_DQS_DN(3)
    U1  R58 DDR1_SA_DQS_DN3 SOCKET4677_AZIF0045P001C01CS-SA    I91 @S9S_MB_2U_LIB.S9S_MB_2U(SCH_1):PAGE52
   J19   45 DQS3_A_C SCONN288_ADR50017P130CC-SCONN2A   I178 @S9S_MB_2U_LIB.S9S_MB_2U(SCH_1):PAGE100
   J20   45 DQS3_A_C SCONN288_ADR50017P087CC-SCONN2A   I178 @S9S_MB_2U_LIB.S9S_MB_2U(SCH_1):PAGE101

M_B_CPU1_SA_DQS_DN<4> @S9S_MB_2U_LIB.S9S_MB_2U(SCH_1):M_B_CPU1_SA_DQS_DN(4)
    U1  H55 DDR1_SA_DQS_DN4 SOCKET4677_AZIF0045P001C01CS-SA    I91 @S9S_MB_2U_LIB.S9S_MB_2U(SCH_1):PAGE52
   J19   56 DQS4_A_C SCONN288_ADR50017P130CC-SCONN2A   I178 @S9S_MB_2U_LIB.S9S_MB_2U(SCH_1):PAGE100
   J20   56 DQS4_A_C SCONN288_ADR50017P087CC-SCONN2A   I178 @S9S_MB_2U_LIB.S9S_MB_2U(SCH_1):PAGE101

M_B_CPU1_SA_DQS_DN<5> @S9S_MB_2U_LIB.S9S_MB_2U(SCH_1):M_B_CPU1_SA_DQS_DN(5)
    U1  M73 DDR1_SA_DQS_DN5 SOCKET4677_AZIF0045P001C01CS-SA    I91 @S9S_MB_2U_LIB.S9S_MB_2U(SCH_1):PAGE52
   J19  156 DQS5_A_C||TDQS5_A_C||DQS5_A_T||TDQS5_A_T SCONN288_ADR50017P130CC-SCONN2A   I178 @S9S_MB_2U_LIB.S9S_MB_2U(SCH_1):PAGE100
   J20  156 DQS5_A_C||TDQS5_A_C||DQS5_A_T||TDQS5_A_T SCONN288_ADR50017P087CC-SCONN2A   I178 @S9S_MB_2U_LIB.S9S_MB_2U(SCH_1):PAGE101

M_B_CPU1_SA_DQS_DN<6> @S9S_MB_2U_LIB.S9S_MB_2U(SCH_1):M_B_CPU1_SA_DQS_DN(6)
    U1 AA70 DDR1_SA_DQS_DN6 SOCKET4677_AZIF0045P001C01CS-SA    I91 @S9S_MB_2U_LIB.S9S_MB_2U(SCH_1):PAGE52
   J19  167 DQS6_A_C||TDQS6_A_C||DQS6_A_T||TDQS6_A_T SCONN288_ADR50017P130CC-SCONN2A   I178 @S9S_MB_2U_LIB.S9S_MB_2U(SCH_1):PAGE100
   J20  167 DQS6_A_C||TDQS6_A_C||DQS6_A_T||TDQS6_A_T SCONN288_ADR50017P087CC-SCONN2A   I178 @S9S_MB_2U_LIB.S9S_MB_2U(SCH_1):PAGE101

M_B_CPU1_SA_DQS_DN<7> @S9S_MB_2U_LIB.S9S_MB_2U(SCH_1):M_B_CPU1_SA_DQS_DN(7)
    U1  M61 DDR1_SA_DQS_DN7 SOCKET4677_AZIF0045P001C01CS-SA    I91 @S9S_MB_2U_LIB.S9S_MB_2U(SCH_1):PAGE52
   J19  178 DQS7_A_C||TDQS7_A_C SCONN288_ADR50017P130CC-SCONN2A   I178 @S9S_MB_2U_LIB.S9S_MB_2U(SCH_1):PAGE100
   J20  178 DQS7_A_C||TDQS7_A_C SCONN288_ADR50017P087CC-SCONN2A   I178 @S9S_MB_2U_LIB.S9S_MB_2U(SCH_1):PAGE101

M_B_CPU1_SA_DQS_DN<8> @S9S_MB_2U_LIB.S9S_MB_2U(SCH_1):M_B_CPU1_SA_DQS_DN(8)
    U1 AA58 DDR1_SA_DQS_DN8 SOCKET4677_AZIF0045P001C01CS-SA    I91 @S9S_MB_2U_LIB.S9S_MB_2U(SCH_1):PAGE52
   J19  189 DQS8_A_C||TDQS8_A_C SCONN288_ADR50017P130CC-SCONN2A   I178 @S9S_MB_2U_LIB.S9S_MB_2U(SCH_1):PAGE100
   J20  189 DQS8_A_C||TDQS8_A_C SCONN288_ADR50017P087CC-SCONN2A   I178 @S9S_MB_2U_LIB.S9S_MB_2U(SCH_1):PAGE101

M_B_CPU1_SA_DQS_DN<9> @S9S_MB_2U_LIB.S9S_MB_2U(SCH_1):M_B_CPU1_SA_DQS_DN(9)
    U1  M55 DDR1_SA_DQS_DN9 SOCKET4677_AZIF0045P001C01CS-SA    I91 @S9S_MB_2U_LIB.S9S_MB_2U(SCH_1):PAGE52
   J19  200 DQS9_A_C||TDQS9_A_C SCONN288_ADR50017P130CC-SCONN2A   I178 @S9S_MB_2U_LIB.S9S_MB_2U(SCH_1):PAGE100
   J20  200 DQS9_A_C||TDQS9_A_C SCONN288_ADR50017P087CC-SCONN2A   I178 @S9S_MB_2U_LIB.S9S_MB_2U(SCH_1):PAGE101

M_B_CPU1_SA_DQS_DP<0> @S9S_MB_2U_LIB.S9S_MB_2U(SCH_1):M_B_CPU1_SA_DQS_DP(0)
    U1  K73 DDR1_SA_DQS_DP0 SOCKET4677_AZIF0045P001C01CS-SA    I91 @S9S_MB_2U_LIB.S9S_MB_2U(SCH_1):PAGE52
   J19   11 DQS0_A_T SCONN288_ADR50017P130CC-SCONN2A   I178 @S9S_MB_2U_LIB.S9S_MB_2U(SCH_1):PAGE100
   J20   11 DQS0_A_T SCONN288_ADR50017P087CC-SCONN2A   I178 @S9S_MB_2U_LIB.S9S_MB_2U(SCH_1):PAGE101

M_B_CPU1_SA_DQS_DP<1> @S9S_MB_2U_LIB.S9S_MB_2U(SCH_1):M_B_CPU1_SA_DQS_DP(1)
    U1  U70 DDR1_SA_DQS_DP1 SOCKET4677_AZIF0045P001C01CS-SA    I91 @S9S_MB_2U_LIB.S9S_MB_2U(SCH_1):PAGE52
   J19   22 DQS1_A_T SCONN288_ADR50017P130CC-SCONN2A   I178 @S9S_MB_2U_LIB.S9S_MB_2U(SCH_1):PAGE100
   J20   22 DQS1_A_T SCONN288_ADR50017P087CC-SCONN2A   I178 @S9S_MB_2U_LIB.S9S_MB_2U(SCH_1):PAGE101

M_B_CPU1_SA_DQS_DP<2> @S9S_MB_2U_LIB.S9S_MB_2U(SCH_1):M_B_CPU1_SA_DQS_DP(2)
    U1  K61 DDR1_SA_DQS_DP2 SOCKET4677_AZIF0045P001C01CS-SA    I91 @S9S_MB_2U_LIB.S9S_MB_2U(SCH_1):PAGE52
   J19   33 DQS2_A_T SCONN288_ADR50017P130CC-SCONN2A   I178 @S9S_MB_2U_LIB.S9S_MB_2U(SCH_1):PAGE100
   J20   33 DQS2_A_T SCONN288_ADR50017P087CC-SCONN2A   I178 @S9S_MB_2U_LIB.S9S_MB_2U(SCH_1):PAGE101

M_B_CPU1_SA_DQS_DP<3> @S9S_MB_2U_LIB.S9S_MB_2U(SCH_1):M_B_CPU1_SA_DQS_DP(3)
    U1  U58 DDR1_SA_DQS_DP3 SOCKET4677_AZIF0045P001C01CS-SA    I91 @S9S_MB_2U_LIB.S9S_MB_2U(SCH_1):PAGE52
   J19   44 DQS3_A_T SCONN288_ADR50017P130CC-SCONN2A   I178 @S9S_MB_2U_LIB.S9S_MB_2U(SCH_1):PAGE100
   J20   44 DQS3_A_T SCONN288_ADR50017P087CC-SCONN2A   I178 @S9S_MB_2U_LIB.S9S_MB_2U(SCH_1):PAGE101

M_B_CPU1_SA_DQS_DP<4> @S9S_MB_2U_LIB.S9S_MB_2U(SCH_1):M_B_CPU1_SA_DQS_DP(4)
    U1  K55 DDR1_SA_DQS_DP4 SOCKET4677_AZIF0045P001C01CS-SA    I91 @S9S_MB_2U_LIB.S9S_MB_2U(SCH_1):PAGE52
   J19   55 DQS4_A_T SCONN288_ADR50017P130CC-SCONN2A   I178 @S9S_MB_2U_LIB.S9S_MB_2U(SCH_1):PAGE100
   J20   55 DQS4_A_T SCONN288_ADR50017P087CC-SCONN2A   I178 @S9S_MB_2U_LIB.S9S_MB_2U(SCH_1):PAGE101

M_B_CPU1_SA_DQS_DP<5> @S9S_MB_2U_LIB.S9S_MB_2U(SCH_1):M_B_CPU1_SA_DQS_DP(5)
    U1  P73 DDR1_SA_DQS_DP5 SOCKET4677_AZIF0045P001C01CS-SA    I91 @S9S_MB_2U_LIB.S9S_MB_2U(SCH_1):PAGE52
   J19  157 DQS5_A_T||TDQS5_A_T SCONN288_ADR50017P130CC-SCONN2A   I178 @S9S_MB_2U_LIB.S9S_MB_2U(SCH_1):PAGE100
   J20  157 DQS5_A_T||TDQS5_A_T SCONN288_ADR50017P087CC-SCONN2A   I178 @S9S_MB_2U_LIB.S9S_MB_2U(SCH_1):PAGE101

M_B_CPU1_SA_DQS_DP<6> @S9S_MB_2U_LIB.S9S_MB_2U(SCH_1):M_B_CPU1_SA_DQS_DP(6)
    U1  W70 DDR1_SA_DQS_DP6 SOCKET4677_AZIF0045P001C01CS-SA    I91 @S9S_MB_2U_LIB.S9S_MB_2U(SCH_1):PAGE52
   J19  168 DQS6_A_T||TDQS6_A_T SCONN288_ADR50017P130CC-SCONN2A   I178 @S9S_MB_2U_LIB.S9S_MB_2U(SCH_1):PAGE100
   J20  168 DQS6_A_T||TDQS6_A_T SCONN288_ADR50017P087CC-SCONN2A   I178 @S9S_MB_2U_LIB.S9S_MB_2U(SCH_1):PAGE101

M_B_CPU1_SA_DQS_DP<7> @S9S_MB_2U_LIB.S9S_MB_2U(SCH_1):M_B_CPU1_SA_DQS_DP(7)
    U1  P61 DDR1_SA_DQS_DP7 SOCKET4677_AZIF0045P001C01CS-SA    I91 @S9S_MB_2U_LIB.S9S_MB_2U(SCH_1):PAGE52
   J19  179 DQS7_A_T||TDQS7_A_T SCONN288_ADR50017P130CC-SCONN2A   I178 @S9S_MB_2U_LIB.S9S_MB_2U(SCH_1):PAGE100
   J20  179 DQS7_A_T||TDQS7_A_T SCONN288_ADR50017P087CC-SCONN2A   I178 @S9S_MB_2U_LIB.S9S_MB_2U(SCH_1):PAGE101

M_B_CPU1_SA_DQS_DP<8> @S9S_MB_2U_LIB.S9S_MB_2U(SCH_1):M_B_CPU1_SA_DQS_DP(8)
    U1  W58 DDR1_SA_DQS_DP8 SOCKET4677_AZIF0045P001C01CS-SA    I91 @S9S_MB_2U_LIB.S9S_MB_2U(SCH_1):PAGE52
   J19  190 DQS8_A_T||TDQS8_A_T SCONN288_ADR50017P130CC-SCONN2A   I178 @S9S_MB_2U_LIB.S9S_MB_2U(SCH_1):PAGE100
   J20  190 DQS8_A_T||TDQS8_A_T SCONN288_ADR50017P087CC-SCONN2A   I178 @S9S_MB_2U_LIB.S9S_MB_2U(SCH_1):PAGE101

M_B_CPU1_SA_DQS_DP<9> @S9S_MB_2U_LIB.S9S_MB_2U(SCH_1):M_B_CPU1_SA_DQS_DP(9)
    U1  P55 DDR1_SA_DQS_DP9 SOCKET4677_AZIF0045P001C01CS-SA    I91 @S9S_MB_2U_LIB.S9S_MB_2U(SCH_1):PAGE52
   J19  201 DQS9_A_T||TDQS9_A_T SCONN288_ADR50017P130CC-SCONN2A   I178 @S9S_MB_2U_LIB.S9S_MB_2U(SCH_1):PAGE100
   J20  201 DQS9_A_T||TDQS9_A_T SCONN288_ADR50017P087CC-SCONN2A   I178 @S9S_MB_2U_LIB.S9S_MB_2U(SCH_1):PAGE101

M_B_CPU1_SA_PAR @S9S_MB_2U_LIB.S9S_MB_2U(SCH_1):M_B_CPU1_SA_PAR
    U1  W43 DDR1_SA_PAR SOCKET4677_AZIF0045P001C01CS-SA    I91 @S9S_MB_2U_LIB.S9S_MB_2U(SCH_1):PAGE52
   J19   74  PAR_A SCONN288_ADR50017P130CC-SCONN2A    I25 @S9S_MB_2U_LIB.S9S_MB_2U(SCH_1):PAGE100
   J20   74  PAR_A SCONN288_ADR50017P087CC-SCONN2A    I47 @S9S_MB_2U_LIB.S9S_MB_2U(SCH_1):PAGE101

M_B_CPU1_SA_RSP<0> @S9S_MB_2U_LIB.S9S_MB_2U(SCH_1):M_B_CPU1_SA_RSP(0)
    U1 AL48 DDR1_A_RSP0 SOCKET4677_AZIF0045P001C01CS-SA    I91 @S9S_MB_2U_LIB.S9S_MB_2U(SCH_1):PAGE52
   J19   86 LBD||RSP_A_N SCONN288_ADR50017P130CC-SCONN2A    I25 @S9S_MB_2U_LIB.S9S_MB_2U(SCH_1):PAGE100

M_B_CPU1_SA_RSP<1> @S9S_MB_2U_LIB.S9S_MB_2U(SCH_1):M_B_CPU1_SA_RSP(1)
    U1 AK47 DDR1_A_RSP1 SOCKET4677_AZIF0045P001C01CS-SA    I91 @S9S_MB_2U_LIB.S9S_MB_2U(SCH_1):PAGE52
   J20   86 LBD||RSP_A_N SCONN288_ADR50017P087CC-SCONN2A    I47 @S9S_MB_2U_LIB.S9S_MB_2U(SCH_1):PAGE101

M_B_CPU1_SB_CA<0> @S9S_MB_2U_LIB.S9S_MB_2U(SCH_1):M_B_CPU1_SB_CA(0)
    U1  T44 DDR1_SB_CA0 SOCKET4677_AZIF0045P001C01CS-SA    I91 @S9S_MB_2U_LIB.S9S_MB_2U(SCH_1):PAGE52
   J19   76  CA0_B SCONN288_ADR50017P130CC-SCONN2A    I25 @S9S_MB_2U_LIB.S9S_MB_2U(SCH_1):PAGE100
   J20   76  CA0_B SCONN288_ADR50017P087CC-SCONN2A    I47 @S9S_MB_2U_LIB.S9S_MB_2U(SCH_1):PAGE101

M_B_CPU1_SB_CA<1> @S9S_MB_2U_LIB.S9S_MB_2U(SCH_1):M_B_CPU1_SB_CA(1)
    U1  U43 DDR1_SB_CA1 SOCKET4677_AZIF0045P001C01CS-SA    I91 @S9S_MB_2U_LIB.S9S_MB_2U(SCH_1):PAGE52
   J19  221  CA1_B SCONN288_ADR50017P130CC-SCONN2A    I25 @S9S_MB_2U_LIB.S9S_MB_2U(SCH_1):PAGE100
   J20  221  CA1_B SCONN288_ADR50017P087CC-SCONN2A    I47 @S9S_MB_2U_LIB.S9S_MB_2U(SCH_1):PAGE101

M_B_CPU1_SB_CA<2> @S9S_MB_2U_LIB.S9S_MB_2U(SCH_1):M_B_CPU1_SB_CA(2)
    U1  K44 DDR1_SB_CA2 SOCKET4677_AZIF0045P001C01CS-SA    I91 @S9S_MB_2U_LIB.S9S_MB_2U(SCH_1):PAGE52
   J19   78  CA2_B SCONN288_ADR50017P130CC-SCONN2A    I25 @S9S_MB_2U_LIB.S9S_MB_2U(SCH_1):PAGE100
   J20   78  CA2_B SCONN288_ADR50017P087CC-SCONN2A    I47 @S9S_MB_2U_LIB.S9S_MB_2U(SCH_1):PAGE101

M_B_CPU1_SB_CA<3> @S9S_MB_2U_LIB.S9S_MB_2U(SCH_1):M_B_CPU1_SB_CA(3)
    U1  M44 DDR1_SB_CA3 SOCKET4677_AZIF0045P001C01CS-SA    I91 @S9S_MB_2U_LIB.S9S_MB_2U(SCH_1):PAGE52
   J19  223  CA3_B SCONN288_ADR50017P130CC-SCONN2A    I25 @S9S_MB_2U_LIB.S9S_MB_2U(SCH_1):PAGE100
   J20  223  CA3_B SCONN288_ADR50017P087CC-SCONN2A    I47 @S9S_MB_2U_LIB.S9S_MB_2U(SCH_1):PAGE101

M_B_CPU1_SB_CA<4> @S9S_MB_2U_LIB.S9S_MB_2U(SCH_1):M_B_CPU1_SB_CA(4)
    U1  J43 DDR1_SB_CA4 SOCKET4677_AZIF0045P001C01CS-SA    I91 @S9S_MB_2U_LIB.S9S_MB_2U(SCH_1):PAGE52
   J19   80  CA4_B SCONN288_ADR50017P130CC-SCONN2A    I25 @S9S_MB_2U_LIB.S9S_MB_2U(SCH_1):PAGE100
   J20   80  CA4_B SCONN288_ADR50017P087CC-SCONN2A    I47 @S9S_MB_2U_LIB.S9S_MB_2U(SCH_1):PAGE101

M_B_CPU1_SB_CA<5> @S9S_MB_2U_LIB.S9S_MB_2U(SCH_1):M_B_CPU1_SB_CA(5)
    U1  N43 DDR1_SB_CA5 SOCKET4677_AZIF0045P001C01CS-SA    I91 @S9S_MB_2U_LIB.S9S_MB_2U(SCH_1):PAGE52
   J19  225  CA5_B SCONN288_ADR50017P130CC-SCONN2A    I25 @S9S_MB_2U_LIB.S9S_MB_2U(SCH_1):PAGE100
   J20  225  CA5_B SCONN288_ADR50017P087CC-SCONN2A    I47 @S9S_MB_2U_LIB.S9S_MB_2U(SCH_1):PAGE101

M_B_CPU1_SB_CA<6> @S9S_MB_2U_LIB.S9S_MB_2U(SCH_1):M_B_CPU1_SB_CA(6)
    U1  H42 DDR1_SB_CA6 SOCKET4677_AZIF0045P001C01CS-SA    I91 @S9S_MB_2U_LIB.S9S_MB_2U(SCH_1):PAGE52
   J19   82  CA6_B SCONN288_ADR50017P130CC-SCONN2A    I25 @S9S_MB_2U_LIB.S9S_MB_2U(SCH_1):PAGE100
   J20   82  CA6_B SCONN288_ADR50017P087CC-SCONN2A    I47 @S9S_MB_2U_LIB.S9S_MB_2U(SCH_1):PAGE101

M_B_CPU1_SB_CB<0> @S9S_MB_2U_LIB.S9S_MB_2U(SCH_1):M_B_CPU1_SB_CB(0)
    U1  J35 DDR1_SB_ECC0 SOCKET4677_AZIF0045P001C01CS-SA    I91 @S9S_MB_2U_LIB.S9S_MB_2U(SCH_1):PAGE52
   J19   96  CB0_B SCONN288_ADR50017P130CC-SCONN2A    I25 @S9S_MB_2U_LIB.S9S_MB_2U(SCH_1):PAGE100
   J20   96  CB0_B SCONN288_ADR50017P087CC-SCONN2A    I47 @S9S_MB_2U_LIB.S9S_MB_2U(SCH_1):PAGE101

M_B_CPU1_SB_CB<1> @S9S_MB_2U_LIB.S9S_MB_2U(SCH_1):M_B_CPU1_SB_CB(1)
    U1  K34 DDR1_SB_ECC1 SOCKET4677_AZIF0045P001C01CS-SA    I91 @S9S_MB_2U_LIB.S9S_MB_2U(SCH_1):PAGE52
   J19   98  CB1_B SCONN288_ADR50017P130CC-SCONN2A    I25 @S9S_MB_2U_LIB.S9S_MB_2U(SCH_1):PAGE100
   J20   98  CB1_B SCONN288_ADR50017P087CC-SCONN2A    I47 @S9S_MB_2U_LIB.S9S_MB_2U(SCH_1):PAGE101

M_B_CPU1_SB_CB<2> @S9S_MB_2U_LIB.S9S_MB_2U(SCH_1):M_B_CPU1_SB_CB(2)
    U1  N35 DDR1_SB_ECC2 SOCKET4677_AZIF0045P001C01CS-SA    I91 @S9S_MB_2U_LIB.S9S_MB_2U(SCH_1):PAGE52
   J19  241  CB2_B SCONN288_ADR50017P130CC-SCONN2A    I25 @S9S_MB_2U_LIB.S9S_MB_2U(SCH_1):PAGE100
   J20  241  CB2_B SCONN288_ADR50017P087CC-SCONN2A    I47 @S9S_MB_2U_LIB.S9S_MB_2U(SCH_1):PAGE101

M_B_CPU1_SB_CB<3> @S9S_MB_2U_LIB.S9S_MB_2U(SCH_1):M_B_CPU1_SB_CB(3)
    U1  M34 DDR1_SB_ECC3 SOCKET4677_AZIF0045P001C01CS-SA    I91 @S9S_MB_2U_LIB.S9S_MB_2U(SCH_1):PAGE52
   J19  243  CB3_B SCONN288_ADR50017P130CC-SCONN2A    I25 @S9S_MB_2U_LIB.S9S_MB_2U(SCH_1):PAGE100
   J20  243  CB3_B SCONN288_ADR50017P087CC-SCONN2A    I47 @S9S_MB_2U_LIB.S9S_MB_2U(SCH_1):PAGE101

M_B_CPU1_SB_CB<4> @S9S_MB_2U_LIB.S9S_MB_2U(SCH_1):M_B_CPU1_SB_CB(4)
    U1  K38 DDR1_SB_ECC4 SOCKET4677_AZIF0045P001C01CS-SA    I91 @S9S_MB_2U_LIB.S9S_MB_2U(SCH_1):PAGE52
   J19   89  CB4_B SCONN288_ADR50017P130CC-SCONN2A    I25 @S9S_MB_2U_LIB.S9S_MB_2U(SCH_1):PAGE100
   J20   89  CB4_B SCONN288_ADR50017P087CC-SCONN2A    I47 @S9S_MB_2U_LIB.S9S_MB_2U(SCH_1):PAGE101

M_B_CPU1_SB_CB<5> @S9S_MB_2U_LIB.S9S_MB_2U(SCH_1):M_B_CPU1_SB_CB(5)
    U1  J37 DDR1_SB_ECC5 SOCKET4677_AZIF0045P001C01CS-SA    I91 @S9S_MB_2U_LIB.S9S_MB_2U(SCH_1):PAGE52
   J19   91  CB5_B SCONN288_ADR50017P130CC-SCONN2A    I25 @S9S_MB_2U_LIB.S9S_MB_2U(SCH_1):PAGE100
   J20   91  CB5_B SCONN288_ADR50017P087CC-SCONN2A    I47 @S9S_MB_2U_LIB.S9S_MB_2U(SCH_1):PAGE101

M_B_CPU1_SB_CB<6> @S9S_MB_2U_LIB.S9S_MB_2U(SCH_1):M_B_CPU1_SB_CB(6)
    U1  M38 DDR1_SB_ECC6 SOCKET4677_AZIF0045P001C01CS-SA    I91 @S9S_MB_2U_LIB.S9S_MB_2U(SCH_1):PAGE52
   J19  234  CB6_B SCONN288_ADR50017P130CC-SCONN2A    I25 @S9S_MB_2U_LIB.S9S_MB_2U(SCH_1):PAGE100
   J20  234  CB6_B SCONN288_ADR50017P087CC-SCONN2A    I47 @S9S_MB_2U_LIB.S9S_MB_2U(SCH_1):PAGE101

M_B_CPU1_SB_CB<7> @S9S_MB_2U_LIB.S9S_MB_2U(SCH_1):M_B_CPU1_SB_CB(7)
    U1  N37 DDR1_SB_ECC7 SOCKET4677_AZIF0045P001C01CS-SA    I91 @S9S_MB_2U_LIB.S9S_MB_2U(SCH_1):PAGE52
   J19  236  CB7_B SCONN288_ADR50017P130CC-SCONN2A    I25 @S9S_MB_2U_LIB.S9S_MB_2U(SCH_1):PAGE100
   J20  236  CB7_B SCONN288_ADR50017P087CC-SCONN2A    I47 @S9S_MB_2U_LIB.S9S_MB_2U(SCH_1):PAGE101

M_B_CPU1_SB_CS_N<0> @S9S_MB_2U_LIB.S9S_MB_2U(SCH_1):M_B_CPU1_SB_CS_N(0)
    U1  J41 DDR1_SB_CS_N0 SOCKET4677_AZIF0045P001C01CS-SA    I91 @S9S_MB_2U_LIB.S9S_MB_2U(SCH_1):PAGE52
   J19   84 CS0_B_N SCONN288_ADR50017P130CC-SCONN2A    I25 @S9S_MB_2U_LIB.S9S_MB_2U(SCH_1):PAGE100

M_B_CPU1_SB_CS_N<1> @S9S_MB_2U_LIB.S9S_MB_2U(SCH_1):M_B_CPU1_SB_CS_N(1)
    U1  K40 DDR1_SB_CS_N1 SOCKET4677_AZIF0045P001C01CS-SA    I91 @S9S_MB_2U_LIB.S9S_MB_2U(SCH_1):PAGE52
   J19  229 CS1_B_N SCONN288_ADR50017P130CC-SCONN2A    I25 @S9S_MB_2U_LIB.S9S_MB_2U(SCH_1):PAGE100

M_B_CPU1_SB_CS_N<2> @S9S_MB_2U_LIB.S9S_MB_2U(SCH_1):M_B_CPU1_SB_CS_N(2)
    U1  N41 DDR1_SB_CS_N2 SOCKET4677_AZIF0045P001C01CS-SA    I91 @S9S_MB_2U_LIB.S9S_MB_2U(SCH_1):PAGE52
   J20   84 CS0_B_N SCONN288_ADR50017P087CC-SCONN2A    I47 @S9S_MB_2U_LIB.S9S_MB_2U(SCH_1):PAGE101

M_B_CPU1_SB_CS_N<3> @S9S_MB_2U_LIB.S9S_MB_2U(SCH_1):M_B_CPU1_SB_CS_N(3)
    U1  M40 DDR1_SB_CS_N3 SOCKET4677_AZIF0045P001C01CS-SA    I91 @S9S_MB_2U_LIB.S9S_MB_2U(SCH_1):PAGE52
   J20  229 CS1_B_N SCONN288_ADR50017P087CC-SCONN2A    I47 @S9S_MB_2U_LIB.S9S_MB_2U(SCH_1):PAGE101

M_B_CPU1_SB_DQ<0> @S9S_MB_2U_LIB.S9S_MB_2U(SCH_1):M_B_CPU1_SB_DQ(0)
    U1  U29 DDR1_SB_DQ0 SOCKET4677_AZIF0045P001C01CS-SA    I91 @S9S_MB_2U_LIB.S9S_MB_2U(SCH_1):PAGE52
   J19  100  DQ0_B SCONN288_ADR50017P130CC-SCONN2A    I25 @S9S_MB_2U_LIB.S9S_MB_2U(SCH_1):PAGE100
   J20  100  DQ0_B SCONN288_ADR50017P087CC-SCONN2A    I47 @S9S_MB_2U_LIB.S9S_MB_2U(SCH_1):PAGE101

M_B_CPU1_SB_DQ<10> @S9S_MB_2U_LIB.S9S_MB_2U(SCH_1):M_B_CPU1_SB_DQ(10)
    U1  M26 DDR1_SB_DQ10 SOCKET4677_AZIF0045P001C01CS-SA    I91 @S9S_MB_2U_LIB.S9S_MB_2U(SCH_1):PAGE52
   J19  256 DQ10_B SCONN288_ADR50017P130CC-SCONN2A    I25 @S9S_MB_2U_LIB.S9S_MB_2U(SCH_1):PAGE100
   J20  256 DQ10_B SCONN288_ADR50017P087CC-SCONN2A    I47 @S9S_MB_2U_LIB.S9S_MB_2U(SCH_1):PAGE101

M_B_CPU1_SB_DQ<11> @S9S_MB_2U_LIB.S9S_MB_2U(SCH_1):M_B_CPU1_SB_DQ(11)
    U1  N25 DDR1_SB_DQ11 SOCKET4677_AZIF0045P001C01CS-SA    I91 @S9S_MB_2U_LIB.S9S_MB_2U(SCH_1):PAGE52
   J19  258 DQ11_B SCONN288_ADR50017P130CC-SCONN2A    I25 @S9S_MB_2U_LIB.S9S_MB_2U(SCH_1):PAGE100
   J20  258 DQ11_B SCONN288_ADR50017P087CC-SCONN2A    I47 @S9S_MB_2U_LIB.S9S_MB_2U(SCH_1):PAGE101

M_B_CPU1_SB_DQ<12> @S9S_MB_2U_LIB.S9S_MB_2U(SCH_1):M_B_CPU1_SB_DQ(12)
    U1  J23 DDR1_SB_DQ12 SOCKET4677_AZIF0045P001C01CS-SA    I91 @S9S_MB_2U_LIB.S9S_MB_2U(SCH_1):PAGE52
   J19  118 DQ12_B SCONN288_ADR50017P130CC-SCONN2A    I25 @S9S_MB_2U_LIB.S9S_MB_2U(SCH_1):PAGE100
   J20  118 DQ12_B SCONN288_ADR50017P087CC-SCONN2A    I47 @S9S_MB_2U_LIB.S9S_MB_2U(SCH_1):PAGE101

M_B_CPU1_SB_DQ<13> @S9S_MB_2U_LIB.S9S_MB_2U(SCH_1):M_B_CPU1_SB_DQ(13)
    U1  K22 DDR1_SB_DQ13 SOCKET4677_AZIF0045P001C01CS-SA    I91 @S9S_MB_2U_LIB.S9S_MB_2U(SCH_1):PAGE52
   J19  120 DQ13_B SCONN288_ADR50017P130CC-SCONN2A    I25 @S9S_MB_2U_LIB.S9S_MB_2U(SCH_1):PAGE100
   J20  120 DQ13_B SCONN288_ADR50017P087CC-SCONN2A    I47 @S9S_MB_2U_LIB.S9S_MB_2U(SCH_1):PAGE101

M_B_CPU1_SB_DQ<14> @S9S_MB_2U_LIB.S9S_MB_2U(SCH_1):M_B_CPU1_SB_DQ(14)
    U1  N23 DDR1_SB_DQ14 SOCKET4677_AZIF0045P001C01CS-SA    I91 @S9S_MB_2U_LIB.S9S_MB_2U(SCH_1):PAGE52
   J19  263 DQ14_B SCONN288_ADR50017P130CC-SCONN2A    I25 @S9S_MB_2U_LIB.S9S_MB_2U(SCH_1):PAGE100
   J20  263 DQ14_B SCONN288_ADR50017P087CC-SCONN2A    I47 @S9S_MB_2U_LIB.S9S_MB_2U(SCH_1):PAGE101

M_B_CPU1_SB_DQ<15> @S9S_MB_2U_LIB.S9S_MB_2U(SCH_1):M_B_CPU1_SB_DQ(15)
    U1  M22 DDR1_SB_DQ15 SOCKET4677_AZIF0045P001C01CS-SA    I91 @S9S_MB_2U_LIB.S9S_MB_2U(SCH_1):PAGE52
   J19  265 DQ15_B SCONN288_ADR50017P130CC-SCONN2A    I25 @S9S_MB_2U_LIB.S9S_MB_2U(SCH_1):PAGE100
   J20  265 DQ15_B SCONN288_ADR50017P087CC-SCONN2A    I47 @S9S_MB_2U_LIB.S9S_MB_2U(SCH_1):PAGE101

M_B_CPU1_SB_DQ<16> @S9S_MB_2U_LIB.S9S_MB_2U(SCH_1):M_B_CPU1_SB_DQ(16)
    U1  K20 DDR1_SB_DQ16 SOCKET4677_AZIF0045P001C01CS-SA    I91 @S9S_MB_2U_LIB.S9S_MB_2U(SCH_1):PAGE52
   J19  122 DQ16_B SCONN288_ADR50017P130CC-SCONN2A    I25 @S9S_MB_2U_LIB.S9S_MB_2U(SCH_1):PAGE100
   J20  122 DQ16_B SCONN288_ADR50017P087CC-SCONN2A    I47 @S9S_MB_2U_LIB.S9S_MB_2U(SCH_1):PAGE101

M_B_CPU1_SB_DQ<17> @S9S_MB_2U_LIB.S9S_MB_2U(SCH_1):M_B_CPU1_SB_DQ(17)
    U1  J19 DDR1_SB_DQ17 SOCKET4677_AZIF0045P001C01CS-SA    I91 @S9S_MB_2U_LIB.S9S_MB_2U(SCH_1):PAGE52
   J19  124 DQ17_B SCONN288_ADR50017P130CC-SCONN2A    I25 @S9S_MB_2U_LIB.S9S_MB_2U(SCH_1):PAGE100
   J20  124 DQ17_B SCONN288_ADR50017P087CC-SCONN2A    I47 @S9S_MB_2U_LIB.S9S_MB_2U(SCH_1):PAGE101

M_B_CPU1_SB_DQ<18> @S9S_MB_2U_LIB.S9S_MB_2U(SCH_1):M_B_CPU1_SB_DQ(18)
    U1  M20 DDR1_SB_DQ18 SOCKET4677_AZIF0045P001C01CS-SA    I91 @S9S_MB_2U_LIB.S9S_MB_2U(SCH_1):PAGE52
   J19  267 DQ18_B SCONN288_ADR50017P130CC-SCONN2A    I25 @S9S_MB_2U_LIB.S9S_MB_2U(SCH_1):PAGE100
   J20  267 DQ18_B SCONN288_ADR50017P087CC-SCONN2A    I47 @S9S_MB_2U_LIB.S9S_MB_2U(SCH_1):PAGE101

M_B_CPU1_SB_DQ<19> @S9S_MB_2U_LIB.S9S_MB_2U(SCH_1):M_B_CPU1_SB_DQ(19)
    U1  N19 DDR1_SB_DQ19 SOCKET4677_AZIF0045P001C01CS-SA    I91 @S9S_MB_2U_LIB.S9S_MB_2U(SCH_1):PAGE52
   J19  269 DQ19_B SCONN288_ADR50017P130CC-SCONN2A    I25 @S9S_MB_2U_LIB.S9S_MB_2U(SCH_1):PAGE100
   J20  269 DQ19_B SCONN288_ADR50017P087CC-SCONN2A    I47 @S9S_MB_2U_LIB.S9S_MB_2U(SCH_1):PAGE101

M_B_CPU1_SB_DQ<1> @S9S_MB_2U_LIB.S9S_MB_2U(SCH_1):M_B_CPU1_SB_DQ(1)
    U1  T28 DDR1_SB_DQ1 SOCKET4677_AZIF0045P001C01CS-SA    I91 @S9S_MB_2U_LIB.S9S_MB_2U(SCH_1):PAGE52
   J19  102  DQ1_B SCONN288_ADR50017P130CC-SCONN2A    I25 @S9S_MB_2U_LIB.S9S_MB_2U(SCH_1):PAGE100
   J20  102  DQ1_B SCONN288_ADR50017P087CC-SCONN2A    I47 @S9S_MB_2U_LIB.S9S_MB_2U(SCH_1):PAGE101

M_B_CPU1_SB_DQ<20> @S9S_MB_2U_LIB.S9S_MB_2U(SCH_1):M_B_CPU1_SB_DQ(20)
    U1  J17 DDR1_SB_DQ20 SOCKET4677_AZIF0045P001C01CS-SA    I91 @S9S_MB_2U_LIB.S9S_MB_2U(SCH_1):PAGE52
   J19  129 DQ20_B SCONN288_ADR50017P130CC-SCONN2A    I25 @S9S_MB_2U_LIB.S9S_MB_2U(SCH_1):PAGE100
   J20  129 DQ20_B SCONN288_ADR50017P087CC-SCONN2A    I47 @S9S_MB_2U_LIB.S9S_MB_2U(SCH_1):PAGE101

M_B_CPU1_SB_DQ<21> @S9S_MB_2U_LIB.S9S_MB_2U(SCH_1):M_B_CPU1_SB_DQ(21)
    U1  K16 DDR1_SB_DQ21 SOCKET4677_AZIF0045P001C01CS-SA    I91 @S9S_MB_2U_LIB.S9S_MB_2U(SCH_1):PAGE52
   J19  131 DQ21_B SCONN288_ADR50017P130CC-SCONN2A    I25 @S9S_MB_2U_LIB.S9S_MB_2U(SCH_1):PAGE100
   J20  131 DQ21_B SCONN288_ADR50017P087CC-SCONN2A    I47 @S9S_MB_2U_LIB.S9S_MB_2U(SCH_1):PAGE101

M_B_CPU1_SB_DQ<22> @S9S_MB_2U_LIB.S9S_MB_2U(SCH_1):M_B_CPU1_SB_DQ(22)
    U1  N17 DDR1_SB_DQ22 SOCKET4677_AZIF0045P001C01CS-SA    I91 @S9S_MB_2U_LIB.S9S_MB_2U(SCH_1):PAGE52
   J19  274 DQ22_B SCONN288_ADR50017P130CC-SCONN2A    I25 @S9S_MB_2U_LIB.S9S_MB_2U(SCH_1):PAGE100
   J20  274 DQ22_B SCONN288_ADR50017P087CC-SCONN2A    I47 @S9S_MB_2U_LIB.S9S_MB_2U(SCH_1):PAGE101

M_B_CPU1_SB_DQ<23> @S9S_MB_2U_LIB.S9S_MB_2U(SCH_1):M_B_CPU1_SB_DQ(23)
    U1  M16 DDR1_SB_DQ23 SOCKET4677_AZIF0045P001C01CS-SA    I91 @S9S_MB_2U_LIB.S9S_MB_2U(SCH_1):PAGE52
   J19  276 DQ23_B SCONN288_ADR50017P130CC-SCONN2A    I25 @S9S_MB_2U_LIB.S9S_MB_2U(SCH_1):PAGE100
   J20  276 DQ23_B SCONN288_ADR50017P087CC-SCONN2A    I47 @S9S_MB_2U_LIB.S9S_MB_2U(SCH_1):PAGE101

M_B_CPU1_SB_DQ<24> @S9S_MB_2U_LIB.S9S_MB_2U(SCH_1):M_B_CPU1_SB_DQ(24)
    U1  C17 DDR1_SB_DQ24 SOCKET4677_AZIF0045P001C01CS-SA    I91 @S9S_MB_2U_LIB.S9S_MB_2U(SCH_1):PAGE52
   J19  133 DQ24_B SCONN288_ADR50017P130CC-SCONN2A    I25 @S9S_MB_2U_LIB.S9S_MB_2U(SCH_1):PAGE100
   J20  133 DQ24_B SCONN288_ADR50017P087CC-SCONN2A    I47 @S9S_MB_2U_LIB.S9S_MB_2U(SCH_1):PAGE101

M_B_CPU1_SB_DQ<25> @S9S_MB_2U_LIB.S9S_MB_2U(SCH_1):M_B_CPU1_SB_DQ(25)
    U1  B16 DDR1_SB_DQ25 SOCKET4677_AZIF0045P001C01CS-SA    I91 @S9S_MB_2U_LIB.S9S_MB_2U(SCH_1):PAGE52
   J19  135 DQ25_B SCONN288_ADR50017P130CC-SCONN2A    I25 @S9S_MB_2U_LIB.S9S_MB_2U(SCH_1):PAGE100
   J20  135 DQ25_B SCONN288_ADR50017P087CC-SCONN2A    I47 @S9S_MB_2U_LIB.S9S_MB_2U(SCH_1):PAGE101

M_B_CPU1_SB_DQ<26> @S9S_MB_2U_LIB.S9S_MB_2U(SCH_1):M_B_CPU1_SB_DQ(26)
    U1  E17 DDR1_SB_DQ26 SOCKET4677_AZIF0045P001C01CS-SA    I91 @S9S_MB_2U_LIB.S9S_MB_2U(SCH_1):PAGE52
   J19  278 DQ26_B SCONN288_ADR50017P130CC-SCONN2A    I25 @S9S_MB_2U_LIB.S9S_MB_2U(SCH_1):PAGE100
   J20  278 DQ26_B SCONN288_ADR50017P087CC-SCONN2A    I47 @S9S_MB_2U_LIB.S9S_MB_2U(SCH_1):PAGE101

M_B_CPU1_SB_DQ<27> @S9S_MB_2U_LIB.S9S_MB_2U(SCH_1):M_B_CPU1_SB_DQ(27)
    U1  F16 DDR1_SB_DQ27 SOCKET4677_AZIF0045P001C01CS-SA    I91 @S9S_MB_2U_LIB.S9S_MB_2U(SCH_1):PAGE52
   J19  280 DQ27_B SCONN288_ADR50017P130CC-SCONN2A    I25 @S9S_MB_2U_LIB.S9S_MB_2U(SCH_1):PAGE100
   J20  280 DQ27_B SCONN288_ADR50017P087CC-SCONN2A    I47 @S9S_MB_2U_LIB.S9S_MB_2U(SCH_1):PAGE101

M_B_CPU1_SB_DQ<28> @S9S_MB_2U_LIB.S9S_MB_2U(SCH_1):M_B_CPU1_SB_DQ(28)
    U1  C13 DDR1_SB_DQ28 SOCKET4677_AZIF0045P001C01CS-SA    I91 @S9S_MB_2U_LIB.S9S_MB_2U(SCH_1):PAGE52
   J19  140 DQ28_B SCONN288_ADR50017P130CC-SCONN2A    I25 @S9S_MB_2U_LIB.S9S_MB_2U(SCH_1):PAGE100
   J20  140 DQ28_B SCONN288_ADR50017P087CC-SCONN2A    I47 @S9S_MB_2U_LIB.S9S_MB_2U(SCH_1):PAGE101

M_B_CPU1_SB_DQ<29> @S9S_MB_2U_LIB.S9S_MB_2U(SCH_1):M_B_CPU1_SB_DQ(29)
    U1  E13 DDR1_SB_DQ29 SOCKET4677_AZIF0045P001C01CS-SA    I91 @S9S_MB_2U_LIB.S9S_MB_2U(SCH_1):PAGE52
   J19  142 DQ29_B SCONN288_ADR50017P130CC-SCONN2A    I25 @S9S_MB_2U_LIB.S9S_MB_2U(SCH_1):PAGE100
   J20  142 DQ29_B SCONN288_ADR50017P087CC-SCONN2A    I47 @S9S_MB_2U_LIB.S9S_MB_2U(SCH_1):PAGE101

M_B_CPU1_SB_DQ<2> @S9S_MB_2U_LIB.S9S_MB_2U(SCH_1):M_B_CPU1_SB_DQ(2)
    U1  W29 DDR1_SB_DQ2 SOCKET4677_AZIF0045P001C01CS-SA    I91 @S9S_MB_2U_LIB.S9S_MB_2U(SCH_1):PAGE52
   J19  245  DQ2_B SCONN288_ADR50017P130CC-SCONN2A    I25 @S9S_MB_2U_LIB.S9S_MB_2U(SCH_1):PAGE100
   J20  245  DQ2_B SCONN288_ADR50017P087CC-SCONN2A    I47 @S9S_MB_2U_LIB.S9S_MB_2U(SCH_1):PAGE101

M_B_CPU1_SB_DQ<30> @S9S_MB_2U_LIB.S9S_MB_2U(SCH_1):M_B_CPU1_SB_DQ(30)
    U1  B14 DDR1_SB_DQ30 SOCKET4677_AZIF0045P001C01CS-SA    I91 @S9S_MB_2U_LIB.S9S_MB_2U(SCH_1):PAGE52
   J19  285 DQ30_B SCONN288_ADR50017P130CC-SCONN2A    I25 @S9S_MB_2U_LIB.S9S_MB_2U(SCH_1):PAGE100
   J20  285 DQ30_B SCONN288_ADR50017P087CC-SCONN2A    I47 @S9S_MB_2U_LIB.S9S_MB_2U(SCH_1):PAGE101

M_B_CPU1_SB_DQ<31> @S9S_MB_2U_LIB.S9S_MB_2U(SCH_1):M_B_CPU1_SB_DQ(31)
    U1  F14 DDR1_SB_DQ31 SOCKET4677_AZIF0045P001C01CS-SA    I91 @S9S_MB_2U_LIB.S9S_MB_2U(SCH_1):PAGE52
   J19  287 DQ31_B SCONN288_ADR50017P130CC-SCONN2A    I25 @S9S_MB_2U_LIB.S9S_MB_2U(SCH_1):PAGE100
   J20  287 DQ31_B SCONN288_ADR50017P087CC-SCONN2A    I47 @S9S_MB_2U_LIB.S9S_MB_2U(SCH_1):PAGE101

M_B_CPU1_SB_DQ<3> @S9S_MB_2U_LIB.S9S_MB_2U(SCH_1):M_B_CPU1_SB_DQ(3)
    U1  Y28 DDR1_SB_DQ3 SOCKET4677_AZIF0045P001C01CS-SA    I91 @S9S_MB_2U_LIB.S9S_MB_2U(SCH_1):PAGE52
   J19  247  DQ3_B SCONN288_ADR50017P130CC-SCONN2A    I25 @S9S_MB_2U_LIB.S9S_MB_2U(SCH_1):PAGE100
   J20  247  DQ3_B SCONN288_ADR50017P087CC-SCONN2A    I47 @S9S_MB_2U_LIB.S9S_MB_2U(SCH_1):PAGE101

M_B_CPU1_SB_DQ<4> @S9S_MB_2U_LIB.S9S_MB_2U(SCH_1):M_B_CPU1_SB_DQ(4)
    U1  T26 DDR1_SB_DQ4 SOCKET4677_AZIF0045P001C01CS-SA    I91 @S9S_MB_2U_LIB.S9S_MB_2U(SCH_1):PAGE52
   J19  107  DQ4_B SCONN288_ADR50017P130CC-SCONN2A    I25 @S9S_MB_2U_LIB.S9S_MB_2U(SCH_1):PAGE100
   J20  107  DQ4_B SCONN288_ADR50017P087CC-SCONN2A    I47 @S9S_MB_2U_LIB.S9S_MB_2U(SCH_1):PAGE101

M_B_CPU1_SB_DQ<5> @S9S_MB_2U_LIB.S9S_MB_2U(SCH_1):M_B_CPU1_SB_DQ(5)
    U1  U25 DDR1_SB_DQ5 SOCKET4677_AZIF0045P001C01CS-SA    I91 @S9S_MB_2U_LIB.S9S_MB_2U(SCH_1):PAGE52
   J19  109  DQ5_B SCONN288_ADR50017P130CC-SCONN2A    I25 @S9S_MB_2U_LIB.S9S_MB_2U(SCH_1):PAGE100
   J20  109  DQ5_B SCONN288_ADR50017P087CC-SCONN2A    I47 @S9S_MB_2U_LIB.S9S_MB_2U(SCH_1):PAGE101

M_B_CPU1_SB_DQ<6> @S9S_MB_2U_LIB.S9S_MB_2U(SCH_1):M_B_CPU1_SB_DQ(6)
    U1  Y26 DDR1_SB_DQ6 SOCKET4677_AZIF0045P001C01CS-SA    I91 @S9S_MB_2U_LIB.S9S_MB_2U(SCH_1):PAGE52
   J19  252  DQ6_B SCONN288_ADR50017P130CC-SCONN2A    I25 @S9S_MB_2U_LIB.S9S_MB_2U(SCH_1):PAGE100
   J20  252  DQ6_B SCONN288_ADR50017P087CC-SCONN2A    I47 @S9S_MB_2U_LIB.S9S_MB_2U(SCH_1):PAGE101

M_B_CPU1_SB_DQ<7> @S9S_MB_2U_LIB.S9S_MB_2U(SCH_1):M_B_CPU1_SB_DQ(7)
    U1  W25 DDR1_SB_DQ7 SOCKET4677_AZIF0045P001C01CS-SA    I91 @S9S_MB_2U_LIB.S9S_MB_2U(SCH_1):PAGE52
   J19  254  DQ7_B SCONN288_ADR50017P130CC-SCONN2A    I25 @S9S_MB_2U_LIB.S9S_MB_2U(SCH_1):PAGE100
   J20  254  DQ7_B SCONN288_ADR50017P087CC-SCONN2A    I47 @S9S_MB_2U_LIB.S9S_MB_2U(SCH_1):PAGE101

M_B_CPU1_SB_DQ<8> @S9S_MB_2U_LIB.S9S_MB_2U(SCH_1):M_B_CPU1_SB_DQ(8)
    U1  K26 DDR1_SB_DQ8 SOCKET4677_AZIF0045P001C01CS-SA    I91 @S9S_MB_2U_LIB.S9S_MB_2U(SCH_1):PAGE52
   J19  111  DQ8_B SCONN288_ADR50017P130CC-SCONN2A    I25 @S9S_MB_2U_LIB.S9S_MB_2U(SCH_1):PAGE100
   J20  111  DQ8_B SCONN288_ADR50017P087CC-SCONN2A    I47 @S9S_MB_2U_LIB.S9S_MB_2U(SCH_1):PAGE101

M_B_CPU1_SB_DQ<9> @S9S_MB_2U_LIB.S9S_MB_2U(SCH_1):M_B_CPU1_SB_DQ(9)
    U1  J25 DDR1_SB_DQ9 SOCKET4677_AZIF0045P001C01CS-SA    I91 @S9S_MB_2U_LIB.S9S_MB_2U(SCH_1):PAGE52
   J19  113  DQ9_B SCONN288_ADR50017P130CC-SCONN2A    I25 @S9S_MB_2U_LIB.S9S_MB_2U(SCH_1):PAGE100
   J20  113  DQ9_B SCONN288_ADR50017P087CC-SCONN2A    I47 @S9S_MB_2U_LIB.S9S_MB_2U(SCH_1):PAGE101

M_B_CPU1_SB_DQS_DN<0> @S9S_MB_2U_LIB.S9S_MB_2U(SCH_1):M_B_CPU1_SB_DQS_DN(0)
    U1  R27 DDR1_SB_DQS_DN0 SOCKET4677_AZIF0045P001C01CS-SA    I91 @S9S_MB_2U_LIB.S9S_MB_2U(SCH_1):PAGE52
   J19  105 DQS0_B_C SCONN288_ADR50017P130CC-SCONN2A   I178 @S9S_MB_2U_LIB.S9S_MB_2U(SCH_1):PAGE100
   J20  105 DQS0_B_C SCONN288_ADR50017P087CC-SCONN2A   I178 @S9S_MB_2U_LIB.S9S_MB_2U(SCH_1):PAGE101

M_B_CPU1_SB_DQS_DN<1> @S9S_MB_2U_LIB.S9S_MB_2U(SCH_1):M_B_CPU1_SB_DQS_DN(1)
    U1  H24 DDR1_SB_DQS_DN1 SOCKET4677_AZIF0045P001C01CS-SA    I91 @S9S_MB_2U_LIB.S9S_MB_2U(SCH_1):PAGE52
   J19  116 DQS1_B_C SCONN288_ADR50017P130CC-SCONN2A   I178 @S9S_MB_2U_LIB.S9S_MB_2U(SCH_1):PAGE100
   J20  116 DQS1_B_C SCONN288_ADR50017P087CC-SCONN2A   I178 @S9S_MB_2U_LIB.S9S_MB_2U(SCH_1):PAGE101

M_B_CPU1_SB_DQS_DN<2> @S9S_MB_2U_LIB.S9S_MB_2U(SCH_1):M_B_CPU1_SB_DQS_DN(2)
    U1  H18 DDR1_SB_DQS_DN2 SOCKET4677_AZIF0045P001C01CS-SA    I91 @S9S_MB_2U_LIB.S9S_MB_2U(SCH_1):PAGE52
   J19  127 DQS2_B_C SCONN288_ADR50017P130CC-SCONN2A   I178 @S9S_MB_2U_LIB.S9S_MB_2U(SCH_1):PAGE100
   J20  127 DQS2_B_C SCONN288_ADR50017P087CC-SCONN2A   I178 @S9S_MB_2U_LIB.S9S_MB_2U(SCH_1):PAGE101

M_B_CPU1_SB_DQS_DN<3> @S9S_MB_2U_LIB.S9S_MB_2U(SCH_1):M_B_CPU1_SB_DQS_DN(3)
    U1  A15 DDR1_SB_DQS_DN3 SOCKET4677_AZIF0045P001C01CS-SA    I91 @S9S_MB_2U_LIB.S9S_MB_2U(SCH_1):PAGE52
   J19  138 DQS3_B_C SCONN288_ADR50017P130CC-SCONN2A   I178 @S9S_MB_2U_LIB.S9S_MB_2U(SCH_1):PAGE100
   J20  138 DQS3_B_C SCONN288_ADR50017P087CC-SCONN2A   I178 @S9S_MB_2U_LIB.S9S_MB_2U(SCH_1):PAGE101

M_B_CPU1_SB_DQS_DN<4> @S9S_MB_2U_LIB.S9S_MB_2U(SCH_1):M_B_CPU1_SB_DQS_DN(4)
    U1  P36 DDR1_SB_DQS_DN4 SOCKET4677_AZIF0045P001C01CS-SA    I91 @S9S_MB_2U_LIB.S9S_MB_2U(SCH_1):PAGE52
   J19  238 DQS4_B_C SCONN288_ADR50017P130CC-SCONN2A   I178 @S9S_MB_2U_LIB.S9S_MB_2U(SCH_1):PAGE100
   J20  238 DQS4_B_C SCONN288_ADR50017P087CC-SCONN2A   I178 @S9S_MB_2U_LIB.S9S_MB_2U(SCH_1):PAGE101

M_B_CPU1_SB_DQS_DN<5> @S9S_MB_2U_LIB.S9S_MB_2U(SCH_1):M_B_CPU1_SB_DQS_DN(5)
    U1  W27 DDR1_SB_DQS_DN5 SOCKET4677_AZIF0045P001C01CS-SA    I91 @S9S_MB_2U_LIB.S9S_MB_2U(SCH_1):PAGE52
   J19  249 DQS5_B_C||TDQS5_B_C SCONN288_ADR50017P130CC-SCONN2A   I178 @S9S_MB_2U_LIB.S9S_MB_2U(SCH_1):PAGE100
   J20  249 DQS5_B_C||TDQS5_B_C SCONN288_ADR50017P087CC-SCONN2A   I178 @S9S_MB_2U_LIB.S9S_MB_2U(SCH_1):PAGE101

M_B_CPU1_SB_DQS_DN<6> @S9S_MB_2U_LIB.S9S_MB_2U(SCH_1):M_B_CPU1_SB_DQS_DN(6)
    U1  M24 DDR1_SB_DQS_DN6 SOCKET4677_AZIF0045P001C01CS-SA    I91 @S9S_MB_2U_LIB.S9S_MB_2U(SCH_1):PAGE52
   J19  260 DQS6_B_C||TDQS6_B_C SCONN288_ADR50017P130CC-SCONN2A   I178 @S9S_MB_2U_LIB.S9S_MB_2U(SCH_1):PAGE100
   J20  260 DQS6_B_C||TDQS6_B_C SCONN288_ADR50017P087CC-SCONN2A   I178 @S9S_MB_2U_LIB.S9S_MB_2U(SCH_1):PAGE101

M_B_CPU1_SB_DQS_DN<7> @S9S_MB_2U_LIB.S9S_MB_2U(SCH_1):M_B_CPU1_SB_DQS_DN(7)
    U1  M18 DDR1_SB_DQS_DN7 SOCKET4677_AZIF0045P001C01CS-SA    I91 @S9S_MB_2U_LIB.S9S_MB_2U(SCH_1):PAGE52
   J19  271 DQS7_B_C||TDQS7_B_C SCONN288_ADR50017P130CC-SCONN2A   I178 @S9S_MB_2U_LIB.S9S_MB_2U(SCH_1):PAGE100
   J20  271 DQS7_B_C||TDQS7_B_C SCONN288_ADR50017P087CC-SCONN2A   I178 @S9S_MB_2U_LIB.S9S_MB_2U(SCH_1):PAGE101

M_B_CPU1_SB_DQS_DN<8> @S9S_MB_2U_LIB.S9S_MB_2U(SCH_1):M_B_CPU1_SB_DQS_DN(8)
    U1  E15 DDR1_SB_DQS_DN8 SOCKET4677_AZIF0045P001C01CS-SA    I91 @S9S_MB_2U_LIB.S9S_MB_2U(SCH_1):PAGE52
   J19  282 DQS8_B_C||TDQS8_B_C SCONN288_ADR50017P130CC-SCONN2A   I178 @S9S_MB_2U_LIB.S9S_MB_2U(SCH_1):PAGE100
   J20  282 DQS8_B_C||TDQS8_B_C SCONN288_ADR50017P087CC-SCONN2A   I178 @S9S_MB_2U_LIB.S9S_MB_2U(SCH_1):PAGE101

M_B_CPU1_SB_DQS_DN<9> @S9S_MB_2U_LIB.S9S_MB_2U(SCH_1):M_B_CPU1_SB_DQS_DN(9)
    U1  K36 DDR1_SB_DQS_DN9 SOCKET4677_AZIF0045P001C01CS-SA    I91 @S9S_MB_2U_LIB.S9S_MB_2U(SCH_1):PAGE52
   J19   94 DQS9_B_C||TDQS9_B_C SCONN288_ADR50017P130CC-SCONN2A   I178 @S9S_MB_2U_LIB.S9S_MB_2U(SCH_1):PAGE100
   J20   94 DQS9_B_C||TDQS9_B_C SCONN288_ADR50017P087CC-SCONN2A   I178 @S9S_MB_2U_LIB.S9S_MB_2U(SCH_1):PAGE101

M_B_CPU1_SB_DQS_DP<0> @S9S_MB_2U_LIB.S9S_MB_2U(SCH_1):M_B_CPU1_SB_DQS_DP(0)
    U1  U27 DDR1_SB_DQS_DP0 SOCKET4677_AZIF0045P001C01CS-SA    I91 @S9S_MB_2U_LIB.S9S_MB_2U(SCH_1):PAGE52
   J19  104 DQS0_B_T SCONN288_ADR50017P130CC-SCONN2A   I178 @S9S_MB_2U_LIB.S9S_MB_2U(SCH_1):PAGE100
   J20  104 DQS0_B_T SCONN288_ADR50017P087CC-SCONN2A   I178 @S9S_MB_2U_LIB.S9S_MB_2U(SCH_1):PAGE101

M_B_CPU1_SB_DQS_DP<1> @S9S_MB_2U_LIB.S9S_MB_2U(SCH_1):M_B_CPU1_SB_DQS_DP(1)
    U1  K24 DDR1_SB_DQS_DP1 SOCKET4677_AZIF0045P001C01CS-SA    I91 @S9S_MB_2U_LIB.S9S_MB_2U(SCH_1):PAGE52
   J19  115 DQS1_B_T SCONN288_ADR50017P130CC-SCONN2A   I178 @S9S_MB_2U_LIB.S9S_MB_2U(SCH_1):PAGE100
   J20  115 DQS1_B_T SCONN288_ADR50017P087CC-SCONN2A   I178 @S9S_MB_2U_LIB.S9S_MB_2U(SCH_1):PAGE101

M_B_CPU1_SB_DQS_DP<2> @S9S_MB_2U_LIB.S9S_MB_2U(SCH_1):M_B_CPU1_SB_DQS_DP(2)
    U1  K18 DDR1_SB_DQS_DP2 SOCKET4677_AZIF0045P001C01CS-SA    I91 @S9S_MB_2U_LIB.S9S_MB_2U(SCH_1):PAGE52
   J19  126 DQS2_B_T SCONN288_ADR50017P130CC-SCONN2A   I178 @S9S_MB_2U_LIB.S9S_MB_2U(SCH_1):PAGE100
   J20  126 DQS2_B_T SCONN288_ADR50017P087CC-SCONN2A   I178 @S9S_MB_2U_LIB.S9S_MB_2U(SCH_1):PAGE101

M_B_CPU1_SB_DQS_DP<3> @S9S_MB_2U_LIB.S9S_MB_2U(SCH_1):M_B_CPU1_SB_DQS_DP(3)
    U1  C15 DDR1_SB_DQS_DP3 SOCKET4677_AZIF0045P001C01CS-SA    I91 @S9S_MB_2U_LIB.S9S_MB_2U(SCH_1):PAGE52
   J19  137 DQS3_B_T SCONN288_ADR50017P130CC-SCONN2A   I178 @S9S_MB_2U_LIB.S9S_MB_2U(SCH_1):PAGE100
   J20  137 DQS3_B_T SCONN288_ADR50017P087CC-SCONN2A   I178 @S9S_MB_2U_LIB.S9S_MB_2U(SCH_1):PAGE101

M_B_CPU1_SB_DQS_DP<4> @S9S_MB_2U_LIB.S9S_MB_2U(SCH_1):M_B_CPU1_SB_DQS_DP(4)
    U1  M36 DDR1_SB_DQS_DP4 SOCKET4677_AZIF0045P001C01CS-SA    I91 @S9S_MB_2U_LIB.S9S_MB_2U(SCH_1):PAGE52
   J19  239 DQS4_B_T SCONN288_ADR50017P130CC-SCONN2A   I178 @S9S_MB_2U_LIB.S9S_MB_2U(SCH_1):PAGE100
   J20  239 DQS4_B_T SCONN288_ADR50017P087CC-SCONN2A   I178 @S9S_MB_2U_LIB.S9S_MB_2U(SCH_1):PAGE101

M_B_CPU1_SB_DQS_DP<5> @S9S_MB_2U_LIB.S9S_MB_2U(SCH_1):M_B_CPU1_SB_DQS_DP(5)
    U1 AA27 DDR1_SB_DQS_DP5 SOCKET4677_AZIF0045P001C01CS-SA    I91 @S9S_MB_2U_LIB.S9S_MB_2U(SCH_1):PAGE52
   J19  250 DQS5_B_T||TDQS5_B_T SCONN288_ADR50017P130CC-SCONN2A   I178 @S9S_MB_2U_LIB.S9S_MB_2U(SCH_1):PAGE100
   J20  250 DQS5_B_T||TDQS5_B_T SCONN288_ADR50017P087CC-SCONN2A   I178 @S9S_MB_2U_LIB.S9S_MB_2U(SCH_1):PAGE101

M_B_CPU1_SB_DQS_DP<6> @S9S_MB_2U_LIB.S9S_MB_2U(SCH_1):M_B_CPU1_SB_DQS_DP(6)
    U1  P24 DDR1_SB_DQS_DP6 SOCKET4677_AZIF0045P001C01CS-SA    I91 @S9S_MB_2U_LIB.S9S_MB_2U(SCH_1):PAGE52
   J19  261 DQS6_B_T||TDQS6_B_T SCONN288_ADR50017P130CC-SCONN2A   I178 @S9S_MB_2U_LIB.S9S_MB_2U(SCH_1):PAGE100
   J20  261 DQS6_B_T||TDQS6_B_T SCONN288_ADR50017P087CC-SCONN2A   I178 @S9S_MB_2U_LIB.S9S_MB_2U(SCH_1):PAGE101

M_B_CPU1_SB_DQS_DP<7> @S9S_MB_2U_LIB.S9S_MB_2U(SCH_1):M_B_CPU1_SB_DQS_DP(7)
    U1  P18 DDR1_SB_DQS_DP7 SOCKET4677_AZIF0045P001C01CS-SA    I91 @S9S_MB_2U_LIB.S9S_MB_2U(SCH_1):PAGE52
   J19  272 DQS7_B_T||TDQS7_B_T SCONN288_ADR50017P130CC-SCONN2A   I178 @S9S_MB_2U_LIB.S9S_MB_2U(SCH_1):PAGE100
   J20  272 DQS7_B_T||TDQS7_B_T SCONN288_ADR50017P087CC-SCONN2A   I178 @S9S_MB_2U_LIB.S9S_MB_2U(SCH_1):PAGE101

M_B_CPU1_SB_DQS_DP<8> @S9S_MB_2U_LIB.S9S_MB_2U(SCH_1):M_B_CPU1_SB_DQS_DP(8)
    U1  G15 DDR1_SB_DQS_DP8 SOCKET4677_AZIF0045P001C01CS-SA    I91 @S9S_MB_2U_LIB.S9S_MB_2U(SCH_1):PAGE52
   J19  283 DQS8_B_T||TDQS8_B_T SCONN288_ADR50017P130CC-SCONN2A   I178 @S9S_MB_2U_LIB.S9S_MB_2U(SCH_1):PAGE100
   J20  283 DQS8_B_T||TDQS8_B_T SCONN288_ADR50017P087CC-SCONN2A   I178 @S9S_MB_2U_LIB.S9S_MB_2U(SCH_1):PAGE101

M_B_CPU1_SB_DQS_DP<9> @S9S_MB_2U_LIB.S9S_MB_2U(SCH_1):M_B_CPU1_SB_DQS_DP(9)
    U1  H36 DDR1_SB_DQS_DP9 SOCKET4677_AZIF0045P001C01CS-SA    I91 @S9S_MB_2U_LIB.S9S_MB_2U(SCH_1):PAGE52
   J19   93 DQS9_B_T||TDQS9_B_T||DBI4_B_N SCONN288_ADR50017P130CC-SCONN2A   I178 @S9S_MB_2U_LIB.S9S_MB_2U(SCH_1):PAGE100
   J20   93 DQS9_B_T||TDQS9_B_T||DBI4_B_N SCONN288_ADR50017P087CC-SCONN2A   I178 @S9S_MB_2U_LIB.S9S_MB_2U(SCH_1):PAGE101

M_B_CPU1_SB_PAR @S9S_MB_2U_LIB.S9S_MB_2U(SCH_1):M_B_CPU1_SB_PAR
    U1  P42 DDR1_SB_PAR SOCKET4677_AZIF0045P001C01CS-SA    I91 @S9S_MB_2U_LIB.S9S_MB_2U(SCH_1):PAGE52
   J19  227  PAR_B SCONN288_ADR50017P130CC-SCONN2A    I25 @S9S_MB_2U_LIB.S9S_MB_2U(SCH_1):PAGE100
   J20  227  PAR_B SCONN288_ADR50017P087CC-SCONN2A    I47 @S9S_MB_2U_LIB.S9S_MB_2U(SCH_1):PAGE101

M_B_CPU1_SB_RSP<0> @S9S_MB_2U_LIB.S9S_MB_2U(SCH_1):M_B_CPU1_SB_RSP(0)
    U1 AN48 DDR1_B_RSP0 SOCKET4677_AZIF0045P001C01CS-SA    I91 @S9S_MB_2U_LIB.S9S_MB_2U(SCH_1):PAGE52
   J19   87 LBS||RSP_B_N SCONN288_ADR50017P130CC-SCONN2A    I25 @S9S_MB_2U_LIB.S9S_MB_2U(SCH_1):PAGE100

M_B_CPU1_SB_RSP<1> @S9S_MB_2U_LIB.S9S_MB_2U(SCH_1):M_B_CPU1_SB_RSP(1)
    U1 AP47 DDR1_B_RSP1 SOCKET4677_AZIF0045P001C01CS-SA    I91 @S9S_MB_2U_LIB.S9S_MB_2U(SCH_1):PAGE52
   J20   87 LBS||RSP_B_N SCONN288_ADR50017P087CC-SCONN2A    I47 @S9S_MB_2U_LIB.S9S_MB_2U(SCH_1):PAGE101

M_C_CPU0_ALERT_N @S9S_MB_2U_LIB.S9S_MB_2U(SCH_1):M_C_CPU0_ALERT_N
    U2 AT47 DDR2_ALERT_N SOCKET4677_AZIF0045P001C01CS-SA   I169 @S9S_MB_2U_LIB.S9S_MB_2U(SCH_1):PAGE22
    J5   62 ALERT_N SCONN288_ADR50017P130CC-SCONN2A    I24 @S9S_MB_2U_LIB.S9S_MB_2U(SCH_1):PAGE86
    J6   62 ALERT_N SCONN288_ADR50017P087CC-SCONN2A    I46 @S9S_MB_2U_LIB.S9S_MB_2U(SCH_1):PAGE87

M_C_CPU0_CLK_DN<0> @S9S_MB_2U_LIB.S9S_MB_2U(SCH_1):M_C_CPU0_CLK_DN(0)
    U2 AB49 DDR2_CLK_DN0 SOCKET4677_AZIF0045P001C01CS-SA   I169 @S9S_MB_2U_LIB.S9S_MB_2U(SCH_1):PAGE22
    J5  218   CK_C SCONN288_ADR50017P130CC-SCONN2A    I24 @S9S_MB_2U_LIB.S9S_MB_2U(SCH_1):PAGE86

M_C_CPU0_CLK_DN<1> @S9S_MB_2U_LIB.S9S_MB_2U(SCH_1):M_C_CPU0_CLK_DN(1)
    U2 AF49 DDR2_CLK_DN1 SOCKET4677_AZIF0045P001C01CS-SA   I169 @S9S_MB_2U_LIB.S9S_MB_2U(SCH_1):PAGE22
    J6  218   CK_C SCONN288_ADR50017P087CC-SCONN2A    I46 @S9S_MB_2U_LIB.S9S_MB_2U(SCH_1):PAGE87

M_C_CPU0_CLK_DP<0> @S9S_MB_2U_LIB.S9S_MB_2U(SCH_1):M_C_CPU0_CLK_DP(0)
    U2 AD49 DDR2_CLK_DP0 SOCKET4677_AZIF0045P001C01CS-SA   I169 @S9S_MB_2U_LIB.S9S_MB_2U(SCH_1):PAGE22
    J5  217   CK_T SCONN288_ADR50017P130CC-SCONN2A    I24 @S9S_MB_2U_LIB.S9S_MB_2U(SCH_1):PAGE86

M_C_CPU0_CLK_DP<1> @S9S_MB_2U_LIB.S9S_MB_2U(SCH_1):M_C_CPU0_CLK_DP(1)
    U2 AH49 DDR2_CLK_DP1 SOCKET4677_AZIF0045P001C01CS-SA   I169 @S9S_MB_2U_LIB.S9S_MB_2U(SCH_1):PAGE22
    J6  217   CK_T SCONN288_ADR50017P087CC-SCONN2A    I46 @S9S_MB_2U_LIB.S9S_MB_2U(SCH_1):PAGE87

M_C_CPU0_SA_CA<0> @S9S_MB_2U_LIB.S9S_MB_2U(SCH_1):M_C_CPU0_SA_CA(0)
    U2  R52 DDR2_SA_CA0 SOCKET4677_AZIF0045P001C01CS-SA   I169 @S9S_MB_2U_LIB.S9S_MB_2U(SCH_1):PAGE22
    J5   66  CA0_A SCONN288_ADR50017P130CC-SCONN2A    I24 @S9S_MB_2U_LIB.S9S_MB_2U(SCH_1):PAGE86
    J6   66  CA0_A SCONN288_ADR50017P087CC-SCONN2A    I46 @S9S_MB_2U_LIB.S9S_MB_2U(SCH_1):PAGE87

M_C_CPU0_SA_CA<1> @S9S_MB_2U_LIB.S9S_MB_2U(SCH_1):M_C_CPU0_SA_CA(1)
    U2 AA52 DDR2_SA_CA1 SOCKET4677_AZIF0045P001C01CS-SA   I169 @S9S_MB_2U_LIB.S9S_MB_2U(SCH_1):PAGE22
    J5  211  CA1_A SCONN288_ADR50017P130CC-SCONN2A    I24 @S9S_MB_2U_LIB.S9S_MB_2U(SCH_1):PAGE86
    J6  211  CA1_A SCONN288_ADR50017P087CC-SCONN2A    I46 @S9S_MB_2U_LIB.S9S_MB_2U(SCH_1):PAGE87

M_C_CPU0_SA_CA<2> @S9S_MB_2U_LIB.S9S_MB_2U(SCH_1):M_C_CPU0_SA_CA(2)
    U2  T51 DDR2_SA_CA2 SOCKET4677_AZIF0045P001C01CS-SA   I169 @S9S_MB_2U_LIB.S9S_MB_2U(SCH_1):PAGE22
    J5   68  CA2_A SCONN288_ADR50017P130CC-SCONN2A    I24 @S9S_MB_2U_LIB.S9S_MB_2U(SCH_1):PAGE86
    J6   68  CA2_A SCONN288_ADR50017P087CC-SCONN2A    I46 @S9S_MB_2U_LIB.S9S_MB_2U(SCH_1):PAGE87

M_C_CPU0_SA_CA<3> @S9S_MB_2U_LIB.S9S_MB_2U(SCH_1):M_C_CPU0_SA_CA(3)
    U2  Y51 DDR2_SA_CA3 SOCKET4677_AZIF0045P001C01CS-SA   I169 @S9S_MB_2U_LIB.S9S_MB_2U(SCH_1):PAGE22
    J5  213  CA3_A SCONN288_ADR50017P130CC-SCONN2A    I24 @S9S_MB_2U_LIB.S9S_MB_2U(SCH_1):PAGE86
    J6  213  CA3_A SCONN288_ADR50017P087CC-SCONN2A    I46 @S9S_MB_2U_LIB.S9S_MB_2U(SCH_1):PAGE87

M_C_CPU0_SA_CA<4> @S9S_MB_2U_LIB.S9S_MB_2U(SCH_1):M_C_CPU0_SA_CA(4)
    U2  U50 DDR2_SA_CA4 SOCKET4677_AZIF0045P001C01CS-SA   I169 @S9S_MB_2U_LIB.S9S_MB_2U(SCH_1):PAGE22
    J5   70  CA4_A SCONN288_ADR50017P130CC-SCONN2A    I24 @S9S_MB_2U_LIB.S9S_MB_2U(SCH_1):PAGE86
    J6   70  CA4_A SCONN288_ADR50017P087CC-SCONN2A    I46 @S9S_MB_2U_LIB.S9S_MB_2U(SCH_1):PAGE87

M_C_CPU0_SA_CA<5> @S9S_MB_2U_LIB.S9S_MB_2U(SCH_1):M_C_CPU0_SA_CA(5)
    U2  W50 DDR2_SA_CA5 SOCKET4677_AZIF0045P001C01CS-SA   I169 @S9S_MB_2U_LIB.S9S_MB_2U(SCH_1):PAGE22
    J5  215  CA5_A SCONN288_ADR50017P130CC-SCONN2A    I24 @S9S_MB_2U_LIB.S9S_MB_2U(SCH_1):PAGE86
    J6  215  CA5_A SCONN288_ADR50017P087CC-SCONN2A    I46 @S9S_MB_2U_LIB.S9S_MB_2U(SCH_1):PAGE87

M_C_CPU0_SA_CA<6> @S9S_MB_2U_LIB.S9S_MB_2U(SCH_1):M_C_CPU0_SA_CA(6)
    U2  U48 DDR2_SA_CA6 SOCKET4677_AZIF0045P001C01CS-SA   I169 @S9S_MB_2U_LIB.S9S_MB_2U(SCH_1):PAGE22
    J5   72  CA6_A SCONN288_ADR50017P130CC-SCONN2A    I24 @S9S_MB_2U_LIB.S9S_MB_2U(SCH_1):PAGE86
    J6   72  CA6_A SCONN288_ADR50017P087CC-SCONN2A    I46 @S9S_MB_2U_LIB.S9S_MB_2U(SCH_1):PAGE87

M_C_CPU0_SA_CB<0> @S9S_MB_2U_LIB.S9S_MB_2U(SCH_1):M_C_CPU0_SA_CB(0)
    U2 AD57 DDR2_SA_ECC0 SOCKET4677_AZIF0045P001C01CS-SA   I169 @S9S_MB_2U_LIB.S9S_MB_2U(SCH_1):PAGE22
    J5   51  CB0_A SCONN288_ADR50017P130CC-SCONN2A    I24 @S9S_MB_2U_LIB.S9S_MB_2U(SCH_1):PAGE86
    J6   51  CB0_A SCONN288_ADR50017P087CC-SCONN2A    I46 @S9S_MB_2U_LIB.S9S_MB_2U(SCH_1):PAGE87

M_C_CPU0_SA_CB<1> @S9S_MB_2U_LIB.S9S_MB_2U(SCH_1):M_C_CPU0_SA_CB(1)
    U2 AC56 DDR2_SA_ECC1 SOCKET4677_AZIF0045P001C01CS-SA   I169 @S9S_MB_2U_LIB.S9S_MB_2U(SCH_1):PAGE22
    J5   53  CB1_A SCONN288_ADR50017P130CC-SCONN2A    I24 @S9S_MB_2U_LIB.S9S_MB_2U(SCH_1):PAGE86
    J6   53  CB1_A SCONN288_ADR50017P087CC-SCONN2A    I46 @S9S_MB_2U_LIB.S9S_MB_2U(SCH_1):PAGE87

M_C_CPU0_SA_CB<2> @S9S_MB_2U_LIB.S9S_MB_2U(SCH_1):M_C_CPU0_SA_CB(2)
    U2 AF57 DDR2_SA_ECC2 SOCKET4677_AZIF0045P001C01CS-SA   I169 @S9S_MB_2U_LIB.S9S_MB_2U(SCH_1):PAGE22
    J5  196  CB2_A SCONN288_ADR50017P130CC-SCONN2A    I24 @S9S_MB_2U_LIB.S9S_MB_2U(SCH_1):PAGE86
    J6  196  CB2_A SCONN288_ADR50017P087CC-SCONN2A    I46 @S9S_MB_2U_LIB.S9S_MB_2U(SCH_1):PAGE87

M_C_CPU0_SA_CB<3> @S9S_MB_2U_LIB.S9S_MB_2U(SCH_1):M_C_CPU0_SA_CB(3)
    U2 AG56 DDR2_SA_ECC3 SOCKET4677_AZIF0045P001C01CS-SA   I169 @S9S_MB_2U_LIB.S9S_MB_2U(SCH_1):PAGE22
    J5  198  CB3_A SCONN288_ADR50017P130CC-SCONN2A    I24 @S9S_MB_2U_LIB.S9S_MB_2U(SCH_1):PAGE86
    J6  198  CB3_A SCONN288_ADR50017P087CC-SCONN2A    I46 @S9S_MB_2U_LIB.S9S_MB_2U(SCH_1):PAGE87

M_C_CPU0_SA_CB<4> @S9S_MB_2U_LIB.S9S_MB_2U(SCH_1):M_C_CPU0_SA_CB(4)
    U2 AC54 DDR2_SA_ECC4 SOCKET4677_AZIF0045P001C01CS-SA   I169 @S9S_MB_2U_LIB.S9S_MB_2U(SCH_1):PAGE22
    J5   58  CB4_A SCONN288_ADR50017P130CC-SCONN2A    I24 @S9S_MB_2U_LIB.S9S_MB_2U(SCH_1):PAGE86
    J6   58  CB4_A SCONN288_ADR50017P087CC-SCONN2A    I46 @S9S_MB_2U_LIB.S9S_MB_2U(SCH_1):PAGE87

M_C_CPU0_SA_CB<5> @S9S_MB_2U_LIB.S9S_MB_2U(SCH_1):M_C_CPU0_SA_CB(5)
    U2 AD53 DDR2_SA_ECC5 SOCKET4677_AZIF0045P001C01CS-SA   I169 @S9S_MB_2U_LIB.S9S_MB_2U(SCH_1):PAGE22
    J5   60  CB5_A SCONN288_ADR50017P130CC-SCONN2A    I24 @S9S_MB_2U_LIB.S9S_MB_2U(SCH_1):PAGE86
    J6   60  CB5_A SCONN288_ADR50017P087CC-SCONN2A    I46 @S9S_MB_2U_LIB.S9S_MB_2U(SCH_1):PAGE87

M_C_CPU0_SA_CB<6> @S9S_MB_2U_LIB.S9S_MB_2U(SCH_1):M_C_CPU0_SA_CB(6)
    U2 AG54 DDR2_SA_ECC6 SOCKET4677_AZIF0045P001C01CS-SA   I169 @S9S_MB_2U_LIB.S9S_MB_2U(SCH_1):PAGE22
    J5  203  CB6_A SCONN288_ADR50017P130CC-SCONN2A    I24 @S9S_MB_2U_LIB.S9S_MB_2U(SCH_1):PAGE86
    J6  203  CB6_A SCONN288_ADR50017P087CC-SCONN2A    I46 @S9S_MB_2U_LIB.S9S_MB_2U(SCH_1):PAGE87

M_C_CPU0_SA_CB<7> @S9S_MB_2U_LIB.S9S_MB_2U(SCH_1):M_C_CPU0_SA_CB(7)
    U2 AF53 DDR2_SA_ECC7 SOCKET4677_AZIF0045P001C01CS-SA   I169 @S9S_MB_2U_LIB.S9S_MB_2U(SCH_1):PAGE22
    J5  205  CB7_A SCONN288_ADR50017P130CC-SCONN2A    I24 @S9S_MB_2U_LIB.S9S_MB_2U(SCH_1):PAGE86
    J6  205  CB7_A SCONN288_ADR50017P087CC-SCONN2A    I46 @S9S_MB_2U_LIB.S9S_MB_2U(SCH_1):PAGE87

M_C_CPU0_SA_CS_N<0> @S9S_MB_2U_LIB.S9S_MB_2U(SCH_1):M_C_CPU0_SA_CS_N(0)
    U2  U54 DDR2_SA_CS_N0 SOCKET4677_AZIF0045P001C01CS-SA   I169 @S9S_MB_2U_LIB.S9S_MB_2U(SCH_1):PAGE22
    J5   64 CS0_A_N SCONN288_ADR50017P130CC-SCONN2A    I24 @S9S_MB_2U_LIB.S9S_MB_2U(SCH_1):PAGE86

M_C_CPU0_SA_CS_N<1> @S9S_MB_2U_LIB.S9S_MB_2U(SCH_1):M_C_CPU0_SA_CS_N(1)
    U2  T53 DDR2_SA_CS_N1 SOCKET4677_AZIF0045P001C01CS-SA   I169 @S9S_MB_2U_LIB.S9S_MB_2U(SCH_1):PAGE22
    J5  209 CS1_A_N SCONN288_ADR50017P130CC-SCONN2A    I24 @S9S_MB_2U_LIB.S9S_MB_2U(SCH_1):PAGE86

M_C_CPU0_SA_CS_N<2> @S9S_MB_2U_LIB.S9S_MB_2U(SCH_1):M_C_CPU0_SA_CS_N(2)
    U2  W54 DDR2_SA_CS_N2 SOCKET4677_AZIF0045P001C01CS-SA   I169 @S9S_MB_2U_LIB.S9S_MB_2U(SCH_1):PAGE22
    J6   64 CS0_A_N SCONN288_ADR50017P087CC-SCONN2A    I46 @S9S_MB_2U_LIB.S9S_MB_2U(SCH_1):PAGE87

M_C_CPU0_SA_CS_N<3> @S9S_MB_2U_LIB.S9S_MB_2U(SCH_1):M_C_CPU0_SA_CS_N(3)
    U2  Y53 DDR2_SA_CS_N3 SOCKET4677_AZIF0045P001C01CS-SA   I169 @S9S_MB_2U_LIB.S9S_MB_2U(SCH_1):PAGE22
    J6  209 CS1_A_N SCONN288_ADR50017P087CC-SCONN2A    I46 @S9S_MB_2U_LIB.S9S_MB_2U(SCH_1):PAGE87

M_C_CPU0_SA_DQ<0> @S9S_MB_2U_LIB.S9S_MB_2U(SCH_1):M_C_CPU0_SA_DQ(0)
    U2  U78 DDR2_SA_DQ0 SOCKET4677_AZIF0045P001C01CS-SA   I169 @S9S_MB_2U_LIB.S9S_MB_2U(SCH_1):PAGE22
    J5    7  DQ0_A SCONN288_ADR50017P130CC-SCONN2A    I24 @S9S_MB_2U_LIB.S9S_MB_2U(SCH_1):PAGE86
    J6    7  DQ0_A SCONN288_ADR50017P087CC-SCONN2A    I46 @S9S_MB_2U_LIB.S9S_MB_2U(SCH_1):PAGE87

M_C_CPU0_SA_DQ<10> @S9S_MB_2U_LIB.S9S_MB_2U(SCH_1):M_C_CPU0_SA_DQ(10)
    U2 AF69 DDR2_SA_DQ10 SOCKET4677_AZIF0045P001C01CS-SA   I169 @S9S_MB_2U_LIB.S9S_MB_2U(SCH_1):PAGE22
    J5  163 DQ10_A SCONN288_ADR50017P130CC-SCONN2A    I24 @S9S_MB_2U_LIB.S9S_MB_2U(SCH_1):PAGE86
    J6  163 DQ10_A SCONN288_ADR50017P087CC-SCONN2A    I46 @S9S_MB_2U_LIB.S9S_MB_2U(SCH_1):PAGE87

M_C_CPU0_SA_DQ<11> @S9S_MB_2U_LIB.S9S_MB_2U(SCH_1):M_C_CPU0_SA_DQ(11)
    U2 AG68 DDR2_SA_DQ11 SOCKET4677_AZIF0045P001C01CS-SA   I169 @S9S_MB_2U_LIB.S9S_MB_2U(SCH_1):PAGE22
    J5  165 DQ11_A SCONN288_ADR50017P130CC-SCONN2A    I24 @S9S_MB_2U_LIB.S9S_MB_2U(SCH_1):PAGE86
    J6  165 DQ11_A SCONN288_ADR50017P087CC-SCONN2A    I46 @S9S_MB_2U_LIB.S9S_MB_2U(SCH_1):PAGE87

M_C_CPU0_SA_DQ<12> @S9S_MB_2U_LIB.S9S_MB_2U(SCH_1):M_C_CPU0_SA_DQ(12)
    U2 AC66 DDR2_SA_DQ12 SOCKET4677_AZIF0045P001C01CS-SA   I169 @S9S_MB_2U_LIB.S9S_MB_2U(SCH_1):PAGE22
    J5   25 DQ12_A SCONN288_ADR50017P130CC-SCONN2A    I24 @S9S_MB_2U_LIB.S9S_MB_2U(SCH_1):PAGE86
    J6   25 DQ12_A SCONN288_ADR50017P087CC-SCONN2A    I46 @S9S_MB_2U_LIB.S9S_MB_2U(SCH_1):PAGE87

M_C_CPU0_SA_DQ<13> @S9S_MB_2U_LIB.S9S_MB_2U(SCH_1):M_C_CPU0_SA_DQ(13)
    U2 AD65 DDR2_SA_DQ13 SOCKET4677_AZIF0045P001C01CS-SA   I169 @S9S_MB_2U_LIB.S9S_MB_2U(SCH_1):PAGE22
    J5   27 DQ13_A SCONN288_ADR50017P130CC-SCONN2A    I24 @S9S_MB_2U_LIB.S9S_MB_2U(SCH_1):PAGE86
    J6   27 DQ13_A SCONN288_ADR50017P087CC-SCONN2A    I46 @S9S_MB_2U_LIB.S9S_MB_2U(SCH_1):PAGE87

M_C_CPU0_SA_DQ<14> @S9S_MB_2U_LIB.S9S_MB_2U(SCH_1):M_C_CPU0_SA_DQ(14)
    U2 AG66 DDR2_SA_DQ14 SOCKET4677_AZIF0045P001C01CS-SA   I169 @S9S_MB_2U_LIB.S9S_MB_2U(SCH_1):PAGE22
    J5  170 DQ14_A SCONN288_ADR50017P130CC-SCONN2A    I24 @S9S_MB_2U_LIB.S9S_MB_2U(SCH_1):PAGE86
    J6  170 DQ14_A SCONN288_ADR50017P087CC-SCONN2A    I46 @S9S_MB_2U_LIB.S9S_MB_2U(SCH_1):PAGE87

M_C_CPU0_SA_DQ<15> @S9S_MB_2U_LIB.S9S_MB_2U(SCH_1):M_C_CPU0_SA_DQ(15)
    U2 AF65 DDR2_SA_DQ15 SOCKET4677_AZIF0045P001C01CS-SA   I169 @S9S_MB_2U_LIB.S9S_MB_2U(SCH_1):PAGE22
    J5  172 DQ15_A SCONN288_ADR50017P130CC-SCONN2A    I24 @S9S_MB_2U_LIB.S9S_MB_2U(SCH_1):PAGE86
    J6  172 DQ15_A SCONN288_ADR50017P087CC-SCONN2A    I46 @S9S_MB_2U_LIB.S9S_MB_2U(SCH_1):PAGE87

M_C_CPU0_SA_DQ<16> @S9S_MB_2U_LIB.S9S_MB_2U(SCH_1):M_C_CPU0_SA_DQ(16)
    U2  U66 DDR2_SA_DQ16 SOCKET4677_AZIF0045P001C01CS-SA   I169 @S9S_MB_2U_LIB.S9S_MB_2U(SCH_1):PAGE22
    J5   29 DQ16_A SCONN288_ADR50017P130CC-SCONN2A    I24 @S9S_MB_2U_LIB.S9S_MB_2U(SCH_1):PAGE86
    J6   29 DQ16_A SCONN288_ADR50017P087CC-SCONN2A    I46 @S9S_MB_2U_LIB.S9S_MB_2U(SCH_1):PAGE87

M_C_CPU0_SA_DQ<17> @S9S_MB_2U_LIB.S9S_MB_2U(SCH_1):M_C_CPU0_SA_DQ(17)
    U2  T65 DDR2_SA_DQ17 SOCKET4677_AZIF0045P001C01CS-SA   I169 @S9S_MB_2U_LIB.S9S_MB_2U(SCH_1):PAGE22
    J5   31 DQ17_A SCONN288_ADR50017P130CC-SCONN2A    I24 @S9S_MB_2U_LIB.S9S_MB_2U(SCH_1):PAGE86
    J6   31 DQ17_A SCONN288_ADR50017P087CC-SCONN2A    I46 @S9S_MB_2U_LIB.S9S_MB_2U(SCH_1):PAGE87

M_C_CPU0_SA_DQ<18> @S9S_MB_2U_LIB.S9S_MB_2U(SCH_1):M_C_CPU0_SA_DQ(18)
    U2  W66 DDR2_SA_DQ18 SOCKET4677_AZIF0045P001C01CS-SA   I169 @S9S_MB_2U_LIB.S9S_MB_2U(SCH_1):PAGE22
    J5  174 DQ18_A SCONN288_ADR50017P130CC-SCONN2A    I24 @S9S_MB_2U_LIB.S9S_MB_2U(SCH_1):PAGE86
    J6  174 DQ18_A SCONN288_ADR50017P087CC-SCONN2A    I46 @S9S_MB_2U_LIB.S9S_MB_2U(SCH_1):PAGE87

M_C_CPU0_SA_DQ<19> @S9S_MB_2U_LIB.S9S_MB_2U(SCH_1):M_C_CPU0_SA_DQ(19)
    U2  Y65 DDR2_SA_DQ19 SOCKET4677_AZIF0045P001C01CS-SA   I169 @S9S_MB_2U_LIB.S9S_MB_2U(SCH_1):PAGE22
    J5  176 DQ19_A SCONN288_ADR50017P130CC-SCONN2A    I24 @S9S_MB_2U_LIB.S9S_MB_2U(SCH_1):PAGE86
    J6  176 DQ19_A SCONN288_ADR50017P087CC-SCONN2A    I46 @S9S_MB_2U_LIB.S9S_MB_2U(SCH_1):PAGE87

M_C_CPU0_SA_DQ<1> @S9S_MB_2U_LIB.S9S_MB_2U(SCH_1):M_C_CPU0_SA_DQ(1)
    U2  T77 DDR2_SA_DQ1 SOCKET4677_AZIF0045P001C01CS-SA   I169 @S9S_MB_2U_LIB.S9S_MB_2U(SCH_1):PAGE22
    J5    9  DQ1_A SCONN288_ADR50017P130CC-SCONN2A    I24 @S9S_MB_2U_LIB.S9S_MB_2U(SCH_1):PAGE86
    J6    9  DQ1_A SCONN288_ADR50017P087CC-SCONN2A    I46 @S9S_MB_2U_LIB.S9S_MB_2U(SCH_1):PAGE87

M_C_CPU0_SA_DQ<20> @S9S_MB_2U_LIB.S9S_MB_2U(SCH_1):M_C_CPU0_SA_DQ(20)
    U2  T63 DDR2_SA_DQ20 SOCKET4677_AZIF0045P001C01CS-SA   I169 @S9S_MB_2U_LIB.S9S_MB_2U(SCH_1):PAGE22
    J5   36 DQ20_A SCONN288_ADR50017P130CC-SCONN2A    I24 @S9S_MB_2U_LIB.S9S_MB_2U(SCH_1):PAGE86
    J6   36 DQ20_A SCONN288_ADR50017P087CC-SCONN2A    I46 @S9S_MB_2U_LIB.S9S_MB_2U(SCH_1):PAGE87

M_C_CPU0_SA_DQ<21> @S9S_MB_2U_LIB.S9S_MB_2U(SCH_1):M_C_CPU0_SA_DQ(21)
    U2  U62 DDR2_SA_DQ21 SOCKET4677_AZIF0045P001C01CS-SA   I169 @S9S_MB_2U_LIB.S9S_MB_2U(SCH_1):PAGE22
    J5   38 DQ21_A SCONN288_ADR50017P130CC-SCONN2A    I24 @S9S_MB_2U_LIB.S9S_MB_2U(SCH_1):PAGE86
    J6   38 DQ21_A SCONN288_ADR50017P087CC-SCONN2A    I46 @S9S_MB_2U_LIB.S9S_MB_2U(SCH_1):PAGE87

M_C_CPU0_SA_DQ<22> @S9S_MB_2U_LIB.S9S_MB_2U(SCH_1):M_C_CPU0_SA_DQ(22)
    U2  Y63 DDR2_SA_DQ22 SOCKET4677_AZIF0045P001C01CS-SA   I169 @S9S_MB_2U_LIB.S9S_MB_2U(SCH_1):PAGE22
    J5  181 DQ22_A SCONN288_ADR50017P130CC-SCONN2A    I24 @S9S_MB_2U_LIB.S9S_MB_2U(SCH_1):PAGE86
    J6  181 DQ22_A SCONN288_ADR50017P087CC-SCONN2A    I46 @S9S_MB_2U_LIB.S9S_MB_2U(SCH_1):PAGE87

M_C_CPU0_SA_DQ<23> @S9S_MB_2U_LIB.S9S_MB_2U(SCH_1):M_C_CPU0_SA_DQ(23)
    U2  W62 DDR2_SA_DQ23 SOCKET4677_AZIF0045P001C01CS-SA   I169 @S9S_MB_2U_LIB.S9S_MB_2U(SCH_1):PAGE22
    J5  183 DQ23_A SCONN288_ADR50017P130CC-SCONN2A    I24 @S9S_MB_2U_LIB.S9S_MB_2U(SCH_1):PAGE86
    J6  183 DQ23_A SCONN288_ADR50017P087CC-SCONN2A    I46 @S9S_MB_2U_LIB.S9S_MB_2U(SCH_1):PAGE87

M_C_CPU0_SA_DQ<24> @S9S_MB_2U_LIB.S9S_MB_2U(SCH_1):M_C_CPU0_SA_DQ(24)
    U2 AD63 DDR2_SA_DQ24 SOCKET4677_AZIF0045P001C01CS-SA   I169 @S9S_MB_2U_LIB.S9S_MB_2U(SCH_1):PAGE22
    J5   40 DQ24_A SCONN288_ADR50017P130CC-SCONN2A    I24 @S9S_MB_2U_LIB.S9S_MB_2U(SCH_1):PAGE86
    J6   40 DQ24_A SCONN288_ADR50017P087CC-SCONN2A    I46 @S9S_MB_2U_LIB.S9S_MB_2U(SCH_1):PAGE87

M_C_CPU0_SA_DQ<25> @S9S_MB_2U_LIB.S9S_MB_2U(SCH_1):M_C_CPU0_SA_DQ(25)
    U2 AC62 DDR2_SA_DQ25 SOCKET4677_AZIF0045P001C01CS-SA   I169 @S9S_MB_2U_LIB.S9S_MB_2U(SCH_1):PAGE22
    J5   42 DQ25_A SCONN288_ADR50017P130CC-SCONN2A    I24 @S9S_MB_2U_LIB.S9S_MB_2U(SCH_1):PAGE86
    J6   42 DQ25_A SCONN288_ADR50017P087CC-SCONN2A    I46 @S9S_MB_2U_LIB.S9S_MB_2U(SCH_1):PAGE87

M_C_CPU0_SA_DQ<26> @S9S_MB_2U_LIB.S9S_MB_2U(SCH_1):M_C_CPU0_SA_DQ(26)
    U2 AF63 DDR2_SA_DQ26 SOCKET4677_AZIF0045P001C01CS-SA   I169 @S9S_MB_2U_LIB.S9S_MB_2U(SCH_1):PAGE22
    J5  185 DQ26_A SCONN288_ADR50017P130CC-SCONN2A    I24 @S9S_MB_2U_LIB.S9S_MB_2U(SCH_1):PAGE86
    J6  185 DQ26_A SCONN288_ADR50017P087CC-SCONN2A    I46 @S9S_MB_2U_LIB.S9S_MB_2U(SCH_1):PAGE87

M_C_CPU0_SA_DQ<27> @S9S_MB_2U_LIB.S9S_MB_2U(SCH_1):M_C_CPU0_SA_DQ(27)
    U2 AG62 DDR2_SA_DQ27 SOCKET4677_AZIF0045P001C01CS-SA   I169 @S9S_MB_2U_LIB.S9S_MB_2U(SCH_1):PAGE22
    J5  187 DQ27_A SCONN288_ADR50017P130CC-SCONN2A    I24 @S9S_MB_2U_LIB.S9S_MB_2U(SCH_1):PAGE86
    J6  187 DQ27_A SCONN288_ADR50017P087CC-SCONN2A    I46 @S9S_MB_2U_LIB.S9S_MB_2U(SCH_1):PAGE87

M_C_CPU0_SA_DQ<28> @S9S_MB_2U_LIB.S9S_MB_2U(SCH_1):M_C_CPU0_SA_DQ(28)
    U2 AC60 DDR2_SA_DQ28 SOCKET4677_AZIF0045P001C01CS-SA   I169 @S9S_MB_2U_LIB.S9S_MB_2U(SCH_1):PAGE22
    J5   47 DQ28_A SCONN288_ADR50017P130CC-SCONN2A    I24 @S9S_MB_2U_LIB.S9S_MB_2U(SCH_1):PAGE86
    J6   47 DQ28_A SCONN288_ADR50017P087CC-SCONN2A    I46 @S9S_MB_2U_LIB.S9S_MB_2U(SCH_1):PAGE87

M_C_CPU0_SA_DQ<29> @S9S_MB_2U_LIB.S9S_MB_2U(SCH_1):M_C_CPU0_SA_DQ(29)
    U2 AD59 DDR2_SA_DQ29 SOCKET4677_AZIF0045P001C01CS-SA   I169 @S9S_MB_2U_LIB.S9S_MB_2U(SCH_1):PAGE22
    J5   49 DQ29_A SCONN288_ADR50017P130CC-SCONN2A    I24 @S9S_MB_2U_LIB.S9S_MB_2U(SCH_1):PAGE86
    J6   49 DQ29_A SCONN288_ADR50017P087CC-SCONN2A    I46 @S9S_MB_2U_LIB.S9S_MB_2U(SCH_1):PAGE87

M_C_CPU0_SA_DQ<2> @S9S_MB_2U_LIB.S9S_MB_2U(SCH_1):M_C_CPU0_SA_DQ(2)
    U2  W78 DDR2_SA_DQ2 SOCKET4677_AZIF0045P001C01CS-SA   I169 @S9S_MB_2U_LIB.S9S_MB_2U(SCH_1):PAGE22
    J5  152  DQ2_A SCONN288_ADR50017P130CC-SCONN2A    I24 @S9S_MB_2U_LIB.S9S_MB_2U(SCH_1):PAGE86
    J6  152  DQ2_A SCONN288_ADR50017P087CC-SCONN2A    I46 @S9S_MB_2U_LIB.S9S_MB_2U(SCH_1):PAGE87

M_C_CPU0_SA_DQ<30> @S9S_MB_2U_LIB.S9S_MB_2U(SCH_1):M_C_CPU0_SA_DQ(30)
    U2 AG60 DDR2_SA_DQ30 SOCKET4677_AZIF0045P001C01CS-SA   I169 @S9S_MB_2U_LIB.S9S_MB_2U(SCH_1):PAGE22
    J5  192 DQ30_A SCONN288_ADR50017P130CC-SCONN2A    I24 @S9S_MB_2U_LIB.S9S_MB_2U(SCH_1):PAGE86
    J6  192 DQ30_A SCONN288_ADR50017P087CC-SCONN2A    I46 @S9S_MB_2U_LIB.S9S_MB_2U(SCH_1):PAGE87

M_C_CPU0_SA_DQ<31> @S9S_MB_2U_LIB.S9S_MB_2U(SCH_1):M_C_CPU0_SA_DQ(31)
    U2 AF59 DDR2_SA_DQ31 SOCKET4677_AZIF0045P001C01CS-SA   I169 @S9S_MB_2U_LIB.S9S_MB_2U(SCH_1):PAGE22
    J5  194 DQ31_A SCONN288_ADR50017P130CC-SCONN2A    I24 @S9S_MB_2U_LIB.S9S_MB_2U(SCH_1):PAGE86
    J6  194 DQ31_A SCONN288_ADR50017P087CC-SCONN2A    I46 @S9S_MB_2U_LIB.S9S_MB_2U(SCH_1):PAGE87

M_C_CPU0_SA_DQ<3> @S9S_MB_2U_LIB.S9S_MB_2U(SCH_1):M_C_CPU0_SA_DQ(3)
    U2  Y77 DDR2_SA_DQ3 SOCKET4677_AZIF0045P001C01CS-SA   I169 @S9S_MB_2U_LIB.S9S_MB_2U(SCH_1):PAGE22
    J5  154  DQ3_A SCONN288_ADR50017P130CC-SCONN2A    I24 @S9S_MB_2U_LIB.S9S_MB_2U(SCH_1):PAGE86
    J6  154  DQ3_A SCONN288_ADR50017P087CC-SCONN2A    I46 @S9S_MB_2U_LIB.S9S_MB_2U(SCH_1):PAGE87

M_C_CPU0_SA_DQ<4> @S9S_MB_2U_LIB.S9S_MB_2U(SCH_1):M_C_CPU0_SA_DQ(4)
    U2  T75 DDR2_SA_DQ4 SOCKET4677_AZIF0045P001C01CS-SA   I169 @S9S_MB_2U_LIB.S9S_MB_2U(SCH_1):PAGE22
    J5   14  DQ4_A SCONN288_ADR50017P130CC-SCONN2A    I24 @S9S_MB_2U_LIB.S9S_MB_2U(SCH_1):PAGE86
    J6   14  DQ4_A SCONN288_ADR50017P087CC-SCONN2A    I46 @S9S_MB_2U_LIB.S9S_MB_2U(SCH_1):PAGE87

M_C_CPU0_SA_DQ<5> @S9S_MB_2U_LIB.S9S_MB_2U(SCH_1):M_C_CPU0_SA_DQ(5)
    U2  U74 DDR2_SA_DQ5 SOCKET4677_AZIF0045P001C01CS-SA   I169 @S9S_MB_2U_LIB.S9S_MB_2U(SCH_1):PAGE22
    J5   16  DQ5_A SCONN288_ADR50017P130CC-SCONN2A    I24 @S9S_MB_2U_LIB.S9S_MB_2U(SCH_1):PAGE86
    J6   16  DQ5_A SCONN288_ADR50017P087CC-SCONN2A    I46 @S9S_MB_2U_LIB.S9S_MB_2U(SCH_1):PAGE87

M_C_CPU0_SA_DQ<6> @S9S_MB_2U_LIB.S9S_MB_2U(SCH_1):M_C_CPU0_SA_DQ(6)
    U2  Y75 DDR2_SA_DQ6 SOCKET4677_AZIF0045P001C01CS-SA   I169 @S9S_MB_2U_LIB.S9S_MB_2U(SCH_1):PAGE22
    J5  159  DQ6_A SCONN288_ADR50017P130CC-SCONN2A    I24 @S9S_MB_2U_LIB.S9S_MB_2U(SCH_1):PAGE86
    J6  159  DQ6_A SCONN288_ADR50017P087CC-SCONN2A    I46 @S9S_MB_2U_LIB.S9S_MB_2U(SCH_1):PAGE87

M_C_CPU0_SA_DQ<7> @S9S_MB_2U_LIB.S9S_MB_2U(SCH_1):M_C_CPU0_SA_DQ(7)
    U2  W74 DDR2_SA_DQ7 SOCKET4677_AZIF0045P001C01CS-SA   I169 @S9S_MB_2U_LIB.S9S_MB_2U(SCH_1):PAGE22
    J5  161  DQ7_A SCONN288_ADR50017P130CC-SCONN2A    I24 @S9S_MB_2U_LIB.S9S_MB_2U(SCH_1):PAGE86
    J6  161  DQ7_A SCONN288_ADR50017P087CC-SCONN2A    I46 @S9S_MB_2U_LIB.S9S_MB_2U(SCH_1):PAGE87

M_C_CPU0_SA_DQ<8> @S9S_MB_2U_LIB.S9S_MB_2U(SCH_1):M_C_CPU0_SA_DQ(8)
    U2 AD69 DDR2_SA_DQ8 SOCKET4677_AZIF0045P001C01CS-SA   I169 @S9S_MB_2U_LIB.S9S_MB_2U(SCH_1):PAGE22
    J5   18  DQ8_A SCONN288_ADR50017P130CC-SCONN2A    I24 @S9S_MB_2U_LIB.S9S_MB_2U(SCH_1):PAGE86
    J6   18  DQ8_A SCONN288_ADR50017P087CC-SCONN2A    I46 @S9S_MB_2U_LIB.S9S_MB_2U(SCH_1):PAGE87

M_C_CPU0_SA_DQ<9> @S9S_MB_2U_LIB.S9S_MB_2U(SCH_1):M_C_CPU0_SA_DQ(9)
    U2 AC68 DDR2_SA_DQ9 SOCKET4677_AZIF0045P001C01CS-SA   I169 @S9S_MB_2U_LIB.S9S_MB_2U(SCH_1):PAGE22
    J5   20  DQ9_A SCONN288_ADR50017P130CC-SCONN2A    I24 @S9S_MB_2U_LIB.S9S_MB_2U(SCH_1):PAGE86
    J6   20  DQ9_A SCONN288_ADR50017P087CC-SCONN2A    I46 @S9S_MB_2U_LIB.S9S_MB_2U(SCH_1):PAGE87

M_C_CPU0_SA_DQS_DN<0> @S9S_MB_2U_LIB.S9S_MB_2U(SCH_1):M_C_CPU0_SA_DQS_DN(0)
    U2  R76 DDR2_SA_DQS_DN0 SOCKET4677_AZIF0045P001C01CS-SA   I169 @S9S_MB_2U_LIB.S9S_MB_2U(SCH_1):PAGE22
    J5   12 DQS0_A_C SCONN288_ADR50017P130CC-SCONN2A   I178 @S9S_MB_2U_LIB.S9S_MB_2U(SCH_1):PAGE86
    J6   12 DQS0_A_C SCONN288_ADR50017P087CC-SCONN2A   I178 @S9S_MB_2U_LIB.S9S_MB_2U(SCH_1):PAGE87

M_C_CPU0_SA_DQS_DN<1> @S9S_MB_2U_LIB.S9S_MB_2U(SCH_1):M_C_CPU0_SA_DQS_DN(1)
    U2 AB67 DDR2_SA_DQS_DN1 SOCKET4677_AZIF0045P001C01CS-SA   I169 @S9S_MB_2U_LIB.S9S_MB_2U(SCH_1):PAGE22
    J5   23 DQS1_A_C SCONN288_ADR50017P130CC-SCONN2A   I178 @S9S_MB_2U_LIB.S9S_MB_2U(SCH_1):PAGE86
    J6   23 DQS1_A_C SCONN288_ADR50017P087CC-SCONN2A   I178 @S9S_MB_2U_LIB.S9S_MB_2U(SCH_1):PAGE87

M_C_CPU0_SA_DQS_DN<2> @S9S_MB_2U_LIB.S9S_MB_2U(SCH_1):M_C_CPU0_SA_DQS_DN(2)
    U2  R64 DDR2_SA_DQS_DN2 SOCKET4677_AZIF0045P001C01CS-SA   I169 @S9S_MB_2U_LIB.S9S_MB_2U(SCH_1):PAGE22
    J5   34 DQS2_A_C SCONN288_ADR50017P130CC-SCONN2A   I178 @S9S_MB_2U_LIB.S9S_MB_2U(SCH_1):PAGE86
    J6   34 DQS2_A_C SCONN288_ADR50017P087CC-SCONN2A   I178 @S9S_MB_2U_LIB.S9S_MB_2U(SCH_1):PAGE87

M_C_CPU0_SA_DQS_DN<3> @S9S_MB_2U_LIB.S9S_MB_2U(SCH_1):M_C_CPU0_SA_DQS_DN(3)
    U2 AB61 DDR2_SA_DQS_DN3 SOCKET4677_AZIF0045P001C01CS-SA   I169 @S9S_MB_2U_LIB.S9S_MB_2U(SCH_1):PAGE22
    J5   45 DQS3_A_C SCONN288_ADR50017P130CC-SCONN2A   I178 @S9S_MB_2U_LIB.S9S_MB_2U(SCH_1):PAGE86
    J6   45 DQS3_A_C SCONN288_ADR50017P087CC-SCONN2A   I178 @S9S_MB_2U_LIB.S9S_MB_2U(SCH_1):PAGE87

M_C_CPU0_SA_DQS_DN<4> @S9S_MB_2U_LIB.S9S_MB_2U(SCH_1):M_C_CPU0_SA_DQS_DN(4)
    U2 AD55 DDR2_SA_DQS_DN4 SOCKET4677_AZIF0045P001C01CS-SA   I169 @S9S_MB_2U_LIB.S9S_MB_2U(SCH_1):PAGE22
    J5   56 DQS4_A_C SCONN288_ADR50017P130CC-SCONN2A   I178 @S9S_MB_2U_LIB.S9S_MB_2U(SCH_1):PAGE86
    J6   56 DQS4_A_C SCONN288_ADR50017P087CC-SCONN2A   I178 @S9S_MB_2U_LIB.S9S_MB_2U(SCH_1):PAGE87

M_C_CPU0_SA_DQS_DN<5> @S9S_MB_2U_LIB.S9S_MB_2U(SCH_1):M_C_CPU0_SA_DQS_DN(5)
    U2  W76 DDR2_SA_DQS_DN5 SOCKET4677_AZIF0045P001C01CS-SA   I169 @S9S_MB_2U_LIB.S9S_MB_2U(SCH_1):PAGE22
    J5  156 DQS5_A_C||TDQS5_A_C||DQS5_A_T||TDQS5_A_T SCONN288_ADR50017P130CC-SCONN2A   I178 @S9S_MB_2U_LIB.S9S_MB_2U(SCH_1):PAGE86
    J6  156 DQS5_A_C||TDQS5_A_C||DQS5_A_T||TDQS5_A_T SCONN288_ADR50017P087CC-SCONN2A   I178 @S9S_MB_2U_LIB.S9S_MB_2U(SCH_1):PAGE87

M_C_CPU0_SA_DQS_DN<6> @S9S_MB_2U_LIB.S9S_MB_2U(SCH_1):M_C_CPU0_SA_DQS_DN(6)
    U2 AH67 DDR2_SA_DQS_DN6 SOCKET4677_AZIF0045P001C01CS-SA   I169 @S9S_MB_2U_LIB.S9S_MB_2U(SCH_1):PAGE22
    J5  167 DQS6_A_C||TDQS6_A_C||DQS6_A_T||TDQS6_A_T SCONN288_ADR50017P130CC-SCONN2A   I178 @S9S_MB_2U_LIB.S9S_MB_2U(SCH_1):PAGE86
    J6  167 DQS6_A_C||TDQS6_A_C||DQS6_A_T||TDQS6_A_T SCONN288_ADR50017P087CC-SCONN2A   I178 @S9S_MB_2U_LIB.S9S_MB_2U(SCH_1):PAGE87

M_C_CPU0_SA_DQS_DN<7> @S9S_MB_2U_LIB.S9S_MB_2U(SCH_1):M_C_CPU0_SA_DQS_DN(7)
    U2 AA64 DDR2_SA_DQS_DN7 SOCKET4677_AZIF0045P001C01CS-SA   I169 @S9S_MB_2U_LIB.S9S_MB_2U(SCH_1):PAGE22
    J5  178 DQS7_A_C||TDQS7_A_C SCONN288_ADR50017P130CC-SCONN2A   I178 @S9S_MB_2U_LIB.S9S_MB_2U(SCH_1):PAGE86
    J6  178 DQS7_A_C||TDQS7_A_C SCONN288_ADR50017P087CC-SCONN2A   I178 @S9S_MB_2U_LIB.S9S_MB_2U(SCH_1):PAGE87

M_C_CPU0_SA_DQS_DN<8> @S9S_MB_2U_LIB.S9S_MB_2U(SCH_1):M_C_CPU0_SA_DQS_DN(8)
    U2 AF61 DDR2_SA_DQS_DN8 SOCKET4677_AZIF0045P001C01CS-SA   I169 @S9S_MB_2U_LIB.S9S_MB_2U(SCH_1):PAGE22
    J5  189 DQS8_A_C||TDQS8_A_C SCONN288_ADR50017P130CC-SCONN2A   I178 @S9S_MB_2U_LIB.S9S_MB_2U(SCH_1):PAGE86
    J6  189 DQS8_A_C||TDQS8_A_C SCONN288_ADR50017P087CC-SCONN2A   I178 @S9S_MB_2U_LIB.S9S_MB_2U(SCH_1):PAGE87

M_C_CPU0_SA_DQS_DN<9> @S9S_MB_2U_LIB.S9S_MB_2U(SCH_1):M_C_CPU0_SA_DQS_DN(9)
    U2 AH55 DDR2_SA_DQS_DN9 SOCKET4677_AZIF0045P001C01CS-SA   I169 @S9S_MB_2U_LIB.S9S_MB_2U(SCH_1):PAGE22
    J5  200 DQS9_A_C||TDQS9_A_C SCONN288_ADR50017P130CC-SCONN2A   I178 @S9S_MB_2U_LIB.S9S_MB_2U(SCH_1):PAGE86
    J6  200 DQS9_A_C||TDQS9_A_C SCONN288_ADR50017P087CC-SCONN2A   I178 @S9S_MB_2U_LIB.S9S_MB_2U(SCH_1):PAGE87

M_C_CPU0_SA_DQS_DP<0> @S9S_MB_2U_LIB.S9S_MB_2U(SCH_1):M_C_CPU0_SA_DQS_DP(0)
    U2  U76 DDR2_SA_DQS_DP0 SOCKET4677_AZIF0045P001C01CS-SA   I169 @S9S_MB_2U_LIB.S9S_MB_2U(SCH_1):PAGE22
    J5   11 DQS0_A_T SCONN288_ADR50017P130CC-SCONN2A   I178 @S9S_MB_2U_LIB.S9S_MB_2U(SCH_1):PAGE86
    J6   11 DQS0_A_T SCONN288_ADR50017P087CC-SCONN2A   I178 @S9S_MB_2U_LIB.S9S_MB_2U(SCH_1):PAGE87

M_C_CPU0_SA_DQS_DP<1> @S9S_MB_2U_LIB.S9S_MB_2U(SCH_1):M_C_CPU0_SA_DQS_DP(1)
    U2 AD67 DDR2_SA_DQS_DP1 SOCKET4677_AZIF0045P001C01CS-SA   I169 @S9S_MB_2U_LIB.S9S_MB_2U(SCH_1):PAGE22
    J5   22 DQS1_A_T SCONN288_ADR50017P130CC-SCONN2A   I178 @S9S_MB_2U_LIB.S9S_MB_2U(SCH_1):PAGE86
    J6   22 DQS1_A_T SCONN288_ADR50017P087CC-SCONN2A   I178 @S9S_MB_2U_LIB.S9S_MB_2U(SCH_1):PAGE87

M_C_CPU0_SA_DQS_DP<2> @S9S_MB_2U_LIB.S9S_MB_2U(SCH_1):M_C_CPU0_SA_DQS_DP(2)
    U2  U64 DDR2_SA_DQS_DP2 SOCKET4677_AZIF0045P001C01CS-SA   I169 @S9S_MB_2U_LIB.S9S_MB_2U(SCH_1):PAGE22
    J5   33 DQS2_A_T SCONN288_ADR50017P130CC-SCONN2A   I178 @S9S_MB_2U_LIB.S9S_MB_2U(SCH_1):PAGE86
    J6   33 DQS2_A_T SCONN288_ADR50017P087CC-SCONN2A   I178 @S9S_MB_2U_LIB.S9S_MB_2U(SCH_1):PAGE87

M_C_CPU0_SA_DQS_DP<3> @S9S_MB_2U_LIB.S9S_MB_2U(SCH_1):M_C_CPU0_SA_DQS_DP(3)
    U2 AD61 DDR2_SA_DQS_DP3 SOCKET4677_AZIF0045P001C01CS-SA   I169 @S9S_MB_2U_LIB.S9S_MB_2U(SCH_1):PAGE22
    J5   44 DQS3_A_T SCONN288_ADR50017P130CC-SCONN2A   I178 @S9S_MB_2U_LIB.S9S_MB_2U(SCH_1):PAGE86
    J6   44 DQS3_A_T SCONN288_ADR50017P087CC-SCONN2A   I178 @S9S_MB_2U_LIB.S9S_MB_2U(SCH_1):PAGE87

M_C_CPU0_SA_DQS_DP<4> @S9S_MB_2U_LIB.S9S_MB_2U(SCH_1):M_C_CPU0_SA_DQS_DP(4)
    U2 AB55 DDR2_SA_DQS_DP4 SOCKET4677_AZIF0045P001C01CS-SA   I169 @S9S_MB_2U_LIB.S9S_MB_2U(SCH_1):PAGE22
    J5   55 DQS4_A_T SCONN288_ADR50017P130CC-SCONN2A   I178 @S9S_MB_2U_LIB.S9S_MB_2U(SCH_1):PAGE86
    J6   55 DQS4_A_T SCONN288_ADR50017P087CC-SCONN2A   I178 @S9S_MB_2U_LIB.S9S_MB_2U(SCH_1):PAGE87

M_C_CPU0_SA_DQS_DP<5> @S9S_MB_2U_LIB.S9S_MB_2U(SCH_1):M_C_CPU0_SA_DQS_DP(5)
    U2 AA76 DDR2_SA_DQS_DP5 SOCKET4677_AZIF0045P001C01CS-SA   I169 @S9S_MB_2U_LIB.S9S_MB_2U(SCH_1):PAGE22
    J5  157 DQS5_A_T||TDQS5_A_T SCONN288_ADR50017P130CC-SCONN2A   I178 @S9S_MB_2U_LIB.S9S_MB_2U(SCH_1):PAGE86
    J6  157 DQS5_A_T||TDQS5_A_T SCONN288_ADR50017P087CC-SCONN2A   I178 @S9S_MB_2U_LIB.S9S_MB_2U(SCH_1):PAGE87

M_C_CPU0_SA_DQS_DP<6> @S9S_MB_2U_LIB.S9S_MB_2U(SCH_1):M_C_CPU0_SA_DQS_DP(6)
    U2 AF67 DDR2_SA_DQS_DP6 SOCKET4677_AZIF0045P001C01CS-SA   I169 @S9S_MB_2U_LIB.S9S_MB_2U(SCH_1):PAGE22
    J5  168 DQS6_A_T||TDQS6_A_T SCONN288_ADR50017P130CC-SCONN2A   I178 @S9S_MB_2U_LIB.S9S_MB_2U(SCH_1):PAGE86
    J6  168 DQS6_A_T||TDQS6_A_T SCONN288_ADR50017P087CC-SCONN2A   I178 @S9S_MB_2U_LIB.S9S_MB_2U(SCH_1):PAGE87

M_C_CPU0_SA_DQS_DP<7> @S9S_MB_2U_LIB.S9S_MB_2U(SCH_1):M_C_CPU0_SA_DQS_DP(7)
    U2  W64 DDR2_SA_DQS_DP7 SOCKET4677_AZIF0045P001C01CS-SA   I169 @S9S_MB_2U_LIB.S9S_MB_2U(SCH_1):PAGE22
    J5  179 DQS7_A_T||TDQS7_A_T SCONN288_ADR50017P130CC-SCONN2A   I178 @S9S_MB_2U_LIB.S9S_MB_2U(SCH_1):PAGE86
    J6  179 DQS7_A_T||TDQS7_A_T SCONN288_ADR50017P087CC-SCONN2A   I178 @S9S_MB_2U_LIB.S9S_MB_2U(SCH_1):PAGE87

M_C_CPU0_SA_DQS_DP<8> @S9S_MB_2U_LIB.S9S_MB_2U(SCH_1):M_C_CPU0_SA_DQS_DP(8)
    U2 AH61 DDR2_SA_DQS_DP8 SOCKET4677_AZIF0045P001C01CS-SA   I169 @S9S_MB_2U_LIB.S9S_MB_2U(SCH_1):PAGE22
    J5  190 DQS8_A_T||TDQS8_A_T SCONN288_ADR50017P130CC-SCONN2A   I178 @S9S_MB_2U_LIB.S9S_MB_2U(SCH_1):PAGE86
    J6  190 DQS8_A_T||TDQS8_A_T SCONN288_ADR50017P087CC-SCONN2A   I178 @S9S_MB_2U_LIB.S9S_MB_2U(SCH_1):PAGE87

M_C_CPU0_SA_DQS_DP<9> @S9S_MB_2U_LIB.S9S_MB_2U(SCH_1):M_C_CPU0_SA_DQS_DP(9)
    U2 AF55 DDR2_SA_DQS_DP9 SOCKET4677_AZIF0045P001C01CS-SA   I169 @S9S_MB_2U_LIB.S9S_MB_2U(SCH_1):PAGE22
    J5  201 DQS9_A_T||TDQS9_A_T SCONN288_ADR50017P130CC-SCONN2A   I178 @S9S_MB_2U_LIB.S9S_MB_2U(SCH_1):PAGE86
    J6  201 DQS9_A_T||TDQS9_A_T SCONN288_ADR50017P087CC-SCONN2A   I178 @S9S_MB_2U_LIB.S9S_MB_2U(SCH_1):PAGE87

M_C_CPU0_SA_PAR @S9S_MB_2U_LIB.S9S_MB_2U(SCH_1):M_C_CPU0_SA_PAR
    U2  T47 DDR2_SA_PAR SOCKET4677_AZIF0045P001C01CS-SA   I169 @S9S_MB_2U_LIB.S9S_MB_2U(SCH_1):PAGE22
    J5   74  PAR_A SCONN288_ADR50017P130CC-SCONN2A    I24 @S9S_MB_2U_LIB.S9S_MB_2U(SCH_1):PAGE86
    J6   74  PAR_A SCONN288_ADR50017P087CC-SCONN2A    I46 @S9S_MB_2U_LIB.S9S_MB_2U(SCH_1):PAGE87

M_C_CPU0_SA_RSP<0> @S9S_MB_2U_LIB.S9S_MB_2U(SCH_1):M_C_CPU0_SA_RSP(0)
    U2 AC48 DDR2_A_RSP0 SOCKET4677_AZIF0045P001C01CS-SA   I169 @S9S_MB_2U_LIB.S9S_MB_2U(SCH_1):PAGE22
    J5   86 LBD||RSP_A_N SCONN288_ADR50017P130CC-SCONN2A    I24 @S9S_MB_2U_LIB.S9S_MB_2U(SCH_1):PAGE86

M_C_CPU0_SA_RSP<1> @S9S_MB_2U_LIB.S9S_MB_2U(SCH_1):M_C_CPU0_SA_RSP(1)
    U2 AD47 DDR2_A_RSP1 SOCKET4677_AZIF0045P001C01CS-SA   I169 @S9S_MB_2U_LIB.S9S_MB_2U(SCH_1):PAGE22
    J6   86 LBD||RSP_A_N SCONN288_ADR50017P087CC-SCONN2A    I46 @S9S_MB_2U_LIB.S9S_MB_2U(SCH_1):PAGE87

M_C_CPU0_SB_CA<0> @S9S_MB_2U_LIB.S9S_MB_2U(SCH_1):M_C_CPU0_SB_CA(0)
    U2  W48 DDR2_SB_CA0 SOCKET4677_AZIF0045P001C01CS-SA   I169 @S9S_MB_2U_LIB.S9S_MB_2U(SCH_1):PAGE22
    J5   76  CA0_B SCONN288_ADR50017P130CC-SCONN2A    I24 @S9S_MB_2U_LIB.S9S_MB_2U(SCH_1):PAGE86
    J6   76  CA0_B SCONN288_ADR50017P087CC-SCONN2A    I46 @S9S_MB_2U_LIB.S9S_MB_2U(SCH_1):PAGE87

M_C_CPU0_SB_CA<1> @S9S_MB_2U_LIB.S9S_MB_2U(SCH_1):M_C_CPU0_SB_CA(1)
    U2  Y47 DDR2_SB_CA1 SOCKET4677_AZIF0045P001C01CS-SA   I169 @S9S_MB_2U_LIB.S9S_MB_2U(SCH_1):PAGE22
    J5  221  CA1_B SCONN288_ADR50017P130CC-SCONN2A    I24 @S9S_MB_2U_LIB.S9S_MB_2U(SCH_1):PAGE86
    J6  221  CA1_B SCONN288_ADR50017P087CC-SCONN2A    I46 @S9S_MB_2U_LIB.S9S_MB_2U(SCH_1):PAGE87

M_C_CPU0_SB_CA<2> @S9S_MB_2U_LIB.S9S_MB_2U(SCH_1):M_C_CPU0_SB_CA(2)
    U2  U41 DDR2_SB_CA2 SOCKET4677_AZIF0045P001C01CS-SA   I169 @S9S_MB_2U_LIB.S9S_MB_2U(SCH_1):PAGE22
    J5   78  CA2_B SCONN288_ADR50017P130CC-SCONN2A    I24 @S9S_MB_2U_LIB.S9S_MB_2U(SCH_1):PAGE86
    J6   78  CA2_B SCONN288_ADR50017P087CC-SCONN2A    I46 @S9S_MB_2U_LIB.S9S_MB_2U(SCH_1):PAGE87

M_C_CPU0_SB_CA<3> @S9S_MB_2U_LIB.S9S_MB_2U(SCH_1):M_C_CPU0_SB_CA(3)
    U2  W41 DDR2_SB_CA3 SOCKET4677_AZIF0045P001C01CS-SA   I169 @S9S_MB_2U_LIB.S9S_MB_2U(SCH_1):PAGE22
    J5  223  CA3_B SCONN288_ADR50017P130CC-SCONN2A    I24 @S9S_MB_2U_LIB.S9S_MB_2U(SCH_1):PAGE86
    J6  223  CA3_B SCONN288_ADR50017P087CC-SCONN2A    I46 @S9S_MB_2U_LIB.S9S_MB_2U(SCH_1):PAGE87

M_C_CPU0_SB_CA<4> @S9S_MB_2U_LIB.S9S_MB_2U(SCH_1):M_C_CPU0_SB_CA(4)
    U2  T40 DDR2_SB_CA4 SOCKET4677_AZIF0045P001C01CS-SA   I169 @S9S_MB_2U_LIB.S9S_MB_2U(SCH_1):PAGE22
    J5   80  CA4_B SCONN288_ADR50017P130CC-SCONN2A    I24 @S9S_MB_2U_LIB.S9S_MB_2U(SCH_1):PAGE86
    J6   80  CA4_B SCONN288_ADR50017P087CC-SCONN2A    I46 @S9S_MB_2U_LIB.S9S_MB_2U(SCH_1):PAGE87

M_C_CPU0_SB_CA<5> @S9S_MB_2U_LIB.S9S_MB_2U(SCH_1):M_C_CPU0_SB_CA(5)
    U2  Y40 DDR2_SB_CA5 SOCKET4677_AZIF0045P001C01CS-SA   I169 @S9S_MB_2U_LIB.S9S_MB_2U(SCH_1):PAGE22
    J5  225  CA5_B SCONN288_ADR50017P130CC-SCONN2A    I24 @S9S_MB_2U_LIB.S9S_MB_2U(SCH_1):PAGE86
    J6  225  CA5_B SCONN288_ADR50017P087CC-SCONN2A    I46 @S9S_MB_2U_LIB.S9S_MB_2U(SCH_1):PAGE87

M_C_CPU0_SB_CA<6> @S9S_MB_2U_LIB.S9S_MB_2U(SCH_1):M_C_CPU0_SB_CA(6)
    U2  R39 DDR2_SB_CA6 SOCKET4677_AZIF0045P001C01CS-SA   I169 @S9S_MB_2U_LIB.S9S_MB_2U(SCH_1):PAGE22
    J5   82  CA6_B SCONN288_ADR50017P130CC-SCONN2A    I24 @S9S_MB_2U_LIB.S9S_MB_2U(SCH_1):PAGE86
    J6   82  CA6_B SCONN288_ADR50017P087CC-SCONN2A    I46 @S9S_MB_2U_LIB.S9S_MB_2U(SCH_1):PAGE87

M_C_CPU0_SB_CB<0> @S9S_MB_2U_LIB.S9S_MB_2U(SCH_1):M_C_CPU0_SB_CB(0)
    U2  T32 DDR2_SB_ECC0 SOCKET4677_AZIF0045P001C01CS-SA   I169 @S9S_MB_2U_LIB.S9S_MB_2U(SCH_1):PAGE22
    J5   96  CB0_B SCONN288_ADR50017P130CC-SCONN2A    I24 @S9S_MB_2U_LIB.S9S_MB_2U(SCH_1):PAGE86
    J6   96  CB0_B SCONN288_ADR50017P087CC-SCONN2A    I46 @S9S_MB_2U_LIB.S9S_MB_2U(SCH_1):PAGE87

M_C_CPU0_SB_CB<1> @S9S_MB_2U_LIB.S9S_MB_2U(SCH_1):M_C_CPU0_SB_CB(1)
    U2  U31 DDR2_SB_ECC1 SOCKET4677_AZIF0045P001C01CS-SA   I169 @S9S_MB_2U_LIB.S9S_MB_2U(SCH_1):PAGE22
    J5   98  CB1_B SCONN288_ADR50017P130CC-SCONN2A    I24 @S9S_MB_2U_LIB.S9S_MB_2U(SCH_1):PAGE86
    J6   98  CB1_B SCONN288_ADR50017P087CC-SCONN2A    I46 @S9S_MB_2U_LIB.S9S_MB_2U(SCH_1):PAGE87

M_C_CPU0_SB_CB<2> @S9S_MB_2U_LIB.S9S_MB_2U(SCH_1):M_C_CPU0_SB_CB(2)
    U2  Y32 DDR2_SB_ECC2 SOCKET4677_AZIF0045P001C01CS-SA   I169 @S9S_MB_2U_LIB.S9S_MB_2U(SCH_1):PAGE22
    J5  241  CB2_B SCONN288_ADR50017P130CC-SCONN2A    I24 @S9S_MB_2U_LIB.S9S_MB_2U(SCH_1):PAGE86
    J6  241  CB2_B SCONN288_ADR50017P087CC-SCONN2A    I46 @S9S_MB_2U_LIB.S9S_MB_2U(SCH_1):PAGE87

M_C_CPU0_SB_CB<3> @S9S_MB_2U_LIB.S9S_MB_2U(SCH_1):M_C_CPU0_SB_CB(3)
    U2  W31 DDR2_SB_ECC3 SOCKET4677_AZIF0045P001C01CS-SA   I169 @S9S_MB_2U_LIB.S9S_MB_2U(SCH_1):PAGE22
    J5  243  CB3_B SCONN288_ADR50017P130CC-SCONN2A    I24 @S9S_MB_2U_LIB.S9S_MB_2U(SCH_1):PAGE86
    J6  243  CB3_B SCONN288_ADR50017P087CC-SCONN2A    I46 @S9S_MB_2U_LIB.S9S_MB_2U(SCH_1):PAGE87

M_C_CPU0_SB_CB<4> @S9S_MB_2U_LIB.S9S_MB_2U(SCH_1):M_C_CPU0_SB_CB(4)
    U2  U35 DDR2_SB_ECC4 SOCKET4677_AZIF0045P001C01CS-SA   I169 @S9S_MB_2U_LIB.S9S_MB_2U(SCH_1):PAGE22
    J5   89  CB4_B SCONN288_ADR50017P130CC-SCONN2A    I24 @S9S_MB_2U_LIB.S9S_MB_2U(SCH_1):PAGE86
    J6   89  CB4_B SCONN288_ADR50017P087CC-SCONN2A    I46 @S9S_MB_2U_LIB.S9S_MB_2U(SCH_1):PAGE87

M_C_CPU0_SB_CB<5> @S9S_MB_2U_LIB.S9S_MB_2U(SCH_1):M_C_CPU0_SB_CB(5)
    U2  T34 DDR2_SB_ECC5 SOCKET4677_AZIF0045P001C01CS-SA   I169 @S9S_MB_2U_LIB.S9S_MB_2U(SCH_1):PAGE22
    J5   91  CB5_B SCONN288_ADR50017P130CC-SCONN2A    I24 @S9S_MB_2U_LIB.S9S_MB_2U(SCH_1):PAGE86
    J6   91  CB5_B SCONN288_ADR50017P087CC-SCONN2A    I46 @S9S_MB_2U_LIB.S9S_MB_2U(SCH_1):PAGE87

M_C_CPU0_SB_CB<6> @S9S_MB_2U_LIB.S9S_MB_2U(SCH_1):M_C_CPU0_SB_CB(6)
    U2  W35 DDR2_SB_ECC6 SOCKET4677_AZIF0045P001C01CS-SA   I169 @S9S_MB_2U_LIB.S9S_MB_2U(SCH_1):PAGE22
    J5  234  CB6_B SCONN288_ADR50017P130CC-SCONN2A    I24 @S9S_MB_2U_LIB.S9S_MB_2U(SCH_1):PAGE86
    J6  234  CB6_B SCONN288_ADR50017P087CC-SCONN2A    I46 @S9S_MB_2U_LIB.S9S_MB_2U(SCH_1):PAGE87

M_C_CPU0_SB_CB<7> @S9S_MB_2U_LIB.S9S_MB_2U(SCH_1):M_C_CPU0_SB_CB(7)
    U2  Y34 DDR2_SB_ECC7 SOCKET4677_AZIF0045P001C01CS-SA   I169 @S9S_MB_2U_LIB.S9S_MB_2U(SCH_1):PAGE22
    J5  236  CB7_B SCONN288_ADR50017P130CC-SCONN2A    I24 @S9S_MB_2U_LIB.S9S_MB_2U(SCH_1):PAGE86
    J6  236  CB7_B SCONN288_ADR50017P087CC-SCONN2A    I46 @S9S_MB_2U_LIB.S9S_MB_2U(SCH_1):PAGE87

M_C_CPU0_SB_CS_N<0> @S9S_MB_2U_LIB.S9S_MB_2U(SCH_1):M_C_CPU0_SB_CS_N(0)
    U2  T38 DDR2_SB_CS_N0 SOCKET4677_AZIF0045P001C01CS-SA   I169 @S9S_MB_2U_LIB.S9S_MB_2U(SCH_1):PAGE22
    J5   84 CS0_B_N SCONN288_ADR50017P130CC-SCONN2A    I24 @S9S_MB_2U_LIB.S9S_MB_2U(SCH_1):PAGE86

M_C_CPU0_SB_CS_N<1> @S9S_MB_2U_LIB.S9S_MB_2U(SCH_1):M_C_CPU0_SB_CS_N(1)
    U2  U37 DDR2_SB_CS_N1 SOCKET4677_AZIF0045P001C01CS-SA   I169 @S9S_MB_2U_LIB.S9S_MB_2U(SCH_1):PAGE22
    J5  229 CS1_B_N SCONN288_ADR50017P130CC-SCONN2A    I24 @S9S_MB_2U_LIB.S9S_MB_2U(SCH_1):PAGE86

M_C_CPU0_SB_CS_N<2> @S9S_MB_2U_LIB.S9S_MB_2U(SCH_1):M_C_CPU0_SB_CS_N(2)
    U2  Y38 DDR2_SB_CS_N2 SOCKET4677_AZIF0045P001C01CS-SA   I169 @S9S_MB_2U_LIB.S9S_MB_2U(SCH_1):PAGE22
    J6   84 CS0_B_N SCONN288_ADR50017P087CC-SCONN2A    I46 @S9S_MB_2U_LIB.S9S_MB_2U(SCH_1):PAGE87

M_C_CPU0_SB_CS_N<3> @S9S_MB_2U_LIB.S9S_MB_2U(SCH_1):M_C_CPU0_SB_CS_N(3)
    U2  W37 DDR2_SB_CS_N3 SOCKET4677_AZIF0045P001C01CS-SA   I169 @S9S_MB_2U_LIB.S9S_MB_2U(SCH_1):PAGE22
    J6  229 CS1_B_N SCONN288_ADR50017P087CC-SCONN2A    I46 @S9S_MB_2U_LIB.S9S_MB_2U(SCH_1):PAGE87

M_C_CPU0_SB_DQ<0> @S9S_MB_2U_LIB.S9S_MB_2U(SCH_1):M_C_CPU0_SB_DQ(0)
    U2 AD38 DDR2_SB_DQ0 SOCKET4677_AZIF0045P001C01CS-SA   I169 @S9S_MB_2U_LIB.S9S_MB_2U(SCH_1):PAGE22
    J5  100  DQ0_B SCONN288_ADR50017P130CC-SCONN2A    I24 @S9S_MB_2U_LIB.S9S_MB_2U(SCH_1):PAGE86
    J6  100  DQ0_B SCONN288_ADR50017P087CC-SCONN2A    I46 @S9S_MB_2U_LIB.S9S_MB_2U(SCH_1):PAGE87

M_C_CPU0_SB_DQ<10> @S9S_MB_2U_LIB.S9S_MB_2U(SCH_1):M_C_CPU0_SB_DQ(10)
    U2 AF32 DDR2_SB_DQ10 SOCKET4677_AZIF0045P001C01CS-SA   I169 @S9S_MB_2U_LIB.S9S_MB_2U(SCH_1):PAGE22
    J5  256 DQ10_B SCONN288_ADR50017P130CC-SCONN2A    I24 @S9S_MB_2U_LIB.S9S_MB_2U(SCH_1):PAGE86
    J6  256 DQ10_B SCONN288_ADR50017P087CC-SCONN2A    I46 @S9S_MB_2U_LIB.S9S_MB_2U(SCH_1):PAGE87

M_C_CPU0_SB_DQ<11> @S9S_MB_2U_LIB.S9S_MB_2U(SCH_1):M_C_CPU0_SB_DQ(11)
    U2 AG31 DDR2_SB_DQ11 SOCKET4677_AZIF0045P001C01CS-SA   I169 @S9S_MB_2U_LIB.S9S_MB_2U(SCH_1):PAGE22
    J5  258 DQ11_B SCONN288_ADR50017P130CC-SCONN2A    I24 @S9S_MB_2U_LIB.S9S_MB_2U(SCH_1):PAGE86
    J6  258 DQ11_B SCONN288_ADR50017P087CC-SCONN2A    I46 @S9S_MB_2U_LIB.S9S_MB_2U(SCH_1):PAGE87

M_C_CPU0_SB_DQ<12> @S9S_MB_2U_LIB.S9S_MB_2U(SCH_1):M_C_CPU0_SB_DQ(12)
    U2 AC29 DDR2_SB_DQ12 SOCKET4677_AZIF0045P001C01CS-SA   I169 @S9S_MB_2U_LIB.S9S_MB_2U(SCH_1):PAGE22
    J5  118 DQ12_B SCONN288_ADR50017P130CC-SCONN2A    I24 @S9S_MB_2U_LIB.S9S_MB_2U(SCH_1):PAGE86
    J6  118 DQ12_B SCONN288_ADR50017P087CC-SCONN2A    I46 @S9S_MB_2U_LIB.S9S_MB_2U(SCH_1):PAGE87

M_C_CPU0_SB_DQ<13> @S9S_MB_2U_LIB.S9S_MB_2U(SCH_1):M_C_CPU0_SB_DQ(13)
    U2 AD28 DDR2_SB_DQ13 SOCKET4677_AZIF0045P001C01CS-SA   I169 @S9S_MB_2U_LIB.S9S_MB_2U(SCH_1):PAGE22
    J5  120 DQ13_B SCONN288_ADR50017P130CC-SCONN2A    I24 @S9S_MB_2U_LIB.S9S_MB_2U(SCH_1):PAGE86
    J6  120 DQ13_B SCONN288_ADR50017P087CC-SCONN2A    I46 @S9S_MB_2U_LIB.S9S_MB_2U(SCH_1):PAGE87

M_C_CPU0_SB_DQ<14> @S9S_MB_2U_LIB.S9S_MB_2U(SCH_1):M_C_CPU0_SB_DQ(14)
    U2 AG29 DDR2_SB_DQ14 SOCKET4677_AZIF0045P001C01CS-SA   I169 @S9S_MB_2U_LIB.S9S_MB_2U(SCH_1):PAGE22
    J5  263 DQ14_B SCONN288_ADR50017P130CC-SCONN2A    I24 @S9S_MB_2U_LIB.S9S_MB_2U(SCH_1):PAGE86
    J6  263 DQ14_B SCONN288_ADR50017P087CC-SCONN2A    I46 @S9S_MB_2U_LIB.S9S_MB_2U(SCH_1):PAGE87

M_C_CPU0_SB_DQ<15> @S9S_MB_2U_LIB.S9S_MB_2U(SCH_1):M_C_CPU0_SB_DQ(15)
    U2 AF28 DDR2_SB_DQ15 SOCKET4677_AZIF0045P001C01CS-SA   I169 @S9S_MB_2U_LIB.S9S_MB_2U(SCH_1):PAGE22
    J5  265 DQ15_B SCONN288_ADR50017P130CC-SCONN2A    I24 @S9S_MB_2U_LIB.S9S_MB_2U(SCH_1):PAGE86
    J6  265 DQ15_B SCONN288_ADR50017P087CC-SCONN2A    I46 @S9S_MB_2U_LIB.S9S_MB_2U(SCH_1):PAGE87

M_C_CPU0_SB_DQ<16> @S9S_MB_2U_LIB.S9S_MB_2U(SCH_1):M_C_CPU0_SB_DQ(16)
    U2  U23 DDR2_SB_DQ16 SOCKET4677_AZIF0045P001C01CS-SA   I169 @S9S_MB_2U_LIB.S9S_MB_2U(SCH_1):PAGE22
    J5  122 DQ16_B SCONN288_ADR50017P130CC-SCONN2A    I24 @S9S_MB_2U_LIB.S9S_MB_2U(SCH_1):PAGE86
    J6  122 DQ16_B SCONN288_ADR50017P087CC-SCONN2A    I46 @S9S_MB_2U_LIB.S9S_MB_2U(SCH_1):PAGE87

M_C_CPU0_SB_DQ<17> @S9S_MB_2U_LIB.S9S_MB_2U(SCH_1):M_C_CPU0_SB_DQ(17)
    U2  T22 DDR2_SB_DQ17 SOCKET4677_AZIF0045P001C01CS-SA   I169 @S9S_MB_2U_LIB.S9S_MB_2U(SCH_1):PAGE22
    J5  124 DQ17_B SCONN288_ADR50017P130CC-SCONN2A    I24 @S9S_MB_2U_LIB.S9S_MB_2U(SCH_1):PAGE86
    J6  124 DQ17_B SCONN288_ADR50017P087CC-SCONN2A    I46 @S9S_MB_2U_LIB.S9S_MB_2U(SCH_1):PAGE87

M_C_CPU0_SB_DQ<18> @S9S_MB_2U_LIB.S9S_MB_2U(SCH_1):M_C_CPU0_SB_DQ(18)
    U2  W23 DDR2_SB_DQ18 SOCKET4677_AZIF0045P001C01CS-SA   I169 @S9S_MB_2U_LIB.S9S_MB_2U(SCH_1):PAGE22
    J5  267 DQ18_B SCONN288_ADR50017P130CC-SCONN2A    I24 @S9S_MB_2U_LIB.S9S_MB_2U(SCH_1):PAGE86
    J6  267 DQ18_B SCONN288_ADR50017P087CC-SCONN2A    I46 @S9S_MB_2U_LIB.S9S_MB_2U(SCH_1):PAGE87

M_C_CPU0_SB_DQ<19> @S9S_MB_2U_LIB.S9S_MB_2U(SCH_1):M_C_CPU0_SB_DQ(19)
    U2  Y22 DDR2_SB_DQ19 SOCKET4677_AZIF0045P001C01CS-SA   I169 @S9S_MB_2U_LIB.S9S_MB_2U(SCH_1):PAGE22
    J5  269 DQ19_B SCONN288_ADR50017P130CC-SCONN2A    I24 @S9S_MB_2U_LIB.S9S_MB_2U(SCH_1):PAGE86
    J6  269 DQ19_B SCONN288_ADR50017P087CC-SCONN2A    I46 @S9S_MB_2U_LIB.S9S_MB_2U(SCH_1):PAGE87

M_C_CPU0_SB_DQ<1> @S9S_MB_2U_LIB.S9S_MB_2U(SCH_1):M_C_CPU0_SB_DQ(1)
    U2 AC37 DDR2_SB_DQ1 SOCKET4677_AZIF0045P001C01CS-SA   I169 @S9S_MB_2U_LIB.S9S_MB_2U(SCH_1):PAGE22
    J5  102  DQ1_B SCONN288_ADR50017P130CC-SCONN2A    I24 @S9S_MB_2U_LIB.S9S_MB_2U(SCH_1):PAGE86
    J6  102  DQ1_B SCONN288_ADR50017P087CC-SCONN2A    I46 @S9S_MB_2U_LIB.S9S_MB_2U(SCH_1):PAGE87

M_C_CPU0_SB_DQ<20> @S9S_MB_2U_LIB.S9S_MB_2U(SCH_1):M_C_CPU0_SB_DQ(20)
    U2  T20 DDR2_SB_DQ20 SOCKET4677_AZIF0045P001C01CS-SA   I169 @S9S_MB_2U_LIB.S9S_MB_2U(SCH_1):PAGE22
    J5  129 DQ20_B SCONN288_ADR50017P130CC-SCONN2A    I24 @S9S_MB_2U_LIB.S9S_MB_2U(SCH_1):PAGE86
    J6  129 DQ20_B SCONN288_ADR50017P087CC-SCONN2A    I46 @S9S_MB_2U_LIB.S9S_MB_2U(SCH_1):PAGE87

M_C_CPU0_SB_DQ<21> @S9S_MB_2U_LIB.S9S_MB_2U(SCH_1):M_C_CPU0_SB_DQ(21)
    U2  U19 DDR2_SB_DQ21 SOCKET4677_AZIF0045P001C01CS-SA   I169 @S9S_MB_2U_LIB.S9S_MB_2U(SCH_1):PAGE22
    J5  131 DQ21_B SCONN288_ADR50017P130CC-SCONN2A    I24 @S9S_MB_2U_LIB.S9S_MB_2U(SCH_1):PAGE86
    J6  131 DQ21_B SCONN288_ADR50017P087CC-SCONN2A    I46 @S9S_MB_2U_LIB.S9S_MB_2U(SCH_1):PAGE87

M_C_CPU0_SB_DQ<22> @S9S_MB_2U_LIB.S9S_MB_2U(SCH_1):M_C_CPU0_SB_DQ(22)
    U2  Y20 DDR2_SB_DQ22 SOCKET4677_AZIF0045P001C01CS-SA   I169 @S9S_MB_2U_LIB.S9S_MB_2U(SCH_1):PAGE22
    J5  274 DQ22_B SCONN288_ADR50017P130CC-SCONN2A    I24 @S9S_MB_2U_LIB.S9S_MB_2U(SCH_1):PAGE86
    J6  274 DQ22_B SCONN288_ADR50017P087CC-SCONN2A    I46 @S9S_MB_2U_LIB.S9S_MB_2U(SCH_1):PAGE87

M_C_CPU0_SB_DQ<23> @S9S_MB_2U_LIB.S9S_MB_2U(SCH_1):M_C_CPU0_SB_DQ(23)
    U2  W19 DDR2_SB_DQ23 SOCKET4677_AZIF0045P001C01CS-SA   I169 @S9S_MB_2U_LIB.S9S_MB_2U(SCH_1):PAGE22
    J5  276 DQ23_B SCONN288_ADR50017P130CC-SCONN2A    I24 @S9S_MB_2U_LIB.S9S_MB_2U(SCH_1):PAGE86
    J6  276 DQ23_B SCONN288_ADR50017P087CC-SCONN2A    I46 @S9S_MB_2U_LIB.S9S_MB_2U(SCH_1):PAGE87

M_C_CPU0_SB_DQ<24> @S9S_MB_2U_LIB.S9S_MB_2U(SCH_1):M_C_CPU0_SB_DQ(24)
    U2 AD20 DDR2_SB_DQ24 SOCKET4677_AZIF0045P001C01CS-SA   I169 @S9S_MB_2U_LIB.S9S_MB_2U(SCH_1):PAGE22
    J5  133 DQ24_B SCONN288_ADR50017P130CC-SCONN2A    I24 @S9S_MB_2U_LIB.S9S_MB_2U(SCH_1):PAGE86
    J6  133 DQ24_B SCONN288_ADR50017P087CC-SCONN2A    I46 @S9S_MB_2U_LIB.S9S_MB_2U(SCH_1):PAGE87

M_C_CPU0_SB_DQ<25> @S9S_MB_2U_LIB.S9S_MB_2U(SCH_1):M_C_CPU0_SB_DQ(25)
    U2 AC19 DDR2_SB_DQ25 SOCKET4677_AZIF0045P001C01CS-SA   I169 @S9S_MB_2U_LIB.S9S_MB_2U(SCH_1):PAGE22
    J5  135 DQ25_B SCONN288_ADR50017P130CC-SCONN2A    I24 @S9S_MB_2U_LIB.S9S_MB_2U(SCH_1):PAGE86
    J6  135 DQ25_B SCONN288_ADR50017P087CC-SCONN2A    I46 @S9S_MB_2U_LIB.S9S_MB_2U(SCH_1):PAGE87

M_C_CPU0_SB_DQ<26> @S9S_MB_2U_LIB.S9S_MB_2U(SCH_1):M_C_CPU0_SB_DQ(26)
    U2 AF20 DDR2_SB_DQ26 SOCKET4677_AZIF0045P001C01CS-SA   I169 @S9S_MB_2U_LIB.S9S_MB_2U(SCH_1):PAGE22
    J5  278 DQ26_B SCONN288_ADR50017P130CC-SCONN2A    I24 @S9S_MB_2U_LIB.S9S_MB_2U(SCH_1):PAGE86
    J6  278 DQ26_B SCONN288_ADR50017P087CC-SCONN2A    I46 @S9S_MB_2U_LIB.S9S_MB_2U(SCH_1):PAGE87

M_C_CPU0_SB_DQ<27> @S9S_MB_2U_LIB.S9S_MB_2U(SCH_1):M_C_CPU0_SB_DQ(27)
    U2 AG19 DDR2_SB_DQ27 SOCKET4677_AZIF0045P001C01CS-SA   I169 @S9S_MB_2U_LIB.S9S_MB_2U(SCH_1):PAGE22
    J5  280 DQ27_B SCONN288_ADR50017P130CC-SCONN2A    I24 @S9S_MB_2U_LIB.S9S_MB_2U(SCH_1):PAGE86
    J6  280 DQ27_B SCONN288_ADR50017P087CC-SCONN2A    I46 @S9S_MB_2U_LIB.S9S_MB_2U(SCH_1):PAGE87

M_C_CPU0_SB_DQ<28> @S9S_MB_2U_LIB.S9S_MB_2U(SCH_1):M_C_CPU0_SB_DQ(28)
    U2 AA17 DDR2_SB_DQ28 SOCKET4677_AZIF0045P001C01CS-SA   I169 @S9S_MB_2U_LIB.S9S_MB_2U(SCH_1):PAGE22
    J5  140 DQ28_B SCONN288_ADR50017P130CC-SCONN2A    I24 @S9S_MB_2U_LIB.S9S_MB_2U(SCH_1):PAGE86
    J6  140 DQ28_B SCONN288_ADR50017P087CC-SCONN2A    I46 @S9S_MB_2U_LIB.S9S_MB_2U(SCH_1):PAGE87

M_C_CPU0_SB_DQ<29> @S9S_MB_2U_LIB.S9S_MB_2U(SCH_1):M_C_CPU0_SB_DQ(29)
    U2 AG17 DDR2_SB_DQ29 SOCKET4677_AZIF0045P001C01CS-SA   I169 @S9S_MB_2U_LIB.S9S_MB_2U(SCH_1):PAGE22
    J5  142 DQ29_B SCONN288_ADR50017P130CC-SCONN2A    I24 @S9S_MB_2U_LIB.S9S_MB_2U(SCH_1):PAGE86
    J6  142 DQ29_B SCONN288_ADR50017P087CC-SCONN2A    I46 @S9S_MB_2U_LIB.S9S_MB_2U(SCH_1):PAGE87

M_C_CPU0_SB_DQ<2> @S9S_MB_2U_LIB.S9S_MB_2U(SCH_1):M_C_CPU0_SB_DQ(2)
    U2 AF38 DDR2_SB_DQ2 SOCKET4677_AZIF0045P001C01CS-SA   I169 @S9S_MB_2U_LIB.S9S_MB_2U(SCH_1):PAGE22
    J5  245  DQ2_B SCONN288_ADR50017P130CC-SCONN2A    I24 @S9S_MB_2U_LIB.S9S_MB_2U(SCH_1):PAGE86
    J6  245  DQ2_B SCONN288_ADR50017P087CC-SCONN2A    I46 @S9S_MB_2U_LIB.S9S_MB_2U(SCH_1):PAGE87

M_C_CPU0_SB_DQ<30> @S9S_MB_2U_LIB.S9S_MB_2U(SCH_1):M_C_CPU0_SB_DQ(30)
    U2 AC17 DDR2_SB_DQ30 SOCKET4677_AZIF0045P001C01CS-SA   I169 @S9S_MB_2U_LIB.S9S_MB_2U(SCH_1):PAGE22
    J5  285 DQ30_B SCONN288_ADR50017P130CC-SCONN2A    I24 @S9S_MB_2U_LIB.S9S_MB_2U(SCH_1):PAGE86
    J6  285 DQ30_B SCONN288_ADR50017P087CC-SCONN2A    I46 @S9S_MB_2U_LIB.S9S_MB_2U(SCH_1):PAGE87

M_C_CPU0_SB_DQ<31> @S9S_MB_2U_LIB.S9S_MB_2U(SCH_1):M_C_CPU0_SB_DQ(31)
    U2 AJ17 DDR2_SB_DQ31 SOCKET4677_AZIF0045P001C01CS-SA   I169 @S9S_MB_2U_LIB.S9S_MB_2U(SCH_1):PAGE22
    J5  287 DQ31_B SCONN288_ADR50017P130CC-SCONN2A    I24 @S9S_MB_2U_LIB.S9S_MB_2U(SCH_1):PAGE86
    J6  287 DQ31_B SCONN288_ADR50017P087CC-SCONN2A    I46 @S9S_MB_2U_LIB.S9S_MB_2U(SCH_1):PAGE87

M_C_CPU0_SB_DQ<3> @S9S_MB_2U_LIB.S9S_MB_2U(SCH_1):M_C_CPU0_SB_DQ(3)
    U2 AG37 DDR2_SB_DQ3 SOCKET4677_AZIF0045P001C01CS-SA   I169 @S9S_MB_2U_LIB.S9S_MB_2U(SCH_1):PAGE22
    J5  247  DQ3_B SCONN288_ADR50017P130CC-SCONN2A    I24 @S9S_MB_2U_LIB.S9S_MB_2U(SCH_1):PAGE86
    J6  247  DQ3_B SCONN288_ADR50017P087CC-SCONN2A    I46 @S9S_MB_2U_LIB.S9S_MB_2U(SCH_1):PAGE87

M_C_CPU0_SB_DQ<4> @S9S_MB_2U_LIB.S9S_MB_2U(SCH_1):M_C_CPU0_SB_DQ(4)
    U2 AC35 DDR2_SB_DQ4 SOCKET4677_AZIF0045P001C01CS-SA   I169 @S9S_MB_2U_LIB.S9S_MB_2U(SCH_1):PAGE22
    J5  107  DQ4_B SCONN288_ADR50017P130CC-SCONN2A    I24 @S9S_MB_2U_LIB.S9S_MB_2U(SCH_1):PAGE86
    J6  107  DQ4_B SCONN288_ADR50017P087CC-SCONN2A    I46 @S9S_MB_2U_LIB.S9S_MB_2U(SCH_1):PAGE87

M_C_CPU0_SB_DQ<5> @S9S_MB_2U_LIB.S9S_MB_2U(SCH_1):M_C_CPU0_SB_DQ(5)
    U2 AD34 DDR2_SB_DQ5 SOCKET4677_AZIF0045P001C01CS-SA   I169 @S9S_MB_2U_LIB.S9S_MB_2U(SCH_1):PAGE22
    J5  109  DQ5_B SCONN288_ADR50017P130CC-SCONN2A    I24 @S9S_MB_2U_LIB.S9S_MB_2U(SCH_1):PAGE86
    J6  109  DQ5_B SCONN288_ADR50017P087CC-SCONN2A    I46 @S9S_MB_2U_LIB.S9S_MB_2U(SCH_1):PAGE87

M_C_CPU0_SB_DQ<6> @S9S_MB_2U_LIB.S9S_MB_2U(SCH_1):M_C_CPU0_SB_DQ(6)
    U2 AG35 DDR2_SB_DQ6 SOCKET4677_AZIF0045P001C01CS-SA   I169 @S9S_MB_2U_LIB.S9S_MB_2U(SCH_1):PAGE22
    J5  252  DQ6_B SCONN288_ADR50017P130CC-SCONN2A    I24 @S9S_MB_2U_LIB.S9S_MB_2U(SCH_1):PAGE86
    J6  252  DQ6_B SCONN288_ADR50017P087CC-SCONN2A    I46 @S9S_MB_2U_LIB.S9S_MB_2U(SCH_1):PAGE87

M_C_CPU0_SB_DQ<7> @S9S_MB_2U_LIB.S9S_MB_2U(SCH_1):M_C_CPU0_SB_DQ(7)
    U2 AF34 DDR2_SB_DQ7 SOCKET4677_AZIF0045P001C01CS-SA   I169 @S9S_MB_2U_LIB.S9S_MB_2U(SCH_1):PAGE22
    J5  254  DQ7_B SCONN288_ADR50017P130CC-SCONN2A    I24 @S9S_MB_2U_LIB.S9S_MB_2U(SCH_1):PAGE86
    J6  254  DQ7_B SCONN288_ADR50017P087CC-SCONN2A    I46 @S9S_MB_2U_LIB.S9S_MB_2U(SCH_1):PAGE87

M_C_CPU0_SB_DQ<8> @S9S_MB_2U_LIB.S9S_MB_2U(SCH_1):M_C_CPU0_SB_DQ(8)
    U2 AD32 DDR2_SB_DQ8 SOCKET4677_AZIF0045P001C01CS-SA   I169 @S9S_MB_2U_LIB.S9S_MB_2U(SCH_1):PAGE22
    J5  111  DQ8_B SCONN288_ADR50017P130CC-SCONN2A    I24 @S9S_MB_2U_LIB.S9S_MB_2U(SCH_1):PAGE86
    J6  111  DQ8_B SCONN288_ADR50017P087CC-SCONN2A    I46 @S9S_MB_2U_LIB.S9S_MB_2U(SCH_1):PAGE87

M_C_CPU0_SB_DQ<9> @S9S_MB_2U_LIB.S9S_MB_2U(SCH_1):M_C_CPU0_SB_DQ(9)
    U2 AC31 DDR2_SB_DQ9 SOCKET4677_AZIF0045P001C01CS-SA   I169 @S9S_MB_2U_LIB.S9S_MB_2U(SCH_1):PAGE22
    J5  113  DQ9_B SCONN288_ADR50017P130CC-SCONN2A    I24 @S9S_MB_2U_LIB.S9S_MB_2U(SCH_1):PAGE86
    J6  113  DQ9_B SCONN288_ADR50017P087CC-SCONN2A    I46 @S9S_MB_2U_LIB.S9S_MB_2U(SCH_1):PAGE87

M_C_CPU0_SB_DQS_DN<0> @S9S_MB_2U_LIB.S9S_MB_2U(SCH_1):M_C_CPU0_SB_DQS_DN(0)
    U2 AB36 DDR2_SB_DQS_DN0 SOCKET4677_AZIF0045P001C01CS-SA   I169 @S9S_MB_2U_LIB.S9S_MB_2U(SCH_1):PAGE22
    J5  105 DQS0_B_C SCONN288_ADR50017P130CC-SCONN2A   I178 @S9S_MB_2U_LIB.S9S_MB_2U(SCH_1):PAGE86
    J6  105 DQS0_B_C SCONN288_ADR50017P087CC-SCONN2A   I178 @S9S_MB_2U_LIB.S9S_MB_2U(SCH_1):PAGE87

M_C_CPU0_SB_DQS_DN<1> @S9S_MB_2U_LIB.S9S_MB_2U(SCH_1):M_C_CPU0_SB_DQS_DN(1)
    U2 AB30 DDR2_SB_DQS_DN1 SOCKET4677_AZIF0045P001C01CS-SA   I169 @S9S_MB_2U_LIB.S9S_MB_2U(SCH_1):PAGE22
    J5  116 DQS1_B_C SCONN288_ADR50017P130CC-SCONN2A   I178 @S9S_MB_2U_LIB.S9S_MB_2U(SCH_1):PAGE86
    J6  116 DQS1_B_C SCONN288_ADR50017P087CC-SCONN2A   I178 @S9S_MB_2U_LIB.S9S_MB_2U(SCH_1):PAGE87

M_C_CPU0_SB_DQS_DN<2> @S9S_MB_2U_LIB.S9S_MB_2U(SCH_1):M_C_CPU0_SB_DQS_DN(2)
    U2  R21 DDR2_SB_DQS_DN2 SOCKET4677_AZIF0045P001C01CS-SA   I169 @S9S_MB_2U_LIB.S9S_MB_2U(SCH_1):PAGE22
    J5  127 DQS2_B_C SCONN288_ADR50017P130CC-SCONN2A   I178 @S9S_MB_2U_LIB.S9S_MB_2U(SCH_1):PAGE86
    J6  127 DQS2_B_C SCONN288_ADR50017P087CC-SCONN2A   I178 @S9S_MB_2U_LIB.S9S_MB_2U(SCH_1):PAGE87

M_C_CPU0_SB_DQS_DN<3> @S9S_MB_2U_LIB.S9S_MB_2U(SCH_1):M_C_CPU0_SB_DQS_DN(3)
    U2 AB18 DDR2_SB_DQS_DN3 SOCKET4677_AZIF0045P001C01CS-SA   I169 @S9S_MB_2U_LIB.S9S_MB_2U(SCH_1):PAGE22
    J5  138 DQS3_B_C SCONN288_ADR50017P130CC-SCONN2A   I178 @S9S_MB_2U_LIB.S9S_MB_2U(SCH_1):PAGE86
    J6  138 DQS3_B_C SCONN288_ADR50017P087CC-SCONN2A   I178 @S9S_MB_2U_LIB.S9S_MB_2U(SCH_1):PAGE87

M_C_CPU0_SB_DQS_DN<4> @S9S_MB_2U_LIB.S9S_MB_2U(SCH_1):M_C_CPU0_SB_DQS_DN(4)
    U2  W33 DDR2_SB_DQS_DN4 SOCKET4677_AZIF0045P001C01CS-SA   I169 @S9S_MB_2U_LIB.S9S_MB_2U(SCH_1):PAGE22
    J5  238 DQS4_B_C SCONN288_ADR50017P130CC-SCONN2A   I178 @S9S_MB_2U_LIB.S9S_MB_2U(SCH_1):PAGE86
    J6  238 DQS4_B_C SCONN288_ADR50017P087CC-SCONN2A   I178 @S9S_MB_2U_LIB.S9S_MB_2U(SCH_1):PAGE87

M_C_CPU0_SB_DQS_DN<5> @S9S_MB_2U_LIB.S9S_MB_2U(SCH_1):M_C_CPU0_SB_DQS_DN(5)
    U2 AF36 DDR2_SB_DQS_DN5 SOCKET4677_AZIF0045P001C01CS-SA   I169 @S9S_MB_2U_LIB.S9S_MB_2U(SCH_1):PAGE22
    J5  249 DQS5_B_C||TDQS5_B_C SCONN288_ADR50017P130CC-SCONN2A   I178 @S9S_MB_2U_LIB.S9S_MB_2U(SCH_1):PAGE86
    J6  249 DQS5_B_C||TDQS5_B_C SCONN288_ADR50017P087CC-SCONN2A   I178 @S9S_MB_2U_LIB.S9S_MB_2U(SCH_1):PAGE87

M_C_CPU0_SB_DQS_DN<6> @S9S_MB_2U_LIB.S9S_MB_2U(SCH_1):M_C_CPU0_SB_DQS_DN(6)
    U2 AF30 DDR2_SB_DQS_DN6 SOCKET4677_AZIF0045P001C01CS-SA   I169 @S9S_MB_2U_LIB.S9S_MB_2U(SCH_1):PAGE22
    J5  260 DQS6_B_C||TDQS6_B_C SCONN288_ADR50017P130CC-SCONN2A   I178 @S9S_MB_2U_LIB.S9S_MB_2U(SCH_1):PAGE86
    J6  260 DQS6_B_C||TDQS6_B_C SCONN288_ADR50017P087CC-SCONN2A   I178 @S9S_MB_2U_LIB.S9S_MB_2U(SCH_1):PAGE87

M_C_CPU0_SB_DQS_DN<7> @S9S_MB_2U_LIB.S9S_MB_2U(SCH_1):M_C_CPU0_SB_DQS_DN(7)
    U2  W21 DDR2_SB_DQS_DN7 SOCKET4677_AZIF0045P001C01CS-SA   I169 @S9S_MB_2U_LIB.S9S_MB_2U(SCH_1):PAGE22
    J5  271 DQS7_B_C||TDQS7_B_C SCONN288_ADR50017P130CC-SCONN2A   I178 @S9S_MB_2U_LIB.S9S_MB_2U(SCH_1):PAGE86
    J6  271 DQS7_B_C||TDQS7_B_C SCONN288_ADR50017P087CC-SCONN2A   I178 @S9S_MB_2U_LIB.S9S_MB_2U(SCH_1):PAGE87

M_C_CPU0_SB_DQS_DN<8> @S9S_MB_2U_LIB.S9S_MB_2U(SCH_1):M_C_CPU0_SB_DQS_DN(8)
    U2 AF18 DDR2_SB_DQS_DN8 SOCKET4677_AZIF0045P001C01CS-SA   I169 @S9S_MB_2U_LIB.S9S_MB_2U(SCH_1):PAGE22
    J5  282 DQS8_B_C||TDQS8_B_C SCONN288_ADR50017P130CC-SCONN2A   I178 @S9S_MB_2U_LIB.S9S_MB_2U(SCH_1):PAGE86
    J6  282 DQS8_B_C||TDQS8_B_C SCONN288_ADR50017P087CC-SCONN2A   I178 @S9S_MB_2U_LIB.S9S_MB_2U(SCH_1):PAGE87

M_C_CPU0_SB_DQS_DN<9> @S9S_MB_2U_LIB.S9S_MB_2U(SCH_1):M_C_CPU0_SB_DQS_DN(9)
    U2  R33 DDR2_SB_DQS_DN9 SOCKET4677_AZIF0045P001C01CS-SA   I169 @S9S_MB_2U_LIB.S9S_MB_2U(SCH_1):PAGE22
    J5   94 DQS9_B_C||TDQS9_B_C SCONN288_ADR50017P130CC-SCONN2A   I178 @S9S_MB_2U_LIB.S9S_MB_2U(SCH_1):PAGE86
    J6   94 DQS9_B_C||TDQS9_B_C SCONN288_ADR50017P087CC-SCONN2A   I178 @S9S_MB_2U_LIB.S9S_MB_2U(SCH_1):PAGE87

M_C_CPU0_SB_DQS_DP<0> @S9S_MB_2U_LIB.S9S_MB_2U(SCH_1):M_C_CPU0_SB_DQS_DP(0)
    U2 AD36 DDR2_SB_DQS_DP0 SOCKET4677_AZIF0045P001C01CS-SA   I169 @S9S_MB_2U_LIB.S9S_MB_2U(SCH_1):PAGE22
    J5  104 DQS0_B_T SCONN288_ADR50017P130CC-SCONN2A   I178 @S9S_MB_2U_LIB.S9S_MB_2U(SCH_1):PAGE86
    J6  104 DQS0_B_T SCONN288_ADR50017P087CC-SCONN2A   I178 @S9S_MB_2U_LIB.S9S_MB_2U(SCH_1):PAGE87

M_C_CPU0_SB_DQS_DP<1> @S9S_MB_2U_LIB.S9S_MB_2U(SCH_1):M_C_CPU0_SB_DQS_DP(1)
    U2 AD30 DDR2_SB_DQS_DP1 SOCKET4677_AZIF0045P001C01CS-SA   I169 @S9S_MB_2U_LIB.S9S_MB_2U(SCH_1):PAGE22
    J5  115 DQS1_B_T SCONN288_ADR50017P130CC-SCONN2A   I178 @S9S_MB_2U_LIB.S9S_MB_2U(SCH_1):PAGE86
    J6  115 DQS1_B_T SCONN288_ADR50017P087CC-SCONN2A   I178 @S9S_MB_2U_LIB.S9S_MB_2U(SCH_1):PAGE87

M_C_CPU0_SB_DQS_DP<2> @S9S_MB_2U_LIB.S9S_MB_2U(SCH_1):M_C_CPU0_SB_DQS_DP(2)
    U2  U21 DDR2_SB_DQS_DP2 SOCKET4677_AZIF0045P001C01CS-SA   I169 @S9S_MB_2U_LIB.S9S_MB_2U(SCH_1):PAGE22
    J5  126 DQS2_B_T SCONN288_ADR50017P130CC-SCONN2A   I178 @S9S_MB_2U_LIB.S9S_MB_2U(SCH_1):PAGE86
    J6  126 DQS2_B_T SCONN288_ADR50017P087CC-SCONN2A   I178 @S9S_MB_2U_LIB.S9S_MB_2U(SCH_1):PAGE87

M_C_CPU0_SB_DQS_DP<3> @S9S_MB_2U_LIB.S9S_MB_2U(SCH_1):M_C_CPU0_SB_DQS_DP(3)
    U2 AD18 DDR2_SB_DQS_DP3 SOCKET4677_AZIF0045P001C01CS-SA   I169 @S9S_MB_2U_LIB.S9S_MB_2U(SCH_1):PAGE22
    J5  137 DQS3_B_T SCONN288_ADR50017P130CC-SCONN2A   I178 @S9S_MB_2U_LIB.S9S_MB_2U(SCH_1):PAGE86
    J6  137 DQS3_B_T SCONN288_ADR50017P087CC-SCONN2A   I178 @S9S_MB_2U_LIB.S9S_MB_2U(SCH_1):PAGE87

M_C_CPU0_SB_DQS_DP<4> @S9S_MB_2U_LIB.S9S_MB_2U(SCH_1):M_C_CPU0_SB_DQS_DP(4)
    U2 AA33 DDR2_SB_DQS_DP4 SOCKET4677_AZIF0045P001C01CS-SA   I169 @S9S_MB_2U_LIB.S9S_MB_2U(SCH_1):PAGE22
    J5  239 DQS4_B_T SCONN288_ADR50017P130CC-SCONN2A   I178 @S9S_MB_2U_LIB.S9S_MB_2U(SCH_1):PAGE86
    J6  239 DQS4_B_T SCONN288_ADR50017P087CC-SCONN2A   I178 @S9S_MB_2U_LIB.S9S_MB_2U(SCH_1):PAGE87

M_C_CPU0_SB_DQS_DP<5> @S9S_MB_2U_LIB.S9S_MB_2U(SCH_1):M_C_CPU0_SB_DQS_DP(5)
    U2 AH36 DDR2_SB_DQS_DP5 SOCKET4677_AZIF0045P001C01CS-SA   I169 @S9S_MB_2U_LIB.S9S_MB_2U(SCH_1):PAGE22
    J5  250 DQS5_B_T||TDQS5_B_T SCONN288_ADR50017P130CC-SCONN2A   I178 @S9S_MB_2U_LIB.S9S_MB_2U(SCH_1):PAGE86
    J6  250 DQS5_B_T||TDQS5_B_T SCONN288_ADR50017P087CC-SCONN2A   I178 @S9S_MB_2U_LIB.S9S_MB_2U(SCH_1):PAGE87

M_C_CPU0_SB_DQS_DP<6> @S9S_MB_2U_LIB.S9S_MB_2U(SCH_1):M_C_CPU0_SB_DQS_DP(6)
    U2 AH30 DDR2_SB_DQS_DP6 SOCKET4677_AZIF0045P001C01CS-SA   I169 @S9S_MB_2U_LIB.S9S_MB_2U(SCH_1):PAGE22
    J5  261 DQS6_B_T||TDQS6_B_T SCONN288_ADR50017P130CC-SCONN2A   I178 @S9S_MB_2U_LIB.S9S_MB_2U(SCH_1):PAGE86
    J6  261 DQS6_B_T||TDQS6_B_T SCONN288_ADR50017P087CC-SCONN2A   I178 @S9S_MB_2U_LIB.S9S_MB_2U(SCH_1):PAGE87

M_C_CPU0_SB_DQS_DP<7> @S9S_MB_2U_LIB.S9S_MB_2U(SCH_1):M_C_CPU0_SB_DQS_DP(7)
    U2 AA21 DDR2_SB_DQS_DP7 SOCKET4677_AZIF0045P001C01CS-SA   I169 @S9S_MB_2U_LIB.S9S_MB_2U(SCH_1):PAGE22
    J5  272 DQS7_B_T||TDQS7_B_T SCONN288_ADR50017P130CC-SCONN2A   I178 @S9S_MB_2U_LIB.S9S_MB_2U(SCH_1):PAGE86
    J6  272 DQS7_B_T||TDQS7_B_T SCONN288_ADR50017P087CC-SCONN2A   I178 @S9S_MB_2U_LIB.S9S_MB_2U(SCH_1):PAGE87

M_C_CPU0_SB_DQS_DP<8> @S9S_MB_2U_LIB.S9S_MB_2U(SCH_1):M_C_CPU0_SB_DQS_DP(8)
    U2 AH18 DDR2_SB_DQS_DP8 SOCKET4677_AZIF0045P001C01CS-SA   I169 @S9S_MB_2U_LIB.S9S_MB_2U(SCH_1):PAGE22
    J5  283 DQS8_B_T||TDQS8_B_T SCONN288_ADR50017P130CC-SCONN2A   I178 @S9S_MB_2U_LIB.S9S_MB_2U(SCH_1):PAGE86
    J6  283 DQS8_B_T||TDQS8_B_T SCONN288_ADR50017P087CC-SCONN2A   I178 @S9S_MB_2U_LIB.S9S_MB_2U(SCH_1):PAGE87

M_C_CPU0_SB_DQS_DP<9> @S9S_MB_2U_LIB.S9S_MB_2U(SCH_1):M_C_CPU0_SB_DQS_DP(9)
    U2  U33 DDR2_SB_DQS_DP9 SOCKET4677_AZIF0045P001C01CS-SA   I169 @S9S_MB_2U_LIB.S9S_MB_2U(SCH_1):PAGE22
    J5   93 DQS9_B_T||TDQS9_B_T||DBI4_B_N SCONN288_ADR50017P130CC-SCONN2A   I178 @S9S_MB_2U_LIB.S9S_MB_2U(SCH_1):PAGE86
    J6   93 DQS9_B_T||TDQS9_B_T||DBI4_B_N SCONN288_ADR50017P087CC-SCONN2A   I178 @S9S_MB_2U_LIB.S9S_MB_2U(SCH_1):PAGE87

M_C_CPU0_SB_PAR @S9S_MB_2U_LIB.S9S_MB_2U(SCH_1):M_C_CPU0_SB_PAR
    U2 AA39 DDR2_SB_PAR SOCKET4677_AZIF0045P001C01CS-SA   I169 @S9S_MB_2U_LIB.S9S_MB_2U(SCH_1):PAGE22
    J5  227  PAR_B SCONN288_ADR50017P130CC-SCONN2A    I24 @S9S_MB_2U_LIB.S9S_MB_2U(SCH_1):PAGE86
    J6  227  PAR_B SCONN288_ADR50017P087CC-SCONN2A    I46 @S9S_MB_2U_LIB.S9S_MB_2U(SCH_1):PAGE87

M_C_CPU0_SB_RSP<0> @S9S_MB_2U_LIB.S9S_MB_2U(SCH_1):M_C_CPU0_SB_RSP(0)
    U2 AG48 DDR2_B_RSP0 SOCKET4677_AZIF0045P001C01CS-SA   I169 @S9S_MB_2U_LIB.S9S_MB_2U(SCH_1):PAGE22
    J5   87 LBS||RSP_B_N SCONN288_ADR50017P130CC-SCONN2A    I24 @S9S_MB_2U_LIB.S9S_MB_2U(SCH_1):PAGE86

M_C_CPU0_SB_RSP<1> @S9S_MB_2U_LIB.S9S_MB_2U(SCH_1):M_C_CPU0_SB_RSP(1)
    U2 AF47 DDR2_B_RSP1 SOCKET4677_AZIF0045P001C01CS-SA   I169 @S9S_MB_2U_LIB.S9S_MB_2U(SCH_1):PAGE22
    J6   87 LBS||RSP_B_N SCONN288_ADR50017P087CC-SCONN2A    I46 @S9S_MB_2U_LIB.S9S_MB_2U(SCH_1):PAGE87

M_C_CPU1_ALERT_N @S9S_MB_2U_LIB.S9S_MB_2U(SCH_1):M_C_CPU1_ALERT_N
    U1 AT47 DDR2_ALERT_N SOCKET4677_AZIF0045P001C01CS-SA    I91 @S9S_MB_2U_LIB.S9S_MB_2U(SCH_1):PAGE53
   J21   62 ALERT_N SCONN288_ADR50017P130CC-SCONN2A    I13 @S9S_MB_2U_LIB.S9S_MB_2U(SCH_1):PAGE102
   J22   62 ALERT_N SCONN288_ADR50017P087CC-SCONN2A    I51 @S9S_MB_2U_LIB.S9S_MB_2U(SCH_1):PAGE103

M_C_CPU1_CLK_DN<0> @S9S_MB_2U_LIB.S9S_MB_2U(SCH_1):M_C_CPU1_CLK_DN(0)
    U1 AB49 DDR2_CLK_DN0 SOCKET4677_AZIF0045P001C01CS-SA    I91 @S9S_MB_2U_LIB.S9S_MB_2U(SCH_1):PAGE53
   J21  218   CK_C SCONN288_ADR50017P130CC-SCONN2A    I13 @S9S_MB_2U_LIB.S9S_MB_2U(SCH_1):PAGE102

M_C_CPU1_CLK_DN<1> @S9S_MB_2U_LIB.S9S_MB_2U(SCH_1):M_C_CPU1_CLK_DN(1)
    U1 AF49 DDR2_CLK_DN1 SOCKET4677_AZIF0045P001C01CS-SA    I91 @S9S_MB_2U_LIB.S9S_MB_2U(SCH_1):PAGE53
   J22  218   CK_C SCONN288_ADR50017P087CC-SCONN2A    I51 @S9S_MB_2U_LIB.S9S_MB_2U(SCH_1):PAGE103

M_C_CPU1_CLK_DP<0> @S9S_MB_2U_LIB.S9S_MB_2U(SCH_1):M_C_CPU1_CLK_DP(0)
    U1 AD49 DDR2_CLK_DP0 SOCKET4677_AZIF0045P001C01CS-SA    I91 @S9S_MB_2U_LIB.S9S_MB_2U(SCH_1):PAGE53
   J21  217   CK_T SCONN288_ADR50017P130CC-SCONN2A    I13 @S9S_MB_2U_LIB.S9S_MB_2U(SCH_1):PAGE102

M_C_CPU1_CLK_DP<1> @S9S_MB_2U_LIB.S9S_MB_2U(SCH_1):M_C_CPU1_CLK_DP(1)
    U1 AH49 DDR2_CLK_DP1 SOCKET4677_AZIF0045P001C01CS-SA    I91 @S9S_MB_2U_LIB.S9S_MB_2U(SCH_1):PAGE53
   J22  217   CK_T SCONN288_ADR50017P087CC-SCONN2A    I51 @S9S_MB_2U_LIB.S9S_MB_2U(SCH_1):PAGE103

M_C_CPU1_SA_CA<0> @S9S_MB_2U_LIB.S9S_MB_2U(SCH_1):M_C_CPU1_SA_CA(0)
    U1  R52 DDR2_SA_CA0 SOCKET4677_AZIF0045P001C01CS-SA    I91 @S9S_MB_2U_LIB.S9S_MB_2U(SCH_1):PAGE53
   J21   66  CA0_A SCONN288_ADR50017P130CC-SCONN2A    I13 @S9S_MB_2U_LIB.S9S_MB_2U(SCH_1):PAGE102
   J22   66  CA0_A SCONN288_ADR50017P087CC-SCONN2A    I51 @S9S_MB_2U_LIB.S9S_MB_2U(SCH_1):PAGE103

M_C_CPU1_SA_CA<1> @S9S_MB_2U_LIB.S9S_MB_2U(SCH_1):M_C_CPU1_SA_CA(1)
    U1 AA52 DDR2_SA_CA1 SOCKET4677_AZIF0045P001C01CS-SA    I91 @S9S_MB_2U_LIB.S9S_MB_2U(SCH_1):PAGE53
   J21  211  CA1_A SCONN288_ADR50017P130CC-SCONN2A    I13 @S9S_MB_2U_LIB.S9S_MB_2U(SCH_1):PAGE102
   J22  211  CA1_A SCONN288_ADR50017P087CC-SCONN2A    I51 @S9S_MB_2U_LIB.S9S_MB_2U(SCH_1):PAGE103

M_C_CPU1_SA_CA<2> @S9S_MB_2U_LIB.S9S_MB_2U(SCH_1):M_C_CPU1_SA_CA(2)
    U1  T51 DDR2_SA_CA2 SOCKET4677_AZIF0045P001C01CS-SA    I91 @S9S_MB_2U_LIB.S9S_MB_2U(SCH_1):PAGE53
   J21   68  CA2_A SCONN288_ADR50017P130CC-SCONN2A    I13 @S9S_MB_2U_LIB.S9S_MB_2U(SCH_1):PAGE102
   J22   68  CA2_A SCONN288_ADR50017P087CC-SCONN2A    I51 @S9S_MB_2U_LIB.S9S_MB_2U(SCH_1):PAGE103

M_C_CPU1_SA_CA<3> @S9S_MB_2U_LIB.S9S_MB_2U(SCH_1):M_C_CPU1_SA_CA(3)
    U1  Y51 DDR2_SA_CA3 SOCKET4677_AZIF0045P001C01CS-SA    I91 @S9S_MB_2U_LIB.S9S_MB_2U(SCH_1):PAGE53
   J21  213  CA3_A SCONN288_ADR50017P130CC-SCONN2A    I13 @S9S_MB_2U_LIB.S9S_MB_2U(SCH_1):PAGE102
   J22  213  CA3_A SCONN288_ADR50017P087CC-SCONN2A    I51 @S9S_MB_2U_LIB.S9S_MB_2U(SCH_1):PAGE103

M_C_CPU1_SA_CA<4> @S9S_MB_2U_LIB.S9S_MB_2U(SCH_1):M_C_CPU1_SA_CA(4)
    U1  U50 DDR2_SA_CA4 SOCKET4677_AZIF0045P001C01CS-SA    I91 @S9S_MB_2U_LIB.S9S_MB_2U(SCH_1):PAGE53
   J21   70  CA4_A SCONN288_ADR50017P130CC-SCONN2A    I13 @S9S_MB_2U_LIB.S9S_MB_2U(SCH_1):PAGE102
   J22   70  CA4_A SCONN288_ADR50017P087CC-SCONN2A    I51 @S9S_MB_2U_LIB.S9S_MB_2U(SCH_1):PAGE103

M_C_CPU1_SA_CA<5> @S9S_MB_2U_LIB.S9S_MB_2U(SCH_1):M_C_CPU1_SA_CA(5)
    U1  W50 DDR2_SA_CA5 SOCKET4677_AZIF0045P001C01CS-SA    I91 @S9S_MB_2U_LIB.S9S_MB_2U(SCH_1):PAGE53
   J21  215  CA5_A SCONN288_ADR50017P130CC-SCONN2A    I13 @S9S_MB_2U_LIB.S9S_MB_2U(SCH_1):PAGE102
   J22  215  CA5_A SCONN288_ADR50017P087CC-SCONN2A    I51 @S9S_MB_2U_LIB.S9S_MB_2U(SCH_1):PAGE103

M_C_CPU1_SA_CA<6> @S9S_MB_2U_LIB.S9S_MB_2U(SCH_1):M_C_CPU1_SA_CA(6)
    U1  U48 DDR2_SA_CA6 SOCKET4677_AZIF0045P001C01CS-SA    I91 @S9S_MB_2U_LIB.S9S_MB_2U(SCH_1):PAGE53
   J21   72  CA6_A SCONN288_ADR50017P130CC-SCONN2A    I13 @S9S_MB_2U_LIB.S9S_MB_2U(SCH_1):PAGE102
   J22   72  CA6_A SCONN288_ADR50017P087CC-SCONN2A    I51 @S9S_MB_2U_LIB.S9S_MB_2U(SCH_1):PAGE103

M_C_CPU1_SA_CB<0> @S9S_MB_2U_LIB.S9S_MB_2U(SCH_1):M_C_CPU1_SA_CB(0)
    U1 AD57 DDR2_SA_ECC0 SOCKET4677_AZIF0045P001C01CS-SA    I91 @S9S_MB_2U_LIB.S9S_MB_2U(SCH_1):PAGE53
   J21   51  CB0_A SCONN288_ADR50017P130CC-SCONN2A    I13 @S9S_MB_2U_LIB.S9S_MB_2U(SCH_1):PAGE102
   J22   51  CB0_A SCONN288_ADR50017P087CC-SCONN2A    I51 @S9S_MB_2U_LIB.S9S_MB_2U(SCH_1):PAGE103

M_C_CPU1_SA_CB<1> @S9S_MB_2U_LIB.S9S_MB_2U(SCH_1):M_C_CPU1_SA_CB(1)
    U1 AC56 DDR2_SA_ECC1 SOCKET4677_AZIF0045P001C01CS-SA    I91 @S9S_MB_2U_LIB.S9S_MB_2U(SCH_1):PAGE53
   J21   53  CB1_A SCONN288_ADR50017P130CC-SCONN2A    I13 @S9S_MB_2U_LIB.S9S_MB_2U(SCH_1):PAGE102
   J22   53  CB1_A SCONN288_ADR50017P087CC-SCONN2A    I51 @S9S_MB_2U_LIB.S9S_MB_2U(SCH_1):PAGE103

M_C_CPU1_SA_CB<2> @S9S_MB_2U_LIB.S9S_MB_2U(SCH_1):M_C_CPU1_SA_CB(2)
    U1 AF57 DDR2_SA_ECC2 SOCKET4677_AZIF0045P001C01CS-SA    I91 @S9S_MB_2U_LIB.S9S_MB_2U(SCH_1):PAGE53
   J21  196  CB2_A SCONN288_ADR50017P130CC-SCONN2A    I13 @S9S_MB_2U_LIB.S9S_MB_2U(SCH_1):PAGE102
   J22  196  CB2_A SCONN288_ADR50017P087CC-SCONN2A    I51 @S9S_MB_2U_LIB.S9S_MB_2U(SCH_1):PAGE103

M_C_CPU1_SA_CB<3> @S9S_MB_2U_LIB.S9S_MB_2U(SCH_1):M_C_CPU1_SA_CB(3)
    U1 AG56 DDR2_SA_ECC3 SOCKET4677_AZIF0045P001C01CS-SA    I91 @S9S_MB_2U_LIB.S9S_MB_2U(SCH_1):PAGE53
   J21  198  CB3_A SCONN288_ADR50017P130CC-SCONN2A    I13 @S9S_MB_2U_LIB.S9S_MB_2U(SCH_1):PAGE102
   J22  198  CB3_A SCONN288_ADR50017P087CC-SCONN2A    I51 @S9S_MB_2U_LIB.S9S_MB_2U(SCH_1):PAGE103

M_C_CPU1_SA_CB<4> @S9S_MB_2U_LIB.S9S_MB_2U(SCH_1):M_C_CPU1_SA_CB(4)
    U1 AC54 DDR2_SA_ECC4 SOCKET4677_AZIF0045P001C01CS-SA    I91 @S9S_MB_2U_LIB.S9S_MB_2U(SCH_1):PAGE53
   J21   58  CB4_A SCONN288_ADR50017P130CC-SCONN2A    I13 @S9S_MB_2U_LIB.S9S_MB_2U(SCH_1):PAGE102
   J22   58  CB4_A SCONN288_ADR50017P087CC-SCONN2A    I51 @S9S_MB_2U_LIB.S9S_MB_2U(SCH_1):PAGE103

M_C_CPU1_SA_CB<5> @S9S_MB_2U_LIB.S9S_MB_2U(SCH_1):M_C_CPU1_SA_CB(5)
    U1 AD53 DDR2_SA_ECC5 SOCKET4677_AZIF0045P001C01CS-SA    I91 @S9S_MB_2U_LIB.S9S_MB_2U(SCH_1):PAGE53
   J21   60  CB5_A SCONN288_ADR50017P130CC-SCONN2A    I13 @S9S_MB_2U_LIB.S9S_MB_2U(SCH_1):PAGE102
   J22   60  CB5_A SCONN288_ADR50017P087CC-SCONN2A    I51 @S9S_MB_2U_LIB.S9S_MB_2U(SCH_1):PAGE103

M_C_CPU1_SA_CB<6> @S9S_MB_2U_LIB.S9S_MB_2U(SCH_1):M_C_CPU1_SA_CB(6)
    U1 AG54 DDR2_SA_ECC6 SOCKET4677_AZIF0045P001C01CS-SA    I91 @S9S_MB_2U_LIB.S9S_MB_2U(SCH_1):PAGE53
   J21  203  CB6_A SCONN288_ADR50017P130CC-SCONN2A    I13 @S9S_MB_2U_LIB.S9S_MB_2U(SCH_1):PAGE102
   J22  203  CB6_A SCONN288_ADR50017P087CC-SCONN2A    I51 @S9S_MB_2U_LIB.S9S_MB_2U(SCH_1):PAGE103

M_C_CPU1_SA_CB<7> @S9S_MB_2U_LIB.S9S_MB_2U(SCH_1):M_C_CPU1_SA_CB(7)
    U1 AF53 DDR2_SA_ECC7 SOCKET4677_AZIF0045P001C01CS-SA    I91 @S9S_MB_2U_LIB.S9S_MB_2U(SCH_1):PAGE53
   J21  205  CB7_A SCONN288_ADR50017P130CC-SCONN2A    I13 @S9S_MB_2U_LIB.S9S_MB_2U(SCH_1):PAGE102
   J22  205  CB7_A SCONN288_ADR50017P087CC-SCONN2A    I51 @S9S_MB_2U_LIB.S9S_MB_2U(SCH_1):PAGE103

M_C_CPU1_SA_CS_N<0> @S9S_MB_2U_LIB.S9S_MB_2U(SCH_1):M_C_CPU1_SA_CS_N(0)
    U1  U54 DDR2_SA_CS_N0 SOCKET4677_AZIF0045P001C01CS-SA    I91 @S9S_MB_2U_LIB.S9S_MB_2U(SCH_1):PAGE53
   J21   64 CS0_A_N SCONN288_ADR50017P130CC-SCONN2A    I13 @S9S_MB_2U_LIB.S9S_MB_2U(SCH_1):PAGE102

M_C_CPU1_SA_CS_N<1> @S9S_MB_2U_LIB.S9S_MB_2U(SCH_1):M_C_CPU1_SA_CS_N(1)
    U1  T53 DDR2_SA_CS_N1 SOCKET4677_AZIF0045P001C01CS-SA    I91 @S9S_MB_2U_LIB.S9S_MB_2U(SCH_1):PAGE53
   J21  209 CS1_A_N SCONN288_ADR50017P130CC-SCONN2A    I13 @S9S_MB_2U_LIB.S9S_MB_2U(SCH_1):PAGE102

M_C_CPU1_SA_CS_N<2> @S9S_MB_2U_LIB.S9S_MB_2U(SCH_1):M_C_CPU1_SA_CS_N(2)
    U1  W54 DDR2_SA_CS_N2 SOCKET4677_AZIF0045P001C01CS-SA    I91 @S9S_MB_2U_LIB.S9S_MB_2U(SCH_1):PAGE53
   J22   64 CS0_A_N SCONN288_ADR50017P087CC-SCONN2A    I51 @S9S_MB_2U_LIB.S9S_MB_2U(SCH_1):PAGE103

M_C_CPU1_SA_CS_N<3> @S9S_MB_2U_LIB.S9S_MB_2U(SCH_1):M_C_CPU1_SA_CS_N(3)
    U1  Y53 DDR2_SA_CS_N3 SOCKET4677_AZIF0045P001C01CS-SA    I91 @S9S_MB_2U_LIB.S9S_MB_2U(SCH_1):PAGE53
   J22  209 CS1_A_N SCONN288_ADR50017P087CC-SCONN2A    I51 @S9S_MB_2U_LIB.S9S_MB_2U(SCH_1):PAGE103

M_C_CPU1_SA_DQ<0> @S9S_MB_2U_LIB.S9S_MB_2U(SCH_1):M_C_CPU1_SA_DQ(0)
    U1  U78 DDR2_SA_DQ0 SOCKET4677_AZIF0045P001C01CS-SA    I91 @S9S_MB_2U_LIB.S9S_MB_2U(SCH_1):PAGE53
   J21    7  DQ0_A SCONN288_ADR50017P130CC-SCONN2A    I13 @S9S_MB_2U_LIB.S9S_MB_2U(SCH_1):PAGE102
   J22    7  DQ0_A SCONN288_ADR50017P087CC-SCONN2A    I51 @S9S_MB_2U_LIB.S9S_MB_2U(SCH_1):PAGE103

M_C_CPU1_SA_DQ<10> @S9S_MB_2U_LIB.S9S_MB_2U(SCH_1):M_C_CPU1_SA_DQ(10)
    U1 AF69 DDR2_SA_DQ10 SOCKET4677_AZIF0045P001C01CS-SA    I91 @S9S_MB_2U_LIB.S9S_MB_2U(SCH_1):PAGE53
   J21  163 DQ10_A SCONN288_ADR50017P130CC-SCONN2A    I13 @S9S_MB_2U_LIB.S9S_MB_2U(SCH_1):PAGE102
   J22  163 DQ10_A SCONN288_ADR50017P087CC-SCONN2A    I51 @S9S_MB_2U_LIB.S9S_MB_2U(SCH_1):PAGE103

M_C_CPU1_SA_DQ<11> @S9S_MB_2U_LIB.S9S_MB_2U(SCH_1):M_C_CPU1_SA_DQ(11)
    U1 AG68 DDR2_SA_DQ11 SOCKET4677_AZIF0045P001C01CS-SA    I91 @S9S_MB_2U_LIB.S9S_MB_2U(SCH_1):PAGE53
   J21  165 DQ11_A SCONN288_ADR50017P130CC-SCONN2A    I13 @S9S_MB_2U_LIB.S9S_MB_2U(SCH_1):PAGE102
   J22  165 DQ11_A SCONN288_ADR50017P087CC-SCONN2A    I51 @S9S_MB_2U_LIB.S9S_MB_2U(SCH_1):PAGE103

M_C_CPU1_SA_DQ<12> @S9S_MB_2U_LIB.S9S_MB_2U(SCH_1):M_C_CPU1_SA_DQ(12)
    U1 AC66 DDR2_SA_DQ12 SOCKET4677_AZIF0045P001C01CS-SA    I91 @S9S_MB_2U_LIB.S9S_MB_2U(SCH_1):PAGE53
   J21   25 DQ12_A SCONN288_ADR50017P130CC-SCONN2A    I13 @S9S_MB_2U_LIB.S9S_MB_2U(SCH_1):PAGE102
   J22   25 DQ12_A SCONN288_ADR50017P087CC-SCONN2A    I51 @S9S_MB_2U_LIB.S9S_MB_2U(SCH_1):PAGE103

M_C_CPU1_SA_DQ<13> @S9S_MB_2U_LIB.S9S_MB_2U(SCH_1):M_C_CPU1_SA_DQ(13)
    U1 AD65 DDR2_SA_DQ13 SOCKET4677_AZIF0045P001C01CS-SA    I91 @S9S_MB_2U_LIB.S9S_MB_2U(SCH_1):PAGE53
   J21   27 DQ13_A SCONN288_ADR50017P130CC-SCONN2A    I13 @S9S_MB_2U_LIB.S9S_MB_2U(SCH_1):PAGE102
   J22   27 DQ13_A SCONN288_ADR50017P087CC-SCONN2A    I51 @S9S_MB_2U_LIB.S9S_MB_2U(SCH_1):PAGE103

M_C_CPU1_SA_DQ<14> @S9S_MB_2U_LIB.S9S_MB_2U(SCH_1):M_C_CPU1_SA_DQ(14)
    U1 AG66 DDR2_SA_DQ14 SOCKET4677_AZIF0045P001C01CS-SA    I91 @S9S_MB_2U_LIB.S9S_MB_2U(SCH_1):PAGE53
   J21  170 DQ14_A SCONN288_ADR50017P130CC-SCONN2A    I13 @S9S_MB_2U_LIB.S9S_MB_2U(SCH_1):PAGE102
   J22  170 DQ14_A SCONN288_ADR50017P087CC-SCONN2A    I51 @S9S_MB_2U_LIB.S9S_MB_2U(SCH_1):PAGE103

M_C_CPU1_SA_DQ<15> @S9S_MB_2U_LIB.S9S_MB_2U(SCH_1):M_C_CPU1_SA_DQ(15)
    U1 AF65 DDR2_SA_DQ15 SOCKET4677_AZIF0045P001C01CS-SA    I91 @S9S_MB_2U_LIB.S9S_MB_2U(SCH_1):PAGE53
   J21  172 DQ15_A SCONN288_ADR50017P130CC-SCONN2A    I13 @S9S_MB_2U_LIB.S9S_MB_2U(SCH_1):PAGE102
   J22  172 DQ15_A SCONN288_ADR50017P087CC-SCONN2A    I51 @S9S_MB_2U_LIB.S9S_MB_2U(SCH_1):PAGE103

M_C_CPU1_SA_DQ<16> @S9S_MB_2U_LIB.S9S_MB_2U(SCH_1):M_C_CPU1_SA_DQ(16)
    U1  U66 DDR2_SA_DQ16 SOCKET4677_AZIF0045P001C01CS-SA    I91 @S9S_MB_2U_LIB.S9S_MB_2U(SCH_1):PAGE53
   J21   29 DQ16_A SCONN288_ADR50017P130CC-SCONN2A    I13 @S9S_MB_2U_LIB.S9S_MB_2U(SCH_1):PAGE102
   J22   29 DQ16_A SCONN288_ADR50017P087CC-SCONN2A    I51 @S9S_MB_2U_LIB.S9S_MB_2U(SCH_1):PAGE103

M_C_CPU1_SA_DQ<17> @S9S_MB_2U_LIB.S9S_MB_2U(SCH_1):M_C_CPU1_SA_DQ(17)
    U1  T65 DDR2_SA_DQ17 SOCKET4677_AZIF0045P001C01CS-SA    I91 @S9S_MB_2U_LIB.S9S_MB_2U(SCH_1):PAGE53
   J21   31 DQ17_A SCONN288_ADR50017P130CC-SCONN2A    I13 @S9S_MB_2U_LIB.S9S_MB_2U(SCH_1):PAGE102
   J22   31 DQ17_A SCONN288_ADR50017P087CC-SCONN2A    I51 @S9S_MB_2U_LIB.S9S_MB_2U(SCH_1):PAGE103

M_C_CPU1_SA_DQ<18> @S9S_MB_2U_LIB.S9S_MB_2U(SCH_1):M_C_CPU1_SA_DQ(18)
    U1  W66 DDR2_SA_DQ18 SOCKET4677_AZIF0045P001C01CS-SA    I91 @S9S_MB_2U_LIB.S9S_MB_2U(SCH_1):PAGE53
   J21  174 DQ18_A SCONN288_ADR50017P130CC-SCONN2A    I13 @S9S_MB_2U_LIB.S9S_MB_2U(SCH_1):PAGE102
   J22  174 DQ18_A SCONN288_ADR50017P087CC-SCONN2A    I51 @S9S_MB_2U_LIB.S9S_MB_2U(SCH_1):PAGE103

M_C_CPU1_SA_DQ<19> @S9S_MB_2U_LIB.S9S_MB_2U(SCH_1):M_C_CPU1_SA_DQ(19)
    U1  Y65 DDR2_SA_DQ19 SOCKET4677_AZIF0045P001C01CS-SA    I91 @S9S_MB_2U_LIB.S9S_MB_2U(SCH_1):PAGE53
   J21  176 DQ19_A SCONN288_ADR50017P130CC-SCONN2A    I13 @S9S_MB_2U_LIB.S9S_MB_2U(SCH_1):PAGE102
   J22  176 DQ19_A SCONN288_ADR50017P087CC-SCONN2A    I51 @S9S_MB_2U_LIB.S9S_MB_2U(SCH_1):PAGE103

M_C_CPU1_SA_DQ<1> @S9S_MB_2U_LIB.S9S_MB_2U(SCH_1):M_C_CPU1_SA_DQ(1)
    U1  T77 DDR2_SA_DQ1 SOCKET4677_AZIF0045P001C01CS-SA    I91 @S9S_MB_2U_LIB.S9S_MB_2U(SCH_1):PAGE53
   J21    9  DQ1_A SCONN288_ADR50017P130CC-SCONN2A    I13 @S9S_MB_2U_LIB.S9S_MB_2U(SCH_1):PAGE102
   J22    9  DQ1_A SCONN288_ADR50017P087CC-SCONN2A    I51 @S9S_MB_2U_LIB.S9S_MB_2U(SCH_1):PAGE103

M_C_CPU1_SA_DQ<20> @S9S_MB_2U_LIB.S9S_MB_2U(SCH_1):M_C_CPU1_SA_DQ(20)
    U1  T63 DDR2_SA_DQ20 SOCKET4677_AZIF0045P001C01CS-SA    I91 @S9S_MB_2U_LIB.S9S_MB_2U(SCH_1):PAGE53
   J21   36 DQ20_A SCONN288_ADR50017P130CC-SCONN2A    I13 @S9S_MB_2U_LIB.S9S_MB_2U(SCH_1):PAGE102
   J22   36 DQ20_A SCONN288_ADR50017P087CC-SCONN2A    I51 @S9S_MB_2U_LIB.S9S_MB_2U(SCH_1):PAGE103

M_C_CPU1_SA_DQ<21> @S9S_MB_2U_LIB.S9S_MB_2U(SCH_1):M_C_CPU1_SA_DQ(21)
    U1  U62 DDR2_SA_DQ21 SOCKET4677_AZIF0045P001C01CS-SA    I91 @S9S_MB_2U_LIB.S9S_MB_2U(SCH_1):PAGE53
   J21   38 DQ21_A SCONN288_ADR50017P130CC-SCONN2A    I13 @S9S_MB_2U_LIB.S9S_MB_2U(SCH_1):PAGE102
   J22   38 DQ21_A SCONN288_ADR50017P087CC-SCONN2A    I51 @S9S_MB_2U_LIB.S9S_MB_2U(SCH_1):PAGE103

M_C_CPU1_SA_DQ<22> @S9S_MB_2U_LIB.S9S_MB_2U(SCH_1):M_C_CPU1_SA_DQ(22)
    U1  Y63 DDR2_SA_DQ22 SOCKET4677_AZIF0045P001C01CS-SA    I91 @S9S_MB_2U_LIB.S9S_MB_2U(SCH_1):PAGE53
   J21  181 DQ22_A SCONN288_ADR50017P130CC-SCONN2A    I13 @S9S_MB_2U_LIB.S9S_MB_2U(SCH_1):PAGE102
   J22  181 DQ22_A SCONN288_ADR50017P087CC-SCONN2A    I51 @S9S_MB_2U_LIB.S9S_MB_2U(SCH_1):PAGE103

M_C_CPU1_SA_DQ<23> @S9S_MB_2U_LIB.S9S_MB_2U(SCH_1):M_C_CPU1_SA_DQ(23)
    U1  W62 DDR2_SA_DQ23 SOCKET4677_AZIF0045P001C01CS-SA    I91 @S9S_MB_2U_LIB.S9S_MB_2U(SCH_1):PAGE53
   J21  183 DQ23_A SCONN288_ADR50017P130CC-SCONN2A    I13 @S9S_MB_2U_LIB.S9S_MB_2U(SCH_1):PAGE102
   J22  183 DQ23_A SCONN288_ADR50017P087CC-SCONN2A    I51 @S9S_MB_2U_LIB.S9S_MB_2U(SCH_1):PAGE103

M_C_CPU1_SA_DQ<24> @S9S_MB_2U_LIB.S9S_MB_2U(SCH_1):M_C_CPU1_SA_DQ(24)
    U1 AD63 DDR2_SA_DQ24 SOCKET4677_AZIF0045P001C01CS-SA    I91 @S9S_MB_2U_LIB.S9S_MB_2U(SCH_1):PAGE53
   J21   40 DQ24_A SCONN288_ADR50017P130CC-SCONN2A    I13 @S9S_MB_2U_LIB.S9S_MB_2U(SCH_1):PAGE102
   J22   40 DQ24_A SCONN288_ADR50017P087CC-SCONN2A    I51 @S9S_MB_2U_LIB.S9S_MB_2U(SCH_1):PAGE103

M_C_CPU1_SA_DQ<25> @S9S_MB_2U_LIB.S9S_MB_2U(SCH_1):M_C_CPU1_SA_DQ(25)
    U1 AC62 DDR2_SA_DQ25 SOCKET4677_AZIF0045P001C01CS-SA    I91 @S9S_MB_2U_LIB.S9S_MB_2U(SCH_1):PAGE53
   J21   42 DQ25_A SCONN288_ADR50017P130CC-SCONN2A    I13 @S9S_MB_2U_LIB.S9S_MB_2U(SCH_1):PAGE102
   J22   42 DQ25_A SCONN288_ADR50017P087CC-SCONN2A    I51 @S9S_MB_2U_LIB.S9S_MB_2U(SCH_1):PAGE103

M_C_CPU1_SA_DQ<26> @S9S_MB_2U_LIB.S9S_MB_2U(SCH_1):M_C_CPU1_SA_DQ(26)
    U1 AF63 DDR2_SA_DQ26 SOCKET4677_AZIF0045P001C01CS-SA    I91 @S9S_MB_2U_LIB.S9S_MB_2U(SCH_1):PAGE53
   J21  185 DQ26_A SCONN288_ADR50017P130CC-SCONN2A    I13 @S9S_MB_2U_LIB.S9S_MB_2U(SCH_1):PAGE102
   J22  185 DQ26_A SCONN288_ADR50017P087CC-SCONN2A    I51 @S9S_MB_2U_LIB.S9S_MB_2U(SCH_1):PAGE103

M_C_CPU1_SA_DQ<27> @S9S_MB_2U_LIB.S9S_MB_2U(SCH_1):M_C_CPU1_SA_DQ(27)
    U1 AG62 DDR2_SA_DQ27 SOCKET4677_AZIF0045P001C01CS-SA    I91 @S9S_MB_2U_LIB.S9S_MB_2U(SCH_1):PAGE53
   J21  187 DQ27_A SCONN288_ADR50017P130CC-SCONN2A    I13 @S9S_MB_2U_LIB.S9S_MB_2U(SCH_1):PAGE102
   J22  187 DQ27_A SCONN288_ADR50017P087CC-SCONN2A    I51 @S9S_MB_2U_LIB.S9S_MB_2U(SCH_1):PAGE103

M_C_CPU1_SA_DQ<28> @S9S_MB_2U_LIB.S9S_MB_2U(SCH_1):M_C_CPU1_SA_DQ(28)
    U1 AC60 DDR2_SA_DQ28 SOCKET4677_AZIF0045P001C01CS-SA    I91 @S9S_MB_2U_LIB.S9S_MB_2U(SCH_1):PAGE53
   J21   47 DQ28_A SCONN288_ADR50017P130CC-SCONN2A    I13 @S9S_MB_2U_LIB.S9S_MB_2U(SCH_1):PAGE102
   J22   47 DQ28_A SCONN288_ADR50017P087CC-SCONN2A    I51 @S9S_MB_2U_LIB.S9S_MB_2U(SCH_1):PAGE103

M_C_CPU1_SA_DQ<29> @S9S_MB_2U_LIB.S9S_MB_2U(SCH_1):M_C_CPU1_SA_DQ(29)
    U1 AD59 DDR2_SA_DQ29 SOCKET4677_AZIF0045P001C01CS-SA    I91 @S9S_MB_2U_LIB.S9S_MB_2U(SCH_1):PAGE53
   J21   49 DQ29_A SCONN288_ADR50017P130CC-SCONN2A    I13 @S9S_MB_2U_LIB.S9S_MB_2U(SCH_1):PAGE102
   J22   49 DQ29_A SCONN288_ADR50017P087CC-SCONN2A    I51 @S9S_MB_2U_LIB.S9S_MB_2U(SCH_1):PAGE103

M_C_CPU1_SA_DQ<2> @S9S_MB_2U_LIB.S9S_MB_2U(SCH_1):M_C_CPU1_SA_DQ(2)
    U1  W78 DDR2_SA_DQ2 SOCKET4677_AZIF0045P001C01CS-SA    I91 @S9S_MB_2U_LIB.S9S_MB_2U(SCH_1):PAGE53
   J21  152  DQ2_A SCONN288_ADR50017P130CC-SCONN2A    I13 @S9S_MB_2U_LIB.S9S_MB_2U(SCH_1):PAGE102
   J22  152  DQ2_A SCONN288_ADR50017P087CC-SCONN2A    I51 @S9S_MB_2U_LIB.S9S_MB_2U(SCH_1):PAGE103

M_C_CPU1_SA_DQ<30> @S9S_MB_2U_LIB.S9S_MB_2U(SCH_1):M_C_CPU1_SA_DQ(30)
    U1 AG60 DDR2_SA_DQ30 SOCKET4677_AZIF0045P001C01CS-SA    I91 @S9S_MB_2U_LIB.S9S_MB_2U(SCH_1):PAGE53
   J21  192 DQ30_A SCONN288_ADR50017P130CC-SCONN2A    I13 @S9S_MB_2U_LIB.S9S_MB_2U(SCH_1):PAGE102
   J22  192 DQ30_A SCONN288_ADR50017P087CC-SCONN2A    I51 @S9S_MB_2U_LIB.S9S_MB_2U(SCH_1):PAGE103

M_C_CPU1_SA_DQ<31> @S9S_MB_2U_LIB.S9S_MB_2U(SCH_1):M_C_CPU1_SA_DQ(31)
    U1 AF59 DDR2_SA_DQ31 SOCKET4677_AZIF0045P001C01CS-SA    I91 @S9S_MB_2U_LIB.S9S_MB_2U(SCH_1):PAGE53
   J21  194 DQ31_A SCONN288_ADR50017P130CC-SCONN2A    I13 @S9S_MB_2U_LIB.S9S_MB_2U(SCH_1):PAGE102
   J22  194 DQ31_A SCONN288_ADR50017P087CC-SCONN2A    I51 @S9S_MB_2U_LIB.S9S_MB_2U(SCH_1):PAGE103

M_C_CPU1_SA_DQ<3> @S9S_MB_2U_LIB.S9S_MB_2U(SCH_1):M_C_CPU1_SA_DQ(3)
    U1  Y77 DDR2_SA_DQ3 SOCKET4677_AZIF0045P001C01CS-SA    I91 @S9S_MB_2U_LIB.S9S_MB_2U(SCH_1):PAGE53
   J21  154  DQ3_A SCONN288_ADR50017P130CC-SCONN2A    I13 @S9S_MB_2U_LIB.S9S_MB_2U(SCH_1):PAGE102
   J22  154  DQ3_A SCONN288_ADR50017P087CC-SCONN2A    I51 @S9S_MB_2U_LIB.S9S_MB_2U(SCH_1):PAGE103

M_C_CPU1_SA_DQ<4> @S9S_MB_2U_LIB.S9S_MB_2U(SCH_1):M_C_CPU1_SA_DQ(4)
    U1  T75 DDR2_SA_DQ4 SOCKET4677_AZIF0045P001C01CS-SA    I91 @S9S_MB_2U_LIB.S9S_MB_2U(SCH_1):PAGE53
   J21   14  DQ4_A SCONN288_ADR50017P130CC-SCONN2A    I13 @S9S_MB_2U_LIB.S9S_MB_2U(SCH_1):PAGE102
   J22   14  DQ4_A SCONN288_ADR50017P087CC-SCONN2A    I51 @S9S_MB_2U_LIB.S9S_MB_2U(SCH_1):PAGE103

M_C_CPU1_SA_DQ<5> @S9S_MB_2U_LIB.S9S_MB_2U(SCH_1):M_C_CPU1_SA_DQ(5)
    U1  U74 DDR2_SA_DQ5 SOCKET4677_AZIF0045P001C01CS-SA    I91 @S9S_MB_2U_LIB.S9S_MB_2U(SCH_1):PAGE53
   J21   16  DQ5_A SCONN288_ADR50017P130CC-SCONN2A    I13 @S9S_MB_2U_LIB.S9S_MB_2U(SCH_1):PAGE102
   J22   16  DQ5_A SCONN288_ADR50017P087CC-SCONN2A    I51 @S9S_MB_2U_LIB.S9S_MB_2U(SCH_1):PAGE103

M_C_CPU1_SA_DQ<6> @S9S_MB_2U_LIB.S9S_MB_2U(SCH_1):M_C_CPU1_SA_DQ(6)
    U1  Y75 DDR2_SA_DQ6 SOCKET4677_AZIF0045P001C01CS-SA    I91 @S9S_MB_2U_LIB.S9S_MB_2U(SCH_1):PAGE53
   J21  159  DQ6_A SCONN288_ADR50017P130CC-SCONN2A    I13 @S9S_MB_2U_LIB.S9S_MB_2U(SCH_1):PAGE102
   J22  159  DQ6_A SCONN288_ADR50017P087CC-SCONN2A    I51 @S9S_MB_2U_LIB.S9S_MB_2U(SCH_1):PAGE103

M_C_CPU1_SA_DQ<7> @S9S_MB_2U_LIB.S9S_MB_2U(SCH_1):M_C_CPU1_SA_DQ(7)
    U1  W74 DDR2_SA_DQ7 SOCKET4677_AZIF0045P001C01CS-SA    I91 @S9S_MB_2U_LIB.S9S_MB_2U(SCH_1):PAGE53
   J21  161  DQ7_A SCONN288_ADR50017P130CC-SCONN2A    I13 @S9S_MB_2U_LIB.S9S_MB_2U(SCH_1):PAGE102
   J22  161  DQ7_A SCONN288_ADR50017P087CC-SCONN2A    I51 @S9S_MB_2U_LIB.S9S_MB_2U(SCH_1):PAGE103

M_C_CPU1_SA_DQ<8> @S9S_MB_2U_LIB.S9S_MB_2U(SCH_1):M_C_CPU1_SA_DQ(8)
    U1 AD69 DDR2_SA_DQ8 SOCKET4677_AZIF0045P001C01CS-SA    I91 @S9S_MB_2U_LIB.S9S_MB_2U(SCH_1):PAGE53
   J21   18  DQ8_A SCONN288_ADR50017P130CC-SCONN2A    I13 @S9S_MB_2U_LIB.S9S_MB_2U(SCH_1):PAGE102
   J22   18  DQ8_A SCONN288_ADR50017P087CC-SCONN2A    I51 @S9S_MB_2U_LIB.S9S_MB_2U(SCH_1):PAGE103

M_C_CPU1_SA_DQ<9> @S9S_MB_2U_LIB.S9S_MB_2U(SCH_1):M_C_CPU1_SA_DQ(9)
    U1 AC68 DDR2_SA_DQ9 SOCKET4677_AZIF0045P001C01CS-SA    I91 @S9S_MB_2U_LIB.S9S_MB_2U(SCH_1):PAGE53
   J21   20  DQ9_A SCONN288_ADR50017P130CC-SCONN2A    I13 @S9S_MB_2U_LIB.S9S_MB_2U(SCH_1):PAGE102
   J22   20  DQ9_A SCONN288_ADR50017P087CC-SCONN2A    I51 @S9S_MB_2U_LIB.S9S_MB_2U(SCH_1):PAGE103

M_C_CPU1_SA_DQS_DN<0> @S9S_MB_2U_LIB.S9S_MB_2U(SCH_1):M_C_CPU1_SA_DQS_DN(0)
    U1  R76 DDR2_SA_DQS_DN0 SOCKET4677_AZIF0045P001C01CS-SA    I91 @S9S_MB_2U_LIB.S9S_MB_2U(SCH_1):PAGE53
   J21   12 DQS0_A_C SCONN288_ADR50017P130CC-SCONN2A   I178 @S9S_MB_2U_LIB.S9S_MB_2U(SCH_1):PAGE102
   J22   12 DQS0_A_C SCONN288_ADR50017P087CC-SCONN2A   I178 @S9S_MB_2U_LIB.S9S_MB_2U(SCH_1):PAGE103

M_C_CPU1_SA_DQS_DN<1> @S9S_MB_2U_LIB.S9S_MB_2U(SCH_1):M_C_CPU1_SA_DQS_DN(1)
    U1 AB67 DDR2_SA_DQS_DN1 SOCKET4677_AZIF0045P001C01CS-SA    I91 @S9S_MB_2U_LIB.S9S_MB_2U(SCH_1):PAGE53
   J21   23 DQS1_A_C SCONN288_ADR50017P130CC-SCONN2A   I178 @S9S_MB_2U_LIB.S9S_MB_2U(SCH_1):PAGE102
   J22   23 DQS1_A_C SCONN288_ADR50017P087CC-SCONN2A   I178 @S9S_MB_2U_LIB.S9S_MB_2U(SCH_1):PAGE103

M_C_CPU1_SA_DQS_DN<2> @S9S_MB_2U_LIB.S9S_MB_2U(SCH_1):M_C_CPU1_SA_DQS_DN(2)
    U1  R64 DDR2_SA_DQS_DN2 SOCKET4677_AZIF0045P001C01CS-SA    I91 @S9S_MB_2U_LIB.S9S_MB_2U(SCH_1):PAGE53
   J21   34 DQS2_A_C SCONN288_ADR50017P130CC-SCONN2A   I178 @S9S_MB_2U_LIB.S9S_MB_2U(SCH_1):PAGE102
   J22   34 DQS2_A_C SCONN288_ADR50017P087CC-SCONN2A   I178 @S9S_MB_2U_LIB.S9S_MB_2U(SCH_1):PAGE103

M_C_CPU1_SA_DQS_DN<3> @S9S_MB_2U_LIB.S9S_MB_2U(SCH_1):M_C_CPU1_SA_DQS_DN(3)
    U1 AB61 DDR2_SA_DQS_DN3 SOCKET4677_AZIF0045P001C01CS-SA    I91 @S9S_MB_2U_LIB.S9S_MB_2U(SCH_1):PAGE53
   J21   45 DQS3_A_C SCONN288_ADR50017P130CC-SCONN2A   I178 @S9S_MB_2U_LIB.S9S_MB_2U(SCH_1):PAGE102
   J22   45 DQS3_A_C SCONN288_ADR50017P087CC-SCONN2A   I178 @S9S_MB_2U_LIB.S9S_MB_2U(SCH_1):PAGE103

M_C_CPU1_SA_DQS_DN<4> @S9S_MB_2U_LIB.S9S_MB_2U(SCH_1):M_C_CPU1_SA_DQS_DN(4)
    U1 AD55 DDR2_SA_DQS_DN4 SOCKET4677_AZIF0045P001C01CS-SA    I91 @S9S_MB_2U_LIB.S9S_MB_2U(SCH_1):PAGE53
   J21   56 DQS4_A_C SCONN288_ADR50017P130CC-SCONN2A   I178 @S9S_MB_2U_LIB.S9S_MB_2U(SCH_1):PAGE102
   J22   56 DQS4_A_C SCONN288_ADR50017P087CC-SCONN2A   I178 @S9S_MB_2U_LIB.S9S_MB_2U(SCH_1):PAGE103

M_C_CPU1_SA_DQS_DN<5> @S9S_MB_2U_LIB.S9S_MB_2U(SCH_1):M_C_CPU1_SA_DQS_DN(5)
    U1  W76 DDR2_SA_DQS_DN5 SOCKET4677_AZIF0045P001C01CS-SA    I91 @S9S_MB_2U_LIB.S9S_MB_2U(SCH_1):PAGE53
   J21  156 DQS5_A_C||TDQS5_A_C||DQS5_A_T||TDQS5_A_T SCONN288_ADR50017P130CC-SCONN2A   I178 @S9S_MB_2U_LIB.S9S_MB_2U(SCH_1):PAGE102
   J22  156 DQS5_A_C||TDQS5_A_C||DQS5_A_T||TDQS5_A_T SCONN288_ADR50017P087CC-SCONN2A   I178 @S9S_MB_2U_LIB.S9S_MB_2U(SCH_1):PAGE103

M_C_CPU1_SA_DQS_DN<6> @S9S_MB_2U_LIB.S9S_MB_2U(SCH_1):M_C_CPU1_SA_DQS_DN(6)
    U1 AH67 DDR2_SA_DQS_DN6 SOCKET4677_AZIF0045P001C01CS-SA    I91 @S9S_MB_2U_LIB.S9S_MB_2U(SCH_1):PAGE53
   J21  167 DQS6_A_C||TDQS6_A_C||DQS6_A_T||TDQS6_A_T SCONN288_ADR50017P130CC-SCONN2A   I178 @S9S_MB_2U_LIB.S9S_MB_2U(SCH_1):PAGE102
   J22  167 DQS6_A_C||TDQS6_A_C||DQS6_A_T||TDQS6_A_T SCONN288_ADR50017P087CC-SCONN2A   I178 @S9S_MB_2U_LIB.S9S_MB_2U(SCH_1):PAGE103

M_C_CPU1_SA_DQS_DN<7> @S9S_MB_2U_LIB.S9S_MB_2U(SCH_1):M_C_CPU1_SA_DQS_DN(7)
    U1 AA64 DDR2_SA_DQS_DN7 SOCKET4677_AZIF0045P001C01CS-SA    I91 @S9S_MB_2U_LIB.S9S_MB_2U(SCH_1):PAGE53
   J21  178 DQS7_A_C||TDQS7_A_C SCONN288_ADR50017P130CC-SCONN2A   I178 @S9S_MB_2U_LIB.S9S_MB_2U(SCH_1):PAGE102
   J22  178 DQS7_A_C||TDQS7_A_C SCONN288_ADR50017P087CC-SCONN2A   I178 @S9S_MB_2U_LIB.S9S_MB_2U(SCH_1):PAGE103

M_C_CPU1_SA_DQS_DN<8> @S9S_MB_2U_LIB.S9S_MB_2U(SCH_1):M_C_CPU1_SA_DQS_DN(8)
    U1 AF61 DDR2_SA_DQS_DN8 SOCKET4677_AZIF0045P001C01CS-SA    I91 @S9S_MB_2U_LIB.S9S_MB_2U(SCH_1):PAGE53
   J21  189 DQS8_A_C||TDQS8_A_C SCONN288_ADR50017P130CC-SCONN2A   I178 @S9S_MB_2U_LIB.S9S_MB_2U(SCH_1):PAGE102
   J22  189 DQS8_A_C||TDQS8_A_C SCONN288_ADR50017P087CC-SCONN2A   I178 @S9S_MB_2U_LIB.S9S_MB_2U(SCH_1):PAGE103

M_C_CPU1_SA_DQS_DN<9> @S9S_MB_2U_LIB.S9S_MB_2U(SCH_1):M_C_CPU1_SA_DQS_DN(9)
    U1 AH55 DDR2_SA_DQS_DN9 SOCKET4677_AZIF0045P001C01CS-SA    I91 @S9S_MB_2U_LIB.S9S_MB_2U(SCH_1):PAGE53
   J21  200 DQS9_A_C||TDQS9_A_C SCONN288_ADR50017P130CC-SCONN2A   I178 @S9S_MB_2U_LIB.S9S_MB_2U(SCH_1):PAGE102
   J22  200 DQS9_A_C||TDQS9_A_C SCONN288_ADR50017P087CC-SCONN2A   I178 @S9S_MB_2U_LIB.S9S_MB_2U(SCH_1):PAGE103

M_C_CPU1_SA_DQS_DP<0> @S9S_MB_2U_LIB.S9S_MB_2U(SCH_1):M_C_CPU1_SA_DQS_DP(0)
    U1  U76 DDR2_SA_DQS_DP0 SOCKET4677_AZIF0045P001C01CS-SA    I91 @S9S_MB_2U_LIB.S9S_MB_2U(SCH_1):PAGE53
   J21   11 DQS0_A_T SCONN288_ADR50017P130CC-SCONN2A   I178 @S9S_MB_2U_LIB.S9S_MB_2U(SCH_1):PAGE102
   J22   11 DQS0_A_T SCONN288_ADR50017P087CC-SCONN2A   I178 @S9S_MB_2U_LIB.S9S_MB_2U(SCH_1):PAGE103

M_C_CPU1_SA_DQS_DP<1> @S9S_MB_2U_LIB.S9S_MB_2U(SCH_1):M_C_CPU1_SA_DQS_DP(1)
    U1 AD67 DDR2_SA_DQS_DP1 SOCKET4677_AZIF0045P001C01CS-SA    I91 @S9S_MB_2U_LIB.S9S_MB_2U(SCH_1):PAGE53
   J21   22 DQS1_A_T SCONN288_ADR50017P130CC-SCONN2A   I178 @S9S_MB_2U_LIB.S9S_MB_2U(SCH_1):PAGE102
   J22   22 DQS1_A_T SCONN288_ADR50017P087CC-SCONN2A   I178 @S9S_MB_2U_LIB.S9S_MB_2U(SCH_1):PAGE103

M_C_CPU1_SA_DQS_DP<2> @S9S_MB_2U_LIB.S9S_MB_2U(SCH_1):M_C_CPU1_SA_DQS_DP(2)
    U1  U64 DDR2_SA_DQS_DP2 SOCKET4677_AZIF0045P001C01CS-SA    I91 @S9S_MB_2U_LIB.S9S_MB_2U(SCH_1):PAGE53
   J21   33 DQS2_A_T SCONN288_ADR50017P130CC-SCONN2A   I178 @S9S_MB_2U_LIB.S9S_MB_2U(SCH_1):PAGE102
   J22   33 DQS2_A_T SCONN288_ADR50017P087CC-SCONN2A   I178 @S9S_MB_2U_LIB.S9S_MB_2U(SCH_1):PAGE103

M_C_CPU1_SA_DQS_DP<3> @S9S_MB_2U_LIB.S9S_MB_2U(SCH_1):M_C_CPU1_SA_DQS_DP(3)
    U1 AD61 DDR2_SA_DQS_DP3 SOCKET4677_AZIF0045P001C01CS-SA    I91 @S9S_MB_2U_LIB.S9S_MB_2U(SCH_1):PAGE53
   J21   44 DQS3_A_T SCONN288_ADR50017P130CC-SCONN2A   I178 @S9S_MB_2U_LIB.S9S_MB_2U(SCH_1):PAGE102
   J22   44 DQS3_A_T SCONN288_ADR50017P087CC-SCONN2A   I178 @S9S_MB_2U_LIB.S9S_MB_2U(SCH_1):PAGE103

M_C_CPU1_SA_DQS_DP<4> @S9S_MB_2U_LIB.S9S_MB_2U(SCH_1):M_C_CPU1_SA_DQS_DP(4)
    U1 AB55 DDR2_SA_DQS_DP4 SOCKET4677_AZIF0045P001C01CS-SA    I91 @S9S_MB_2U_LIB.S9S_MB_2U(SCH_1):PAGE53
   J21   55 DQS4_A_T SCONN288_ADR50017P130CC-SCONN2A   I178 @S9S_MB_2U_LIB.S9S_MB_2U(SCH_1):PAGE102
   J22   55 DQS4_A_T SCONN288_ADR50017P087CC-SCONN2A   I178 @S9S_MB_2U_LIB.S9S_MB_2U(SCH_1):PAGE103

M_C_CPU1_SA_DQS_DP<5> @S9S_MB_2U_LIB.S9S_MB_2U(SCH_1):M_C_CPU1_SA_DQS_DP(5)
    U1 AA76 DDR2_SA_DQS_DP5 SOCKET4677_AZIF0045P001C01CS-SA    I91 @S9S_MB_2U_LIB.S9S_MB_2U(SCH_1):PAGE53
   J21  157 DQS5_A_T||TDQS5_A_T SCONN288_ADR50017P130CC-SCONN2A   I178 @S9S_MB_2U_LIB.S9S_MB_2U(SCH_1):PAGE102
   J22  157 DQS5_A_T||TDQS5_A_T SCONN288_ADR50017P087CC-SCONN2A   I178 @S9S_MB_2U_LIB.S9S_MB_2U(SCH_1):PAGE103

M_C_CPU1_SA_DQS_DP<6> @S9S_MB_2U_LIB.S9S_MB_2U(SCH_1):M_C_CPU1_SA_DQS_DP(6)
    U1 AF67 DDR2_SA_DQS_DP6 SOCKET4677_AZIF0045P001C01CS-SA    I91 @S9S_MB_2U_LIB.S9S_MB_2U(SCH_1):PAGE53
   J21  168 DQS6_A_T||TDQS6_A_T SCONN288_ADR50017P130CC-SCONN2A   I178 @S9S_MB_2U_LIB.S9S_MB_2U(SCH_1):PAGE102
   J22  168 DQS6_A_T||TDQS6_A_T SCONN288_ADR50017P087CC-SCONN2A   I178 @S9S_MB_2U_LIB.S9S_MB_2U(SCH_1):PAGE103

M_C_CPU1_SA_DQS_DP<7> @S9S_MB_2U_LIB.S9S_MB_2U(SCH_1):M_C_CPU1_SA_DQS_DP(7)
    U1  W64 DDR2_SA_DQS_DP7 SOCKET4677_AZIF0045P001C01CS-SA    I91 @S9S_MB_2U_LIB.S9S_MB_2U(SCH_1):PAGE53
   J21  179 DQS7_A_T||TDQS7_A_T SCONN288_ADR50017P130CC-SCONN2A   I178 @S9S_MB_2U_LIB.S9S_MB_2U(SCH_1):PAGE102
   J22  179 DQS7_A_T||TDQS7_A_T SCONN288_ADR50017P087CC-SCONN2A   I178 @S9S_MB_2U_LIB.S9S_MB_2U(SCH_1):PAGE103

M_C_CPU1_SA_DQS_DP<8> @S9S_MB_2U_LIB.S9S_MB_2U(SCH_1):M_C_CPU1_SA_DQS_DP(8)
    U1 AH61 DDR2_SA_DQS_DP8 SOCKET4677_AZIF0045P001C01CS-SA    I91 @S9S_MB_2U_LIB.S9S_MB_2U(SCH_1):PAGE53
   J21  190 DQS8_A_T||TDQS8_A_T SCONN288_ADR50017P130CC-SCONN2A   I178 @S9S_MB_2U_LIB.S9S_MB_2U(SCH_1):PAGE102
   J22  190 DQS8_A_T||TDQS8_A_T SCONN288_ADR50017P087CC-SCONN2A   I178 @S9S_MB_2U_LIB.S9S_MB_2U(SCH_1):PAGE103

M_C_CPU1_SA_DQS_DP<9> @S9S_MB_2U_LIB.S9S_MB_2U(SCH_1):M_C_CPU1_SA_DQS_DP(9)
    U1 AF55 DDR2_SA_DQS_DP9 SOCKET4677_AZIF0045P001C01CS-SA    I91 @S9S_MB_2U_LIB.S9S_MB_2U(SCH_1):PAGE53
   J21  201 DQS9_A_T||TDQS9_A_T SCONN288_ADR50017P130CC-SCONN2A   I178 @S9S_MB_2U_LIB.S9S_MB_2U(SCH_1):PAGE102
   J22  201 DQS9_A_T||TDQS9_A_T SCONN288_ADR50017P087CC-SCONN2A   I178 @S9S_MB_2U_LIB.S9S_MB_2U(SCH_1):PAGE103

M_C_CPU1_SA_PAR @S9S_MB_2U_LIB.S9S_MB_2U(SCH_1):M_C_CPU1_SA_PAR
    U1  T47 DDR2_SA_PAR SOCKET4677_AZIF0045P001C01CS-SA    I91 @S9S_MB_2U_LIB.S9S_MB_2U(SCH_1):PAGE53
   J21   74  PAR_A SCONN288_ADR50017P130CC-SCONN2A    I13 @S9S_MB_2U_LIB.S9S_MB_2U(SCH_1):PAGE102
   J22   74  PAR_A SCONN288_ADR50017P087CC-SCONN2A    I51 @S9S_MB_2U_LIB.S9S_MB_2U(SCH_1):PAGE103

M_C_CPU1_SA_RSP<0> @S9S_MB_2U_LIB.S9S_MB_2U(SCH_1):M_C_CPU1_SA_RSP(0)
    U1 AC48 DDR2_A_RSP0 SOCKET4677_AZIF0045P001C01CS-SA    I91 @S9S_MB_2U_LIB.S9S_MB_2U(SCH_1):PAGE53
   J21   86 LBD||RSP_A_N SCONN288_ADR50017P130CC-SCONN2A    I13 @S9S_MB_2U_LIB.S9S_MB_2U(SCH_1):PAGE102

M_C_CPU1_SA_RSP<1> @S9S_MB_2U_LIB.S9S_MB_2U(SCH_1):M_C_CPU1_SA_RSP(1)
    U1 AD47 DDR2_A_RSP1 SOCKET4677_AZIF0045P001C01CS-SA    I91 @S9S_MB_2U_LIB.S9S_MB_2U(SCH_1):PAGE53
   J22   86 LBD||RSP_A_N SCONN288_ADR50017P087CC-SCONN2A    I51 @S9S_MB_2U_LIB.S9S_MB_2U(SCH_1):PAGE103

M_C_CPU1_SB_CA<0> @S9S_MB_2U_LIB.S9S_MB_2U(SCH_1):M_C_CPU1_SB_CA(0)
    U1  W48 DDR2_SB_CA0 SOCKET4677_AZIF0045P001C01CS-SA    I91 @S9S_MB_2U_LIB.S9S_MB_2U(SCH_1):PAGE53
   J21   76  CA0_B SCONN288_ADR50017P130CC-SCONN2A    I13 @S9S_MB_2U_LIB.S9S_MB_2U(SCH_1):PAGE102
   J22   76  CA0_B SCONN288_ADR50017P087CC-SCONN2A    I51 @S9S_MB_2U_LIB.S9S_MB_2U(SCH_1):PAGE103

M_C_CPU1_SB_CA<1> @S9S_MB_2U_LIB.S9S_MB_2U(SCH_1):M_C_CPU1_SB_CA(1)
    U1  Y47 DDR2_SB_CA1 SOCKET4677_AZIF0045P001C01CS-SA    I91 @S9S_MB_2U_LIB.S9S_MB_2U(SCH_1):PAGE53
   J21  221  CA1_B SCONN288_ADR50017P130CC-SCONN2A    I13 @S9S_MB_2U_LIB.S9S_MB_2U(SCH_1):PAGE102
   J22  221  CA1_B SCONN288_ADR50017P087CC-SCONN2A    I51 @S9S_MB_2U_LIB.S9S_MB_2U(SCH_1):PAGE103

M_C_CPU1_SB_CA<2> @S9S_MB_2U_LIB.S9S_MB_2U(SCH_1):M_C_CPU1_SB_CA(2)
    U1  U41 DDR2_SB_CA2 SOCKET4677_AZIF0045P001C01CS-SA    I91 @S9S_MB_2U_LIB.S9S_MB_2U(SCH_1):PAGE53
   J21   78  CA2_B SCONN288_ADR50017P130CC-SCONN2A    I13 @S9S_MB_2U_LIB.S9S_MB_2U(SCH_1):PAGE102
   J22   78  CA2_B SCONN288_ADR50017P087CC-SCONN2A    I51 @S9S_MB_2U_LIB.S9S_MB_2U(SCH_1):PAGE103

M_C_CPU1_SB_CA<3> @S9S_MB_2U_LIB.S9S_MB_2U(SCH_1):M_C_CPU1_SB_CA(3)
    U1  W41 DDR2_SB_CA3 SOCKET4677_AZIF0045P001C01CS-SA    I91 @S9S_MB_2U_LIB.S9S_MB_2U(SCH_1):PAGE53
   J21  223  CA3_B SCONN288_ADR50017P130CC-SCONN2A    I13 @S9S_MB_2U_LIB.S9S_MB_2U(SCH_1):PAGE102
   J22  223  CA3_B SCONN288_ADR50017P087CC-SCONN2A    I51 @S9S_MB_2U_LIB.S9S_MB_2U(SCH_1):PAGE103

M_C_CPU1_SB_CA<4> @S9S_MB_2U_LIB.S9S_MB_2U(SCH_1):M_C_CPU1_SB_CA(4)
    U1  T40 DDR2_SB_CA4 SOCKET4677_AZIF0045P001C01CS-SA    I91 @S9S_MB_2U_LIB.S9S_MB_2U(SCH_1):PAGE53
   J21   80  CA4_B SCONN288_ADR50017P130CC-SCONN2A    I13 @S9S_MB_2U_LIB.S9S_MB_2U(SCH_1):PAGE102
   J22   80  CA4_B SCONN288_ADR50017P087CC-SCONN2A    I51 @S9S_MB_2U_LIB.S9S_MB_2U(SCH_1):PAGE103

M_C_CPU1_SB_CA<5> @S9S_MB_2U_LIB.S9S_MB_2U(SCH_1):M_C_CPU1_SB_CA(5)
    U1  Y40 DDR2_SB_CA5 SOCKET4677_AZIF0045P001C01CS-SA    I91 @S9S_MB_2U_LIB.S9S_MB_2U(SCH_1):PAGE53
   J21  225  CA5_B SCONN288_ADR50017P130CC-SCONN2A    I13 @S9S_MB_2U_LIB.S9S_MB_2U(SCH_1):PAGE102
   J22  225  CA5_B SCONN288_ADR50017P087CC-SCONN2A    I51 @S9S_MB_2U_LIB.S9S_MB_2U(SCH_1):PAGE103

M_C_CPU1_SB_CA<6> @S9S_MB_2U_LIB.S9S_MB_2U(SCH_1):M_C_CPU1_SB_CA(6)
    U1  R39 DDR2_SB_CA6 SOCKET4677_AZIF0045P001C01CS-SA    I91 @S9S_MB_2U_LIB.S9S_MB_2U(SCH_1):PAGE53
   J21   82  CA6_B SCONN288_ADR50017P130CC-SCONN2A    I13 @S9S_MB_2U_LIB.S9S_MB_2U(SCH_1):PAGE102
   J22   82  CA6_B SCONN288_ADR50017P087CC-SCONN2A    I51 @S9S_MB_2U_LIB.S9S_MB_2U(SCH_1):PAGE103

M_C_CPU1_SB_CB<0> @S9S_MB_2U_LIB.S9S_MB_2U(SCH_1):M_C_CPU1_SB_CB(0)
    U1  T32 DDR2_SB_ECC0 SOCKET4677_AZIF0045P001C01CS-SA    I91 @S9S_MB_2U_LIB.S9S_MB_2U(SCH_1):PAGE53
   J21   96  CB0_B SCONN288_ADR50017P130CC-SCONN2A    I13 @S9S_MB_2U_LIB.S9S_MB_2U(SCH_1):PAGE102
   J22   96  CB0_B SCONN288_ADR50017P087CC-SCONN2A    I51 @S9S_MB_2U_LIB.S9S_MB_2U(SCH_1):PAGE103

M_C_CPU1_SB_CB<1> @S9S_MB_2U_LIB.S9S_MB_2U(SCH_1):M_C_CPU1_SB_CB(1)
    U1  U31 DDR2_SB_ECC1 SOCKET4677_AZIF0045P001C01CS-SA    I91 @S9S_MB_2U_LIB.S9S_MB_2U(SCH_1):PAGE53
   J21   98  CB1_B SCONN288_ADR50017P130CC-SCONN2A    I13 @S9S_MB_2U_LIB.S9S_MB_2U(SCH_1):PAGE102
   J22   98  CB1_B SCONN288_ADR50017P087CC-SCONN2A    I51 @S9S_MB_2U_LIB.S9S_MB_2U(SCH_1):PAGE103

M_C_CPU1_SB_CB<2> @S9S_MB_2U_LIB.S9S_MB_2U(SCH_1):M_C_CPU1_SB_CB(2)
    U1  Y32 DDR2_SB_ECC2 SOCKET4677_AZIF0045P001C01CS-SA    I91 @S9S_MB_2U_LIB.S9S_MB_2U(SCH_1):PAGE53
   J21  241  CB2_B SCONN288_ADR50017P130CC-SCONN2A    I13 @S9S_MB_2U_LIB.S9S_MB_2U(SCH_1):PAGE102
   J22  241  CB2_B SCONN288_ADR50017P087CC-SCONN2A    I51 @S9S_MB_2U_LIB.S9S_MB_2U(SCH_1):PAGE103

M_C_CPU1_SB_CB<3> @S9S_MB_2U_LIB.S9S_MB_2U(SCH_1):M_C_CPU1_SB_CB(3)
    U1  W31 DDR2_SB_ECC3 SOCKET4677_AZIF0045P001C01CS-SA    I91 @S9S_MB_2U_LIB.S9S_MB_2U(SCH_1):PAGE53
   J21  243  CB3_B SCONN288_ADR50017P130CC-SCONN2A    I13 @S9S_MB_2U_LIB.S9S_MB_2U(SCH_1):PAGE102
   J22  243  CB3_B SCONN288_ADR50017P087CC-SCONN2A    I51 @S9S_MB_2U_LIB.S9S_MB_2U(SCH_1):PAGE103

M_C_CPU1_SB_CB<4> @S9S_MB_2U_LIB.S9S_MB_2U(SCH_1):M_C_CPU1_SB_CB(4)
    U1  U35 DDR2_SB_ECC4 SOCKET4677_AZIF0045P001C01CS-SA    I91 @S9S_MB_2U_LIB.S9S_MB_2U(SCH_1):PAGE53
   J21   89  CB4_B SCONN288_ADR50017P130CC-SCONN2A    I13 @S9S_MB_2U_LIB.S9S_MB_2U(SCH_1):PAGE102
   J22   89  CB4_B SCONN288_ADR50017P087CC-SCONN2A    I51 @S9S_MB_2U_LIB.S9S_MB_2U(SCH_1):PAGE103

M_C_CPU1_SB_CB<5> @S9S_MB_2U_LIB.S9S_MB_2U(SCH_1):M_C_CPU1_SB_CB(5)
    U1  T34 DDR2_SB_ECC5 SOCKET4677_AZIF0045P001C01CS-SA    I91 @S9S_MB_2U_LIB.S9S_MB_2U(SCH_1):PAGE53
   J21   91  CB5_B SCONN288_ADR50017P130CC-SCONN2A    I13 @S9S_MB_2U_LIB.S9S_MB_2U(SCH_1):PAGE102
   J22   91  CB5_B SCONN288_ADR50017P087CC-SCONN2A    I51 @S9S_MB_2U_LIB.S9S_MB_2U(SCH_1):PAGE103

M_C_CPU1_SB_CB<6> @S9S_MB_2U_LIB.S9S_MB_2U(SCH_1):M_C_CPU1_SB_CB(6)
    U1  W35 DDR2_SB_ECC6 SOCKET4677_AZIF0045P001C01CS-SA    I91 @S9S_MB_2U_LIB.S9S_MB_2U(SCH_1):PAGE53
   J21  234  CB6_B SCONN288_ADR50017P130CC-SCONN2A    I13 @S9S_MB_2U_LIB.S9S_MB_2U(SCH_1):PAGE102
   J22  234  CB6_B SCONN288_ADR50017P087CC-SCONN2A    I51 @S9S_MB_2U_LIB.S9S_MB_2U(SCH_1):PAGE103

M_C_CPU1_SB_CB<7> @S9S_MB_2U_LIB.S9S_MB_2U(SCH_1):M_C_CPU1_SB_CB(7)
    U1  Y34 DDR2_SB_ECC7 SOCKET4677_AZIF0045P001C01CS-SA    I91 @S9S_MB_2U_LIB.S9S_MB_2U(SCH_1):PAGE53
   J21  236  CB7_B SCONN288_ADR50017P130CC-SCONN2A    I13 @S9S_MB_2U_LIB.S9S_MB_2U(SCH_1):PAGE102
   J22  236  CB7_B SCONN288_ADR50017P087CC-SCONN2A    I51 @S9S_MB_2U_LIB.S9S_MB_2U(SCH_1):PAGE103

M_C_CPU1_SB_CS_N<0> @S9S_MB_2U_LIB.S9S_MB_2U(SCH_1):M_C_CPU1_SB_CS_N(0)
    U1  T38 DDR2_SB_CS_N0 SOCKET4677_AZIF0045P001C01CS-SA    I91 @S9S_MB_2U_LIB.S9S_MB_2U(SCH_1):PAGE53
   J21   84 CS0_B_N SCONN288_ADR50017P130CC-SCONN2A    I13 @S9S_MB_2U_LIB.S9S_MB_2U(SCH_1):PAGE102

M_C_CPU1_SB_CS_N<1> @S9S_MB_2U_LIB.S9S_MB_2U(SCH_1):M_C_CPU1_SB_CS_N(1)
    U1  U37 DDR2_SB_CS_N1 SOCKET4677_AZIF0045P001C01CS-SA    I91 @S9S_MB_2U_LIB.S9S_MB_2U(SCH_1):PAGE53
   J21  229 CS1_B_N SCONN288_ADR50017P130CC-SCONN2A    I13 @S9S_MB_2U_LIB.S9S_MB_2U(SCH_1):PAGE102

M_C_CPU1_SB_CS_N<2> @S9S_MB_2U_LIB.S9S_MB_2U(SCH_1):M_C_CPU1_SB_CS_N(2)
    U1  Y38 DDR2_SB_CS_N2 SOCKET4677_AZIF0045P001C01CS-SA    I91 @S9S_MB_2U_LIB.S9S_MB_2U(SCH_1):PAGE53
   J22   84 CS0_B_N SCONN288_ADR50017P087CC-SCONN2A    I51 @S9S_MB_2U_LIB.S9S_MB_2U(SCH_1):PAGE103

M_C_CPU1_SB_CS_N<3> @S9S_MB_2U_LIB.S9S_MB_2U(SCH_1):M_C_CPU1_SB_CS_N(3)
    U1  W37 DDR2_SB_CS_N3 SOCKET4677_AZIF0045P001C01CS-SA    I91 @S9S_MB_2U_LIB.S9S_MB_2U(SCH_1):PAGE53
   J22  229 CS1_B_N SCONN288_ADR50017P087CC-SCONN2A    I51 @S9S_MB_2U_LIB.S9S_MB_2U(SCH_1):PAGE103

M_C_CPU1_SB_DQ<0> @S9S_MB_2U_LIB.S9S_MB_2U(SCH_1):M_C_CPU1_SB_DQ(0)
    U1 AD38 DDR2_SB_DQ0 SOCKET4677_AZIF0045P001C01CS-SA    I91 @S9S_MB_2U_LIB.S9S_MB_2U(SCH_1):PAGE53
   J21  100  DQ0_B SCONN288_ADR50017P130CC-SCONN2A    I13 @S9S_MB_2U_LIB.S9S_MB_2U(SCH_1):PAGE102
   J22  100  DQ0_B SCONN288_ADR50017P087CC-SCONN2A    I51 @S9S_MB_2U_LIB.S9S_MB_2U(SCH_1):PAGE103

M_C_CPU1_SB_DQ<10> @S9S_MB_2U_LIB.S9S_MB_2U(SCH_1):M_C_CPU1_SB_DQ(10)
    U1 AF32 DDR2_SB_DQ10 SOCKET4677_AZIF0045P001C01CS-SA    I91 @S9S_MB_2U_LIB.S9S_MB_2U(SCH_1):PAGE53
   J21  256 DQ10_B SCONN288_ADR50017P130CC-SCONN2A    I13 @S9S_MB_2U_LIB.S9S_MB_2U(SCH_1):PAGE102
   J22  256 DQ10_B SCONN288_ADR50017P087CC-SCONN2A    I51 @S9S_MB_2U_LIB.S9S_MB_2U(SCH_1):PAGE103

M_C_CPU1_SB_DQ<11> @S9S_MB_2U_LIB.S9S_MB_2U(SCH_1):M_C_CPU1_SB_DQ(11)
    U1 AG31 DDR2_SB_DQ11 SOCKET4677_AZIF0045P001C01CS-SA    I91 @S9S_MB_2U_LIB.S9S_MB_2U(SCH_1):PAGE53
   J21  258 DQ11_B SCONN288_ADR50017P130CC-SCONN2A    I13 @S9S_MB_2U_LIB.S9S_MB_2U(SCH_1):PAGE102
   J22  258 DQ11_B SCONN288_ADR50017P087CC-SCONN2A    I51 @S9S_MB_2U_LIB.S9S_MB_2U(SCH_1):PAGE103

M_C_CPU1_SB_DQ<12> @S9S_MB_2U_LIB.S9S_MB_2U(SCH_1):M_C_CPU1_SB_DQ(12)
    U1 AC29 DDR2_SB_DQ12 SOCKET4677_AZIF0045P001C01CS-SA    I91 @S9S_MB_2U_LIB.S9S_MB_2U(SCH_1):PAGE53
   J21  118 DQ12_B SCONN288_ADR50017P130CC-SCONN2A    I13 @S9S_MB_2U_LIB.S9S_MB_2U(SCH_1):PAGE102
   J22  118 DQ12_B SCONN288_ADR50017P087CC-SCONN2A    I51 @S9S_MB_2U_LIB.S9S_MB_2U(SCH_1):PAGE103

M_C_CPU1_SB_DQ<13> @S9S_MB_2U_LIB.S9S_MB_2U(SCH_1):M_C_CPU1_SB_DQ(13)
    U1 AD28 DDR2_SB_DQ13 SOCKET4677_AZIF0045P001C01CS-SA    I91 @S9S_MB_2U_LIB.S9S_MB_2U(SCH_1):PAGE53
   J21  120 DQ13_B SCONN288_ADR50017P130CC-SCONN2A    I13 @S9S_MB_2U_LIB.S9S_MB_2U(SCH_1):PAGE102
   J22  120 DQ13_B SCONN288_ADR50017P087CC-SCONN2A    I51 @S9S_MB_2U_LIB.S9S_MB_2U(SCH_1):PAGE103

M_C_CPU1_SB_DQ<14> @S9S_MB_2U_LIB.S9S_MB_2U(SCH_1):M_C_CPU1_SB_DQ(14)
    U1 AG29 DDR2_SB_DQ14 SOCKET4677_AZIF0045P001C01CS-SA    I91 @S9S_MB_2U_LIB.S9S_MB_2U(SCH_1):PAGE53
   J21  263 DQ14_B SCONN288_ADR50017P130CC-SCONN2A    I13 @S9S_MB_2U_LIB.S9S_MB_2U(SCH_1):PAGE102
   J22  263 DQ14_B SCONN288_ADR50017P087CC-SCONN2A    I51 @S9S_MB_2U_LIB.S9S_MB_2U(SCH_1):PAGE103

M_C_CPU1_SB_DQ<15> @S9S_MB_2U_LIB.S9S_MB_2U(SCH_1):M_C_CPU1_SB_DQ(15)
    U1 AF28 DDR2_SB_DQ15 SOCKET4677_AZIF0045P001C01CS-SA    I91 @S9S_MB_2U_LIB.S9S_MB_2U(SCH_1):PAGE53
   J21  265 DQ15_B SCONN288_ADR50017P130CC-SCONN2A    I13 @S9S_MB_2U_LIB.S9S_MB_2U(SCH_1):PAGE102
   J22  265 DQ15_B SCONN288_ADR50017P087CC-SCONN2A    I51 @S9S_MB_2U_LIB.S9S_MB_2U(SCH_1):PAGE103

M_C_CPU1_SB_DQ<16> @S9S_MB_2U_LIB.S9S_MB_2U(SCH_1):M_C_CPU1_SB_DQ(16)
    U1  U23 DDR2_SB_DQ16 SOCKET4677_AZIF0045P001C01CS-SA    I91 @S9S_MB_2U_LIB.S9S_MB_2U(SCH_1):PAGE53
   J21  122 DQ16_B SCONN288_ADR50017P130CC-SCONN2A    I13 @S9S_MB_2U_LIB.S9S_MB_2U(SCH_1):PAGE102
   J22  122 DQ16_B SCONN288_ADR50017P087CC-SCONN2A    I51 @S9S_MB_2U_LIB.S9S_MB_2U(SCH_1):PAGE103

M_C_CPU1_SB_DQ<17> @S9S_MB_2U_LIB.S9S_MB_2U(SCH_1):M_C_CPU1_SB_DQ(17)
    U1  T22 DDR2_SB_DQ17 SOCKET4677_AZIF0045P001C01CS-SA    I91 @S9S_MB_2U_LIB.S9S_MB_2U(SCH_1):PAGE53
   J21  124 DQ17_B SCONN288_ADR50017P130CC-SCONN2A    I13 @S9S_MB_2U_LIB.S9S_MB_2U(SCH_1):PAGE102
   J22  124 DQ17_B SCONN288_ADR50017P087CC-SCONN2A    I51 @S9S_MB_2U_LIB.S9S_MB_2U(SCH_1):PAGE103

M_C_CPU1_SB_DQ<18> @S9S_MB_2U_LIB.S9S_MB_2U(SCH_1):M_C_CPU1_SB_DQ(18)
    U1  W23 DDR2_SB_DQ18 SOCKET4677_AZIF0045P001C01CS-SA    I91 @S9S_MB_2U_LIB.S9S_MB_2U(SCH_1):PAGE53
   J21  267 DQ18_B SCONN288_ADR50017P130CC-SCONN2A    I13 @S9S_MB_2U_LIB.S9S_MB_2U(SCH_1):PAGE102
   J22  267 DQ18_B SCONN288_ADR50017P087CC-SCONN2A    I51 @S9S_MB_2U_LIB.S9S_MB_2U(SCH_1):PAGE103

M_C_CPU1_SB_DQ<19> @S9S_MB_2U_LIB.S9S_MB_2U(SCH_1):M_C_CPU1_SB_DQ(19)
    U1  Y22 DDR2_SB_DQ19 SOCKET4677_AZIF0045P001C01CS-SA    I91 @S9S_MB_2U_LIB.S9S_MB_2U(SCH_1):PAGE53
   J21  269 DQ19_B SCONN288_ADR50017P130CC-SCONN2A    I13 @S9S_MB_2U_LIB.S9S_MB_2U(SCH_1):PAGE102
   J22  269 DQ19_B SCONN288_ADR50017P087CC-SCONN2A    I51 @S9S_MB_2U_LIB.S9S_MB_2U(SCH_1):PAGE103

M_C_CPU1_SB_DQ<1> @S9S_MB_2U_LIB.S9S_MB_2U(SCH_1):M_C_CPU1_SB_DQ(1)
    U1 AC37 DDR2_SB_DQ1 SOCKET4677_AZIF0045P001C01CS-SA    I91 @S9S_MB_2U_LIB.S9S_MB_2U(SCH_1):PAGE53
   J21  102  DQ1_B SCONN288_ADR50017P130CC-SCONN2A    I13 @S9S_MB_2U_LIB.S9S_MB_2U(SCH_1):PAGE102
   J22  102  DQ1_B SCONN288_ADR50017P087CC-SCONN2A    I51 @S9S_MB_2U_LIB.S9S_MB_2U(SCH_1):PAGE103

M_C_CPU1_SB_DQ<20> @S9S_MB_2U_LIB.S9S_MB_2U(SCH_1):M_C_CPU1_SB_DQ(20)
    U1  T20 DDR2_SB_DQ20 SOCKET4677_AZIF0045P001C01CS-SA    I91 @S9S_MB_2U_LIB.S9S_MB_2U(SCH_1):PAGE53
   J21  129 DQ20_B SCONN288_ADR50017P130CC-SCONN2A    I13 @S9S_MB_2U_LIB.S9S_MB_2U(SCH_1):PAGE102
   J22  129 DQ20_B SCONN288_ADR50017P087CC-SCONN2A    I51 @S9S_MB_2U_LIB.S9S_MB_2U(SCH_1):PAGE103

M_C_CPU1_SB_DQ<21> @S9S_MB_2U_LIB.S9S_MB_2U(SCH_1):M_C_CPU1_SB_DQ(21)
    U1  U19 DDR2_SB_DQ21 SOCKET4677_AZIF0045P001C01CS-SA    I91 @S9S_MB_2U_LIB.S9S_MB_2U(SCH_1):PAGE53
   J21  131 DQ21_B SCONN288_ADR50017P130CC-SCONN2A    I13 @S9S_MB_2U_LIB.S9S_MB_2U(SCH_1):PAGE102
   J22  131 DQ21_B SCONN288_ADR50017P087CC-SCONN2A    I51 @S9S_MB_2U_LIB.S9S_MB_2U(SCH_1):PAGE103

M_C_CPU1_SB_DQ<22> @S9S_MB_2U_LIB.S9S_MB_2U(SCH_1):M_C_CPU1_SB_DQ(22)
    U1  Y20 DDR2_SB_DQ22 SOCKET4677_AZIF0045P001C01CS-SA    I91 @S9S_MB_2U_LIB.S9S_MB_2U(SCH_1):PAGE53
   J21  274 DQ22_B SCONN288_ADR50017P130CC-SCONN2A    I13 @S9S_MB_2U_LIB.S9S_MB_2U(SCH_1):PAGE102
   J22  274 DQ22_B SCONN288_ADR50017P087CC-SCONN2A    I51 @S9S_MB_2U_LIB.S9S_MB_2U(SCH_1):PAGE103

M_C_CPU1_SB_DQ<23> @S9S_MB_2U_LIB.S9S_MB_2U(SCH_1):M_C_CPU1_SB_DQ(23)
    U1  W19 DDR2_SB_DQ23 SOCKET4677_AZIF0045P001C01CS-SA    I91 @S9S_MB_2U_LIB.S9S_MB_2U(SCH_1):PAGE53
   J21  276 DQ23_B SCONN288_ADR50017P130CC-SCONN2A    I13 @S9S_MB_2U_LIB.S9S_MB_2U(SCH_1):PAGE102
   J22  276 DQ23_B SCONN288_ADR50017P087CC-SCONN2A    I51 @S9S_MB_2U_LIB.S9S_MB_2U(SCH_1):PAGE103

M_C_CPU1_SB_DQ<24> @S9S_MB_2U_LIB.S9S_MB_2U(SCH_1):M_C_CPU1_SB_DQ(24)
    U1 AD20 DDR2_SB_DQ24 SOCKET4677_AZIF0045P001C01CS-SA    I91 @S9S_MB_2U_LIB.S9S_MB_2U(SCH_1):PAGE53
   J21  133 DQ24_B SCONN288_ADR50017P130CC-SCONN2A    I13 @S9S_MB_2U_LIB.S9S_MB_2U(SCH_1):PAGE102
   J22  133 DQ24_B SCONN288_ADR50017P087CC-SCONN2A    I51 @S9S_MB_2U_LIB.S9S_MB_2U(SCH_1):PAGE103

M_C_CPU1_SB_DQ<25> @S9S_MB_2U_LIB.S9S_MB_2U(SCH_1):M_C_CPU1_SB_DQ(25)
    U1 AC19 DDR2_SB_DQ25 SOCKET4677_AZIF0045P001C01CS-SA    I91 @S9S_MB_2U_LIB.S9S_MB_2U(SCH_1):PAGE53
   J21  135 DQ25_B SCONN288_ADR50017P130CC-SCONN2A    I13 @S9S_MB_2U_LIB.S9S_MB_2U(SCH_1):PAGE102
   J22  135 DQ25_B SCONN288_ADR50017P087CC-SCONN2A    I51 @S9S_MB_2U_LIB.S9S_MB_2U(SCH_1):PAGE103

M_C_CPU1_SB_DQ<26> @S9S_MB_2U_LIB.S9S_MB_2U(SCH_1):M_C_CPU1_SB_DQ(26)
    U1 AF20 DDR2_SB_DQ26 SOCKET4677_AZIF0045P001C01CS-SA    I91 @S9S_MB_2U_LIB.S9S_MB_2U(SCH_1):PAGE53
   J21  278 DQ26_B SCONN288_ADR50017P130CC-SCONN2A    I13 @S9S_MB_2U_LIB.S9S_MB_2U(SCH_1):PAGE102
   J22  278 DQ26_B SCONN288_ADR50017P087CC-SCONN2A    I51 @S9S_MB_2U_LIB.S9S_MB_2U(SCH_1):PAGE103

M_C_CPU1_SB_DQ<27> @S9S_MB_2U_LIB.S9S_MB_2U(SCH_1):M_C_CPU1_SB_DQ(27)
    U1 AG19 DDR2_SB_DQ27 SOCKET4677_AZIF0045P001C01CS-SA    I91 @S9S_MB_2U_LIB.S9S_MB_2U(SCH_1):PAGE53
   J21  280 DQ27_B SCONN288_ADR50017P130CC-SCONN2A    I13 @S9S_MB_2U_LIB.S9S_MB_2U(SCH_1):PAGE102
   J22  280 DQ27_B SCONN288_ADR50017P087CC-SCONN2A    I51 @S9S_MB_2U_LIB.S9S_MB_2U(SCH_1):PAGE103

M_C_CPU1_SB_DQ<28> @S9S_MB_2U_LIB.S9S_MB_2U(SCH_1):M_C_CPU1_SB_DQ(28)
    U1 AA17 DDR2_SB_DQ28 SOCKET4677_AZIF0045P001C01CS-SA    I91 @S9S_MB_2U_LIB.S9S_MB_2U(SCH_1):PAGE53
   J21  140 DQ28_B SCONN288_ADR50017P130CC-SCONN2A    I13 @S9S_MB_2U_LIB.S9S_MB_2U(SCH_1):PAGE102
   J22  140 DQ28_B SCONN288_ADR50017P087CC-SCONN2A    I51 @S9S_MB_2U_LIB.S9S_MB_2U(SCH_1):PAGE103

M_C_CPU1_SB_DQ<29> @S9S_MB_2U_LIB.S9S_MB_2U(SCH_1):M_C_CPU1_SB_DQ(29)
    U1 AG17 DDR2_SB_DQ29 SOCKET4677_AZIF0045P001C01CS-SA    I91 @S9S_MB_2U_LIB.S9S_MB_2U(SCH_1):PAGE53
   J21  142 DQ29_B SCONN288_ADR50017P130CC-SCONN2A    I13 @S9S_MB_2U_LIB.S9S_MB_2U(SCH_1):PAGE102
   J22  142 DQ29_B SCONN288_ADR50017P087CC-SCONN2A    I51 @S9S_MB_2U_LIB.S9S_MB_2U(SCH_1):PAGE103

M_C_CPU1_SB_DQ<2> @S9S_MB_2U_LIB.S9S_MB_2U(SCH_1):M_C_CPU1_SB_DQ(2)
    U1 AF38 DDR2_SB_DQ2 SOCKET4677_AZIF0045P001C01CS-SA    I91 @S9S_MB_2U_LIB.S9S_MB_2U(SCH_1):PAGE53
   J21  245  DQ2_B SCONN288_ADR50017P130CC-SCONN2A    I13 @S9S_MB_2U_LIB.S9S_MB_2U(SCH_1):PAGE102
   J22  245  DQ2_B SCONN288_ADR50017P087CC-SCONN2A    I51 @S9S_MB_2U_LIB.S9S_MB_2U(SCH_1):PAGE103

M_C_CPU1_SB_DQ<30> @S9S_MB_2U_LIB.S9S_MB_2U(SCH_1):M_C_CPU1_SB_DQ(30)
    U1 AC17 DDR2_SB_DQ30 SOCKET4677_AZIF0045P001C01CS-SA    I91 @S9S_MB_2U_LIB.S9S_MB_2U(SCH_1):PAGE53
   J21  285 DQ30_B SCONN288_ADR50017P130CC-SCONN2A    I13 @S9S_MB_2U_LIB.S9S_MB_2U(SCH_1):PAGE102
   J22  285 DQ30_B SCONN288_ADR50017P087CC-SCONN2A    I51 @S9S_MB_2U_LIB.S9S_MB_2U(SCH_1):PAGE103

M_C_CPU1_SB_DQ<31> @S9S_MB_2U_LIB.S9S_MB_2U(SCH_1):M_C_CPU1_SB_DQ(31)
    U1 AJ17 DDR2_SB_DQ31 SOCKET4677_AZIF0045P001C01CS-SA    I91 @S9S_MB_2U_LIB.S9S_MB_2U(SCH_1):PAGE53
   J21  287 DQ31_B SCONN288_ADR50017P130CC-SCONN2A    I13 @S9S_MB_2U_LIB.S9S_MB_2U(SCH_1):PAGE102
   J22  287 DQ31_B SCONN288_ADR50017P087CC-SCONN2A    I51 @S9S_MB_2U_LIB.S9S_MB_2U(SCH_1):PAGE103

M_C_CPU1_SB_DQ<3> @S9S_MB_2U_LIB.S9S_MB_2U(SCH_1):M_C_CPU1_SB_DQ(3)
    U1 AG37 DDR2_SB_DQ3 SOCKET4677_AZIF0045P001C01CS-SA    I91 @S9S_MB_2U_LIB.S9S_MB_2U(SCH_1):PAGE53
   J21  247  DQ3_B SCONN288_ADR50017P130CC-SCONN2A    I13 @S9S_MB_2U_LIB.S9S_MB_2U(SCH_1):PAGE102
   J22  247  DQ3_B SCONN288_ADR50017P087CC-SCONN2A    I51 @S9S_MB_2U_LIB.S9S_MB_2U(SCH_1):PAGE103

M_C_CPU1_SB_DQ<4> @S9S_MB_2U_LIB.S9S_MB_2U(SCH_1):M_C_CPU1_SB_DQ(4)
    U1 AC35 DDR2_SB_DQ4 SOCKET4677_AZIF0045P001C01CS-SA    I91 @S9S_MB_2U_LIB.S9S_MB_2U(SCH_1):PAGE53
   J21  107  DQ4_B SCONN288_ADR50017P130CC-SCONN2A    I13 @S9S_MB_2U_LIB.S9S_MB_2U(SCH_1):PAGE102
   J22  107  DQ4_B SCONN288_ADR50017P087CC-SCONN2A    I51 @S9S_MB_2U_LIB.S9S_MB_2U(SCH_1):PAGE103

M_C_CPU1_SB_DQ<5> @S9S_MB_2U_LIB.S9S_MB_2U(SCH_1):M_C_CPU1_SB_DQ(5)
    U1 AD34 DDR2_SB_DQ5 SOCKET4677_AZIF0045P001C01CS-SA    I91 @S9S_MB_2U_LIB.S9S_MB_2U(SCH_1):PAGE53
   J21  109  DQ5_B SCONN288_ADR50017P130CC-SCONN2A    I13 @S9S_MB_2U_LIB.S9S_MB_2U(SCH_1):PAGE102
   J22  109  DQ5_B SCONN288_ADR50017P087CC-SCONN2A    I51 @S9S_MB_2U_LIB.S9S_MB_2U(SCH_1):PAGE103

M_C_CPU1_SB_DQ<6> @S9S_MB_2U_LIB.S9S_MB_2U(SCH_1):M_C_CPU1_SB_DQ(6)
    U1 AG35 DDR2_SB_DQ6 SOCKET4677_AZIF0045P001C01CS-SA    I91 @S9S_MB_2U_LIB.S9S_MB_2U(SCH_1):PAGE53
   J21  252  DQ6_B SCONN288_ADR50017P130CC-SCONN2A    I13 @S9S_MB_2U_LIB.S9S_MB_2U(SCH_1):PAGE102
   J22  252  DQ6_B SCONN288_ADR50017P087CC-SCONN2A    I51 @S9S_MB_2U_LIB.S9S_MB_2U(SCH_1):PAGE103

M_C_CPU1_SB_DQ<7> @S9S_MB_2U_LIB.S9S_MB_2U(SCH_1):M_C_CPU1_SB_DQ(7)
    U1 AF34 DDR2_SB_DQ7 SOCKET4677_AZIF0045P001C01CS-SA    I91 @S9S_MB_2U_LIB.S9S_MB_2U(SCH_1):PAGE53
   J21  254  DQ7_B SCONN288_ADR50017P130CC-SCONN2A    I13 @S9S_MB_2U_LIB.S9S_MB_2U(SCH_1):PAGE102
   J22  254  DQ7_B SCONN288_ADR50017P087CC-SCONN2A    I51 @S9S_MB_2U_LIB.S9S_MB_2U(SCH_1):PAGE103

M_C_CPU1_SB_DQ<8> @S9S_MB_2U_LIB.S9S_MB_2U(SCH_1):M_C_CPU1_SB_DQ(8)
    U1 AD32 DDR2_SB_DQ8 SOCKET4677_AZIF0045P001C01CS-SA    I91 @S9S_MB_2U_LIB.S9S_MB_2U(SCH_1):PAGE53
   J21  111  DQ8_B SCONN288_ADR50017P130CC-SCONN2A    I13 @S9S_MB_2U_LIB.S9S_MB_2U(SCH_1):PAGE102
   J22  111  DQ8_B SCONN288_ADR50017P087CC-SCONN2A    I51 @S9S_MB_2U_LIB.S9S_MB_2U(SCH_1):PAGE103

M_C_CPU1_SB_DQ<9> @S9S_MB_2U_LIB.S9S_MB_2U(SCH_1):M_C_CPU1_SB_DQ(9)
    U1 AC31 DDR2_SB_DQ9 SOCKET4677_AZIF0045P001C01CS-SA    I91 @S9S_MB_2U_LIB.S9S_MB_2U(SCH_1):PAGE53
   J21  113  DQ9_B SCONN288_ADR50017P130CC-SCONN2A    I13 @S9S_MB_2U_LIB.S9S_MB_2U(SCH_1):PAGE102
   J22  113  DQ9_B SCONN288_ADR50017P087CC-SCONN2A    I51 @S9S_MB_2U_LIB.S9S_MB_2U(SCH_1):PAGE103

M_C_CPU1_SB_DQS_DN<0> @S9S_MB_2U_LIB.S9S_MB_2U(SCH_1):M_C_CPU1_SB_DQS_DN(0)
    U1 AB36 DDR2_SB_DQS_DN0 SOCKET4677_AZIF0045P001C01CS-SA    I91 @S9S_MB_2U_LIB.S9S_MB_2U(SCH_1):PAGE53
   J21  105 DQS0_B_C SCONN288_ADR50017P130CC-SCONN2A   I178 @S9S_MB_2U_LIB.S9S_MB_2U(SCH_1):PAGE102
   J22  105 DQS0_B_C SCONN288_ADR50017P087CC-SCONN2A   I178 @S9S_MB_2U_LIB.S9S_MB_2U(SCH_1):PAGE103

M_C_CPU1_SB_DQS_DN<1> @S9S_MB_2U_LIB.S9S_MB_2U(SCH_1):M_C_CPU1_SB_DQS_DN(1)
    U1 AB30 DDR2_SB_DQS_DN1 SOCKET4677_AZIF0045P001C01CS-SA    I91 @S9S_MB_2U_LIB.S9S_MB_2U(SCH_1):PAGE53
   J21  116 DQS1_B_C SCONN288_ADR50017P130CC-SCONN2A   I178 @S9S_MB_2U_LIB.S9S_MB_2U(SCH_1):PAGE102
   J22  116 DQS1_B_C SCONN288_ADR50017P087CC-SCONN2A   I178 @S9S_MB_2U_LIB.S9S_MB_2U(SCH_1):PAGE103

M_C_CPU1_SB_DQS_DN<2> @S9S_MB_2U_LIB.S9S_MB_2U(SCH_1):M_C_CPU1_SB_DQS_DN(2)
    U1  R21 DDR2_SB_DQS_DN2 SOCKET4677_AZIF0045P001C01CS-SA    I91 @S9S_MB_2U_LIB.S9S_MB_2U(SCH_1):PAGE53
   J21  127 DQS2_B_C SCONN288_ADR50017P130CC-SCONN2A   I178 @S9S_MB_2U_LIB.S9S_MB_2U(SCH_1):PAGE102
   J22  127 DQS2_B_C SCONN288_ADR50017P087CC-SCONN2A   I178 @S9S_MB_2U_LIB.S9S_MB_2U(SCH_1):PAGE103

M_C_CPU1_SB_DQS_DN<3> @S9S_MB_2U_LIB.S9S_MB_2U(SCH_1):M_C_CPU1_SB_DQS_DN(3)
    U1 AB18 DDR2_SB_DQS_DN3 SOCKET4677_AZIF0045P001C01CS-SA    I91 @S9S_MB_2U_LIB.S9S_MB_2U(SCH_1):PAGE53
   J21  138 DQS3_B_C SCONN288_ADR50017P130CC-SCONN2A   I178 @S9S_MB_2U_LIB.S9S_MB_2U(SCH_1):PAGE102
   J22  138 DQS3_B_C SCONN288_ADR50017P087CC-SCONN2A   I178 @S9S_MB_2U_LIB.S9S_MB_2U(SCH_1):PAGE103

M_C_CPU1_SB_DQS_DN<4> @S9S_MB_2U_LIB.S9S_MB_2U(SCH_1):M_C_CPU1_SB_DQS_DN(4)
    U1  W33 DDR2_SB_DQS_DN4 SOCKET4677_AZIF0045P001C01CS-SA    I91 @S9S_MB_2U_LIB.S9S_MB_2U(SCH_1):PAGE53
   J21  238 DQS4_B_C SCONN288_ADR50017P130CC-SCONN2A   I178 @S9S_MB_2U_LIB.S9S_MB_2U(SCH_1):PAGE102
   J22  238 DQS4_B_C SCONN288_ADR50017P087CC-SCONN2A   I178 @S9S_MB_2U_LIB.S9S_MB_2U(SCH_1):PAGE103

M_C_CPU1_SB_DQS_DN<5> @S9S_MB_2U_LIB.S9S_MB_2U(SCH_1):M_C_CPU1_SB_DQS_DN(5)
    U1 AF36 DDR2_SB_DQS_DN5 SOCKET4677_AZIF0045P001C01CS-SA    I91 @S9S_MB_2U_LIB.S9S_MB_2U(SCH_1):PAGE53
   J21  249 DQS5_B_C||TDQS5_B_C SCONN288_ADR50017P130CC-SCONN2A   I178 @S9S_MB_2U_LIB.S9S_MB_2U(SCH_1):PAGE102
   J22  249 DQS5_B_C||TDQS5_B_C SCONN288_ADR50017P087CC-SCONN2A   I178 @S9S_MB_2U_LIB.S9S_MB_2U(SCH_1):PAGE103

M_C_CPU1_SB_DQS_DN<6> @S9S_MB_2U_LIB.S9S_MB_2U(SCH_1):M_C_CPU1_SB_DQS_DN(6)
    U1 AF30 DDR2_SB_DQS_DN6 SOCKET4677_AZIF0045P001C01CS-SA    I91 @S9S_MB_2U_LIB.S9S_MB_2U(SCH_1):PAGE53
   J21  260 DQS6_B_C||TDQS6_B_C SCONN288_ADR50017P130CC-SCONN2A   I178 @S9S_MB_2U_LIB.S9S_MB_2U(SCH_1):PAGE102
   J22  260 DQS6_B_C||TDQS6_B_C SCONN288_ADR50017P087CC-SCONN2A   I178 @S9S_MB_2U_LIB.S9S_MB_2U(SCH_1):PAGE103

M_C_CPU1_SB_DQS_DN<7> @S9S_MB_2U_LIB.S9S_MB_2U(SCH_1):M_C_CPU1_SB_DQS_DN(7)
    U1  W21 DDR2_SB_DQS_DN7 SOCKET4677_AZIF0045P001C01CS-SA    I91 @S9S_MB_2U_LIB.S9S_MB_2U(SCH_1):PAGE53
   J21  271 DQS7_B_C||TDQS7_B_C SCONN288_ADR50017P130CC-SCONN2A   I178 @S9S_MB_2U_LIB.S9S_MB_2U(SCH_1):PAGE102
   J22  271 DQS7_B_C||TDQS7_B_C SCONN288_ADR50017P087CC-SCONN2A   I178 @S9S_MB_2U_LIB.S9S_MB_2U(SCH_1):PAGE103

M_C_CPU1_SB_DQS_DN<8> @S9S_MB_2U_LIB.S9S_MB_2U(SCH_1):M_C_CPU1_SB_DQS_DN(8)
    U1 AF18 DDR2_SB_DQS_DN8 SOCKET4677_AZIF0045P001C01CS-SA    I91 @S9S_MB_2U_LIB.S9S_MB_2U(SCH_1):PAGE53
   J21  282 DQS8_B_C||TDQS8_B_C SCONN288_ADR50017P130CC-SCONN2A   I178 @S9S_MB_2U_LIB.S9S_MB_2U(SCH_1):PAGE102
   J22  282 DQS8_B_C||TDQS8_B_C SCONN288_ADR50017P087CC-SCONN2A   I178 @S9S_MB_2U_LIB.S9S_MB_2U(SCH_1):PAGE103

M_C_CPU1_SB_DQS_DN<9> @S9S_MB_2U_LIB.S9S_MB_2U(SCH_1):M_C_CPU1_SB_DQS_DN(9)
    U1  R33 DDR2_SB_DQS_DN9 SOCKET4677_AZIF0045P001C01CS-SA    I91 @S9S_MB_2U_LIB.S9S_MB_2U(SCH_1):PAGE53
   J21   94 DQS9_B_C||TDQS9_B_C SCONN288_ADR50017P130CC-SCONN2A   I178 @S9S_MB_2U_LIB.S9S_MB_2U(SCH_1):PAGE102
   J22   94 DQS9_B_C||TDQS9_B_C SCONN288_ADR50017P087CC-SCONN2A   I178 @S9S_MB_2U_LIB.S9S_MB_2U(SCH_1):PAGE103

M_C_CPU1_SB_DQS_DP<0> @S9S_MB_2U_LIB.S9S_MB_2U(SCH_1):M_C_CPU1_SB_DQS_DP(0)
    U1 AD36 DDR2_SB_DQS_DP0 SOCKET4677_AZIF0045P001C01CS-SA    I91 @S9S_MB_2U_LIB.S9S_MB_2U(SCH_1):PAGE53
   J21  104 DQS0_B_T SCONN288_ADR50017P130CC-SCONN2A   I178 @S9S_MB_2U_LIB.S9S_MB_2U(SCH_1):PAGE102
   J22  104 DQS0_B_T SCONN288_ADR50017P087CC-SCONN2A   I178 @S9S_MB_2U_LIB.S9S_MB_2U(SCH_1):PAGE103

M_C_CPU1_SB_DQS_DP<1> @S9S_MB_2U_LIB.S9S_MB_2U(SCH_1):M_C_CPU1_SB_DQS_DP(1)
    U1 AD30 DDR2_SB_DQS_DP1 SOCKET4677_AZIF0045P001C01CS-SA    I91 @S9S_MB_2U_LIB.S9S_MB_2U(SCH_1):PAGE53
   J21  115 DQS1_B_T SCONN288_ADR50017P130CC-SCONN2A   I178 @S9S_MB_2U_LIB.S9S_MB_2U(SCH_1):PAGE102
   J22  115 DQS1_B_T SCONN288_ADR50017P087CC-SCONN2A   I178 @S9S_MB_2U_LIB.S9S_MB_2U(SCH_1):PAGE103

M_C_CPU1_SB_DQS_DP<2> @S9S_MB_2U_LIB.S9S_MB_2U(SCH_1):M_C_CPU1_SB_DQS_DP(2)
    U1  U21 DDR2_SB_DQS_DP2 SOCKET4677_AZIF0045P001C01CS-SA    I91 @S9S_MB_2U_LIB.S9S_MB_2U(SCH_1):PAGE53
   J21  126 DQS2_B_T SCONN288_ADR50017P130CC-SCONN2A   I178 @S9S_MB_2U_LIB.S9S_MB_2U(SCH_1):PAGE102
   J22  126 DQS2_B_T SCONN288_ADR50017P087CC-SCONN2A   I178 @S9S_MB_2U_LIB.S9S_MB_2U(SCH_1):PAGE103

M_C_CPU1_SB_DQS_DP<3> @S9S_MB_2U_LIB.S9S_MB_2U(SCH_1):M_C_CPU1_SB_DQS_DP(3)
    U1 AD18 DDR2_SB_DQS_DP3 SOCKET4677_AZIF0045P001C01CS-SA    I91 @S9S_MB_2U_LIB.S9S_MB_2U(SCH_1):PAGE53
   J21  137 DQS3_B_T SCONN288_ADR50017P130CC-SCONN2A   I178 @S9S_MB_2U_LIB.S9S_MB_2U(SCH_1):PAGE102
   J22  137 DQS3_B_T SCONN288_ADR50017P087CC-SCONN2A   I178 @S9S_MB_2U_LIB.S9S_MB_2U(SCH_1):PAGE103

M_C_CPU1_SB_DQS_DP<4> @S9S_MB_2U_LIB.S9S_MB_2U(SCH_1):M_C_CPU1_SB_DQS_DP(4)
    U1 AA33 DDR2_SB_DQS_DP4 SOCKET4677_AZIF0045P001C01CS-SA    I91 @S9S_MB_2U_LIB.S9S_MB_2U(SCH_1):PAGE53
   J21  239 DQS4_B_T SCONN288_ADR50017P130CC-SCONN2A   I178 @S9S_MB_2U_LIB.S9S_MB_2U(SCH_1):PAGE102
   J22  239 DQS4_B_T SCONN288_ADR50017P087CC-SCONN2A   I178 @S9S_MB_2U_LIB.S9S_MB_2U(SCH_1):PAGE103

M_C_CPU1_SB_DQS_DP<5> @S9S_MB_2U_LIB.S9S_MB_2U(SCH_1):M_C_CPU1_SB_DQS_DP(5)
    U1 AH36 DDR2_SB_DQS_DP5 SOCKET4677_AZIF0045P001C01CS-SA    I91 @S9S_MB_2U_LIB.S9S_MB_2U(SCH_1):PAGE53
   J21  250 DQS5_B_T||TDQS5_B_T SCONN288_ADR50017P130CC-SCONN2A   I178 @S9S_MB_2U_LIB.S9S_MB_2U(SCH_1):PAGE102
   J22  250 DQS5_B_T||TDQS5_B_T SCONN288_ADR50017P087CC-SCONN2A   I178 @S9S_MB_2U_LIB.S9S_MB_2U(SCH_1):PAGE103

M_C_CPU1_SB_DQS_DP<6> @S9S_MB_2U_LIB.S9S_MB_2U(SCH_1):M_C_CPU1_SB_DQS_DP(6)
    U1 AH30 DDR2_SB_DQS_DP6 SOCKET4677_AZIF0045P001C01CS-SA    I91 @S9S_MB_2U_LIB.S9S_MB_2U(SCH_1):PAGE53
   J21  261 DQS6_B_T||TDQS6_B_T SCONN288_ADR50017P130CC-SCONN2A   I178 @S9S_MB_2U_LIB.S9S_MB_2U(SCH_1):PAGE102
   J22  261 DQS6_B_T||TDQS6_B_T SCONN288_ADR50017P087CC-SCONN2A   I178 @S9S_MB_2U_LIB.S9S_MB_2U(SCH_1):PAGE103

M_C_CPU1_SB_DQS_DP<7> @S9S_MB_2U_LIB.S9S_MB_2U(SCH_1):M_C_CPU1_SB_DQS_DP(7)
    U1 AA21 DDR2_SB_DQS_DP7 SOCKET4677_AZIF0045P001C01CS-SA    I91 @S9S_MB_2U_LIB.S9S_MB_2U(SCH_1):PAGE53
   J21  272 DQS7_B_T||TDQS7_B_T SCONN288_ADR50017P130CC-SCONN2A   I178 @S9S_MB_2U_LIB.S9S_MB_2U(SCH_1):PAGE102
   J22  272 DQS7_B_T||TDQS7_B_T SCONN288_ADR50017P087CC-SCONN2A   I178 @S9S_MB_2U_LIB.S9S_MB_2U(SCH_1):PAGE103

M_C_CPU1_SB_DQS_DP<8> @S9S_MB_2U_LIB.S9S_MB_2U(SCH_1):M_C_CPU1_SB_DQS_DP(8)
    U1 AH18 DDR2_SB_DQS_DP8 SOCKET4677_AZIF0045P001C01CS-SA    I91 @S9S_MB_2U_LIB.S9S_MB_2U(SCH_1):PAGE53
   J21  283 DQS8_B_T||TDQS8_B_T SCONN288_ADR50017P130CC-SCONN2A   I178 @S9S_MB_2U_LIB.S9S_MB_2U(SCH_1):PAGE102
   J22  283 DQS8_B_T||TDQS8_B_T SCONN288_ADR50017P087CC-SCONN2A   I178 @S9S_MB_2U_LIB.S9S_MB_2U(SCH_1):PAGE103

M_C_CPU1_SB_DQS_DP<9> @S9S_MB_2U_LIB.S9S_MB_2U(SCH_1):M_C_CPU1_SB_DQS_DP(9)
    U1  U33 DDR2_SB_DQS_DP9 SOCKET4677_AZIF0045P001C01CS-SA    I91 @S9S_MB_2U_LIB.S9S_MB_2U(SCH_1):PAGE53
   J21   93 DQS9_B_T||TDQS9_B_T||DBI4_B_N SCONN288_ADR50017P130CC-SCONN2A   I178 @S9S_MB_2U_LIB.S9S_MB_2U(SCH_1):PAGE102
   J22   93 DQS9_B_T||TDQS9_B_T||DBI4_B_N SCONN288_ADR50017P087CC-SCONN2A   I178 @S9S_MB_2U_LIB.S9S_MB_2U(SCH_1):PAGE103

M_C_CPU1_SB_PAR @S9S_MB_2U_LIB.S9S_MB_2U(SCH_1):M_C_CPU1_SB_PAR
    U1 AA39 DDR2_SB_PAR SOCKET4677_AZIF0045P001C01CS-SA    I91 @S9S_MB_2U_LIB.S9S_MB_2U(SCH_1):PAGE53
   J21  227  PAR_B SCONN288_ADR50017P130CC-SCONN2A    I13 @S9S_MB_2U_LIB.S9S_MB_2U(SCH_1):PAGE102
   J22  227  PAR_B SCONN288_ADR50017P087CC-SCONN2A    I51 @S9S_MB_2U_LIB.S9S_MB_2U(SCH_1):PAGE103

M_C_CPU1_SB_RSP<0> @S9S_MB_2U_LIB.S9S_MB_2U(SCH_1):M_C_CPU1_SB_RSP(0)
    U1 AG48 DDR2_B_RSP0 SOCKET4677_AZIF0045P001C01CS-SA    I91 @S9S_MB_2U_LIB.S9S_MB_2U(SCH_1):PAGE53
   J21   87 LBS||RSP_B_N SCONN288_ADR50017P130CC-SCONN2A    I13 @S9S_MB_2U_LIB.S9S_MB_2U(SCH_1):PAGE102

M_C_CPU1_SB_RSP<1> @S9S_MB_2U_LIB.S9S_MB_2U(SCH_1):M_C_CPU1_SB_RSP(1)
    U1 AF47 DDR2_B_RSP1 SOCKET4677_AZIF0045P001C01CS-SA    I91 @S9S_MB_2U_LIB.S9S_MB_2U(SCH_1):PAGE53
   J22   87 LBS||RSP_B_N SCONN288_ADR50017P087CC-SCONN2A    I51 @S9S_MB_2U_LIB.S9S_MB_2U(SCH_1):PAGE103

M_D_CPU0_ALERT_N @S9S_MB_2U_LIB.S9S_MB_2U(SCH_1):M_D_CPU0_ALERT_N
    U2 AV47 DDR3_ALERT_N SOCKET4677_AZIF0045P001C01CS-SA   I169 @S9S_MB_2U_LIB.S9S_MB_2U(SCH_1):PAGE23
    J7   62 ALERT_N SCONN288_ADR50017P130CC-SCONN2A    I12 @S9S_MB_2U_LIB.S9S_MB_2U(SCH_1):PAGE88
    J8   62 ALERT_N SCONN288_ADR50017P087CC-SCONN2A    I50 @S9S_MB_2U_LIB.S9S_MB_2U(SCH_1):PAGE89

M_D_CPU0_CLK_DN<0> @S9S_MB_2U_LIB.S9S_MB_2U(SCH_1):M_D_CPU0_CLK_DN(0)
    U2 AJ45 DDR3_CLK_DN0 SOCKET4677_AZIF0045P001C01CS-SA   I169 @S9S_MB_2U_LIB.S9S_MB_2U(SCH_1):PAGE23
    J7  218   CK_C SCONN288_ADR50017P130CC-SCONN2A    I12 @S9S_MB_2U_LIB.S9S_MB_2U(SCH_1):PAGE88

M_D_CPU0_CLK_DN<1> @S9S_MB_2U_LIB.S9S_MB_2U(SCH_1):M_D_CPU0_CLK_DN(1)
    U2 AN45 DDR3_CLK_DN1 SOCKET4677_AZIF0045P001C01CS-SA   I169 @S9S_MB_2U_LIB.S9S_MB_2U(SCH_1):PAGE23
    J8  218   CK_C SCONN288_ADR50017P087CC-SCONN2A    I50 @S9S_MB_2U_LIB.S9S_MB_2U(SCH_1):PAGE89

M_D_CPU0_CLK_DP<0> @S9S_MB_2U_LIB.S9S_MB_2U(SCH_1):M_D_CPU0_CLK_DP(0)
    U2 AL45 DDR3_CLK_DP0 SOCKET4677_AZIF0045P001C01CS-SA   I169 @S9S_MB_2U_LIB.S9S_MB_2U(SCH_1):PAGE23
    J7  217   CK_T SCONN288_ADR50017P130CC-SCONN2A    I12 @S9S_MB_2U_LIB.S9S_MB_2U(SCH_1):PAGE88

M_D_CPU0_CLK_DP<1> @S9S_MB_2U_LIB.S9S_MB_2U(SCH_1):M_D_CPU0_CLK_DP(1)
    U2 AR45 DDR3_CLK_DP1 SOCKET4677_AZIF0045P001C01CS-SA   I169 @S9S_MB_2U_LIB.S9S_MB_2U(SCH_1):PAGE23
    J8  217   CK_T SCONN288_ADR50017P087CC-SCONN2A    I50 @S9S_MB_2U_LIB.S9S_MB_2U(SCH_1):PAGE89

M_D_CPU0_SA_CA<0> @S9S_MB_2U_LIB.S9S_MB_2U(SCH_1):M_D_CPU0_SA_CA(0)
    U2 AJ52 DDR3_SA_CA0 SOCKET4677_AZIF0045P001C01CS-SA   I169 @S9S_MB_2U_LIB.S9S_MB_2U(SCH_1):PAGE23
    J7   66  CA0_A SCONN288_ADR50017P130CC-SCONN2A    I12 @S9S_MB_2U_LIB.S9S_MB_2U(SCH_1):PAGE88
    J8   66  CA0_A SCONN288_ADR50017P087CC-SCONN2A    I50 @S9S_MB_2U_LIB.S9S_MB_2U(SCH_1):PAGE89

M_D_CPU0_SA_CA<1> @S9S_MB_2U_LIB.S9S_MB_2U(SCH_1):M_D_CPU0_SA_CA(1)
    U2 AR52 DDR3_SA_CA1 SOCKET4677_AZIF0045P001C01CS-SA   I169 @S9S_MB_2U_LIB.S9S_MB_2U(SCH_1):PAGE23
    J7  211  CA1_A SCONN288_ADR50017P130CC-SCONN2A    I12 @S9S_MB_2U_LIB.S9S_MB_2U(SCH_1):PAGE88
    J8  211  CA1_A SCONN288_ADR50017P087CC-SCONN2A    I50 @S9S_MB_2U_LIB.S9S_MB_2U(SCH_1):PAGE89

M_D_CPU0_SA_CA<2> @S9S_MB_2U_LIB.S9S_MB_2U(SCH_1):M_D_CPU0_SA_CA(2)
    U2 AK51 DDR3_SA_CA2 SOCKET4677_AZIF0045P001C01CS-SA   I169 @S9S_MB_2U_LIB.S9S_MB_2U(SCH_1):PAGE23
    J7   68  CA2_A SCONN288_ADR50017P130CC-SCONN2A    I12 @S9S_MB_2U_LIB.S9S_MB_2U(SCH_1):PAGE88
    J8   68  CA2_A SCONN288_ADR50017P087CC-SCONN2A    I50 @S9S_MB_2U_LIB.S9S_MB_2U(SCH_1):PAGE89

M_D_CPU0_SA_CA<3> @S9S_MB_2U_LIB.S9S_MB_2U(SCH_1):M_D_CPU0_SA_CA(3)
    U2 AP51 DDR3_SA_CA3 SOCKET4677_AZIF0045P001C01CS-SA   I169 @S9S_MB_2U_LIB.S9S_MB_2U(SCH_1):PAGE23
    J7  213  CA3_A SCONN288_ADR50017P130CC-SCONN2A    I12 @S9S_MB_2U_LIB.S9S_MB_2U(SCH_1):PAGE88
    J8  213  CA3_A SCONN288_ADR50017P087CC-SCONN2A    I50 @S9S_MB_2U_LIB.S9S_MB_2U(SCH_1):PAGE89

M_D_CPU0_SA_CA<4> @S9S_MB_2U_LIB.S9S_MB_2U(SCH_1):M_D_CPU0_SA_CA(4)
    U2 AL50 DDR3_SA_CA4 SOCKET4677_AZIF0045P001C01CS-SA   I169 @S9S_MB_2U_LIB.S9S_MB_2U(SCH_1):PAGE23
    J7   70  CA4_A SCONN288_ADR50017P130CC-SCONN2A    I12 @S9S_MB_2U_LIB.S9S_MB_2U(SCH_1):PAGE88
    J8   70  CA4_A SCONN288_ADR50017P087CC-SCONN2A    I50 @S9S_MB_2U_LIB.S9S_MB_2U(SCH_1):PAGE89

M_D_CPU0_SA_CA<5> @S9S_MB_2U_LIB.S9S_MB_2U(SCH_1):M_D_CPU0_SA_CA(5)
    U2 AN50 DDR3_SA_CA5 SOCKET4677_AZIF0045P001C01CS-SA   I169 @S9S_MB_2U_LIB.S9S_MB_2U(SCH_1):PAGE23
    J7  215  CA5_A SCONN288_ADR50017P130CC-SCONN2A    I12 @S9S_MB_2U_LIB.S9S_MB_2U(SCH_1):PAGE88
    J8  215  CA5_A SCONN288_ADR50017P087CC-SCONN2A    I50 @S9S_MB_2U_LIB.S9S_MB_2U(SCH_1):PAGE89

M_D_CPU0_SA_CA<6> @S9S_MB_2U_LIB.S9S_MB_2U(SCH_1):M_D_CPU0_SA_CA(6)
    U2 AN43 DDR3_SA_CA6 SOCKET4677_AZIF0045P001C01CS-SA   I169 @S9S_MB_2U_LIB.S9S_MB_2U(SCH_1):PAGE23
    J7   72  CA6_A SCONN288_ADR50017P130CC-SCONN2A    I12 @S9S_MB_2U_LIB.S9S_MB_2U(SCH_1):PAGE88
    J8   72  CA6_A SCONN288_ADR50017P087CC-SCONN2A    I50 @S9S_MB_2U_LIB.S9S_MB_2U(SCH_1):PAGE89

M_D_CPU0_SA_CB<0> @S9S_MB_2U_LIB.S9S_MB_2U(SCH_1):M_D_CPU0_SA_CB(0)
    U2 AL60 DDR3_SA_ECC0 SOCKET4677_AZIF0045P001C01CS-SA   I169 @S9S_MB_2U_LIB.S9S_MB_2U(SCH_1):PAGE23
    J7   51  CB0_A SCONN288_ADR50017P130CC-SCONN2A    I12 @S9S_MB_2U_LIB.S9S_MB_2U(SCH_1):PAGE88
    J8   51  CB0_A SCONN288_ADR50017P087CC-SCONN2A    I50 @S9S_MB_2U_LIB.S9S_MB_2U(SCH_1):PAGE89

M_D_CPU0_SA_CB<1> @S9S_MB_2U_LIB.S9S_MB_2U(SCH_1):M_D_CPU0_SA_CB(1)
    U2 AK59 DDR3_SA_ECC1 SOCKET4677_AZIF0045P001C01CS-SA   I169 @S9S_MB_2U_LIB.S9S_MB_2U(SCH_1):PAGE23
    J7   53  CB1_A SCONN288_ADR50017P130CC-SCONN2A    I12 @S9S_MB_2U_LIB.S9S_MB_2U(SCH_1):PAGE88
    J8   53  CB1_A SCONN288_ADR50017P087CC-SCONN2A    I50 @S9S_MB_2U_LIB.S9S_MB_2U(SCH_1):PAGE89

M_D_CPU0_SA_CB<2> @S9S_MB_2U_LIB.S9S_MB_2U(SCH_1):M_D_CPU0_SA_CB(2)
    U2 AN60 DDR3_SA_ECC2 SOCKET4677_AZIF0045P001C01CS-SA   I169 @S9S_MB_2U_LIB.S9S_MB_2U(SCH_1):PAGE23
    J7  196  CB2_A SCONN288_ADR50017P130CC-SCONN2A    I12 @S9S_MB_2U_LIB.S9S_MB_2U(SCH_1):PAGE88
    J8  196  CB2_A SCONN288_ADR50017P087CC-SCONN2A    I50 @S9S_MB_2U_LIB.S9S_MB_2U(SCH_1):PAGE89

M_D_CPU0_SA_CB<3> @S9S_MB_2U_LIB.S9S_MB_2U(SCH_1):M_D_CPU0_SA_CB(3)
    U2 AP59 DDR3_SA_ECC3 SOCKET4677_AZIF0045P001C01CS-SA   I169 @S9S_MB_2U_LIB.S9S_MB_2U(SCH_1):PAGE23
    J7  198  CB3_A SCONN288_ADR50017P130CC-SCONN2A    I12 @S9S_MB_2U_LIB.S9S_MB_2U(SCH_1):PAGE88
    J8  198  CB3_A SCONN288_ADR50017P087CC-SCONN2A    I50 @S9S_MB_2U_LIB.S9S_MB_2U(SCH_1):PAGE89

M_D_CPU0_SA_CB<4> @S9S_MB_2U_LIB.S9S_MB_2U(SCH_1):M_D_CPU0_SA_CB(4)
    U2 AK57 DDR3_SA_ECC4 SOCKET4677_AZIF0045P001C01CS-SA   I169 @S9S_MB_2U_LIB.S9S_MB_2U(SCH_1):PAGE23
    J7   58  CB4_A SCONN288_ADR50017P130CC-SCONN2A    I12 @S9S_MB_2U_LIB.S9S_MB_2U(SCH_1):PAGE88
    J8   58  CB4_A SCONN288_ADR50017P087CC-SCONN2A    I50 @S9S_MB_2U_LIB.S9S_MB_2U(SCH_1):PAGE89

M_D_CPU0_SA_CB<5> @S9S_MB_2U_LIB.S9S_MB_2U(SCH_1):M_D_CPU0_SA_CB(5)
    U2 AL56 DDR3_SA_ECC5 SOCKET4677_AZIF0045P001C01CS-SA   I169 @S9S_MB_2U_LIB.S9S_MB_2U(SCH_1):PAGE23
    J7   60  CB5_A SCONN288_ADR50017P130CC-SCONN2A    I12 @S9S_MB_2U_LIB.S9S_MB_2U(SCH_1):PAGE88
    J8   60  CB5_A SCONN288_ADR50017P087CC-SCONN2A    I50 @S9S_MB_2U_LIB.S9S_MB_2U(SCH_1):PAGE89

M_D_CPU0_SA_CB<6> @S9S_MB_2U_LIB.S9S_MB_2U(SCH_1):M_D_CPU0_SA_CB(6)
    U2 AP57 DDR3_SA_ECC6 SOCKET4677_AZIF0045P001C01CS-SA   I169 @S9S_MB_2U_LIB.S9S_MB_2U(SCH_1):PAGE23
    J7  203  CB6_A SCONN288_ADR50017P130CC-SCONN2A    I12 @S9S_MB_2U_LIB.S9S_MB_2U(SCH_1):PAGE88
    J8  203  CB6_A SCONN288_ADR50017P087CC-SCONN2A    I50 @S9S_MB_2U_LIB.S9S_MB_2U(SCH_1):PAGE89

M_D_CPU0_SA_CB<7> @S9S_MB_2U_LIB.S9S_MB_2U(SCH_1):M_D_CPU0_SA_CB(7)
    U2 AN56 DDR3_SA_ECC7 SOCKET4677_AZIF0045P001C01CS-SA   I169 @S9S_MB_2U_LIB.S9S_MB_2U(SCH_1):PAGE23
    J7  205  CB7_A SCONN288_ADR50017P130CC-SCONN2A    I12 @S9S_MB_2U_LIB.S9S_MB_2U(SCH_1):PAGE88
    J8  205  CB7_A SCONN288_ADR50017P087CC-SCONN2A    I50 @S9S_MB_2U_LIB.S9S_MB_2U(SCH_1):PAGE89

M_D_CPU0_SA_CS_N<0> @S9S_MB_2U_LIB.S9S_MB_2U(SCH_1):M_D_CPU0_SA_CS_N(0)
    U2 AL54 DDR3_SA_CS_N0 SOCKET4677_AZIF0045P001C01CS-SA   I169 @S9S_MB_2U_LIB.S9S_MB_2U(SCH_1):PAGE23
    J7   64 CS0_A_N SCONN288_ADR50017P130CC-SCONN2A    I12 @S9S_MB_2U_LIB.S9S_MB_2U(SCH_1):PAGE88

M_D_CPU0_SA_CS_N<1> @S9S_MB_2U_LIB.S9S_MB_2U(SCH_1):M_D_CPU0_SA_CS_N(1)
    U2 AK53 DDR3_SA_CS_N1 SOCKET4677_AZIF0045P001C01CS-SA   I169 @S9S_MB_2U_LIB.S9S_MB_2U(SCH_1):PAGE23
    J7  209 CS1_A_N SCONN288_ADR50017P130CC-SCONN2A    I12 @S9S_MB_2U_LIB.S9S_MB_2U(SCH_1):PAGE88

M_D_CPU0_SA_CS_N<2> @S9S_MB_2U_LIB.S9S_MB_2U(SCH_1):M_D_CPU0_SA_CS_N(2)
    U2 AN54 DDR3_SA_CS_N2 SOCKET4677_AZIF0045P001C01CS-SA   I169 @S9S_MB_2U_LIB.S9S_MB_2U(SCH_1):PAGE23
    J8   64 CS0_A_N SCONN288_ADR50017P087CC-SCONN2A    I50 @S9S_MB_2U_LIB.S9S_MB_2U(SCH_1):PAGE89

M_D_CPU0_SA_CS_N<3> @S9S_MB_2U_LIB.S9S_MB_2U(SCH_1):M_D_CPU0_SA_CS_N(3)
    U2 AP53 DDR3_SA_CS_N3 SOCKET4677_AZIF0045P001C01CS-SA   I169 @S9S_MB_2U_LIB.S9S_MB_2U(SCH_1):PAGE23
    J8  209 CS1_A_N SCONN288_ADR50017P087CC-SCONN2A    I50 @S9S_MB_2U_LIB.S9S_MB_2U(SCH_1):PAGE89

M_D_CPU0_SA_DQ<0> @S9S_MB_2U_LIB.S9S_MB_2U(SCH_1):M_D_CPU0_SA_DQ(0)
    U2 AD75 DDR3_SA_DQ0 SOCKET4677_AZIF0045P001C01CS-SA   I169 @S9S_MB_2U_LIB.S9S_MB_2U(SCH_1):PAGE23
    J7    7  DQ0_A SCONN288_ADR50017P130CC-SCONN2A    I12 @S9S_MB_2U_LIB.S9S_MB_2U(SCH_1):PAGE88
    J8    7  DQ0_A SCONN288_ADR50017P087CC-SCONN2A    I50 @S9S_MB_2U_LIB.S9S_MB_2U(SCH_1):PAGE89

M_D_CPU0_SA_DQ<10> @S9S_MB_2U_LIB.S9S_MB_2U(SCH_1):M_D_CPU0_SA_DQ(10)
    U2 AN78 DDR3_SA_DQ10 SOCKET4677_AZIF0045P001C01CS-SA   I169 @S9S_MB_2U_LIB.S9S_MB_2U(SCH_1):PAGE23
    J7  163 DQ10_A SCONN288_ADR50017P130CC-SCONN2A    I12 @S9S_MB_2U_LIB.S9S_MB_2U(SCH_1):PAGE88
    J8  163 DQ10_A SCONN288_ADR50017P087CC-SCONN2A    I50 @S9S_MB_2U_LIB.S9S_MB_2U(SCH_1):PAGE89

M_D_CPU0_SA_DQ<11> @S9S_MB_2U_LIB.S9S_MB_2U(SCH_1):M_D_CPU0_SA_DQ(11)
    U2 AP77 DDR3_SA_DQ11 SOCKET4677_AZIF0045P001C01CS-SA   I169 @S9S_MB_2U_LIB.S9S_MB_2U(SCH_1):PAGE23
    J7  165 DQ11_A SCONN288_ADR50017P130CC-SCONN2A    I12 @S9S_MB_2U_LIB.S9S_MB_2U(SCH_1):PAGE88
    J8  165 DQ11_A SCONN288_ADR50017P087CC-SCONN2A    I50 @S9S_MB_2U_LIB.S9S_MB_2U(SCH_1):PAGE89

M_D_CPU0_SA_DQ<12> @S9S_MB_2U_LIB.S9S_MB_2U(SCH_1):M_D_CPU0_SA_DQ(12)
    U2 AK75 DDR3_SA_DQ12 SOCKET4677_AZIF0045P001C01CS-SA   I169 @S9S_MB_2U_LIB.S9S_MB_2U(SCH_1):PAGE23
    J7   25 DQ12_A SCONN288_ADR50017P130CC-SCONN2A    I12 @S9S_MB_2U_LIB.S9S_MB_2U(SCH_1):PAGE88
    J8   25 DQ12_A SCONN288_ADR50017P087CC-SCONN2A    I50 @S9S_MB_2U_LIB.S9S_MB_2U(SCH_1):PAGE89

M_D_CPU0_SA_DQ<13> @S9S_MB_2U_LIB.S9S_MB_2U(SCH_1):M_D_CPU0_SA_DQ(13)
    U2 AL74 DDR3_SA_DQ13 SOCKET4677_AZIF0045P001C01CS-SA   I169 @S9S_MB_2U_LIB.S9S_MB_2U(SCH_1):PAGE23
    J7   27 DQ13_A SCONN288_ADR50017P130CC-SCONN2A    I12 @S9S_MB_2U_LIB.S9S_MB_2U(SCH_1):PAGE88
    J8   27 DQ13_A SCONN288_ADR50017P087CC-SCONN2A    I50 @S9S_MB_2U_LIB.S9S_MB_2U(SCH_1):PAGE89

M_D_CPU0_SA_DQ<14> @S9S_MB_2U_LIB.S9S_MB_2U(SCH_1):M_D_CPU0_SA_DQ(14)
    U2 AP75 DDR3_SA_DQ14 SOCKET4677_AZIF0045P001C01CS-SA   I169 @S9S_MB_2U_LIB.S9S_MB_2U(SCH_1):PAGE23
    J7  170 DQ14_A SCONN288_ADR50017P130CC-SCONN2A    I12 @S9S_MB_2U_LIB.S9S_MB_2U(SCH_1):PAGE88
    J8  170 DQ14_A SCONN288_ADR50017P087CC-SCONN2A    I50 @S9S_MB_2U_LIB.S9S_MB_2U(SCH_1):PAGE89

M_D_CPU0_SA_DQ<15> @S9S_MB_2U_LIB.S9S_MB_2U(SCH_1):M_D_CPU0_SA_DQ(15)
    U2 AN74 DDR3_SA_DQ15 SOCKET4677_AZIF0045P001C01CS-SA   I169 @S9S_MB_2U_LIB.S9S_MB_2U(SCH_1):PAGE23
    J7  172 DQ15_A SCONN288_ADR50017P130CC-SCONN2A    I12 @S9S_MB_2U_LIB.S9S_MB_2U(SCH_1):PAGE88
    J8  172 DQ15_A SCONN288_ADR50017P087CC-SCONN2A    I50 @S9S_MB_2U_LIB.S9S_MB_2U(SCH_1):PAGE89

M_D_CPU0_SA_DQ<16> @S9S_MB_2U_LIB.S9S_MB_2U(SCH_1):M_D_CPU0_SA_DQ(16)
    U2 AL72 DDR3_SA_DQ16 SOCKET4677_AZIF0045P001C01CS-SA   I169 @S9S_MB_2U_LIB.S9S_MB_2U(SCH_1):PAGE23
    J7   29 DQ16_A SCONN288_ADR50017P130CC-SCONN2A    I12 @S9S_MB_2U_LIB.S9S_MB_2U(SCH_1):PAGE88
    J8   29 DQ16_A SCONN288_ADR50017P087CC-SCONN2A    I50 @S9S_MB_2U_LIB.S9S_MB_2U(SCH_1):PAGE89

M_D_CPU0_SA_DQ<17> @S9S_MB_2U_LIB.S9S_MB_2U(SCH_1):M_D_CPU0_SA_DQ(17)
    U2 AK71 DDR3_SA_DQ17 SOCKET4677_AZIF0045P001C01CS-SA   I169 @S9S_MB_2U_LIB.S9S_MB_2U(SCH_1):PAGE23
    J7   31 DQ17_A SCONN288_ADR50017P130CC-SCONN2A    I12 @S9S_MB_2U_LIB.S9S_MB_2U(SCH_1):PAGE88
    J8   31 DQ17_A SCONN288_ADR50017P087CC-SCONN2A    I50 @S9S_MB_2U_LIB.S9S_MB_2U(SCH_1):PAGE89

M_D_CPU0_SA_DQ<18> @S9S_MB_2U_LIB.S9S_MB_2U(SCH_1):M_D_CPU0_SA_DQ(18)
    U2 AN72 DDR3_SA_DQ18 SOCKET4677_AZIF0045P001C01CS-SA   I169 @S9S_MB_2U_LIB.S9S_MB_2U(SCH_1):PAGE23
    J7  174 DQ18_A SCONN288_ADR50017P130CC-SCONN2A    I12 @S9S_MB_2U_LIB.S9S_MB_2U(SCH_1):PAGE88
    J8  174 DQ18_A SCONN288_ADR50017P087CC-SCONN2A    I50 @S9S_MB_2U_LIB.S9S_MB_2U(SCH_1):PAGE89

M_D_CPU0_SA_DQ<19> @S9S_MB_2U_LIB.S9S_MB_2U(SCH_1):M_D_CPU0_SA_DQ(19)
    U2 AP71 DDR3_SA_DQ19 SOCKET4677_AZIF0045P001C01CS-SA   I169 @S9S_MB_2U_LIB.S9S_MB_2U(SCH_1):PAGE23
    J7  176 DQ19_A SCONN288_ADR50017P130CC-SCONN2A    I12 @S9S_MB_2U_LIB.S9S_MB_2U(SCH_1):PAGE88
    J8  176 DQ19_A SCONN288_ADR50017P087CC-SCONN2A    I50 @S9S_MB_2U_LIB.S9S_MB_2U(SCH_1):PAGE89

M_D_CPU0_SA_DQ<1> @S9S_MB_2U_LIB.S9S_MB_2U(SCH_1):M_D_CPU0_SA_DQ(1)
    U2 AC74 DDR3_SA_DQ1 SOCKET4677_AZIF0045P001C01CS-SA   I169 @S9S_MB_2U_LIB.S9S_MB_2U(SCH_1):PAGE23
    J7    9  DQ1_A SCONN288_ADR50017P130CC-SCONN2A    I12 @S9S_MB_2U_LIB.S9S_MB_2U(SCH_1):PAGE88
    J8    9  DQ1_A SCONN288_ADR50017P087CC-SCONN2A    I50 @S9S_MB_2U_LIB.S9S_MB_2U(SCH_1):PAGE89

M_D_CPU0_SA_DQ<20> @S9S_MB_2U_LIB.S9S_MB_2U(SCH_1):M_D_CPU0_SA_DQ(20)
    U2 AK69 DDR3_SA_DQ20 SOCKET4677_AZIF0045P001C01CS-SA   I169 @S9S_MB_2U_LIB.S9S_MB_2U(SCH_1):PAGE23
    J7   36 DQ20_A SCONN288_ADR50017P130CC-SCONN2A    I12 @S9S_MB_2U_LIB.S9S_MB_2U(SCH_1):PAGE88
    J8   36 DQ20_A SCONN288_ADR50017P087CC-SCONN2A    I50 @S9S_MB_2U_LIB.S9S_MB_2U(SCH_1):PAGE89

M_D_CPU0_SA_DQ<21> @S9S_MB_2U_LIB.S9S_MB_2U(SCH_1):M_D_CPU0_SA_DQ(21)
    U2 AL68 DDR3_SA_DQ21 SOCKET4677_AZIF0045P001C01CS-SA   I169 @S9S_MB_2U_LIB.S9S_MB_2U(SCH_1):PAGE23
    J7   38 DQ21_A SCONN288_ADR50017P130CC-SCONN2A    I12 @S9S_MB_2U_LIB.S9S_MB_2U(SCH_1):PAGE88
    J8   38 DQ21_A SCONN288_ADR50017P087CC-SCONN2A    I50 @S9S_MB_2U_LIB.S9S_MB_2U(SCH_1):PAGE89

M_D_CPU0_SA_DQ<22> @S9S_MB_2U_LIB.S9S_MB_2U(SCH_1):M_D_CPU0_SA_DQ(22)
    U2 AP69 DDR3_SA_DQ22 SOCKET4677_AZIF0045P001C01CS-SA   I169 @S9S_MB_2U_LIB.S9S_MB_2U(SCH_1):PAGE23
    J7  181 DQ22_A SCONN288_ADR50017P130CC-SCONN2A    I12 @S9S_MB_2U_LIB.S9S_MB_2U(SCH_1):PAGE88
    J8  181 DQ22_A SCONN288_ADR50017P087CC-SCONN2A    I50 @S9S_MB_2U_LIB.S9S_MB_2U(SCH_1):PAGE89

M_D_CPU0_SA_DQ<23> @S9S_MB_2U_LIB.S9S_MB_2U(SCH_1):M_D_CPU0_SA_DQ(23)
    U2 AN68 DDR3_SA_DQ23 SOCKET4677_AZIF0045P001C01CS-SA   I169 @S9S_MB_2U_LIB.S9S_MB_2U(SCH_1):PAGE23
    J7  183 DQ23_A SCONN288_ADR50017P130CC-SCONN2A    I12 @S9S_MB_2U_LIB.S9S_MB_2U(SCH_1):PAGE88
    J8  183 DQ23_A SCONN288_ADR50017P087CC-SCONN2A    I50 @S9S_MB_2U_LIB.S9S_MB_2U(SCH_1):PAGE89

M_D_CPU0_SA_DQ<24> @S9S_MB_2U_LIB.S9S_MB_2U(SCH_1):M_D_CPU0_SA_DQ(24)
    U2 AL66 DDR3_SA_DQ24 SOCKET4677_AZIF0045P001C01CS-SA   I169 @S9S_MB_2U_LIB.S9S_MB_2U(SCH_1):PAGE23
    J7   40 DQ24_A SCONN288_ADR50017P130CC-SCONN2A    I12 @S9S_MB_2U_LIB.S9S_MB_2U(SCH_1):PAGE88
    J8   40 DQ24_A SCONN288_ADR50017P087CC-SCONN2A    I50 @S9S_MB_2U_LIB.S9S_MB_2U(SCH_1):PAGE89

M_D_CPU0_SA_DQ<25> @S9S_MB_2U_LIB.S9S_MB_2U(SCH_1):M_D_CPU0_SA_DQ(25)
    U2 AK65 DDR3_SA_DQ25 SOCKET4677_AZIF0045P001C01CS-SA   I169 @S9S_MB_2U_LIB.S9S_MB_2U(SCH_1):PAGE23
    J7   42 DQ25_A SCONN288_ADR50017P130CC-SCONN2A    I12 @S9S_MB_2U_LIB.S9S_MB_2U(SCH_1):PAGE88
    J8   42 DQ25_A SCONN288_ADR50017P087CC-SCONN2A    I50 @S9S_MB_2U_LIB.S9S_MB_2U(SCH_1):PAGE89

M_D_CPU0_SA_DQ<26> @S9S_MB_2U_LIB.S9S_MB_2U(SCH_1):M_D_CPU0_SA_DQ(26)
    U2 AN66 DDR3_SA_DQ26 SOCKET4677_AZIF0045P001C01CS-SA   I169 @S9S_MB_2U_LIB.S9S_MB_2U(SCH_1):PAGE23
    J7  185 DQ26_A SCONN288_ADR50017P130CC-SCONN2A    I12 @S9S_MB_2U_LIB.S9S_MB_2U(SCH_1):PAGE88
    J8  185 DQ26_A SCONN288_ADR50017P087CC-SCONN2A    I50 @S9S_MB_2U_LIB.S9S_MB_2U(SCH_1):PAGE89

M_D_CPU0_SA_DQ<27> @S9S_MB_2U_LIB.S9S_MB_2U(SCH_1):M_D_CPU0_SA_DQ(27)
    U2 AP65 DDR3_SA_DQ27 SOCKET4677_AZIF0045P001C01CS-SA   I169 @S9S_MB_2U_LIB.S9S_MB_2U(SCH_1):PAGE23
    J7  187 DQ27_A SCONN288_ADR50017P130CC-SCONN2A    I12 @S9S_MB_2U_LIB.S9S_MB_2U(SCH_1):PAGE88
    J8  187 DQ27_A SCONN288_ADR50017P087CC-SCONN2A    I50 @S9S_MB_2U_LIB.S9S_MB_2U(SCH_1):PAGE89

M_D_CPU0_SA_DQ<28> @S9S_MB_2U_LIB.S9S_MB_2U(SCH_1):M_D_CPU0_SA_DQ(28)
    U2 AK63 DDR3_SA_DQ28 SOCKET4677_AZIF0045P001C01CS-SA   I169 @S9S_MB_2U_LIB.S9S_MB_2U(SCH_1):PAGE23
    J7   47 DQ28_A SCONN288_ADR50017P130CC-SCONN2A    I12 @S9S_MB_2U_LIB.S9S_MB_2U(SCH_1):PAGE88
    J8   47 DQ28_A SCONN288_ADR50017P087CC-SCONN2A    I50 @S9S_MB_2U_LIB.S9S_MB_2U(SCH_1):PAGE89

M_D_CPU0_SA_DQ<29> @S9S_MB_2U_LIB.S9S_MB_2U(SCH_1):M_D_CPU0_SA_DQ(29)
    U2 AL62 DDR3_SA_DQ29 SOCKET4677_AZIF0045P001C01CS-SA   I169 @S9S_MB_2U_LIB.S9S_MB_2U(SCH_1):PAGE23
    J7   49 DQ29_A SCONN288_ADR50017P130CC-SCONN2A    I12 @S9S_MB_2U_LIB.S9S_MB_2U(SCH_1):PAGE88
    J8   49 DQ29_A SCONN288_ADR50017P087CC-SCONN2A    I50 @S9S_MB_2U_LIB.S9S_MB_2U(SCH_1):PAGE89

M_D_CPU0_SA_DQ<2> @S9S_MB_2U_LIB.S9S_MB_2U(SCH_1):M_D_CPU0_SA_DQ(2)
    U2 AF75 DDR3_SA_DQ2 SOCKET4677_AZIF0045P001C01CS-SA   I169 @S9S_MB_2U_LIB.S9S_MB_2U(SCH_1):PAGE23
    J7  152  DQ2_A SCONN288_ADR50017P130CC-SCONN2A    I12 @S9S_MB_2U_LIB.S9S_MB_2U(SCH_1):PAGE88
    J8  152  DQ2_A SCONN288_ADR50017P087CC-SCONN2A    I50 @S9S_MB_2U_LIB.S9S_MB_2U(SCH_1):PAGE89

M_D_CPU0_SA_DQ<30> @S9S_MB_2U_LIB.S9S_MB_2U(SCH_1):M_D_CPU0_SA_DQ(30)
    U2 AP63 DDR3_SA_DQ30 SOCKET4677_AZIF0045P001C01CS-SA   I169 @S9S_MB_2U_LIB.S9S_MB_2U(SCH_1):PAGE23
    J7  192 DQ30_A SCONN288_ADR50017P130CC-SCONN2A    I12 @S9S_MB_2U_LIB.S9S_MB_2U(SCH_1):PAGE88
    J8  192 DQ30_A SCONN288_ADR50017P087CC-SCONN2A    I50 @S9S_MB_2U_LIB.S9S_MB_2U(SCH_1):PAGE89

M_D_CPU0_SA_DQ<31> @S9S_MB_2U_LIB.S9S_MB_2U(SCH_1):M_D_CPU0_SA_DQ(31)
    U2 AN62 DDR3_SA_DQ31 SOCKET4677_AZIF0045P001C01CS-SA   I169 @S9S_MB_2U_LIB.S9S_MB_2U(SCH_1):PAGE23
    J7  194 DQ31_A SCONN288_ADR50017P130CC-SCONN2A    I12 @S9S_MB_2U_LIB.S9S_MB_2U(SCH_1):PAGE88
    J8  194 DQ31_A SCONN288_ADR50017P087CC-SCONN2A    I50 @S9S_MB_2U_LIB.S9S_MB_2U(SCH_1):PAGE89

M_D_CPU0_SA_DQ<3> @S9S_MB_2U_LIB.S9S_MB_2U(SCH_1):M_D_CPU0_SA_DQ(3)
    U2 AG74 DDR3_SA_DQ3 SOCKET4677_AZIF0045P001C01CS-SA   I169 @S9S_MB_2U_LIB.S9S_MB_2U(SCH_1):PAGE23
    J7  154  DQ3_A SCONN288_ADR50017P130CC-SCONN2A    I12 @S9S_MB_2U_LIB.S9S_MB_2U(SCH_1):PAGE88
    J8  154  DQ3_A SCONN288_ADR50017P087CC-SCONN2A    I50 @S9S_MB_2U_LIB.S9S_MB_2U(SCH_1):PAGE89

M_D_CPU0_SA_DQ<4> @S9S_MB_2U_LIB.S9S_MB_2U(SCH_1):M_D_CPU0_SA_DQ(4)
    U2 AC72 DDR3_SA_DQ4 SOCKET4677_AZIF0045P001C01CS-SA   I169 @S9S_MB_2U_LIB.S9S_MB_2U(SCH_1):PAGE23
    J7   14  DQ4_A SCONN288_ADR50017P130CC-SCONN2A    I12 @S9S_MB_2U_LIB.S9S_MB_2U(SCH_1):PAGE88
    J8   14  DQ4_A SCONN288_ADR50017P087CC-SCONN2A    I50 @S9S_MB_2U_LIB.S9S_MB_2U(SCH_1):PAGE89

M_D_CPU0_SA_DQ<5> @S9S_MB_2U_LIB.S9S_MB_2U(SCH_1):M_D_CPU0_SA_DQ(5)
    U2 AD71 DDR3_SA_DQ5 SOCKET4677_AZIF0045P001C01CS-SA   I169 @S9S_MB_2U_LIB.S9S_MB_2U(SCH_1):PAGE23
    J7   16  DQ5_A SCONN288_ADR50017P130CC-SCONN2A    I12 @S9S_MB_2U_LIB.S9S_MB_2U(SCH_1):PAGE88
    J8   16  DQ5_A SCONN288_ADR50017P087CC-SCONN2A    I50 @S9S_MB_2U_LIB.S9S_MB_2U(SCH_1):PAGE89

M_D_CPU0_SA_DQ<6> @S9S_MB_2U_LIB.S9S_MB_2U(SCH_1):M_D_CPU0_SA_DQ(6)
    U2 AG72 DDR3_SA_DQ6 SOCKET4677_AZIF0045P001C01CS-SA   I169 @S9S_MB_2U_LIB.S9S_MB_2U(SCH_1):PAGE23
    J7  159  DQ6_A SCONN288_ADR50017P130CC-SCONN2A    I12 @S9S_MB_2U_LIB.S9S_MB_2U(SCH_1):PAGE88
    J8  159  DQ6_A SCONN288_ADR50017P087CC-SCONN2A    I50 @S9S_MB_2U_LIB.S9S_MB_2U(SCH_1):PAGE89

M_D_CPU0_SA_DQ<7> @S9S_MB_2U_LIB.S9S_MB_2U(SCH_1):M_D_CPU0_SA_DQ(7)
    U2 AF71 DDR3_SA_DQ7 SOCKET4677_AZIF0045P001C01CS-SA   I169 @S9S_MB_2U_LIB.S9S_MB_2U(SCH_1):PAGE23
    J7  161  DQ7_A SCONN288_ADR50017P130CC-SCONN2A    I12 @S9S_MB_2U_LIB.S9S_MB_2U(SCH_1):PAGE88
    J8  161  DQ7_A SCONN288_ADR50017P087CC-SCONN2A    I50 @S9S_MB_2U_LIB.S9S_MB_2U(SCH_1):PAGE89

M_D_CPU0_SA_DQ<8> @S9S_MB_2U_LIB.S9S_MB_2U(SCH_1):M_D_CPU0_SA_DQ(8)
    U2 AL78 DDR3_SA_DQ8 SOCKET4677_AZIF0045P001C01CS-SA   I169 @S9S_MB_2U_LIB.S9S_MB_2U(SCH_1):PAGE23
    J7   18  DQ8_A SCONN288_ADR50017P130CC-SCONN2A    I12 @S9S_MB_2U_LIB.S9S_MB_2U(SCH_1):PAGE88
    J8   18  DQ8_A SCONN288_ADR50017P087CC-SCONN2A    I50 @S9S_MB_2U_LIB.S9S_MB_2U(SCH_1):PAGE89

M_D_CPU0_SA_DQ<9> @S9S_MB_2U_LIB.S9S_MB_2U(SCH_1):M_D_CPU0_SA_DQ(9)
    U2 AK77 DDR3_SA_DQ9 SOCKET4677_AZIF0045P001C01CS-SA   I169 @S9S_MB_2U_LIB.S9S_MB_2U(SCH_1):PAGE23
    J7   20  DQ9_A SCONN288_ADR50017P130CC-SCONN2A    I12 @S9S_MB_2U_LIB.S9S_MB_2U(SCH_1):PAGE88
    J8   20  DQ9_A SCONN288_ADR50017P087CC-SCONN2A    I50 @S9S_MB_2U_LIB.S9S_MB_2U(SCH_1):PAGE89

M_D_CPU0_SA_DQS_DN<0> @S9S_MB_2U_LIB.S9S_MB_2U(SCH_1):M_D_CPU0_SA_DQS_DN(0)
    U2 AB73 DDR3_SA_DQS_DN0 SOCKET4677_AZIF0045P001C01CS-SA   I169 @S9S_MB_2U_LIB.S9S_MB_2U(SCH_1):PAGE23
    J7   12 DQS0_A_C SCONN288_ADR50017P130CC-SCONN2A   I178 @S9S_MB_2U_LIB.S9S_MB_2U(SCH_1):PAGE88
    J8   12 DQS0_A_C SCONN288_ADR50017P087CC-SCONN2A   I178 @S9S_MB_2U_LIB.S9S_MB_2U(SCH_1):PAGE89

M_D_CPU0_SA_DQS_DN<1> @S9S_MB_2U_LIB.S9S_MB_2U(SCH_1):M_D_CPU0_SA_DQS_DN(1)
    U2 AJ76 DDR3_SA_DQS_DN1 SOCKET4677_AZIF0045P001C01CS-SA   I169 @S9S_MB_2U_LIB.S9S_MB_2U(SCH_1):PAGE23
    J7   23 DQS1_A_C SCONN288_ADR50017P130CC-SCONN2A   I178 @S9S_MB_2U_LIB.S9S_MB_2U(SCH_1):PAGE88
    J8   23 DQS1_A_C SCONN288_ADR50017P087CC-SCONN2A   I178 @S9S_MB_2U_LIB.S9S_MB_2U(SCH_1):PAGE89

M_D_CPU0_SA_DQS_DN<2> @S9S_MB_2U_LIB.S9S_MB_2U(SCH_1):M_D_CPU0_SA_DQS_DN(2)
    U2 AJ70 DDR3_SA_DQS_DN2 SOCKET4677_AZIF0045P001C01CS-SA   I169 @S9S_MB_2U_LIB.S9S_MB_2U(SCH_1):PAGE23
    J7   34 DQS2_A_C SCONN288_ADR50017P130CC-SCONN2A   I178 @S9S_MB_2U_LIB.S9S_MB_2U(SCH_1):PAGE88
    J8   34 DQS2_A_C SCONN288_ADR50017P087CC-SCONN2A   I178 @S9S_MB_2U_LIB.S9S_MB_2U(SCH_1):PAGE89

M_D_CPU0_SA_DQS_DN<3> @S9S_MB_2U_LIB.S9S_MB_2U(SCH_1):M_D_CPU0_SA_DQS_DN(3)
    U2 AJ64 DDR3_SA_DQS_DN3 SOCKET4677_AZIF0045P001C01CS-SA   I169 @S9S_MB_2U_LIB.S9S_MB_2U(SCH_1):PAGE23
    J7   45 DQS3_A_C SCONN288_ADR50017P130CC-SCONN2A   I178 @S9S_MB_2U_LIB.S9S_MB_2U(SCH_1):PAGE88
    J8   45 DQS3_A_C SCONN288_ADR50017P087CC-SCONN2A   I178 @S9S_MB_2U_LIB.S9S_MB_2U(SCH_1):PAGE89

M_D_CPU0_SA_DQS_DN<4> @S9S_MB_2U_LIB.S9S_MB_2U(SCH_1):M_D_CPU0_SA_DQS_DN(4)
    U2 AJ58 DDR3_SA_DQS_DN4 SOCKET4677_AZIF0045P001C01CS-SA   I169 @S9S_MB_2U_LIB.S9S_MB_2U(SCH_1):PAGE23
    J7   56 DQS4_A_C SCONN288_ADR50017P130CC-SCONN2A   I178 @S9S_MB_2U_LIB.S9S_MB_2U(SCH_1):PAGE88
    J8   56 DQS4_A_C SCONN288_ADR50017P087CC-SCONN2A   I178 @S9S_MB_2U_LIB.S9S_MB_2U(SCH_1):PAGE89

M_D_CPU0_SA_DQS_DN<5> @S9S_MB_2U_LIB.S9S_MB_2U(SCH_1):M_D_CPU0_SA_DQS_DN(5)
    U2 AH73 DDR3_SA_DQS_DN5 SOCKET4677_AZIF0045P001C01CS-SA   I169 @S9S_MB_2U_LIB.S9S_MB_2U(SCH_1):PAGE23
    J7  156 DQS5_A_C||TDQS5_A_C||DQS5_A_T||TDQS5_A_T SCONN288_ADR50017P130CC-SCONN2A   I178 @S9S_MB_2U_LIB.S9S_MB_2U(SCH_1):PAGE88
    J8  156 DQS5_A_C||TDQS5_A_C||DQS5_A_T||TDQS5_A_T SCONN288_ADR50017P087CC-SCONN2A   I178 @S9S_MB_2U_LIB.S9S_MB_2U(SCH_1):PAGE89

M_D_CPU0_SA_DQS_DN<6> @S9S_MB_2U_LIB.S9S_MB_2U(SCH_1):M_D_CPU0_SA_DQS_DN(6)
    U2 AN76 DDR3_SA_DQS_DN6 SOCKET4677_AZIF0045P001C01CS-SA   I169 @S9S_MB_2U_LIB.S9S_MB_2U(SCH_1):PAGE23
    J7  167 DQS6_A_C||TDQS6_A_C||DQS6_A_T||TDQS6_A_T SCONN288_ADR50017P130CC-SCONN2A   I178 @S9S_MB_2U_LIB.S9S_MB_2U(SCH_1):PAGE88
    J8  167 DQS6_A_C||TDQS6_A_C||DQS6_A_T||TDQS6_A_T SCONN288_ADR50017P087CC-SCONN2A   I178 @S9S_MB_2U_LIB.S9S_MB_2U(SCH_1):PAGE89

M_D_CPU0_SA_DQS_DN<7> @S9S_MB_2U_LIB.S9S_MB_2U(SCH_1):M_D_CPU0_SA_DQS_DN(7)
    U2 AN70 DDR3_SA_DQS_DN7 SOCKET4677_AZIF0045P001C01CS-SA   I169 @S9S_MB_2U_LIB.S9S_MB_2U(SCH_1):PAGE23
    J7  178 DQS7_A_C||TDQS7_A_C SCONN288_ADR50017P130CC-SCONN2A   I178 @S9S_MB_2U_LIB.S9S_MB_2U(SCH_1):PAGE88
    J8  178 DQS7_A_C||TDQS7_A_C SCONN288_ADR50017P087CC-SCONN2A   I178 @S9S_MB_2U_LIB.S9S_MB_2U(SCH_1):PAGE89

M_D_CPU0_SA_DQS_DN<8> @S9S_MB_2U_LIB.S9S_MB_2U(SCH_1):M_D_CPU0_SA_DQS_DN(8)
    U2 AN64 DDR3_SA_DQS_DN8 SOCKET4677_AZIF0045P001C01CS-SA   I169 @S9S_MB_2U_LIB.S9S_MB_2U(SCH_1):PAGE23
    J7  189 DQS8_A_C||TDQS8_A_C SCONN288_ADR50017P130CC-SCONN2A   I178 @S9S_MB_2U_LIB.S9S_MB_2U(SCH_1):PAGE88
    J8  189 DQS8_A_C||TDQS8_A_C SCONN288_ADR50017P087CC-SCONN2A   I178 @S9S_MB_2U_LIB.S9S_MB_2U(SCH_1):PAGE89

M_D_CPU0_SA_DQS_DN<9> @S9S_MB_2U_LIB.S9S_MB_2U(SCH_1):M_D_CPU0_SA_DQS_DN(9)
    U2 AN58 DDR3_SA_DQS_DN9 SOCKET4677_AZIF0045P001C01CS-SA   I169 @S9S_MB_2U_LIB.S9S_MB_2U(SCH_1):PAGE23
    J7  200 DQS9_A_C||TDQS9_A_C SCONN288_ADR50017P130CC-SCONN2A   I178 @S9S_MB_2U_LIB.S9S_MB_2U(SCH_1):PAGE88
    J8  200 DQS9_A_C||TDQS9_A_C SCONN288_ADR50017P087CC-SCONN2A   I178 @S9S_MB_2U_LIB.S9S_MB_2U(SCH_1):PAGE89

M_D_CPU0_SA_DQS_DP<0> @S9S_MB_2U_LIB.S9S_MB_2U(SCH_1):M_D_CPU0_SA_DQS_DP(0)
    U2 AD73 DDR3_SA_DQS_DP0 SOCKET4677_AZIF0045P001C01CS-SA   I169 @S9S_MB_2U_LIB.S9S_MB_2U(SCH_1):PAGE23
    J7   11 DQS0_A_T SCONN288_ADR50017P130CC-SCONN2A   I178 @S9S_MB_2U_LIB.S9S_MB_2U(SCH_1):PAGE88
    J8   11 DQS0_A_T SCONN288_ADR50017P087CC-SCONN2A   I178 @S9S_MB_2U_LIB.S9S_MB_2U(SCH_1):PAGE89

M_D_CPU0_SA_DQS_DP<1> @S9S_MB_2U_LIB.S9S_MB_2U(SCH_1):M_D_CPU0_SA_DQS_DP(1)
    U2 AL76 DDR3_SA_DQS_DP1 SOCKET4677_AZIF0045P001C01CS-SA   I169 @S9S_MB_2U_LIB.S9S_MB_2U(SCH_1):PAGE23
    J7   22 DQS1_A_T SCONN288_ADR50017P130CC-SCONN2A   I178 @S9S_MB_2U_LIB.S9S_MB_2U(SCH_1):PAGE88
    J8   22 DQS1_A_T SCONN288_ADR50017P087CC-SCONN2A   I178 @S9S_MB_2U_LIB.S9S_MB_2U(SCH_1):PAGE89

M_D_CPU0_SA_DQS_DP<2> @S9S_MB_2U_LIB.S9S_MB_2U(SCH_1):M_D_CPU0_SA_DQS_DP(2)
    U2 AL70 DDR3_SA_DQS_DP2 SOCKET4677_AZIF0045P001C01CS-SA   I169 @S9S_MB_2U_LIB.S9S_MB_2U(SCH_1):PAGE23
    J7   33 DQS2_A_T SCONN288_ADR50017P130CC-SCONN2A   I178 @S9S_MB_2U_LIB.S9S_MB_2U(SCH_1):PAGE88
    J8   33 DQS2_A_T SCONN288_ADR50017P087CC-SCONN2A   I178 @S9S_MB_2U_LIB.S9S_MB_2U(SCH_1):PAGE89

M_D_CPU0_SA_DQS_DP<3> @S9S_MB_2U_LIB.S9S_MB_2U(SCH_1):M_D_CPU0_SA_DQS_DP(3)
    U2 AL64 DDR3_SA_DQS_DP3 SOCKET4677_AZIF0045P001C01CS-SA   I169 @S9S_MB_2U_LIB.S9S_MB_2U(SCH_1):PAGE23
    J7   44 DQS3_A_T SCONN288_ADR50017P130CC-SCONN2A   I178 @S9S_MB_2U_LIB.S9S_MB_2U(SCH_1):PAGE88
    J8   44 DQS3_A_T SCONN288_ADR50017P087CC-SCONN2A   I178 @S9S_MB_2U_LIB.S9S_MB_2U(SCH_1):PAGE89

M_D_CPU0_SA_DQS_DP<4> @S9S_MB_2U_LIB.S9S_MB_2U(SCH_1):M_D_CPU0_SA_DQS_DP(4)
    U2 AL58 DDR3_SA_DQS_DP4 SOCKET4677_AZIF0045P001C01CS-SA   I169 @S9S_MB_2U_LIB.S9S_MB_2U(SCH_1):PAGE23
    J7   55 DQS4_A_T SCONN288_ADR50017P130CC-SCONN2A   I178 @S9S_MB_2U_LIB.S9S_MB_2U(SCH_1):PAGE88
    J8   55 DQS4_A_T SCONN288_ADR50017P087CC-SCONN2A   I178 @S9S_MB_2U_LIB.S9S_MB_2U(SCH_1):PAGE89

M_D_CPU0_SA_DQS_DP<5> @S9S_MB_2U_LIB.S9S_MB_2U(SCH_1):M_D_CPU0_SA_DQS_DP(5)
    U2 AF73 DDR3_SA_DQS_DP5 SOCKET4677_AZIF0045P001C01CS-SA   I169 @S9S_MB_2U_LIB.S9S_MB_2U(SCH_1):PAGE23
    J7  157 DQS5_A_T||TDQS5_A_T SCONN288_ADR50017P130CC-SCONN2A   I178 @S9S_MB_2U_LIB.S9S_MB_2U(SCH_1):PAGE88
    J8  157 DQS5_A_T||TDQS5_A_T SCONN288_ADR50017P087CC-SCONN2A   I178 @S9S_MB_2U_LIB.S9S_MB_2U(SCH_1):PAGE89

M_D_CPU0_SA_DQS_DP<6> @S9S_MB_2U_LIB.S9S_MB_2U(SCH_1):M_D_CPU0_SA_DQS_DP(6)
    U2 AR76 DDR3_SA_DQS_DP6 SOCKET4677_AZIF0045P001C01CS-SA   I169 @S9S_MB_2U_LIB.S9S_MB_2U(SCH_1):PAGE23
    J7  168 DQS6_A_T||TDQS6_A_T SCONN288_ADR50017P130CC-SCONN2A   I178 @S9S_MB_2U_LIB.S9S_MB_2U(SCH_1):PAGE88
    J8  168 DQS6_A_T||TDQS6_A_T SCONN288_ADR50017P087CC-SCONN2A   I178 @S9S_MB_2U_LIB.S9S_MB_2U(SCH_1):PAGE89

M_D_CPU0_SA_DQS_DP<7> @S9S_MB_2U_LIB.S9S_MB_2U(SCH_1):M_D_CPU0_SA_DQS_DP(7)
    U2 AR70 DDR3_SA_DQS_DP7 SOCKET4677_AZIF0045P001C01CS-SA   I169 @S9S_MB_2U_LIB.S9S_MB_2U(SCH_1):PAGE23
    J7  179 DQS7_A_T||TDQS7_A_T SCONN288_ADR50017P130CC-SCONN2A   I178 @S9S_MB_2U_LIB.S9S_MB_2U(SCH_1):PAGE88
    J8  179 DQS7_A_T||TDQS7_A_T SCONN288_ADR50017P087CC-SCONN2A   I178 @S9S_MB_2U_LIB.S9S_MB_2U(SCH_1):PAGE89

M_D_CPU0_SA_DQS_DP<8> @S9S_MB_2U_LIB.S9S_MB_2U(SCH_1):M_D_CPU0_SA_DQS_DP(8)
    U2 AR64 DDR3_SA_DQS_DP8 SOCKET4677_AZIF0045P001C01CS-SA   I169 @S9S_MB_2U_LIB.S9S_MB_2U(SCH_1):PAGE23
    J7  190 DQS8_A_T||TDQS8_A_T SCONN288_ADR50017P130CC-SCONN2A   I178 @S9S_MB_2U_LIB.S9S_MB_2U(SCH_1):PAGE88
    J8  190 DQS8_A_T||TDQS8_A_T SCONN288_ADR50017P087CC-SCONN2A   I178 @S9S_MB_2U_LIB.S9S_MB_2U(SCH_1):PAGE89

M_D_CPU0_SA_DQS_DP<9> @S9S_MB_2U_LIB.S9S_MB_2U(SCH_1):M_D_CPU0_SA_DQS_DP(9)
    U2 AR58 DDR3_SA_DQS_DP9 SOCKET4677_AZIF0045P001C01CS-SA   I169 @S9S_MB_2U_LIB.S9S_MB_2U(SCH_1):PAGE23
    J7  201 DQS9_A_T||TDQS9_A_T SCONN288_ADR50017P130CC-SCONN2A   I178 @S9S_MB_2U_LIB.S9S_MB_2U(SCH_1):PAGE88
    J8  201 DQS9_A_T||TDQS9_A_T SCONN288_ADR50017P087CC-SCONN2A   I178 @S9S_MB_2U_LIB.S9S_MB_2U(SCH_1):PAGE89

M_D_CPU0_SA_PAR @S9S_MB_2U_LIB.S9S_MB_2U(SCH_1):M_D_CPU0_SA_PAR
    U2 AP44 DDR3_SA_PAR SOCKET4677_AZIF0045P001C01CS-SA   I169 @S9S_MB_2U_LIB.S9S_MB_2U(SCH_1):PAGE23
    J7   74  PAR_A SCONN288_ADR50017P130CC-SCONN2A    I12 @S9S_MB_2U_LIB.S9S_MB_2U(SCH_1):PAGE88
    J8   74  PAR_A SCONN288_ADR50017P087CC-SCONN2A    I50 @S9S_MB_2U_LIB.S9S_MB_2U(SCH_1):PAGE89

M_D_CPU0_SA_RSP<0> @S9S_MB_2U_LIB.S9S_MB_2U(SCH_1):M_D_CPU0_SA_RSP(0)
    U2 AD51 DDR3_A_RSP0 SOCKET4677_AZIF0045P001C01CS-SA   I169 @S9S_MB_2U_LIB.S9S_MB_2U(SCH_1):PAGE23
    J7   86 LBD||RSP_A_N SCONN288_ADR50017P130CC-SCONN2A    I12 @S9S_MB_2U_LIB.S9S_MB_2U(SCH_1):PAGE88

M_D_CPU0_SA_RSP<1> @S9S_MB_2U_LIB.S9S_MB_2U(SCH_1):M_D_CPU0_SA_RSP(1)
    U2 AC50 DDR3_A_RSP1 SOCKET4677_AZIF0045P001C01CS-SA   I169 @S9S_MB_2U_LIB.S9S_MB_2U(SCH_1):PAGE23
    J8   86 LBD||RSP_A_N SCONN288_ADR50017P087CC-SCONN2A    I50 @S9S_MB_2U_LIB.S9S_MB_2U(SCH_1):PAGE89

M_D_CPU0_SB_CA<0> @S9S_MB_2U_LIB.S9S_MB_2U(SCH_1):M_D_CPU0_SB_CA(0)
    U2 AK44 DDR3_SB_CA0 SOCKET4677_AZIF0045P001C01CS-SA   I169 @S9S_MB_2U_LIB.S9S_MB_2U(SCH_1):PAGE23
    J7   76  CA0_B SCONN288_ADR50017P130CC-SCONN2A    I12 @S9S_MB_2U_LIB.S9S_MB_2U(SCH_1):PAGE88
    J8   76  CA0_B SCONN288_ADR50017P087CC-SCONN2A    I50 @S9S_MB_2U_LIB.S9S_MB_2U(SCH_1):PAGE89

M_D_CPU0_SB_CA<1> @S9S_MB_2U_LIB.S9S_MB_2U(SCH_1):M_D_CPU0_SB_CA(1)
    U2 AL43 DDR3_SB_CA1 SOCKET4677_AZIF0045P001C01CS-SA   I169 @S9S_MB_2U_LIB.S9S_MB_2U(SCH_1):PAGE23
    J7  221  CA1_B SCONN288_ADR50017P130CC-SCONN2A    I12 @S9S_MB_2U_LIB.S9S_MB_2U(SCH_1):PAGE88
    J8  221  CA1_B SCONN288_ADR50017P087CC-SCONN2A    I50 @S9S_MB_2U_LIB.S9S_MB_2U(SCH_1):PAGE89

M_D_CPU0_SB_CA<2> @S9S_MB_2U_LIB.S9S_MB_2U(SCH_1):M_D_CPU0_SB_CA(2)
    U2 AD44 DDR3_SB_CA2 SOCKET4677_AZIF0045P001C01CS-SA   I169 @S9S_MB_2U_LIB.S9S_MB_2U(SCH_1):PAGE23
    J7   78  CA2_B SCONN288_ADR50017P130CC-SCONN2A    I12 @S9S_MB_2U_LIB.S9S_MB_2U(SCH_1):PAGE88
    J8   78  CA2_B SCONN288_ADR50017P087CC-SCONN2A    I50 @S9S_MB_2U_LIB.S9S_MB_2U(SCH_1):PAGE89

M_D_CPU0_SB_CA<3> @S9S_MB_2U_LIB.S9S_MB_2U(SCH_1):M_D_CPU0_SB_CA(3)
    U2 AF44 DDR3_SB_CA3 SOCKET4677_AZIF0045P001C01CS-SA   I169 @S9S_MB_2U_LIB.S9S_MB_2U(SCH_1):PAGE23
    J7  223  CA3_B SCONN288_ADR50017P130CC-SCONN2A    I12 @S9S_MB_2U_LIB.S9S_MB_2U(SCH_1):PAGE88
    J8  223  CA3_B SCONN288_ADR50017P087CC-SCONN2A    I50 @S9S_MB_2U_LIB.S9S_MB_2U(SCH_1):PAGE89

M_D_CPU0_SB_CA<4> @S9S_MB_2U_LIB.S9S_MB_2U(SCH_1):M_D_CPU0_SB_CA(4)
    U2 AC43 DDR3_SB_CA4 SOCKET4677_AZIF0045P001C01CS-SA   I169 @S9S_MB_2U_LIB.S9S_MB_2U(SCH_1):PAGE23
    J7   80  CA4_B SCONN288_ADR50017P130CC-SCONN2A    I12 @S9S_MB_2U_LIB.S9S_MB_2U(SCH_1):PAGE88
    J8   80  CA4_B SCONN288_ADR50017P087CC-SCONN2A    I50 @S9S_MB_2U_LIB.S9S_MB_2U(SCH_1):PAGE89

M_D_CPU0_SB_CA<5> @S9S_MB_2U_LIB.S9S_MB_2U(SCH_1):M_D_CPU0_SB_CA(5)
    U2 AG43 DDR3_SB_CA5 SOCKET4677_AZIF0045P001C01CS-SA   I169 @S9S_MB_2U_LIB.S9S_MB_2U(SCH_1):PAGE23
    J7  225  CA5_B SCONN288_ADR50017P130CC-SCONN2A    I12 @S9S_MB_2U_LIB.S9S_MB_2U(SCH_1):PAGE88
    J8  225  CA5_B SCONN288_ADR50017P087CC-SCONN2A    I50 @S9S_MB_2U_LIB.S9S_MB_2U(SCH_1):PAGE89

M_D_CPU0_SB_CA<6> @S9S_MB_2U_LIB.S9S_MB_2U(SCH_1):M_D_CPU0_SB_CA(6)
    U2 AB42 DDR3_SB_CA6 SOCKET4677_AZIF0045P001C01CS-SA   I169 @S9S_MB_2U_LIB.S9S_MB_2U(SCH_1):PAGE23
    J7   82  CA6_B SCONN288_ADR50017P130CC-SCONN2A    I12 @S9S_MB_2U_LIB.S9S_MB_2U(SCH_1):PAGE88
    J8   82  CA6_B SCONN288_ADR50017P087CC-SCONN2A    I50 @S9S_MB_2U_LIB.S9S_MB_2U(SCH_1):PAGE89

M_D_CPU0_SB_CB<0> @S9S_MB_2U_LIB.S9S_MB_2U(SCH_1):M_D_CPU0_SB_CB(0)
    U2 AK38 DDR3_SB_ECC0 SOCKET4677_AZIF0045P001C01CS-SA   I169 @S9S_MB_2U_LIB.S9S_MB_2U(SCH_1):PAGE23
    J7   96  CB0_B SCONN288_ADR50017P130CC-SCONN2A    I12 @S9S_MB_2U_LIB.S9S_MB_2U(SCH_1):PAGE88
    J8   96  CB0_B SCONN288_ADR50017P087CC-SCONN2A    I50 @S9S_MB_2U_LIB.S9S_MB_2U(SCH_1):PAGE89

M_D_CPU0_SB_CB<1> @S9S_MB_2U_LIB.S9S_MB_2U(SCH_1):M_D_CPU0_SB_CB(1)
    U2 AL37 DDR3_SB_ECC1 SOCKET4677_AZIF0045P001C01CS-SA   I169 @S9S_MB_2U_LIB.S9S_MB_2U(SCH_1):PAGE23
    J7   98  CB1_B SCONN288_ADR50017P130CC-SCONN2A    I12 @S9S_MB_2U_LIB.S9S_MB_2U(SCH_1):PAGE88
    J8   98  CB1_B SCONN288_ADR50017P087CC-SCONN2A    I50 @S9S_MB_2U_LIB.S9S_MB_2U(SCH_1):PAGE89

M_D_CPU0_SB_CB<2> @S9S_MB_2U_LIB.S9S_MB_2U(SCH_1):M_D_CPU0_SB_CB(2)
    U2 AP38 DDR3_SB_ECC2 SOCKET4677_AZIF0045P001C01CS-SA   I169 @S9S_MB_2U_LIB.S9S_MB_2U(SCH_1):PAGE23
    J7  241  CB2_B SCONN288_ADR50017P130CC-SCONN2A    I12 @S9S_MB_2U_LIB.S9S_MB_2U(SCH_1):PAGE88
    J8  241  CB2_B SCONN288_ADR50017P087CC-SCONN2A    I50 @S9S_MB_2U_LIB.S9S_MB_2U(SCH_1):PAGE89

M_D_CPU0_SB_CB<3> @S9S_MB_2U_LIB.S9S_MB_2U(SCH_1):M_D_CPU0_SB_CB(3)
    U2 AN37 DDR3_SB_ECC3 SOCKET4677_AZIF0045P001C01CS-SA   I169 @S9S_MB_2U_LIB.S9S_MB_2U(SCH_1):PAGE23
    J7  243  CB3_B SCONN288_ADR50017P130CC-SCONN2A    I12 @S9S_MB_2U_LIB.S9S_MB_2U(SCH_1):PAGE88
    J8  243  CB3_B SCONN288_ADR50017P087CC-SCONN2A    I50 @S9S_MB_2U_LIB.S9S_MB_2U(SCH_1):PAGE89

M_D_CPU0_SB_CB<4> @S9S_MB_2U_LIB.S9S_MB_2U(SCH_1):M_D_CPU0_SB_CB(4)
    U2 AL41 DDR3_SB_ECC4 SOCKET4677_AZIF0045P001C01CS-SA   I169 @S9S_MB_2U_LIB.S9S_MB_2U(SCH_1):PAGE23
    J7   89  CB4_B SCONN288_ADR50017P130CC-SCONN2A    I12 @S9S_MB_2U_LIB.S9S_MB_2U(SCH_1):PAGE88
    J8   89  CB4_B SCONN288_ADR50017P087CC-SCONN2A    I50 @S9S_MB_2U_LIB.S9S_MB_2U(SCH_1):PAGE89

M_D_CPU0_SB_CB<5> @S9S_MB_2U_LIB.S9S_MB_2U(SCH_1):M_D_CPU0_SB_CB(5)
    U2 AK40 DDR3_SB_ECC5 SOCKET4677_AZIF0045P001C01CS-SA   I169 @S9S_MB_2U_LIB.S9S_MB_2U(SCH_1):PAGE23
    J7   91  CB5_B SCONN288_ADR50017P130CC-SCONN2A    I12 @S9S_MB_2U_LIB.S9S_MB_2U(SCH_1):PAGE88
    J8   91  CB5_B SCONN288_ADR50017P087CC-SCONN2A    I50 @S9S_MB_2U_LIB.S9S_MB_2U(SCH_1):PAGE89

M_D_CPU0_SB_CB<6> @S9S_MB_2U_LIB.S9S_MB_2U(SCH_1):M_D_CPU0_SB_CB(6)
    U2 AN41 DDR3_SB_ECC6 SOCKET4677_AZIF0045P001C01CS-SA   I169 @S9S_MB_2U_LIB.S9S_MB_2U(SCH_1):PAGE23
    J7  234  CB6_B SCONN288_ADR50017P130CC-SCONN2A    I12 @S9S_MB_2U_LIB.S9S_MB_2U(SCH_1):PAGE88
    J8  234  CB6_B SCONN288_ADR50017P087CC-SCONN2A    I50 @S9S_MB_2U_LIB.S9S_MB_2U(SCH_1):PAGE89

M_D_CPU0_SB_CB<7> @S9S_MB_2U_LIB.S9S_MB_2U(SCH_1):M_D_CPU0_SB_CB(7)
    U2 AP40 DDR3_SB_ECC7 SOCKET4677_AZIF0045P001C01CS-SA   I169 @S9S_MB_2U_LIB.S9S_MB_2U(SCH_1):PAGE23
    J7  236  CB7_B SCONN288_ADR50017P130CC-SCONN2A    I12 @S9S_MB_2U_LIB.S9S_MB_2U(SCH_1):PAGE88
    J8  236  CB7_B SCONN288_ADR50017P087CC-SCONN2A    I50 @S9S_MB_2U_LIB.S9S_MB_2U(SCH_1):PAGE89

M_D_CPU0_SB_CS_N<0> @S9S_MB_2U_LIB.S9S_MB_2U(SCH_1):M_D_CPU0_SB_CS_N(0)
    U2 AC41 DDR3_SB_CS_N0 SOCKET4677_AZIF0045P001C01CS-SA   I169 @S9S_MB_2U_LIB.S9S_MB_2U(SCH_1):PAGE23
    J7   84 CS0_B_N SCONN288_ADR50017P130CC-SCONN2A    I12 @S9S_MB_2U_LIB.S9S_MB_2U(SCH_1):PAGE88

M_D_CPU0_SB_CS_N<1> @S9S_MB_2U_LIB.S9S_MB_2U(SCH_1):M_D_CPU0_SB_CS_N(1)
    U2 AG41 DDR3_SB_CS_N1 SOCKET4677_AZIF0045P001C01CS-SA   I169 @S9S_MB_2U_LIB.S9S_MB_2U(SCH_1):PAGE23
    J7  229 CS1_B_N SCONN288_ADR50017P130CC-SCONN2A    I12 @S9S_MB_2U_LIB.S9S_MB_2U(SCH_1):PAGE88

M_D_CPU0_SB_CS_N<2> @S9S_MB_2U_LIB.S9S_MB_2U(SCH_1):M_D_CPU0_SB_CS_N(2)
    U2 AF40 DDR3_SB_CS_N2 SOCKET4677_AZIF0045P001C01CS-SA   I169 @S9S_MB_2U_LIB.S9S_MB_2U(SCH_1):PAGE23
    J8   84 CS0_B_N SCONN288_ADR50017P087CC-SCONN2A    I50 @S9S_MB_2U_LIB.S9S_MB_2U(SCH_1):PAGE89

M_D_CPU0_SB_CS_N<3> @S9S_MB_2U_LIB.S9S_MB_2U(SCH_1):M_D_CPU0_SB_CS_N(3)
    U2 AD40 DDR3_SB_CS_N3 SOCKET4677_AZIF0045P001C01CS-SA   I169 @S9S_MB_2U_LIB.S9S_MB_2U(SCH_1):PAGE23
    J8  229 CS1_B_N SCONN288_ADR50017P087CC-SCONN2A    I50 @S9S_MB_2U_LIB.S9S_MB_2U(SCH_1):PAGE89

M_D_CPU0_SB_DQ<0> @S9S_MB_2U_LIB.S9S_MB_2U(SCH_1):M_D_CPU0_SB_DQ(0)
    U2 AL35 DDR3_SB_DQ0 SOCKET4677_AZIF0045P001C01CS-SA   I169 @S9S_MB_2U_LIB.S9S_MB_2U(SCH_1):PAGE23
    J7  100  DQ0_B SCONN288_ADR50017P130CC-SCONN2A    I12 @S9S_MB_2U_LIB.S9S_MB_2U(SCH_1):PAGE88
    J8  100  DQ0_B SCONN288_ADR50017P087CC-SCONN2A    I50 @S9S_MB_2U_LIB.S9S_MB_2U(SCH_1):PAGE89

M_D_CPU0_SB_DQ<10> @S9S_MB_2U_LIB.S9S_MB_2U(SCH_1):M_D_CPU0_SB_DQ(10)
    U2 AN29 DDR3_SB_DQ10 SOCKET4677_AZIF0045P001C01CS-SA   I169 @S9S_MB_2U_LIB.S9S_MB_2U(SCH_1):PAGE23
    J7  256 DQ10_B SCONN288_ADR50017P130CC-SCONN2A    I12 @S9S_MB_2U_LIB.S9S_MB_2U(SCH_1):PAGE88
    J8  256 DQ10_B SCONN288_ADR50017P087CC-SCONN2A    I50 @S9S_MB_2U_LIB.S9S_MB_2U(SCH_1):PAGE89

M_D_CPU0_SB_DQ<11> @S9S_MB_2U_LIB.S9S_MB_2U(SCH_1):M_D_CPU0_SB_DQ(11)
    U2 AP28 DDR3_SB_DQ11 SOCKET4677_AZIF0045P001C01CS-SA   I169 @S9S_MB_2U_LIB.S9S_MB_2U(SCH_1):PAGE23
    J7  258 DQ11_B SCONN288_ADR50017P130CC-SCONN2A    I12 @S9S_MB_2U_LIB.S9S_MB_2U(SCH_1):PAGE88
    J8  258 DQ11_B SCONN288_ADR50017P087CC-SCONN2A    I50 @S9S_MB_2U_LIB.S9S_MB_2U(SCH_1):PAGE89

M_D_CPU0_SB_DQ<12> @S9S_MB_2U_LIB.S9S_MB_2U(SCH_1):M_D_CPU0_SB_DQ(12)
    U2 AK26 DDR3_SB_DQ12 SOCKET4677_AZIF0045P001C01CS-SA   I169 @S9S_MB_2U_LIB.S9S_MB_2U(SCH_1):PAGE23
    J7  118 DQ12_B SCONN288_ADR50017P130CC-SCONN2A    I12 @S9S_MB_2U_LIB.S9S_MB_2U(SCH_1):PAGE88
    J8  118 DQ12_B SCONN288_ADR50017P087CC-SCONN2A    I50 @S9S_MB_2U_LIB.S9S_MB_2U(SCH_1):PAGE89

M_D_CPU0_SB_DQ<13> @S9S_MB_2U_LIB.S9S_MB_2U(SCH_1):M_D_CPU0_SB_DQ(13)
    U2 AL25 DDR3_SB_DQ13 SOCKET4677_AZIF0045P001C01CS-SA   I169 @S9S_MB_2U_LIB.S9S_MB_2U(SCH_1):PAGE23
    J7  120 DQ13_B SCONN288_ADR50017P130CC-SCONN2A    I12 @S9S_MB_2U_LIB.S9S_MB_2U(SCH_1):PAGE88
    J8  120 DQ13_B SCONN288_ADR50017P087CC-SCONN2A    I50 @S9S_MB_2U_LIB.S9S_MB_2U(SCH_1):PAGE89

M_D_CPU0_SB_DQ<14> @S9S_MB_2U_LIB.S9S_MB_2U(SCH_1):M_D_CPU0_SB_DQ(14)
    U2 AP26 DDR3_SB_DQ14 SOCKET4677_AZIF0045P001C01CS-SA   I169 @S9S_MB_2U_LIB.S9S_MB_2U(SCH_1):PAGE23
    J7  263 DQ14_B SCONN288_ADR50017P130CC-SCONN2A    I12 @S9S_MB_2U_LIB.S9S_MB_2U(SCH_1):PAGE88
    J8  263 DQ14_B SCONN288_ADR50017P087CC-SCONN2A    I50 @S9S_MB_2U_LIB.S9S_MB_2U(SCH_1):PAGE89

M_D_CPU0_SB_DQ<15> @S9S_MB_2U_LIB.S9S_MB_2U(SCH_1):M_D_CPU0_SB_DQ(15)
    U2 AN25 DDR3_SB_DQ15 SOCKET4677_AZIF0045P001C01CS-SA   I169 @S9S_MB_2U_LIB.S9S_MB_2U(SCH_1):PAGE23
    J7  265 DQ15_B SCONN288_ADR50017P130CC-SCONN2A    I12 @S9S_MB_2U_LIB.S9S_MB_2U(SCH_1):PAGE88
    J8  265 DQ15_B SCONN288_ADR50017P087CC-SCONN2A    I50 @S9S_MB_2U_LIB.S9S_MB_2U(SCH_1):PAGE89

M_D_CPU0_SB_DQ<16> @S9S_MB_2U_LIB.S9S_MB_2U(SCH_1):M_D_CPU0_SB_DQ(16)
    U2 AD26 DDR3_SB_DQ16 SOCKET4677_AZIF0045P001C01CS-SA   I169 @S9S_MB_2U_LIB.S9S_MB_2U(SCH_1):PAGE23
    J7  122 DQ16_B SCONN288_ADR50017P130CC-SCONN2A    I12 @S9S_MB_2U_LIB.S9S_MB_2U(SCH_1):PAGE88
    J8  122 DQ16_B SCONN288_ADR50017P087CC-SCONN2A    I50 @S9S_MB_2U_LIB.S9S_MB_2U(SCH_1):PAGE89

M_D_CPU0_SB_DQ<17> @S9S_MB_2U_LIB.S9S_MB_2U(SCH_1):M_D_CPU0_SB_DQ(17)
    U2 AC25 DDR3_SB_DQ17 SOCKET4677_AZIF0045P001C01CS-SA   I169 @S9S_MB_2U_LIB.S9S_MB_2U(SCH_1):PAGE23
    J7  124 DQ17_B SCONN288_ADR50017P130CC-SCONN2A    I12 @S9S_MB_2U_LIB.S9S_MB_2U(SCH_1):PAGE88
    J8  124 DQ17_B SCONN288_ADR50017P087CC-SCONN2A    I50 @S9S_MB_2U_LIB.S9S_MB_2U(SCH_1):PAGE89

M_D_CPU0_SB_DQ<18> @S9S_MB_2U_LIB.S9S_MB_2U(SCH_1):M_D_CPU0_SB_DQ(18)
    U2 AF26 DDR3_SB_DQ18 SOCKET4677_AZIF0045P001C01CS-SA   I169 @S9S_MB_2U_LIB.S9S_MB_2U(SCH_1):PAGE23
    J7  267 DQ18_B SCONN288_ADR50017P130CC-SCONN2A    I12 @S9S_MB_2U_LIB.S9S_MB_2U(SCH_1):PAGE88
    J8  267 DQ18_B SCONN288_ADR50017P087CC-SCONN2A    I50 @S9S_MB_2U_LIB.S9S_MB_2U(SCH_1):PAGE89

M_D_CPU0_SB_DQ<19> @S9S_MB_2U_LIB.S9S_MB_2U(SCH_1):M_D_CPU0_SB_DQ(19)
    U2 AG25 DDR3_SB_DQ19 SOCKET4677_AZIF0045P001C01CS-SA   I169 @S9S_MB_2U_LIB.S9S_MB_2U(SCH_1):PAGE23
    J7  269 DQ19_B SCONN288_ADR50017P130CC-SCONN2A    I12 @S9S_MB_2U_LIB.S9S_MB_2U(SCH_1):PAGE88
    J8  269 DQ19_B SCONN288_ADR50017P087CC-SCONN2A    I50 @S9S_MB_2U_LIB.S9S_MB_2U(SCH_1):PAGE89

M_D_CPU0_SB_DQ<1> @S9S_MB_2U_LIB.S9S_MB_2U(SCH_1):M_D_CPU0_SB_DQ(1)
    U2 AK34 DDR3_SB_DQ1 SOCKET4677_AZIF0045P001C01CS-SA   I169 @S9S_MB_2U_LIB.S9S_MB_2U(SCH_1):PAGE23
    J7  102  DQ1_B SCONN288_ADR50017P130CC-SCONN2A    I12 @S9S_MB_2U_LIB.S9S_MB_2U(SCH_1):PAGE88
    J8  102  DQ1_B SCONN288_ADR50017P087CC-SCONN2A    I50 @S9S_MB_2U_LIB.S9S_MB_2U(SCH_1):PAGE89

M_D_CPU0_SB_DQ<20> @S9S_MB_2U_LIB.S9S_MB_2U(SCH_1):M_D_CPU0_SB_DQ(20)
    U2 AC23 DDR3_SB_DQ20 SOCKET4677_AZIF0045P001C01CS-SA   I169 @S9S_MB_2U_LIB.S9S_MB_2U(SCH_1):PAGE23
    J7  129 DQ20_B SCONN288_ADR50017P130CC-SCONN2A    I12 @S9S_MB_2U_LIB.S9S_MB_2U(SCH_1):PAGE88
    J8  129 DQ20_B SCONN288_ADR50017P087CC-SCONN2A    I50 @S9S_MB_2U_LIB.S9S_MB_2U(SCH_1):PAGE89

M_D_CPU0_SB_DQ<21> @S9S_MB_2U_LIB.S9S_MB_2U(SCH_1):M_D_CPU0_SB_DQ(21)
    U2 AD22 DDR3_SB_DQ21 SOCKET4677_AZIF0045P001C01CS-SA   I169 @S9S_MB_2U_LIB.S9S_MB_2U(SCH_1):PAGE23
    J7  131 DQ21_B SCONN288_ADR50017P130CC-SCONN2A    I12 @S9S_MB_2U_LIB.S9S_MB_2U(SCH_1):PAGE88
    J8  131 DQ21_B SCONN288_ADR50017P087CC-SCONN2A    I50 @S9S_MB_2U_LIB.S9S_MB_2U(SCH_1):PAGE89

M_D_CPU0_SB_DQ<22> @S9S_MB_2U_LIB.S9S_MB_2U(SCH_1):M_D_CPU0_SB_DQ(22)
    U2 AG23 DDR3_SB_DQ22 SOCKET4677_AZIF0045P001C01CS-SA   I169 @S9S_MB_2U_LIB.S9S_MB_2U(SCH_1):PAGE23
    J7  274 DQ22_B SCONN288_ADR50017P130CC-SCONN2A    I12 @S9S_MB_2U_LIB.S9S_MB_2U(SCH_1):PAGE88
    J8  274 DQ22_B SCONN288_ADR50017P087CC-SCONN2A    I50 @S9S_MB_2U_LIB.S9S_MB_2U(SCH_1):PAGE89

M_D_CPU0_SB_DQ<23> @S9S_MB_2U_LIB.S9S_MB_2U(SCH_1):M_D_CPU0_SB_DQ(23)
    U2 AF22 DDR3_SB_DQ23 SOCKET4677_AZIF0045P001C01CS-SA   I169 @S9S_MB_2U_LIB.S9S_MB_2U(SCH_1):PAGE23
    J7  276 DQ23_B SCONN288_ADR50017P130CC-SCONN2A    I12 @S9S_MB_2U_LIB.S9S_MB_2U(SCH_1):PAGE88
    J8  276 DQ23_B SCONN288_ADR50017P087CC-SCONN2A    I50 @S9S_MB_2U_LIB.S9S_MB_2U(SCH_1):PAGE89

M_D_CPU0_SB_DQ<24> @S9S_MB_2U_LIB.S9S_MB_2U(SCH_1):M_D_CPU0_SB_DQ(24)
    U2 AL23 DDR3_SB_DQ24 SOCKET4677_AZIF0045P001C01CS-SA   I169 @S9S_MB_2U_LIB.S9S_MB_2U(SCH_1):PAGE23
    J7  133 DQ24_B SCONN288_ADR50017P130CC-SCONN2A    I12 @S9S_MB_2U_LIB.S9S_MB_2U(SCH_1):PAGE88
    J8  133 DQ24_B SCONN288_ADR50017P087CC-SCONN2A    I50 @S9S_MB_2U_LIB.S9S_MB_2U(SCH_1):PAGE89

M_D_CPU0_SB_DQ<25> @S9S_MB_2U_LIB.S9S_MB_2U(SCH_1):M_D_CPU0_SB_DQ(25)
    U2 AK22 DDR3_SB_DQ25 SOCKET4677_AZIF0045P001C01CS-SA   I169 @S9S_MB_2U_LIB.S9S_MB_2U(SCH_1):PAGE23
    J7  135 DQ25_B SCONN288_ADR50017P130CC-SCONN2A    I12 @S9S_MB_2U_LIB.S9S_MB_2U(SCH_1):PAGE88
    J8  135 DQ25_B SCONN288_ADR50017P087CC-SCONN2A    I50 @S9S_MB_2U_LIB.S9S_MB_2U(SCH_1):PAGE89

M_D_CPU0_SB_DQ<26> @S9S_MB_2U_LIB.S9S_MB_2U(SCH_1):M_D_CPU0_SB_DQ(26)
    U2 AN23 DDR3_SB_DQ26 SOCKET4677_AZIF0045P001C01CS-SA   I169 @S9S_MB_2U_LIB.S9S_MB_2U(SCH_1):PAGE23
    J7  278 DQ26_B SCONN288_ADR50017P130CC-SCONN2A    I12 @S9S_MB_2U_LIB.S9S_MB_2U(SCH_1):PAGE88
    J8  278 DQ26_B SCONN288_ADR50017P087CC-SCONN2A    I50 @S9S_MB_2U_LIB.S9S_MB_2U(SCH_1):PAGE89

M_D_CPU0_SB_DQ<27> @S9S_MB_2U_LIB.S9S_MB_2U(SCH_1):M_D_CPU0_SB_DQ(27)
    U2 AP22 DDR3_SB_DQ27 SOCKET4677_AZIF0045P001C01CS-SA   I169 @S9S_MB_2U_LIB.S9S_MB_2U(SCH_1):PAGE23
    J7  280 DQ27_B SCONN288_ADR50017P130CC-SCONN2A    I12 @S9S_MB_2U_LIB.S9S_MB_2U(SCH_1):PAGE88
    J8  280 DQ27_B SCONN288_ADR50017P087CC-SCONN2A    I50 @S9S_MB_2U_LIB.S9S_MB_2U(SCH_1):PAGE89

M_D_CPU0_SB_DQ<28> @S9S_MB_2U_LIB.S9S_MB_2U(SCH_1):M_D_CPU0_SB_DQ(28)
    U2 AK20 DDR3_SB_DQ28 SOCKET4677_AZIF0045P001C01CS-SA   I169 @S9S_MB_2U_LIB.S9S_MB_2U(SCH_1):PAGE23
    J7  140 DQ28_B SCONN288_ADR50017P130CC-SCONN2A    I12 @S9S_MB_2U_LIB.S9S_MB_2U(SCH_1):PAGE88
    J8  140 DQ28_B SCONN288_ADR50017P087CC-SCONN2A    I50 @S9S_MB_2U_LIB.S9S_MB_2U(SCH_1):PAGE89

M_D_CPU0_SB_DQ<29> @S9S_MB_2U_LIB.S9S_MB_2U(SCH_1):M_D_CPU0_SB_DQ(29)
    U2 AL19 DDR3_SB_DQ29 SOCKET4677_AZIF0045P001C01CS-SA   I169 @S9S_MB_2U_LIB.S9S_MB_2U(SCH_1):PAGE23
    J7  142 DQ29_B SCONN288_ADR50017P130CC-SCONN2A    I12 @S9S_MB_2U_LIB.S9S_MB_2U(SCH_1):PAGE88
    J8  142 DQ29_B SCONN288_ADR50017P087CC-SCONN2A    I50 @S9S_MB_2U_LIB.S9S_MB_2U(SCH_1):PAGE89

M_D_CPU0_SB_DQ<2> @S9S_MB_2U_LIB.S9S_MB_2U(SCH_1):M_D_CPU0_SB_DQ(2)
    U2 AN35 DDR3_SB_DQ2 SOCKET4677_AZIF0045P001C01CS-SA   I169 @S9S_MB_2U_LIB.S9S_MB_2U(SCH_1):PAGE23
    J7  245  DQ2_B SCONN288_ADR50017P130CC-SCONN2A    I12 @S9S_MB_2U_LIB.S9S_MB_2U(SCH_1):PAGE88
    J8  245  DQ2_B SCONN288_ADR50017P087CC-SCONN2A    I50 @S9S_MB_2U_LIB.S9S_MB_2U(SCH_1):PAGE89

M_D_CPU0_SB_DQ<30> @S9S_MB_2U_LIB.S9S_MB_2U(SCH_1):M_D_CPU0_SB_DQ(30)
    U2 AP20 DDR3_SB_DQ30 SOCKET4677_AZIF0045P001C01CS-SA   I169 @S9S_MB_2U_LIB.S9S_MB_2U(SCH_1):PAGE23
    J7  285 DQ30_B SCONN288_ADR50017P130CC-SCONN2A    I12 @S9S_MB_2U_LIB.S9S_MB_2U(SCH_1):PAGE88
    J8  285 DQ30_B SCONN288_ADR50017P087CC-SCONN2A    I50 @S9S_MB_2U_LIB.S9S_MB_2U(SCH_1):PAGE89

M_D_CPU0_SB_DQ<31> @S9S_MB_2U_LIB.S9S_MB_2U(SCH_1):M_D_CPU0_SB_DQ(31)
    U2 AN19 DDR3_SB_DQ31 SOCKET4677_AZIF0045P001C01CS-SA   I169 @S9S_MB_2U_LIB.S9S_MB_2U(SCH_1):PAGE23
    J7  287 DQ31_B SCONN288_ADR50017P130CC-SCONN2A    I12 @S9S_MB_2U_LIB.S9S_MB_2U(SCH_1):PAGE88
    J8  287 DQ31_B SCONN288_ADR50017P087CC-SCONN2A    I50 @S9S_MB_2U_LIB.S9S_MB_2U(SCH_1):PAGE89

M_D_CPU0_SB_DQ<3> @S9S_MB_2U_LIB.S9S_MB_2U(SCH_1):M_D_CPU0_SB_DQ(3)
    U2 AP34 DDR3_SB_DQ3 SOCKET4677_AZIF0045P001C01CS-SA   I169 @S9S_MB_2U_LIB.S9S_MB_2U(SCH_1):PAGE23
    J7  247  DQ3_B SCONN288_ADR50017P130CC-SCONN2A    I12 @S9S_MB_2U_LIB.S9S_MB_2U(SCH_1):PAGE88
    J8  247  DQ3_B SCONN288_ADR50017P087CC-SCONN2A    I50 @S9S_MB_2U_LIB.S9S_MB_2U(SCH_1):PAGE89

M_D_CPU0_SB_DQ<4> @S9S_MB_2U_LIB.S9S_MB_2U(SCH_1):M_D_CPU0_SB_DQ(4)
    U2 AK32 DDR3_SB_DQ4 SOCKET4677_AZIF0045P001C01CS-SA   I169 @S9S_MB_2U_LIB.S9S_MB_2U(SCH_1):PAGE23
    J7  107  DQ4_B SCONN288_ADR50017P130CC-SCONN2A    I12 @S9S_MB_2U_LIB.S9S_MB_2U(SCH_1):PAGE88
    J8  107  DQ4_B SCONN288_ADR50017P087CC-SCONN2A    I50 @S9S_MB_2U_LIB.S9S_MB_2U(SCH_1):PAGE89

M_D_CPU0_SB_DQ<5> @S9S_MB_2U_LIB.S9S_MB_2U(SCH_1):M_D_CPU0_SB_DQ(5)
    U2 AL31 DDR3_SB_DQ5 SOCKET4677_AZIF0045P001C01CS-SA   I169 @S9S_MB_2U_LIB.S9S_MB_2U(SCH_1):PAGE23
    J7  109  DQ5_B SCONN288_ADR50017P130CC-SCONN2A    I12 @S9S_MB_2U_LIB.S9S_MB_2U(SCH_1):PAGE88
    J8  109  DQ5_B SCONN288_ADR50017P087CC-SCONN2A    I50 @S9S_MB_2U_LIB.S9S_MB_2U(SCH_1):PAGE89

M_D_CPU0_SB_DQ<6> @S9S_MB_2U_LIB.S9S_MB_2U(SCH_1):M_D_CPU0_SB_DQ(6)
    U2 AP32 DDR3_SB_DQ6 SOCKET4677_AZIF0045P001C01CS-SA   I169 @S9S_MB_2U_LIB.S9S_MB_2U(SCH_1):PAGE23
    J7  252  DQ6_B SCONN288_ADR50017P130CC-SCONN2A    I12 @S9S_MB_2U_LIB.S9S_MB_2U(SCH_1):PAGE88
    J8  252  DQ6_B SCONN288_ADR50017P087CC-SCONN2A    I50 @S9S_MB_2U_LIB.S9S_MB_2U(SCH_1):PAGE89

M_D_CPU0_SB_DQ<7> @S9S_MB_2U_LIB.S9S_MB_2U(SCH_1):M_D_CPU0_SB_DQ(7)
    U2 AN31 DDR3_SB_DQ7 SOCKET4677_AZIF0045P001C01CS-SA   I169 @S9S_MB_2U_LIB.S9S_MB_2U(SCH_1):PAGE23
    J7  254  DQ7_B SCONN288_ADR50017P130CC-SCONN2A    I12 @S9S_MB_2U_LIB.S9S_MB_2U(SCH_1):PAGE88
    J8  254  DQ7_B SCONN288_ADR50017P087CC-SCONN2A    I50 @S9S_MB_2U_LIB.S9S_MB_2U(SCH_1):PAGE89

M_D_CPU0_SB_DQ<8> @S9S_MB_2U_LIB.S9S_MB_2U(SCH_1):M_D_CPU0_SB_DQ(8)
    U2 AL29 DDR3_SB_DQ8 SOCKET4677_AZIF0045P001C01CS-SA   I169 @S9S_MB_2U_LIB.S9S_MB_2U(SCH_1):PAGE23
    J7  111  DQ8_B SCONN288_ADR50017P130CC-SCONN2A    I12 @S9S_MB_2U_LIB.S9S_MB_2U(SCH_1):PAGE88
    J8  111  DQ8_B SCONN288_ADR50017P087CC-SCONN2A    I50 @S9S_MB_2U_LIB.S9S_MB_2U(SCH_1):PAGE89

M_D_CPU0_SB_DQ<9> @S9S_MB_2U_LIB.S9S_MB_2U(SCH_1):M_D_CPU0_SB_DQ(9)
    U2 AK28 DDR3_SB_DQ9 SOCKET4677_AZIF0045P001C01CS-SA   I169 @S9S_MB_2U_LIB.S9S_MB_2U(SCH_1):PAGE23
    J7  113  DQ9_B SCONN288_ADR50017P130CC-SCONN2A    I12 @S9S_MB_2U_LIB.S9S_MB_2U(SCH_1):PAGE88
    J8  113  DQ9_B SCONN288_ADR50017P087CC-SCONN2A    I50 @S9S_MB_2U_LIB.S9S_MB_2U(SCH_1):PAGE89

M_D_CPU0_SB_DQS_DN<0> @S9S_MB_2U_LIB.S9S_MB_2U(SCH_1):M_D_CPU0_SB_DQS_DN(0)
    U2 AJ33 DDR3_SB_DQS_DN0 SOCKET4677_AZIF0045P001C01CS-SA   I169 @S9S_MB_2U_LIB.S9S_MB_2U(SCH_1):PAGE23
    J7  105 DQS0_B_C SCONN288_ADR50017P130CC-SCONN2A   I178 @S9S_MB_2U_LIB.S9S_MB_2U(SCH_1):PAGE88
    J8  105 DQS0_B_C SCONN288_ADR50017P087CC-SCONN2A   I178 @S9S_MB_2U_LIB.S9S_MB_2U(SCH_1):PAGE89

M_D_CPU0_SB_DQS_DN<1> @S9S_MB_2U_LIB.S9S_MB_2U(SCH_1):M_D_CPU0_SB_DQS_DN(1)
    U2 AJ27 DDR3_SB_DQS_DN1 SOCKET4677_AZIF0045P001C01CS-SA   I169 @S9S_MB_2U_LIB.S9S_MB_2U(SCH_1):PAGE23
    J7  116 DQS1_B_C SCONN288_ADR50017P130CC-SCONN2A   I178 @S9S_MB_2U_LIB.S9S_MB_2U(SCH_1):PAGE88
    J8  116 DQS1_B_C SCONN288_ADR50017P087CC-SCONN2A   I178 @S9S_MB_2U_LIB.S9S_MB_2U(SCH_1):PAGE89

M_D_CPU0_SB_DQS_DN<2> @S9S_MB_2U_LIB.S9S_MB_2U(SCH_1):M_D_CPU0_SB_DQS_DN(2)
    U2 AB24 DDR3_SB_DQS_DN2 SOCKET4677_AZIF0045P001C01CS-SA   I169 @S9S_MB_2U_LIB.S9S_MB_2U(SCH_1):PAGE23
    J7  127 DQS2_B_C SCONN288_ADR50017P130CC-SCONN2A   I178 @S9S_MB_2U_LIB.S9S_MB_2U(SCH_1):PAGE88
    J8  127 DQS2_B_C SCONN288_ADR50017P087CC-SCONN2A   I178 @S9S_MB_2U_LIB.S9S_MB_2U(SCH_1):PAGE89

M_D_CPU0_SB_DQS_DN<3> @S9S_MB_2U_LIB.S9S_MB_2U(SCH_1):M_D_CPU0_SB_DQS_DN(3)
    U2 AJ21 DDR3_SB_DQS_DN3 SOCKET4677_AZIF0045P001C01CS-SA   I169 @S9S_MB_2U_LIB.S9S_MB_2U(SCH_1):PAGE23
    J7  138 DQS3_B_C SCONN288_ADR50017P130CC-SCONN2A   I178 @S9S_MB_2U_LIB.S9S_MB_2U(SCH_1):PAGE88
    J8  138 DQS3_B_C SCONN288_ADR50017P087CC-SCONN2A   I178 @S9S_MB_2U_LIB.S9S_MB_2U(SCH_1):PAGE89

M_D_CPU0_SB_DQS_DN<4> @S9S_MB_2U_LIB.S9S_MB_2U(SCH_1):M_D_CPU0_SB_DQS_DN(4)
    U2 AR39 DDR3_SB_DQS_DN4 SOCKET4677_AZIF0045P001C01CS-SA   I169 @S9S_MB_2U_LIB.S9S_MB_2U(SCH_1):PAGE23
    J7  238 DQS4_B_C SCONN288_ADR50017P130CC-SCONN2A   I178 @S9S_MB_2U_LIB.S9S_MB_2U(SCH_1):PAGE88
    J8  238 DQS4_B_C SCONN288_ADR50017P087CC-SCONN2A   I178 @S9S_MB_2U_LIB.S9S_MB_2U(SCH_1):PAGE89

M_D_CPU0_SB_DQS_DN<5> @S9S_MB_2U_LIB.S9S_MB_2U(SCH_1):M_D_CPU0_SB_DQS_DN(5)
    U2 AN33 DDR3_SB_DQS_DN5 SOCKET4677_AZIF0045P001C01CS-SA   I169 @S9S_MB_2U_LIB.S9S_MB_2U(SCH_1):PAGE23
    J7  249 DQS5_B_C||TDQS5_B_C SCONN288_ADR50017P130CC-SCONN2A   I178 @S9S_MB_2U_LIB.S9S_MB_2U(SCH_1):PAGE88
    J8  249 DQS5_B_C||TDQS5_B_C SCONN288_ADR50017P087CC-SCONN2A   I178 @S9S_MB_2U_LIB.S9S_MB_2U(SCH_1):PAGE89

M_D_CPU0_SB_DQS_DN<6> @S9S_MB_2U_LIB.S9S_MB_2U(SCH_1):M_D_CPU0_SB_DQS_DN(6)
    U2 AN27 DDR3_SB_DQS_DN6 SOCKET4677_AZIF0045P001C01CS-SA   I169 @S9S_MB_2U_LIB.S9S_MB_2U(SCH_1):PAGE23
    J7  260 DQS6_B_C||TDQS6_B_C SCONN288_ADR50017P130CC-SCONN2A   I178 @S9S_MB_2U_LIB.S9S_MB_2U(SCH_1):PAGE88
    J8  260 DQS6_B_C||TDQS6_B_C SCONN288_ADR50017P087CC-SCONN2A   I178 @S9S_MB_2U_LIB.S9S_MB_2U(SCH_1):PAGE89

M_D_CPU0_SB_DQS_DN<7> @S9S_MB_2U_LIB.S9S_MB_2U(SCH_1):M_D_CPU0_SB_DQS_DN(7)
    U2 AF24 DDR3_SB_DQS_DN7 SOCKET4677_AZIF0045P001C01CS-SA   I169 @S9S_MB_2U_LIB.S9S_MB_2U(SCH_1):PAGE23
    J7  271 DQS7_B_C||TDQS7_B_C SCONN288_ADR50017P130CC-SCONN2A   I178 @S9S_MB_2U_LIB.S9S_MB_2U(SCH_1):PAGE88
    J8  271 DQS7_B_C||TDQS7_B_C SCONN288_ADR50017P087CC-SCONN2A   I178 @S9S_MB_2U_LIB.S9S_MB_2U(SCH_1):PAGE89

M_D_CPU0_SB_DQS_DN<8> @S9S_MB_2U_LIB.S9S_MB_2U(SCH_1):M_D_CPU0_SB_DQS_DN(8)
    U2 AN21 DDR3_SB_DQS_DN8 SOCKET4677_AZIF0045P001C01CS-SA   I169 @S9S_MB_2U_LIB.S9S_MB_2U(SCH_1):PAGE23
    J7  282 DQS8_B_C||TDQS8_B_C SCONN288_ADR50017P130CC-SCONN2A   I178 @S9S_MB_2U_LIB.S9S_MB_2U(SCH_1):PAGE88
    J8  282 DQS8_B_C||TDQS8_B_C SCONN288_ADR50017P087CC-SCONN2A   I178 @S9S_MB_2U_LIB.S9S_MB_2U(SCH_1):PAGE89

M_D_CPU0_SB_DQS_DN<9> @S9S_MB_2U_LIB.S9S_MB_2U(SCH_1):M_D_CPU0_SB_DQS_DN(9)
    U2 AJ39 DDR3_SB_DQS_DN9 SOCKET4677_AZIF0045P001C01CS-SA   I169 @S9S_MB_2U_LIB.S9S_MB_2U(SCH_1):PAGE23
    J7   94 DQS9_B_C||TDQS9_B_C SCONN288_ADR50017P130CC-SCONN2A   I178 @S9S_MB_2U_LIB.S9S_MB_2U(SCH_1):PAGE88
    J8   94 DQS9_B_C||TDQS9_B_C SCONN288_ADR50017P087CC-SCONN2A   I178 @S9S_MB_2U_LIB.S9S_MB_2U(SCH_1):PAGE89

M_D_CPU0_SB_DQS_DP<0> @S9S_MB_2U_LIB.S9S_MB_2U(SCH_1):M_D_CPU0_SB_DQS_DP(0)
    U2 AL33 DDR3_SB_DQS_DP0 SOCKET4677_AZIF0045P001C01CS-SA   I169 @S9S_MB_2U_LIB.S9S_MB_2U(SCH_1):PAGE23
    J7  104 DQS0_B_T SCONN288_ADR50017P130CC-SCONN2A   I178 @S9S_MB_2U_LIB.S9S_MB_2U(SCH_1):PAGE88
    J8  104 DQS0_B_T SCONN288_ADR50017P087CC-SCONN2A   I178 @S9S_MB_2U_LIB.S9S_MB_2U(SCH_1):PAGE89

M_D_CPU0_SB_DQS_DP<1> @S9S_MB_2U_LIB.S9S_MB_2U(SCH_1):M_D_CPU0_SB_DQS_DP(1)
    U2 AL27 DDR3_SB_DQS_DP1 SOCKET4677_AZIF0045P001C01CS-SA   I169 @S9S_MB_2U_LIB.S9S_MB_2U(SCH_1):PAGE23
    J7  115 DQS1_B_T SCONN288_ADR50017P130CC-SCONN2A   I178 @S9S_MB_2U_LIB.S9S_MB_2U(SCH_1):PAGE88
    J8  115 DQS1_B_T SCONN288_ADR50017P087CC-SCONN2A   I178 @S9S_MB_2U_LIB.S9S_MB_2U(SCH_1):PAGE89

M_D_CPU0_SB_DQS_DP<2> @S9S_MB_2U_LIB.S9S_MB_2U(SCH_1):M_D_CPU0_SB_DQS_DP(2)
    U2 AD24 DDR3_SB_DQS_DP2 SOCKET4677_AZIF0045P001C01CS-SA   I169 @S9S_MB_2U_LIB.S9S_MB_2U(SCH_1):PAGE23
    J7  126 DQS2_B_T SCONN288_ADR50017P130CC-SCONN2A   I178 @S9S_MB_2U_LIB.S9S_MB_2U(SCH_1):PAGE88
    J8  126 DQS2_B_T SCONN288_ADR50017P087CC-SCONN2A   I178 @S9S_MB_2U_LIB.S9S_MB_2U(SCH_1):PAGE89

M_D_CPU0_SB_DQS_DP<3> @S9S_MB_2U_LIB.S9S_MB_2U(SCH_1):M_D_CPU0_SB_DQS_DP(3)
    U2 AL21 DDR3_SB_DQS_DP3 SOCKET4677_AZIF0045P001C01CS-SA   I169 @S9S_MB_2U_LIB.S9S_MB_2U(SCH_1):PAGE23
    J7  137 DQS3_B_T SCONN288_ADR50017P130CC-SCONN2A   I178 @S9S_MB_2U_LIB.S9S_MB_2U(SCH_1):PAGE88
    J8  137 DQS3_B_T SCONN288_ADR50017P087CC-SCONN2A   I178 @S9S_MB_2U_LIB.S9S_MB_2U(SCH_1):PAGE89

M_D_CPU0_SB_DQS_DP<4> @S9S_MB_2U_LIB.S9S_MB_2U(SCH_1):M_D_CPU0_SB_DQS_DP(4)
    U2 AN39 DDR3_SB_DQS_DP4 SOCKET4677_AZIF0045P001C01CS-SA   I169 @S9S_MB_2U_LIB.S9S_MB_2U(SCH_1):PAGE23
    J7  239 DQS4_B_T SCONN288_ADR50017P130CC-SCONN2A   I178 @S9S_MB_2U_LIB.S9S_MB_2U(SCH_1):PAGE88
    J8  239 DQS4_B_T SCONN288_ADR50017P087CC-SCONN2A   I178 @S9S_MB_2U_LIB.S9S_MB_2U(SCH_1):PAGE89

M_D_CPU0_SB_DQS_DP<5> @S9S_MB_2U_LIB.S9S_MB_2U(SCH_1):M_D_CPU0_SB_DQS_DP(5)
    U2 AR33 DDR3_SB_DQS_DP5 SOCKET4677_AZIF0045P001C01CS-SA   I169 @S9S_MB_2U_LIB.S9S_MB_2U(SCH_1):PAGE23
    J7  250 DQS5_B_T||TDQS5_B_T SCONN288_ADR50017P130CC-SCONN2A   I178 @S9S_MB_2U_LIB.S9S_MB_2U(SCH_1):PAGE88
    J8  250 DQS5_B_T||TDQS5_B_T SCONN288_ADR50017P087CC-SCONN2A   I178 @S9S_MB_2U_LIB.S9S_MB_2U(SCH_1):PAGE89

M_D_CPU0_SB_DQS_DP<6> @S9S_MB_2U_LIB.S9S_MB_2U(SCH_1):M_D_CPU0_SB_DQS_DP(6)
    U2 AR27 DDR3_SB_DQS_DP6 SOCKET4677_AZIF0045P001C01CS-SA   I169 @S9S_MB_2U_LIB.S9S_MB_2U(SCH_1):PAGE23
    J7  261 DQS6_B_T||TDQS6_B_T SCONN288_ADR50017P130CC-SCONN2A   I178 @S9S_MB_2U_LIB.S9S_MB_2U(SCH_1):PAGE88
    J8  261 DQS6_B_T||TDQS6_B_T SCONN288_ADR50017P087CC-SCONN2A   I178 @S9S_MB_2U_LIB.S9S_MB_2U(SCH_1):PAGE89

M_D_CPU0_SB_DQS_DP<7> @S9S_MB_2U_LIB.S9S_MB_2U(SCH_1):M_D_CPU0_SB_DQS_DP(7)
    U2 AH24 DDR3_SB_DQS_DP7 SOCKET4677_AZIF0045P001C01CS-SA   I169 @S9S_MB_2U_LIB.S9S_MB_2U(SCH_1):PAGE23
    J7  272 DQS7_B_T||TDQS7_B_T SCONN288_ADR50017P130CC-SCONN2A   I178 @S9S_MB_2U_LIB.S9S_MB_2U(SCH_1):PAGE88
    J8  272 DQS7_B_T||TDQS7_B_T SCONN288_ADR50017P087CC-SCONN2A   I178 @S9S_MB_2U_LIB.S9S_MB_2U(SCH_1):PAGE89

M_D_CPU0_SB_DQS_DP<8> @S9S_MB_2U_LIB.S9S_MB_2U(SCH_1):M_D_CPU0_SB_DQS_DP(8)
    U2 AR21 DDR3_SB_DQS_DP8 SOCKET4677_AZIF0045P001C01CS-SA   I169 @S9S_MB_2U_LIB.S9S_MB_2U(SCH_1):PAGE23
    J7  283 DQS8_B_T||TDQS8_B_T SCONN288_ADR50017P130CC-SCONN2A   I178 @S9S_MB_2U_LIB.S9S_MB_2U(SCH_1):PAGE88
    J8  283 DQS8_B_T||TDQS8_B_T SCONN288_ADR50017P087CC-SCONN2A   I178 @S9S_MB_2U_LIB.S9S_MB_2U(SCH_1):PAGE89

M_D_CPU0_SB_DQS_DP<9> @S9S_MB_2U_LIB.S9S_MB_2U(SCH_1):M_D_CPU0_SB_DQS_DP(9)
    U2 AL39 DDR3_SB_DQS_DP9 SOCKET4677_AZIF0045P001C01CS-SA   I169 @S9S_MB_2U_LIB.S9S_MB_2U(SCH_1):PAGE23
    J7   93 DQS9_B_T||TDQS9_B_T||DBI4_B_N SCONN288_ADR50017P130CC-SCONN2A   I178 @S9S_MB_2U_LIB.S9S_MB_2U(SCH_1):PAGE88
    J8   93 DQS9_B_T||TDQS9_B_T||DBI4_B_N SCONN288_ADR50017P087CC-SCONN2A   I178 @S9S_MB_2U_LIB.S9S_MB_2U(SCH_1):PAGE89

M_D_CPU0_SB_PAR @S9S_MB_2U_LIB.S9S_MB_2U(SCH_1):M_D_CPU0_SB_PAR
    U2 AH42 DDR3_SB_PAR SOCKET4677_AZIF0045P001C01CS-SA   I169 @S9S_MB_2U_LIB.S9S_MB_2U(SCH_1):PAGE23
    J7  227  PAR_B SCONN288_ADR50017P130CC-SCONN2A    I12 @S9S_MB_2U_LIB.S9S_MB_2U(SCH_1):PAGE88
    J8  227  PAR_B SCONN288_ADR50017P087CC-SCONN2A    I50 @S9S_MB_2U_LIB.S9S_MB_2U(SCH_1):PAGE89

M_D_CPU0_SB_RSP<0> @S9S_MB_2U_LIB.S9S_MB_2U(SCH_1):M_D_CPU0_SB_RSP(0)
    U2 AF51 DDR3_B_RSP0 SOCKET4677_AZIF0045P001C01CS-SA   I169 @S9S_MB_2U_LIB.S9S_MB_2U(SCH_1):PAGE23
    J7   87 LBS||RSP_B_N SCONN288_ADR50017P130CC-SCONN2A    I12 @S9S_MB_2U_LIB.S9S_MB_2U(SCH_1):PAGE88

M_D_CPU0_SB_RSP<1> @S9S_MB_2U_LIB.S9S_MB_2U(SCH_1):M_D_CPU0_SB_RSP(1)
    U2 AG50 DDR3_B_RSP1 SOCKET4677_AZIF0045P001C01CS-SA   I169 @S9S_MB_2U_LIB.S9S_MB_2U(SCH_1):PAGE23
    J8   87 LBS||RSP_B_N SCONN288_ADR50017P087CC-SCONN2A    I50 @S9S_MB_2U_LIB.S9S_MB_2U(SCH_1):PAGE89

M_D_CPU1_ALERT_N @S9S_MB_2U_LIB.S9S_MB_2U(SCH_1):M_D_CPU1_ALERT_N
    U1 AV47 DDR3_ALERT_N SOCKET4677_AZIF0045P001C01CS-SA    I91 @S9S_MB_2U_LIB.S9S_MB_2U(SCH_1):PAGE54
   J23   62 ALERT_N SCONN288_ADR50017P130CC-SCONN2A    I25 @S9S_MB_2U_LIB.S9S_MB_2U(SCH_1):PAGE104
   J24   62 ALERT_N SCONN288_ADR50017P087CC-SCONN2A   I178 @S9S_MB_2U_LIB.S9S_MB_2U(SCH_1):PAGE105

M_D_CPU1_CLK_DN<0> @S9S_MB_2U_LIB.S9S_MB_2U(SCH_1):M_D_CPU1_CLK_DN(0)
    U1 AJ45 DDR3_CLK_DN0 SOCKET4677_AZIF0045P001C01CS-SA    I91 @S9S_MB_2U_LIB.S9S_MB_2U(SCH_1):PAGE54
   J23  218   CK_C SCONN288_ADR50017P130CC-SCONN2A    I25 @S9S_MB_2U_LIB.S9S_MB_2U(SCH_1):PAGE104

M_D_CPU1_CLK_DN<1> @S9S_MB_2U_LIB.S9S_MB_2U(SCH_1):M_D_CPU1_CLK_DN(1)
    U1 AN45 DDR3_CLK_DN1 SOCKET4677_AZIF0045P001C01CS-SA    I91 @S9S_MB_2U_LIB.S9S_MB_2U(SCH_1):PAGE54
   J24  218   CK_C SCONN288_ADR50017P087CC-SCONN2A   I178 @S9S_MB_2U_LIB.S9S_MB_2U(SCH_1):PAGE105

M_D_CPU1_CLK_DP<0> @S9S_MB_2U_LIB.S9S_MB_2U(SCH_1):M_D_CPU1_CLK_DP(0)
    U1 AL45 DDR3_CLK_DP0 SOCKET4677_AZIF0045P001C01CS-SA    I91 @S9S_MB_2U_LIB.S9S_MB_2U(SCH_1):PAGE54
   J23  217   CK_T SCONN288_ADR50017P130CC-SCONN2A    I25 @S9S_MB_2U_LIB.S9S_MB_2U(SCH_1):PAGE104

M_D_CPU1_CLK_DP<1> @S9S_MB_2U_LIB.S9S_MB_2U(SCH_1):M_D_CPU1_CLK_DP(1)
    U1 AR45 DDR3_CLK_DP1 SOCKET4677_AZIF0045P001C01CS-SA    I91 @S9S_MB_2U_LIB.S9S_MB_2U(SCH_1):PAGE54
   J24  217   CK_T SCONN288_ADR50017P087CC-SCONN2A   I178 @S9S_MB_2U_LIB.S9S_MB_2U(SCH_1):PAGE105

M_D_CPU1_SA_CA<0> @S9S_MB_2U_LIB.S9S_MB_2U(SCH_1):M_D_CPU1_SA_CA(0)
    U1 AJ52 DDR3_SA_CA0 SOCKET4677_AZIF0045P001C01CS-SA    I91 @S9S_MB_2U_LIB.S9S_MB_2U(SCH_1):PAGE54
   J23   66  CA0_A SCONN288_ADR50017P130CC-SCONN2A    I25 @S9S_MB_2U_LIB.S9S_MB_2U(SCH_1):PAGE104
   J24   66  CA0_A SCONN288_ADR50017P087CC-SCONN2A   I178 @S9S_MB_2U_LIB.S9S_MB_2U(SCH_1):PAGE105

M_D_CPU1_SA_CA<1> @S9S_MB_2U_LIB.S9S_MB_2U(SCH_1):M_D_CPU1_SA_CA(1)
    U1 AR52 DDR3_SA_CA1 SOCKET4677_AZIF0045P001C01CS-SA    I91 @S9S_MB_2U_LIB.S9S_MB_2U(SCH_1):PAGE54
   J23  211  CA1_A SCONN288_ADR50017P130CC-SCONN2A    I25 @S9S_MB_2U_LIB.S9S_MB_2U(SCH_1):PAGE104
   J24  211  CA1_A SCONN288_ADR50017P087CC-SCONN2A   I178 @S9S_MB_2U_LIB.S9S_MB_2U(SCH_1):PAGE105

M_D_CPU1_SA_CA<2> @S9S_MB_2U_LIB.S9S_MB_2U(SCH_1):M_D_CPU1_SA_CA(2)
    U1 AK51 DDR3_SA_CA2 SOCKET4677_AZIF0045P001C01CS-SA    I91 @S9S_MB_2U_LIB.S9S_MB_2U(SCH_1):PAGE54
   J23   68  CA2_A SCONN288_ADR50017P130CC-SCONN2A    I25 @S9S_MB_2U_LIB.S9S_MB_2U(SCH_1):PAGE104
   J24   68  CA2_A SCONN288_ADR50017P087CC-SCONN2A   I178 @S9S_MB_2U_LIB.S9S_MB_2U(SCH_1):PAGE105

M_D_CPU1_SA_CA<3> @S9S_MB_2U_LIB.S9S_MB_2U(SCH_1):M_D_CPU1_SA_CA(3)
    U1 AP51 DDR3_SA_CA3 SOCKET4677_AZIF0045P001C01CS-SA    I91 @S9S_MB_2U_LIB.S9S_MB_2U(SCH_1):PAGE54
   J23  213  CA3_A SCONN288_ADR50017P130CC-SCONN2A    I25 @S9S_MB_2U_LIB.S9S_MB_2U(SCH_1):PAGE104
   J24  213  CA3_A SCONN288_ADR50017P087CC-SCONN2A   I178 @S9S_MB_2U_LIB.S9S_MB_2U(SCH_1):PAGE105

M_D_CPU1_SA_CA<4> @S9S_MB_2U_LIB.S9S_MB_2U(SCH_1):M_D_CPU1_SA_CA(4)
    U1 AL50 DDR3_SA_CA4 SOCKET4677_AZIF0045P001C01CS-SA    I91 @S9S_MB_2U_LIB.S9S_MB_2U(SCH_1):PAGE54
   J23   70  CA4_A SCONN288_ADR50017P130CC-SCONN2A    I25 @S9S_MB_2U_LIB.S9S_MB_2U(SCH_1):PAGE104
   J24   70  CA4_A SCONN288_ADR50017P087CC-SCONN2A   I178 @S9S_MB_2U_LIB.S9S_MB_2U(SCH_1):PAGE105

M_D_CPU1_SA_CA<5> @S9S_MB_2U_LIB.S9S_MB_2U(SCH_1):M_D_CPU1_SA_CA(5)
    U1 AN50 DDR3_SA_CA5 SOCKET4677_AZIF0045P001C01CS-SA    I91 @S9S_MB_2U_LIB.S9S_MB_2U(SCH_1):PAGE54
   J23  215  CA5_A SCONN288_ADR50017P130CC-SCONN2A    I25 @S9S_MB_2U_LIB.S9S_MB_2U(SCH_1):PAGE104
   J24  215  CA5_A SCONN288_ADR50017P087CC-SCONN2A   I178 @S9S_MB_2U_LIB.S9S_MB_2U(SCH_1):PAGE105

M_D_CPU1_SA_CA<6> @S9S_MB_2U_LIB.S9S_MB_2U(SCH_1):M_D_CPU1_SA_CA(6)
    U1 AN43 DDR3_SA_CA6 SOCKET4677_AZIF0045P001C01CS-SA    I91 @S9S_MB_2U_LIB.S9S_MB_2U(SCH_1):PAGE54
   J23   72  CA6_A SCONN288_ADR50017P130CC-SCONN2A    I25 @S9S_MB_2U_LIB.S9S_MB_2U(SCH_1):PAGE104
   J24   72  CA6_A SCONN288_ADR50017P087CC-SCONN2A   I178 @S9S_MB_2U_LIB.S9S_MB_2U(SCH_1):PAGE105

M_D_CPU1_SA_CB<0> @S9S_MB_2U_LIB.S9S_MB_2U(SCH_1):M_D_CPU1_SA_CB(0)
    U1 AL60 DDR3_SA_ECC0 SOCKET4677_AZIF0045P001C01CS-SA    I91 @S9S_MB_2U_LIB.S9S_MB_2U(SCH_1):PAGE54
   J23   51  CB0_A SCONN288_ADR50017P130CC-SCONN2A    I25 @S9S_MB_2U_LIB.S9S_MB_2U(SCH_1):PAGE104
   J24   51  CB0_A SCONN288_ADR50017P087CC-SCONN2A   I178 @S9S_MB_2U_LIB.S9S_MB_2U(SCH_1):PAGE105

M_D_CPU1_SA_CB<1> @S9S_MB_2U_LIB.S9S_MB_2U(SCH_1):M_D_CPU1_SA_CB(1)
    U1 AK59 DDR3_SA_ECC1 SOCKET4677_AZIF0045P001C01CS-SA    I91 @S9S_MB_2U_LIB.S9S_MB_2U(SCH_1):PAGE54
   J23   53  CB1_A SCONN288_ADR50017P130CC-SCONN2A    I25 @S9S_MB_2U_LIB.S9S_MB_2U(SCH_1):PAGE104
   J24   53  CB1_A SCONN288_ADR50017P087CC-SCONN2A   I178 @S9S_MB_2U_LIB.S9S_MB_2U(SCH_1):PAGE105

M_D_CPU1_SA_CB<2> @S9S_MB_2U_LIB.S9S_MB_2U(SCH_1):M_D_CPU1_SA_CB(2)
    U1 AN60 DDR3_SA_ECC2 SOCKET4677_AZIF0045P001C01CS-SA    I91 @S9S_MB_2U_LIB.S9S_MB_2U(SCH_1):PAGE54
   J23  196  CB2_A SCONN288_ADR50017P130CC-SCONN2A    I25 @S9S_MB_2U_LIB.S9S_MB_2U(SCH_1):PAGE104
   J24  196  CB2_A SCONN288_ADR50017P087CC-SCONN2A   I178 @S9S_MB_2U_LIB.S9S_MB_2U(SCH_1):PAGE105

M_D_CPU1_SA_CB<3> @S9S_MB_2U_LIB.S9S_MB_2U(SCH_1):M_D_CPU1_SA_CB(3)
    U1 AP59 DDR3_SA_ECC3 SOCKET4677_AZIF0045P001C01CS-SA    I91 @S9S_MB_2U_LIB.S9S_MB_2U(SCH_1):PAGE54
   J23  198  CB3_A SCONN288_ADR50017P130CC-SCONN2A    I25 @S9S_MB_2U_LIB.S9S_MB_2U(SCH_1):PAGE104
   J24  198  CB3_A SCONN288_ADR50017P087CC-SCONN2A   I178 @S9S_MB_2U_LIB.S9S_MB_2U(SCH_1):PAGE105

M_D_CPU1_SA_CB<4> @S9S_MB_2U_LIB.S9S_MB_2U(SCH_1):M_D_CPU1_SA_CB(4)
    U1 AK57 DDR3_SA_ECC4 SOCKET4677_AZIF0045P001C01CS-SA    I91 @S9S_MB_2U_LIB.S9S_MB_2U(SCH_1):PAGE54
   J23   58  CB4_A SCONN288_ADR50017P130CC-SCONN2A    I25 @S9S_MB_2U_LIB.S9S_MB_2U(SCH_1):PAGE104
   J24   58  CB4_A SCONN288_ADR50017P087CC-SCONN2A   I178 @S9S_MB_2U_LIB.S9S_MB_2U(SCH_1):PAGE105

M_D_CPU1_SA_CB<5> @S9S_MB_2U_LIB.S9S_MB_2U(SCH_1):M_D_CPU1_SA_CB(5)
    U1 AL56 DDR3_SA_ECC5 SOCKET4677_AZIF0045P001C01CS-SA    I91 @S9S_MB_2U_LIB.S9S_MB_2U(SCH_1):PAGE54
   J23   60  CB5_A SCONN288_ADR50017P130CC-SCONN2A    I25 @S9S_MB_2U_LIB.S9S_MB_2U(SCH_1):PAGE104
   J24   60  CB5_A SCONN288_ADR50017P087CC-SCONN2A   I178 @S9S_MB_2U_LIB.S9S_MB_2U(SCH_1):PAGE105

M_D_CPU1_SA_CB<6> @S9S_MB_2U_LIB.S9S_MB_2U(SCH_1):M_D_CPU1_SA_CB(6)
    U1 AP57 DDR3_SA_ECC6 SOCKET4677_AZIF0045P001C01CS-SA    I91 @S9S_MB_2U_LIB.S9S_MB_2U(SCH_1):PAGE54
   J23  203  CB6_A SCONN288_ADR50017P130CC-SCONN2A    I25 @S9S_MB_2U_LIB.S9S_MB_2U(SCH_1):PAGE104
   J24  203  CB6_A SCONN288_ADR50017P087CC-SCONN2A   I178 @S9S_MB_2U_LIB.S9S_MB_2U(SCH_1):PAGE105

M_D_CPU1_SA_CB<7> @S9S_MB_2U_LIB.S9S_MB_2U(SCH_1):M_D_CPU1_SA_CB(7)
    U1 AN56 DDR3_SA_ECC7 SOCKET4677_AZIF0045P001C01CS-SA    I91 @S9S_MB_2U_LIB.S9S_MB_2U(SCH_1):PAGE54
   J23  205  CB7_A SCONN288_ADR50017P130CC-SCONN2A    I25 @S9S_MB_2U_LIB.S9S_MB_2U(SCH_1):PAGE104
   J24  205  CB7_A SCONN288_ADR50017P087CC-SCONN2A   I178 @S9S_MB_2U_LIB.S9S_MB_2U(SCH_1):PAGE105

M_D_CPU1_SA_CS_N<0> @S9S_MB_2U_LIB.S9S_MB_2U(SCH_1):M_D_CPU1_SA_CS_N(0)
    U1 AL54 DDR3_SA_CS_N0 SOCKET4677_AZIF0045P001C01CS-SA    I91 @S9S_MB_2U_LIB.S9S_MB_2U(SCH_1):PAGE54
   J23   64 CS0_A_N SCONN288_ADR50017P130CC-SCONN2A    I25 @S9S_MB_2U_LIB.S9S_MB_2U(SCH_1):PAGE104

M_D_CPU1_SA_CS_N<1> @S9S_MB_2U_LIB.S9S_MB_2U(SCH_1):M_D_CPU1_SA_CS_N(1)
    U1 AK53 DDR3_SA_CS_N1 SOCKET4677_AZIF0045P001C01CS-SA    I91 @S9S_MB_2U_LIB.S9S_MB_2U(SCH_1):PAGE54
   J23  209 CS1_A_N SCONN288_ADR50017P130CC-SCONN2A    I25 @S9S_MB_2U_LIB.S9S_MB_2U(SCH_1):PAGE104

M_D_CPU1_SA_CS_N<2> @S9S_MB_2U_LIB.S9S_MB_2U(SCH_1):M_D_CPU1_SA_CS_N(2)
    U1 AN54 DDR3_SA_CS_N2 SOCKET4677_AZIF0045P001C01CS-SA    I91 @S9S_MB_2U_LIB.S9S_MB_2U(SCH_1):PAGE54
   J24   64 CS0_A_N SCONN288_ADR50017P087CC-SCONN2A   I178 @S9S_MB_2U_LIB.S9S_MB_2U(SCH_1):PAGE105

M_D_CPU1_SA_CS_N<3> @S9S_MB_2U_LIB.S9S_MB_2U(SCH_1):M_D_CPU1_SA_CS_N(3)
    U1 AP53 DDR3_SA_CS_N3 SOCKET4677_AZIF0045P001C01CS-SA    I91 @S9S_MB_2U_LIB.S9S_MB_2U(SCH_1):PAGE54
   J24  209 CS1_A_N SCONN288_ADR50017P087CC-SCONN2A   I178 @S9S_MB_2U_LIB.S9S_MB_2U(SCH_1):PAGE105

M_D_CPU1_SA_DQ<0> @S9S_MB_2U_LIB.S9S_MB_2U(SCH_1):M_D_CPU1_SA_DQ(0)
    U1 AD75 DDR3_SA_DQ0 SOCKET4677_AZIF0045P001C01CS-SA    I91 @S9S_MB_2U_LIB.S9S_MB_2U(SCH_1):PAGE54
   J23    7  DQ0_A SCONN288_ADR50017P130CC-SCONN2A    I25 @S9S_MB_2U_LIB.S9S_MB_2U(SCH_1):PAGE104
   J24    7  DQ0_A SCONN288_ADR50017P087CC-SCONN2A   I178 @S9S_MB_2U_LIB.S9S_MB_2U(SCH_1):PAGE105

M_D_CPU1_SA_DQ<10> @S9S_MB_2U_LIB.S9S_MB_2U(SCH_1):M_D_CPU1_SA_DQ(10)
    U1 AN78 DDR3_SA_DQ10 SOCKET4677_AZIF0045P001C01CS-SA    I91 @S9S_MB_2U_LIB.S9S_MB_2U(SCH_1):PAGE54
   J23  163 DQ10_A SCONN288_ADR50017P130CC-SCONN2A    I25 @S9S_MB_2U_LIB.S9S_MB_2U(SCH_1):PAGE104
   J24  163 DQ10_A SCONN288_ADR50017P087CC-SCONN2A   I178 @S9S_MB_2U_LIB.S9S_MB_2U(SCH_1):PAGE105

M_D_CPU1_SA_DQ<11> @S9S_MB_2U_LIB.S9S_MB_2U(SCH_1):M_D_CPU1_SA_DQ(11)
    U1 AP77 DDR3_SA_DQ11 SOCKET4677_AZIF0045P001C01CS-SA    I91 @S9S_MB_2U_LIB.S9S_MB_2U(SCH_1):PAGE54
   J23  165 DQ11_A SCONN288_ADR50017P130CC-SCONN2A    I25 @S9S_MB_2U_LIB.S9S_MB_2U(SCH_1):PAGE104
   J24  165 DQ11_A SCONN288_ADR50017P087CC-SCONN2A   I178 @S9S_MB_2U_LIB.S9S_MB_2U(SCH_1):PAGE105

M_D_CPU1_SA_DQ<12> @S9S_MB_2U_LIB.S9S_MB_2U(SCH_1):M_D_CPU1_SA_DQ(12)
    U1 AK75 DDR3_SA_DQ12 SOCKET4677_AZIF0045P001C01CS-SA    I91 @S9S_MB_2U_LIB.S9S_MB_2U(SCH_1):PAGE54
   J23   25 DQ12_A SCONN288_ADR50017P130CC-SCONN2A    I25 @S9S_MB_2U_LIB.S9S_MB_2U(SCH_1):PAGE104
   J24   25 DQ12_A SCONN288_ADR50017P087CC-SCONN2A   I178 @S9S_MB_2U_LIB.S9S_MB_2U(SCH_1):PAGE105

M_D_CPU1_SA_DQ<13> @S9S_MB_2U_LIB.S9S_MB_2U(SCH_1):M_D_CPU1_SA_DQ(13)
    U1 AL74 DDR3_SA_DQ13 SOCKET4677_AZIF0045P001C01CS-SA    I91 @S9S_MB_2U_LIB.S9S_MB_2U(SCH_1):PAGE54
   J23   27 DQ13_A SCONN288_ADR50017P130CC-SCONN2A    I25 @S9S_MB_2U_LIB.S9S_MB_2U(SCH_1):PAGE104
   J24   27 DQ13_A SCONN288_ADR50017P087CC-SCONN2A   I178 @S9S_MB_2U_LIB.S9S_MB_2U(SCH_1):PAGE105

M_D_CPU1_SA_DQ<14> @S9S_MB_2U_LIB.S9S_MB_2U(SCH_1):M_D_CPU1_SA_DQ(14)
    U1 AP75 DDR3_SA_DQ14 SOCKET4677_AZIF0045P001C01CS-SA    I91 @S9S_MB_2U_LIB.S9S_MB_2U(SCH_1):PAGE54
   J23  170 DQ14_A SCONN288_ADR50017P130CC-SCONN2A    I25 @S9S_MB_2U_LIB.S9S_MB_2U(SCH_1):PAGE104
   J24  170 DQ14_A SCONN288_ADR50017P087CC-SCONN2A   I178 @S9S_MB_2U_LIB.S9S_MB_2U(SCH_1):PAGE105

M_D_CPU1_SA_DQ<15> @S9S_MB_2U_LIB.S9S_MB_2U(SCH_1):M_D_CPU1_SA_DQ(15)
    U1 AN74 DDR3_SA_DQ15 SOCKET4677_AZIF0045P001C01CS-SA    I91 @S9S_MB_2U_LIB.S9S_MB_2U(SCH_1):PAGE54
   J23  172 DQ15_A SCONN288_ADR50017P130CC-SCONN2A    I25 @S9S_MB_2U_LIB.S9S_MB_2U(SCH_1):PAGE104
   J24  172 DQ15_A SCONN288_ADR50017P087CC-SCONN2A   I178 @S9S_MB_2U_LIB.S9S_MB_2U(SCH_1):PAGE105

M_D_CPU1_SA_DQ<16> @S9S_MB_2U_LIB.S9S_MB_2U(SCH_1):M_D_CPU1_SA_DQ(16)
    U1 AL72 DDR3_SA_DQ16 SOCKET4677_AZIF0045P001C01CS-SA    I91 @S9S_MB_2U_LIB.S9S_MB_2U(SCH_1):PAGE54
   J23   29 DQ16_A SCONN288_ADR50017P130CC-SCONN2A    I25 @S9S_MB_2U_LIB.S9S_MB_2U(SCH_1):PAGE104
   J24   29 DQ16_A SCONN288_ADR50017P087CC-SCONN2A   I178 @S9S_MB_2U_LIB.S9S_MB_2U(SCH_1):PAGE105

M_D_CPU1_SA_DQ<17> @S9S_MB_2U_LIB.S9S_MB_2U(SCH_1):M_D_CPU1_SA_DQ(17)
    U1 AK71 DDR3_SA_DQ17 SOCKET4677_AZIF0045P001C01CS-SA    I91 @S9S_MB_2U_LIB.S9S_MB_2U(SCH_1):PAGE54
   J23   31 DQ17_A SCONN288_ADR50017P130CC-SCONN2A    I25 @S9S_MB_2U_LIB.S9S_MB_2U(SCH_1):PAGE104
   J24   31 DQ17_A SCONN288_ADR50017P087CC-SCONN2A   I178 @S9S_MB_2U_LIB.S9S_MB_2U(SCH_1):PAGE105

M_D_CPU1_SA_DQ<18> @S9S_MB_2U_LIB.S9S_MB_2U(SCH_1):M_D_CPU1_SA_DQ(18)
    U1 AN72 DDR3_SA_DQ18 SOCKET4677_AZIF0045P001C01CS-SA    I91 @S9S_MB_2U_LIB.S9S_MB_2U(SCH_1):PAGE54
   J23  174 DQ18_A SCONN288_ADR50017P130CC-SCONN2A    I25 @S9S_MB_2U_LIB.S9S_MB_2U(SCH_1):PAGE104
   J24  174 DQ18_A SCONN288_ADR50017P087CC-SCONN2A   I178 @S9S_MB_2U_LIB.S9S_MB_2U(SCH_1):PAGE105

M_D_CPU1_SA_DQ<19> @S9S_MB_2U_LIB.S9S_MB_2U(SCH_1):M_D_CPU1_SA_DQ(19)
    U1 AP71 DDR3_SA_DQ19 SOCKET4677_AZIF0045P001C01CS-SA    I91 @S9S_MB_2U_LIB.S9S_MB_2U(SCH_1):PAGE54
   J23  176 DQ19_A SCONN288_ADR50017P130CC-SCONN2A    I25 @S9S_MB_2U_LIB.S9S_MB_2U(SCH_1):PAGE104
   J24  176 DQ19_A SCONN288_ADR50017P087CC-SCONN2A   I178 @S9S_MB_2U_LIB.S9S_MB_2U(SCH_1):PAGE105

M_D_CPU1_SA_DQ<1> @S9S_MB_2U_LIB.S9S_MB_2U(SCH_1):M_D_CPU1_SA_DQ(1)
    U1 AC74 DDR3_SA_DQ1 SOCKET4677_AZIF0045P001C01CS-SA    I91 @S9S_MB_2U_LIB.S9S_MB_2U(SCH_1):PAGE54
   J23    9  DQ1_A SCONN288_ADR50017P130CC-SCONN2A    I25 @S9S_MB_2U_LIB.S9S_MB_2U(SCH_1):PAGE104
   J24    9  DQ1_A SCONN288_ADR50017P087CC-SCONN2A   I178 @S9S_MB_2U_LIB.S9S_MB_2U(SCH_1):PAGE105

M_D_CPU1_SA_DQ<20> @S9S_MB_2U_LIB.S9S_MB_2U(SCH_1):M_D_CPU1_SA_DQ(20)
    U1 AK69 DDR3_SA_DQ20 SOCKET4677_AZIF0045P001C01CS-SA    I91 @S9S_MB_2U_LIB.S9S_MB_2U(SCH_1):PAGE54
   J23   36 DQ20_A SCONN288_ADR50017P130CC-SCONN2A    I25 @S9S_MB_2U_LIB.S9S_MB_2U(SCH_1):PAGE104
   J24   36 DQ20_A SCONN288_ADR50017P087CC-SCONN2A   I178 @S9S_MB_2U_LIB.S9S_MB_2U(SCH_1):PAGE105

M_D_CPU1_SA_DQ<21> @S9S_MB_2U_LIB.S9S_MB_2U(SCH_1):M_D_CPU1_SA_DQ(21)
    U1 AL68 DDR3_SA_DQ21 SOCKET4677_AZIF0045P001C01CS-SA    I91 @S9S_MB_2U_LIB.S9S_MB_2U(SCH_1):PAGE54
   J23   38 DQ21_A SCONN288_ADR50017P130CC-SCONN2A    I25 @S9S_MB_2U_LIB.S9S_MB_2U(SCH_1):PAGE104
   J24   38 DQ21_A SCONN288_ADR50017P087CC-SCONN2A   I178 @S9S_MB_2U_LIB.S9S_MB_2U(SCH_1):PAGE105

M_D_CPU1_SA_DQ<22> @S9S_MB_2U_LIB.S9S_MB_2U(SCH_1):M_D_CPU1_SA_DQ(22)
    U1 AP69 DDR3_SA_DQ22 SOCKET4677_AZIF0045P001C01CS-SA    I91 @S9S_MB_2U_LIB.S9S_MB_2U(SCH_1):PAGE54
   J23  181 DQ22_A SCONN288_ADR50017P130CC-SCONN2A    I25 @S9S_MB_2U_LIB.S9S_MB_2U(SCH_1):PAGE104
   J24  181 DQ22_A SCONN288_ADR50017P087CC-SCONN2A   I178 @S9S_MB_2U_LIB.S9S_MB_2U(SCH_1):PAGE105

M_D_CPU1_SA_DQ<23> @S9S_MB_2U_LIB.S9S_MB_2U(SCH_1):M_D_CPU1_SA_DQ(23)
    U1 AN68 DDR3_SA_DQ23 SOCKET4677_AZIF0045P001C01CS-SA    I91 @S9S_MB_2U_LIB.S9S_MB_2U(SCH_1):PAGE54
   J23  183 DQ23_A SCONN288_ADR50017P130CC-SCONN2A    I25 @S9S_MB_2U_LIB.S9S_MB_2U(SCH_1):PAGE104
   J24  183 DQ23_A SCONN288_ADR50017P087CC-SCONN2A   I178 @S9S_MB_2U_LIB.S9S_MB_2U(SCH_1):PAGE105

M_D_CPU1_SA_DQ<24> @S9S_MB_2U_LIB.S9S_MB_2U(SCH_1):M_D_CPU1_SA_DQ(24)
    U1 AL66 DDR3_SA_DQ24 SOCKET4677_AZIF0045P001C01CS-SA    I91 @S9S_MB_2U_LIB.S9S_MB_2U(SCH_1):PAGE54
   J23   40 DQ24_A SCONN288_ADR50017P130CC-SCONN2A    I25 @S9S_MB_2U_LIB.S9S_MB_2U(SCH_1):PAGE104
   J24   40 DQ24_A SCONN288_ADR50017P087CC-SCONN2A   I178 @S9S_MB_2U_LIB.S9S_MB_2U(SCH_1):PAGE105

M_D_CPU1_SA_DQ<25> @S9S_MB_2U_LIB.S9S_MB_2U(SCH_1):M_D_CPU1_SA_DQ(25)
    U1 AK65 DDR3_SA_DQ25 SOCKET4677_AZIF0045P001C01CS-SA    I91 @S9S_MB_2U_LIB.S9S_MB_2U(SCH_1):PAGE54
   J23   42 DQ25_A SCONN288_ADR50017P130CC-SCONN2A    I25 @S9S_MB_2U_LIB.S9S_MB_2U(SCH_1):PAGE104
   J24   42 DQ25_A SCONN288_ADR50017P087CC-SCONN2A   I178 @S9S_MB_2U_LIB.S9S_MB_2U(SCH_1):PAGE105

M_D_CPU1_SA_DQ<26> @S9S_MB_2U_LIB.S9S_MB_2U(SCH_1):M_D_CPU1_SA_DQ(26)
    U1 AN66 DDR3_SA_DQ26 SOCKET4677_AZIF0045P001C01CS-SA    I91 @S9S_MB_2U_LIB.S9S_MB_2U(SCH_1):PAGE54
   J23  185 DQ26_A SCONN288_ADR50017P130CC-SCONN2A    I25 @S9S_MB_2U_LIB.S9S_MB_2U(SCH_1):PAGE104
   J24  185 DQ26_A SCONN288_ADR50017P087CC-SCONN2A   I178 @S9S_MB_2U_LIB.S9S_MB_2U(SCH_1):PAGE105

M_D_CPU1_SA_DQ<27> @S9S_MB_2U_LIB.S9S_MB_2U(SCH_1):M_D_CPU1_SA_DQ(27)
    U1 AP65 DDR3_SA_DQ27 SOCKET4677_AZIF0045P001C01CS-SA    I91 @S9S_MB_2U_LIB.S9S_MB_2U(SCH_1):PAGE54
   J23  187 DQ27_A SCONN288_ADR50017P130CC-SCONN2A    I25 @S9S_MB_2U_LIB.S9S_MB_2U(SCH_1):PAGE104
   J24  187 DQ27_A SCONN288_ADR50017P087CC-SCONN2A   I178 @S9S_MB_2U_LIB.S9S_MB_2U(SCH_1):PAGE105

M_D_CPU1_SA_DQ<28> @S9S_MB_2U_LIB.S9S_MB_2U(SCH_1):M_D_CPU1_SA_DQ(28)
    U1 AK63 DDR3_SA_DQ28 SOCKET4677_AZIF0045P001C01CS-SA    I91 @S9S_MB_2U_LIB.S9S_MB_2U(SCH_1):PAGE54
   J23   47 DQ28_A SCONN288_ADR50017P130CC-SCONN2A    I25 @S9S_MB_2U_LIB.S9S_MB_2U(SCH_1):PAGE104
   J24   47 DQ28_A SCONN288_ADR50017P087CC-SCONN2A   I178 @S9S_MB_2U_LIB.S9S_MB_2U(SCH_1):PAGE105

M_D_CPU1_SA_DQ<29> @S9S_MB_2U_LIB.S9S_MB_2U(SCH_1):M_D_CPU1_SA_DQ(29)
    U1 AL62 DDR3_SA_DQ29 SOCKET4677_AZIF0045P001C01CS-SA    I91 @S9S_MB_2U_LIB.S9S_MB_2U(SCH_1):PAGE54
   J23   49 DQ29_A SCONN288_ADR50017P130CC-SCONN2A    I25 @S9S_MB_2U_LIB.S9S_MB_2U(SCH_1):PAGE104
   J24   49 DQ29_A SCONN288_ADR50017P087CC-SCONN2A   I178 @S9S_MB_2U_LIB.S9S_MB_2U(SCH_1):PAGE105

M_D_CPU1_SA_DQ<2> @S9S_MB_2U_LIB.S9S_MB_2U(SCH_1):M_D_CPU1_SA_DQ(2)
    U1 AF75 DDR3_SA_DQ2 SOCKET4677_AZIF0045P001C01CS-SA    I91 @S9S_MB_2U_LIB.S9S_MB_2U(SCH_1):PAGE54
   J23  152  DQ2_A SCONN288_ADR50017P130CC-SCONN2A    I25 @S9S_MB_2U_LIB.S9S_MB_2U(SCH_1):PAGE104
   J24  152  DQ2_A SCONN288_ADR50017P087CC-SCONN2A   I178 @S9S_MB_2U_LIB.S9S_MB_2U(SCH_1):PAGE105

M_D_CPU1_SA_DQ<30> @S9S_MB_2U_LIB.S9S_MB_2U(SCH_1):M_D_CPU1_SA_DQ(30)
    U1 AP63 DDR3_SA_DQ30 SOCKET4677_AZIF0045P001C01CS-SA    I91 @S9S_MB_2U_LIB.S9S_MB_2U(SCH_1):PAGE54
   J23  192 DQ30_A SCONN288_ADR50017P130CC-SCONN2A    I25 @S9S_MB_2U_LIB.S9S_MB_2U(SCH_1):PAGE104
   J24  192 DQ30_A SCONN288_ADR50017P087CC-SCONN2A   I178 @S9S_MB_2U_LIB.S9S_MB_2U(SCH_1):PAGE105

M_D_CPU1_SA_DQ<31> @S9S_MB_2U_LIB.S9S_MB_2U(SCH_1):M_D_CPU1_SA_DQ(31)
    U1 AN62 DDR3_SA_DQ31 SOCKET4677_AZIF0045P001C01CS-SA    I91 @S9S_MB_2U_LIB.S9S_MB_2U(SCH_1):PAGE54
   J23  194 DQ31_A SCONN288_ADR50017P130CC-SCONN2A    I25 @S9S_MB_2U_LIB.S9S_MB_2U(SCH_1):PAGE104
   J24  194 DQ31_A SCONN288_ADR50017P087CC-SCONN2A   I178 @S9S_MB_2U_LIB.S9S_MB_2U(SCH_1):PAGE105

M_D_CPU1_SA_DQ<3> @S9S_MB_2U_LIB.S9S_MB_2U(SCH_1):M_D_CPU1_SA_DQ(3)
    U1 AG74 DDR3_SA_DQ3 SOCKET4677_AZIF0045P001C01CS-SA    I91 @S9S_MB_2U_LIB.S9S_MB_2U(SCH_1):PAGE54
   J23  154  DQ3_A SCONN288_ADR50017P130CC-SCONN2A    I25 @S9S_MB_2U_LIB.S9S_MB_2U(SCH_1):PAGE104
   J24  154  DQ3_A SCONN288_ADR50017P087CC-SCONN2A   I178 @S9S_MB_2U_LIB.S9S_MB_2U(SCH_1):PAGE105

M_D_CPU1_SA_DQ<4> @S9S_MB_2U_LIB.S9S_MB_2U(SCH_1):M_D_CPU1_SA_DQ(4)
    U1 AC72 DDR3_SA_DQ4 SOCKET4677_AZIF0045P001C01CS-SA    I91 @S9S_MB_2U_LIB.S9S_MB_2U(SCH_1):PAGE54
   J23   14  DQ4_A SCONN288_ADR50017P130CC-SCONN2A    I25 @S9S_MB_2U_LIB.S9S_MB_2U(SCH_1):PAGE104
   J24   14  DQ4_A SCONN288_ADR50017P087CC-SCONN2A   I178 @S9S_MB_2U_LIB.S9S_MB_2U(SCH_1):PAGE105

M_D_CPU1_SA_DQ<5> @S9S_MB_2U_LIB.S9S_MB_2U(SCH_1):M_D_CPU1_SA_DQ(5)
    U1 AD71 DDR3_SA_DQ5 SOCKET4677_AZIF0045P001C01CS-SA    I91 @S9S_MB_2U_LIB.S9S_MB_2U(SCH_1):PAGE54
   J23   16  DQ5_A SCONN288_ADR50017P130CC-SCONN2A    I25 @S9S_MB_2U_LIB.S9S_MB_2U(SCH_1):PAGE104
   J24   16  DQ5_A SCONN288_ADR50017P087CC-SCONN2A   I178 @S9S_MB_2U_LIB.S9S_MB_2U(SCH_1):PAGE105

M_D_CPU1_SA_DQ<6> @S9S_MB_2U_LIB.S9S_MB_2U(SCH_1):M_D_CPU1_SA_DQ(6)
    U1 AG72 DDR3_SA_DQ6 SOCKET4677_AZIF0045P001C01CS-SA    I91 @S9S_MB_2U_LIB.S9S_MB_2U(SCH_1):PAGE54
   J23  159  DQ6_A SCONN288_ADR50017P130CC-SCONN2A    I25 @S9S_MB_2U_LIB.S9S_MB_2U(SCH_1):PAGE104
   J24  159  DQ6_A SCONN288_ADR50017P087CC-SCONN2A   I178 @S9S_MB_2U_LIB.S9S_MB_2U(SCH_1):PAGE105

M_D_CPU1_SA_DQ<7> @S9S_MB_2U_LIB.S9S_MB_2U(SCH_1):M_D_CPU1_SA_DQ(7)
    U1 AF71 DDR3_SA_DQ7 SOCKET4677_AZIF0045P001C01CS-SA    I91 @S9S_MB_2U_LIB.S9S_MB_2U(SCH_1):PAGE54
   J23  161  DQ7_A SCONN288_ADR50017P130CC-SCONN2A    I25 @S9S_MB_2U_LIB.S9S_MB_2U(SCH_1):PAGE104
   J24  161  DQ7_A SCONN288_ADR50017P087CC-SCONN2A   I178 @S9S_MB_2U_LIB.S9S_MB_2U(SCH_1):PAGE105

M_D_CPU1_SA_DQ<8> @S9S_MB_2U_LIB.S9S_MB_2U(SCH_1):M_D_CPU1_SA_DQ(8)
    U1 AL78 DDR3_SA_DQ8 SOCKET4677_AZIF0045P001C01CS-SA    I91 @S9S_MB_2U_LIB.S9S_MB_2U(SCH_1):PAGE54
   J23   18  DQ8_A SCONN288_ADR50017P130CC-SCONN2A    I25 @S9S_MB_2U_LIB.S9S_MB_2U(SCH_1):PAGE104
   J24   18  DQ8_A SCONN288_ADR50017P087CC-SCONN2A   I178 @S9S_MB_2U_LIB.S9S_MB_2U(SCH_1):PAGE105

M_D_CPU1_SA_DQ<9> @S9S_MB_2U_LIB.S9S_MB_2U(SCH_1):M_D_CPU1_SA_DQ(9)
    U1 AK77 DDR3_SA_DQ9 SOCKET4677_AZIF0045P001C01CS-SA    I91 @S9S_MB_2U_LIB.S9S_MB_2U(SCH_1):PAGE54
   J23   20  DQ9_A SCONN288_ADR50017P130CC-SCONN2A    I25 @S9S_MB_2U_LIB.S9S_MB_2U(SCH_1):PAGE104
   J24   20  DQ9_A SCONN288_ADR50017P087CC-SCONN2A   I178 @S9S_MB_2U_LIB.S9S_MB_2U(SCH_1):PAGE105

M_D_CPU1_SA_DQS_DN<0> @S9S_MB_2U_LIB.S9S_MB_2U(SCH_1):M_D_CPU1_SA_DQS_DN(0)
    U1 AB73 DDR3_SA_DQS_DN0 SOCKET4677_AZIF0045P001C01CS-SA    I91 @S9S_MB_2U_LIB.S9S_MB_2U(SCH_1):PAGE54
   J23   12 DQS0_A_C SCONN288_ADR50017P130CC-SCONN2A   I178 @S9S_MB_2U_LIB.S9S_MB_2U(SCH_1):PAGE104
   J24   12 DQS0_A_C SCONN288_ADR50017P087CC-SCONN2A   I181 @S9S_MB_2U_LIB.S9S_MB_2U(SCH_1):PAGE105

M_D_CPU1_SA_DQS_DN<1> @S9S_MB_2U_LIB.S9S_MB_2U(SCH_1):M_D_CPU1_SA_DQS_DN(1)
    U1 AJ76 DDR3_SA_DQS_DN1 SOCKET4677_AZIF0045P001C01CS-SA    I91 @S9S_MB_2U_LIB.S9S_MB_2U(SCH_1):PAGE54
   J23   23 DQS1_A_C SCONN288_ADR50017P130CC-SCONN2A   I178 @S9S_MB_2U_LIB.S9S_MB_2U(SCH_1):PAGE104
   J24   23 DQS1_A_C SCONN288_ADR50017P087CC-SCONN2A   I181 @S9S_MB_2U_LIB.S9S_MB_2U(SCH_1):PAGE105

M_D_CPU1_SA_DQS_DN<2> @S9S_MB_2U_LIB.S9S_MB_2U(SCH_1):M_D_CPU1_SA_DQS_DN(2)
    U1 AJ70 DDR3_SA_DQS_DN2 SOCKET4677_AZIF0045P001C01CS-SA    I91 @S9S_MB_2U_LIB.S9S_MB_2U(SCH_1):PAGE54
   J23   34 DQS2_A_C SCONN288_ADR50017P130CC-SCONN2A   I178 @S9S_MB_2U_LIB.S9S_MB_2U(SCH_1):PAGE104
   J24   34 DQS2_A_C SCONN288_ADR50017P087CC-SCONN2A   I181 @S9S_MB_2U_LIB.S9S_MB_2U(SCH_1):PAGE105

M_D_CPU1_SA_DQS_DN<3> @S9S_MB_2U_LIB.S9S_MB_2U(SCH_1):M_D_CPU1_SA_DQS_DN(3)
    U1 AJ64 DDR3_SA_DQS_DN3 SOCKET4677_AZIF0045P001C01CS-SA    I91 @S9S_MB_2U_LIB.S9S_MB_2U(SCH_1):PAGE54
   J23   45 DQS3_A_C SCONN288_ADR50017P130CC-SCONN2A   I178 @S9S_MB_2U_LIB.S9S_MB_2U(SCH_1):PAGE104
   J24   45 DQS3_A_C SCONN288_ADR50017P087CC-SCONN2A   I181 @S9S_MB_2U_LIB.S9S_MB_2U(SCH_1):PAGE105

M_D_CPU1_SA_DQS_DN<4> @S9S_MB_2U_LIB.S9S_MB_2U(SCH_1):M_D_CPU1_SA_DQS_DN(4)
    U1 AJ58 DDR3_SA_DQS_DN4 SOCKET4677_AZIF0045P001C01CS-SA    I91 @S9S_MB_2U_LIB.S9S_MB_2U(SCH_1):PAGE54
   J23   56 DQS4_A_C SCONN288_ADR50017P130CC-SCONN2A   I178 @S9S_MB_2U_LIB.S9S_MB_2U(SCH_1):PAGE104
   J24   56 DQS4_A_C SCONN288_ADR50017P087CC-SCONN2A   I181 @S9S_MB_2U_LIB.S9S_MB_2U(SCH_1):PAGE105

M_D_CPU1_SA_DQS_DN<5> @S9S_MB_2U_LIB.S9S_MB_2U(SCH_1):M_D_CPU1_SA_DQS_DN(5)
    U1 AH73 DDR3_SA_DQS_DN5 SOCKET4677_AZIF0045P001C01CS-SA    I91 @S9S_MB_2U_LIB.S9S_MB_2U(SCH_1):PAGE54
   J23  156 DQS5_A_C||TDQS5_A_C||DQS5_A_T||TDQS5_A_T SCONN288_ADR50017P130CC-SCONN2A   I178 @S9S_MB_2U_LIB.S9S_MB_2U(SCH_1):PAGE104
   J24  156 DQS5_A_C||TDQS5_A_C||DQS5_A_T||TDQS5_A_T SCONN288_ADR50017P087CC-SCONN2A   I181 @S9S_MB_2U_LIB.S9S_MB_2U(SCH_1):PAGE105

M_D_CPU1_SA_DQS_DN<6> @S9S_MB_2U_LIB.S9S_MB_2U(SCH_1):M_D_CPU1_SA_DQS_DN(6)
    U1 AN76 DDR3_SA_DQS_DN6 SOCKET4677_AZIF0045P001C01CS-SA    I91 @S9S_MB_2U_LIB.S9S_MB_2U(SCH_1):PAGE54
   J23  167 DQS6_A_C||TDQS6_A_C||DQS6_A_T||TDQS6_A_T SCONN288_ADR50017P130CC-SCONN2A   I178 @S9S_MB_2U_LIB.S9S_MB_2U(SCH_1):PAGE104
   J24  167 DQS6_A_C||TDQS6_A_C||DQS6_A_T||TDQS6_A_T SCONN288_ADR50017P087CC-SCONN2A   I181 @S9S_MB_2U_LIB.S9S_MB_2U(SCH_1):PAGE105

M_D_CPU1_SA_DQS_DN<7> @S9S_MB_2U_LIB.S9S_MB_2U(SCH_1):M_D_CPU1_SA_DQS_DN(7)
    U1 AN70 DDR3_SA_DQS_DN7 SOCKET4677_AZIF0045P001C01CS-SA    I91 @S9S_MB_2U_LIB.S9S_MB_2U(SCH_1):PAGE54
   J23  178 DQS7_A_C||TDQS7_A_C SCONN288_ADR50017P130CC-SCONN2A   I178 @S9S_MB_2U_LIB.S9S_MB_2U(SCH_1):PAGE104
   J24  178 DQS7_A_C||TDQS7_A_C SCONN288_ADR50017P087CC-SCONN2A   I181 @S9S_MB_2U_LIB.S9S_MB_2U(SCH_1):PAGE105

M_D_CPU1_SA_DQS_DN<8> @S9S_MB_2U_LIB.S9S_MB_2U(SCH_1):M_D_CPU1_SA_DQS_DN(8)
    U1 AN64 DDR3_SA_DQS_DN8 SOCKET4677_AZIF0045P001C01CS-SA    I91 @S9S_MB_2U_LIB.S9S_MB_2U(SCH_1):PAGE54
   J23  189 DQS8_A_C||TDQS8_A_C SCONN288_ADR50017P130CC-SCONN2A   I178 @S9S_MB_2U_LIB.S9S_MB_2U(SCH_1):PAGE104
   J24  189 DQS8_A_C||TDQS8_A_C SCONN288_ADR50017P087CC-SCONN2A   I181 @S9S_MB_2U_LIB.S9S_MB_2U(SCH_1):PAGE105

M_D_CPU1_SA_DQS_DN<9> @S9S_MB_2U_LIB.S9S_MB_2U(SCH_1):M_D_CPU1_SA_DQS_DN(9)
    U1 AN58 DDR3_SA_DQS_DN9 SOCKET4677_AZIF0045P001C01CS-SA    I91 @S9S_MB_2U_LIB.S9S_MB_2U(SCH_1):PAGE54
   J23  200 DQS9_A_C||TDQS9_A_C SCONN288_ADR50017P130CC-SCONN2A   I178 @S9S_MB_2U_LIB.S9S_MB_2U(SCH_1):PAGE104
   J24  200 DQS9_A_C||TDQS9_A_C SCONN288_ADR50017P087CC-SCONN2A   I181 @S9S_MB_2U_LIB.S9S_MB_2U(SCH_1):PAGE105

M_D_CPU1_SA_DQS_DP<0> @S9S_MB_2U_LIB.S9S_MB_2U(SCH_1):M_D_CPU1_SA_DQS_DP(0)
    U1 AD73 DDR3_SA_DQS_DP0 SOCKET4677_AZIF0045P001C01CS-SA    I91 @S9S_MB_2U_LIB.S9S_MB_2U(SCH_1):PAGE54
   J23   11 DQS0_A_T SCONN288_ADR50017P130CC-SCONN2A   I178 @S9S_MB_2U_LIB.S9S_MB_2U(SCH_1):PAGE104
   J24   11 DQS0_A_T SCONN288_ADR50017P087CC-SCONN2A   I181 @S9S_MB_2U_LIB.S9S_MB_2U(SCH_1):PAGE105

M_D_CPU1_SA_DQS_DP<1> @S9S_MB_2U_LIB.S9S_MB_2U(SCH_1):M_D_CPU1_SA_DQS_DP(1)
    U1 AL76 DDR3_SA_DQS_DP1 SOCKET4677_AZIF0045P001C01CS-SA    I91 @S9S_MB_2U_LIB.S9S_MB_2U(SCH_1):PAGE54
   J23   22 DQS1_A_T SCONN288_ADR50017P130CC-SCONN2A   I178 @S9S_MB_2U_LIB.S9S_MB_2U(SCH_1):PAGE104
   J24   22 DQS1_A_T SCONN288_ADR50017P087CC-SCONN2A   I181 @S9S_MB_2U_LIB.S9S_MB_2U(SCH_1):PAGE105

M_D_CPU1_SA_DQS_DP<2> @S9S_MB_2U_LIB.S9S_MB_2U(SCH_1):M_D_CPU1_SA_DQS_DP(2)
    U1 AL70 DDR3_SA_DQS_DP2 SOCKET4677_AZIF0045P001C01CS-SA    I91 @S9S_MB_2U_LIB.S9S_MB_2U(SCH_1):PAGE54
   J23   33 DQS2_A_T SCONN288_ADR50017P130CC-SCONN2A   I178 @S9S_MB_2U_LIB.S9S_MB_2U(SCH_1):PAGE104
   J24   33 DQS2_A_T SCONN288_ADR50017P087CC-SCONN2A   I181 @S9S_MB_2U_LIB.S9S_MB_2U(SCH_1):PAGE105

M_D_CPU1_SA_DQS_DP<3> @S9S_MB_2U_LIB.S9S_MB_2U(SCH_1):M_D_CPU1_SA_DQS_DP(3)
    U1 AL64 DDR3_SA_DQS_DP3 SOCKET4677_AZIF0045P001C01CS-SA    I91 @S9S_MB_2U_LIB.S9S_MB_2U(SCH_1):PAGE54
   J23   44 DQS3_A_T SCONN288_ADR50017P130CC-SCONN2A   I178 @S9S_MB_2U_LIB.S9S_MB_2U(SCH_1):PAGE104
   J24   44 DQS3_A_T SCONN288_ADR50017P087CC-SCONN2A   I181 @S9S_MB_2U_LIB.S9S_MB_2U(SCH_1):PAGE105

M_D_CPU1_SA_DQS_DP<4> @S9S_MB_2U_LIB.S9S_MB_2U(SCH_1):M_D_CPU1_SA_DQS_DP(4)
    U1 AL58 DDR3_SA_DQS_DP4 SOCKET4677_AZIF0045P001C01CS-SA    I91 @S9S_MB_2U_LIB.S9S_MB_2U(SCH_1):PAGE54
   J23   55 DQS4_A_T SCONN288_ADR50017P130CC-SCONN2A   I178 @S9S_MB_2U_LIB.S9S_MB_2U(SCH_1):PAGE104
   J24   55 DQS4_A_T SCONN288_ADR50017P087CC-SCONN2A   I181 @S9S_MB_2U_LIB.S9S_MB_2U(SCH_1):PAGE105

M_D_CPU1_SA_DQS_DP<5> @S9S_MB_2U_LIB.S9S_MB_2U(SCH_1):M_D_CPU1_SA_DQS_DP(5)
    U1 AF73 DDR3_SA_DQS_DP5 SOCKET4677_AZIF0045P001C01CS-SA    I91 @S9S_MB_2U_LIB.S9S_MB_2U(SCH_1):PAGE54
   J23  157 DQS5_A_T||TDQS5_A_T SCONN288_ADR50017P130CC-SCONN2A   I178 @S9S_MB_2U_LIB.S9S_MB_2U(SCH_1):PAGE104
   J24  157 DQS5_A_T||TDQS5_A_T SCONN288_ADR50017P087CC-SCONN2A   I181 @S9S_MB_2U_LIB.S9S_MB_2U(SCH_1):PAGE105

M_D_CPU1_SA_DQS_DP<6> @S9S_MB_2U_LIB.S9S_MB_2U(SCH_1):M_D_CPU1_SA_DQS_DP(6)
    U1 AR76 DDR3_SA_DQS_DP6 SOCKET4677_AZIF0045P001C01CS-SA    I91 @S9S_MB_2U_LIB.S9S_MB_2U(SCH_1):PAGE54
   J23  168 DQS6_A_T||TDQS6_A_T SCONN288_ADR50017P130CC-SCONN2A   I178 @S9S_MB_2U_LIB.S9S_MB_2U(SCH_1):PAGE104
   J24  168 DQS6_A_T||TDQS6_A_T SCONN288_ADR50017P087CC-SCONN2A   I181 @S9S_MB_2U_LIB.S9S_MB_2U(SCH_1):PAGE105

M_D_CPU1_SA_DQS_DP<7> @S9S_MB_2U_LIB.S9S_MB_2U(SCH_1):M_D_CPU1_SA_DQS_DP(7)
    U1 AR70 DDR3_SA_DQS_DP7 SOCKET4677_AZIF0045P001C01CS-SA    I91 @S9S_MB_2U_LIB.S9S_MB_2U(SCH_1):PAGE54
   J23  179 DQS7_A_T||TDQS7_A_T SCONN288_ADR50017P130CC-SCONN2A   I178 @S9S_MB_2U_LIB.S9S_MB_2U(SCH_1):PAGE104
   J24  179 DQS7_A_T||TDQS7_A_T SCONN288_ADR50017P087CC-SCONN2A   I181 @S9S_MB_2U_LIB.S9S_MB_2U(SCH_1):PAGE105

M_D_CPU1_SA_DQS_DP<8> @S9S_MB_2U_LIB.S9S_MB_2U(SCH_1):M_D_CPU1_SA_DQS_DP(8)
    U1 AR64 DDR3_SA_DQS_DP8 SOCKET4677_AZIF0045P001C01CS-SA    I91 @S9S_MB_2U_LIB.S9S_MB_2U(SCH_1):PAGE54
   J23  190 DQS8_A_T||TDQS8_A_T SCONN288_ADR50017P130CC-SCONN2A   I178 @S9S_MB_2U_LIB.S9S_MB_2U(SCH_1):PAGE104
   J24  190 DQS8_A_T||TDQS8_A_T SCONN288_ADR50017P087CC-SCONN2A   I181 @S9S_MB_2U_LIB.S9S_MB_2U(SCH_1):PAGE105

M_D_CPU1_SA_DQS_DP<9> @S9S_MB_2U_LIB.S9S_MB_2U(SCH_1):M_D_CPU1_SA_DQS_DP(9)
    U1 AR58 DDR3_SA_DQS_DP9 SOCKET4677_AZIF0045P001C01CS-SA    I91 @S9S_MB_2U_LIB.S9S_MB_2U(SCH_1):PAGE54
   J23  201 DQS9_A_T||TDQS9_A_T SCONN288_ADR50017P130CC-SCONN2A   I178 @S9S_MB_2U_LIB.S9S_MB_2U(SCH_1):PAGE104
   J24  201 DQS9_A_T||TDQS9_A_T SCONN288_ADR50017P087CC-SCONN2A   I181 @S9S_MB_2U_LIB.S9S_MB_2U(SCH_1):PAGE105

M_D_CPU1_SA_PAR @S9S_MB_2U_LIB.S9S_MB_2U(SCH_1):M_D_CPU1_SA_PAR
    U1 AP44 DDR3_SA_PAR SOCKET4677_AZIF0045P001C01CS-SA    I91 @S9S_MB_2U_LIB.S9S_MB_2U(SCH_1):PAGE54
   J23   74  PAR_A SCONN288_ADR50017P130CC-SCONN2A    I25 @S9S_MB_2U_LIB.S9S_MB_2U(SCH_1):PAGE104
   J24   74  PAR_A SCONN288_ADR50017P087CC-SCONN2A   I178 @S9S_MB_2U_LIB.S9S_MB_2U(SCH_1):PAGE105

M_D_CPU1_SA_RSP<0> @S9S_MB_2U_LIB.S9S_MB_2U(SCH_1):M_D_CPU1_SA_RSP(0)
    U1 AD51 DDR3_A_RSP0 SOCKET4677_AZIF0045P001C01CS-SA    I91 @S9S_MB_2U_LIB.S9S_MB_2U(SCH_1):PAGE54
   J23   86 LBD||RSP_A_N SCONN288_ADR50017P130CC-SCONN2A    I25 @S9S_MB_2U_LIB.S9S_MB_2U(SCH_1):PAGE104

M_D_CPU1_SA_RSP<1> @S9S_MB_2U_LIB.S9S_MB_2U(SCH_1):M_D_CPU1_SA_RSP(1)
    U1 AC50 DDR3_A_RSP1 SOCKET4677_AZIF0045P001C01CS-SA    I91 @S9S_MB_2U_LIB.S9S_MB_2U(SCH_1):PAGE54
   J24   86 LBD||RSP_A_N SCONN288_ADR50017P087CC-SCONN2A   I178 @S9S_MB_2U_LIB.S9S_MB_2U(SCH_1):PAGE105

M_D_CPU1_SB_CA<0> @S9S_MB_2U_LIB.S9S_MB_2U(SCH_1):M_D_CPU1_SB_CA(0)
    U1 AK44 DDR3_SB_CA0 SOCKET4677_AZIF0045P001C01CS-SA    I91 @S9S_MB_2U_LIB.S9S_MB_2U(SCH_1):PAGE54
   J23   76  CA0_B SCONN288_ADR50017P130CC-SCONN2A    I25 @S9S_MB_2U_LIB.S9S_MB_2U(SCH_1):PAGE104
   J24   76  CA0_B SCONN288_ADR50017P087CC-SCONN2A   I178 @S9S_MB_2U_LIB.S9S_MB_2U(SCH_1):PAGE105

M_D_CPU1_SB_CA<1> @S9S_MB_2U_LIB.S9S_MB_2U(SCH_1):M_D_CPU1_SB_CA(1)
    U1 AL43 DDR3_SB_CA1 SOCKET4677_AZIF0045P001C01CS-SA    I91 @S9S_MB_2U_LIB.S9S_MB_2U(SCH_1):PAGE54
   J23  221  CA1_B SCONN288_ADR50017P130CC-SCONN2A    I25 @S9S_MB_2U_LIB.S9S_MB_2U(SCH_1):PAGE104
   J24  221  CA1_B SCONN288_ADR50017P087CC-SCONN2A   I178 @S9S_MB_2U_LIB.S9S_MB_2U(SCH_1):PAGE105

M_D_CPU1_SB_CA<2> @S9S_MB_2U_LIB.S9S_MB_2U(SCH_1):M_D_CPU1_SB_CA(2)
    U1 AD44 DDR3_SB_CA2 SOCKET4677_AZIF0045P001C01CS-SA    I91 @S9S_MB_2U_LIB.S9S_MB_2U(SCH_1):PAGE54
   J23   78  CA2_B SCONN288_ADR50017P130CC-SCONN2A    I25 @S9S_MB_2U_LIB.S9S_MB_2U(SCH_1):PAGE104
   J24   78  CA2_B SCONN288_ADR50017P087CC-SCONN2A   I178 @S9S_MB_2U_LIB.S9S_MB_2U(SCH_1):PAGE105

M_D_CPU1_SB_CA<3> @S9S_MB_2U_LIB.S9S_MB_2U(SCH_1):M_D_CPU1_SB_CA(3)
    U1 AF44 DDR3_SB_CA3 SOCKET4677_AZIF0045P001C01CS-SA    I91 @S9S_MB_2U_LIB.S9S_MB_2U(SCH_1):PAGE54
   J23  223  CA3_B SCONN288_ADR50017P130CC-SCONN2A    I25 @S9S_MB_2U_LIB.S9S_MB_2U(SCH_1):PAGE104
   J24  223  CA3_B SCONN288_ADR50017P087CC-SCONN2A   I178 @S9S_MB_2U_LIB.S9S_MB_2U(SCH_1):PAGE105

M_D_CPU1_SB_CA<4> @S9S_MB_2U_LIB.S9S_MB_2U(SCH_1):M_D_CPU1_SB_CA(4)
    U1 AC43 DDR3_SB_CA4 SOCKET4677_AZIF0045P001C01CS-SA    I91 @S9S_MB_2U_LIB.S9S_MB_2U(SCH_1):PAGE54
   J23   80  CA4_B SCONN288_ADR50017P130CC-SCONN2A    I25 @S9S_MB_2U_LIB.S9S_MB_2U(SCH_1):PAGE104
   J24   80  CA4_B SCONN288_ADR50017P087CC-SCONN2A   I178 @S9S_MB_2U_LIB.S9S_MB_2U(SCH_1):PAGE105

M_D_CPU1_SB_CA<5> @S9S_MB_2U_LIB.S9S_MB_2U(SCH_1):M_D_CPU1_SB_CA(5)
    U1 AG43 DDR3_SB_CA5 SOCKET4677_AZIF0045P001C01CS-SA    I91 @S9S_MB_2U_LIB.S9S_MB_2U(SCH_1):PAGE54
   J23  225  CA5_B SCONN288_ADR50017P130CC-SCONN2A    I25 @S9S_MB_2U_LIB.S9S_MB_2U(SCH_1):PAGE104
   J24  225  CA5_B SCONN288_ADR50017P087CC-SCONN2A   I178 @S9S_MB_2U_LIB.S9S_MB_2U(SCH_1):PAGE105

M_D_CPU1_SB_CA<6> @S9S_MB_2U_LIB.S9S_MB_2U(SCH_1):M_D_CPU1_SB_CA(6)
    U1 AB42 DDR3_SB_CA6 SOCKET4677_AZIF0045P001C01CS-SA    I91 @S9S_MB_2U_LIB.S9S_MB_2U(SCH_1):PAGE54
   J23   82  CA6_B SCONN288_ADR50017P130CC-SCONN2A    I25 @S9S_MB_2U_LIB.S9S_MB_2U(SCH_1):PAGE104
   J24   82  CA6_B SCONN288_ADR50017P087CC-SCONN2A   I178 @S9S_MB_2U_LIB.S9S_MB_2U(SCH_1):PAGE105

M_D_CPU1_SB_CB<0> @S9S_MB_2U_LIB.S9S_MB_2U(SCH_1):M_D_CPU1_SB_CB(0)
    U1 AK38 DDR3_SB_ECC0 SOCKET4677_AZIF0045P001C01CS-SA    I91 @S9S_MB_2U_LIB.S9S_MB_2U(SCH_1):PAGE54
   J23   96  CB0_B SCONN288_ADR50017P130CC-SCONN2A    I25 @S9S_MB_2U_LIB.S9S_MB_2U(SCH_1):PAGE104
   J24   96  CB0_B SCONN288_ADR50017P087CC-SCONN2A   I178 @S9S_MB_2U_LIB.S9S_MB_2U(SCH_1):PAGE105

M_D_CPU1_SB_CB<1> @S9S_MB_2U_LIB.S9S_MB_2U(SCH_1):M_D_CPU1_SB_CB(1)
    U1 AL37 DDR3_SB_ECC1 SOCKET4677_AZIF0045P001C01CS-SA    I91 @S9S_MB_2U_LIB.S9S_MB_2U(SCH_1):PAGE54
   J23   98  CB1_B SCONN288_ADR50017P130CC-SCONN2A    I25 @S9S_MB_2U_LIB.S9S_MB_2U(SCH_1):PAGE104
   J24   98  CB1_B SCONN288_ADR50017P087CC-SCONN2A   I178 @S9S_MB_2U_LIB.S9S_MB_2U(SCH_1):PAGE105

M_D_CPU1_SB_CB<2> @S9S_MB_2U_LIB.S9S_MB_2U(SCH_1):M_D_CPU1_SB_CB(2)
    U1 AP38 DDR3_SB_ECC2 SOCKET4677_AZIF0045P001C01CS-SA    I91 @S9S_MB_2U_LIB.S9S_MB_2U(SCH_1):PAGE54
   J23  241  CB2_B SCONN288_ADR50017P130CC-SCONN2A    I25 @S9S_MB_2U_LIB.S9S_MB_2U(SCH_1):PAGE104
   J24  241  CB2_B SCONN288_ADR50017P087CC-SCONN2A   I178 @S9S_MB_2U_LIB.S9S_MB_2U(SCH_1):PAGE105

M_D_CPU1_SB_CB<3> @S9S_MB_2U_LIB.S9S_MB_2U(SCH_1):M_D_CPU1_SB_CB(3)
    U1 AN37 DDR3_SB_ECC3 SOCKET4677_AZIF0045P001C01CS-SA    I91 @S9S_MB_2U_LIB.S9S_MB_2U(SCH_1):PAGE54
   J23  243  CB3_B SCONN288_ADR50017P130CC-SCONN2A    I25 @S9S_MB_2U_LIB.S9S_MB_2U(SCH_1):PAGE104
   J24  243  CB3_B SCONN288_ADR50017P087CC-SCONN2A   I178 @S9S_MB_2U_LIB.S9S_MB_2U(SCH_1):PAGE105

M_D_CPU1_SB_CB<4> @S9S_MB_2U_LIB.S9S_MB_2U(SCH_1):M_D_CPU1_SB_CB(4)
    U1 AL41 DDR3_SB_ECC4 SOCKET4677_AZIF0045P001C01CS-SA    I91 @S9S_MB_2U_LIB.S9S_MB_2U(SCH_1):PAGE54
   J23   89  CB4_B SCONN288_ADR50017P130CC-SCONN2A    I25 @S9S_MB_2U_LIB.S9S_MB_2U(SCH_1):PAGE104
   J24   89  CB4_B SCONN288_ADR50017P087CC-SCONN2A   I178 @S9S_MB_2U_LIB.S9S_MB_2U(SCH_1):PAGE105

M_D_CPU1_SB_CB<5> @S9S_MB_2U_LIB.S9S_MB_2U(SCH_1):M_D_CPU1_SB_CB(5)
    U1 AK40 DDR3_SB_ECC5 SOCKET4677_AZIF0045P001C01CS-SA    I91 @S9S_MB_2U_LIB.S9S_MB_2U(SCH_1):PAGE54
   J23   91  CB5_B SCONN288_ADR50017P130CC-SCONN2A    I25 @S9S_MB_2U_LIB.S9S_MB_2U(SCH_1):PAGE104
   J24   91  CB5_B SCONN288_ADR50017P087CC-SCONN2A   I178 @S9S_MB_2U_LIB.S9S_MB_2U(SCH_1):PAGE105

M_D_CPU1_SB_CB<6> @S9S_MB_2U_LIB.S9S_MB_2U(SCH_1):M_D_CPU1_SB_CB(6)
    U1 AN41 DDR3_SB_ECC6 SOCKET4677_AZIF0045P001C01CS-SA    I91 @S9S_MB_2U_LIB.S9S_MB_2U(SCH_1):PAGE54
   J23  234  CB6_B SCONN288_ADR50017P130CC-SCONN2A    I25 @S9S_MB_2U_LIB.S9S_MB_2U(SCH_1):PAGE104
   J24  234  CB6_B SCONN288_ADR50017P087CC-SCONN2A   I178 @S9S_MB_2U_LIB.S9S_MB_2U(SCH_1):PAGE105

M_D_CPU1_SB_CB<7> @S9S_MB_2U_LIB.S9S_MB_2U(SCH_1):M_D_CPU1_SB_CB(7)
    U1 AP40 DDR3_SB_ECC7 SOCKET4677_AZIF0045P001C01CS-SA    I91 @S9S_MB_2U_LIB.S9S_MB_2U(SCH_1):PAGE54
   J23  236  CB7_B SCONN288_ADR50017P130CC-SCONN2A    I25 @S9S_MB_2U_LIB.S9S_MB_2U(SCH_1):PAGE104
   J24  236  CB7_B SCONN288_ADR50017P087CC-SCONN2A   I178 @S9S_MB_2U_LIB.S9S_MB_2U(SCH_1):PAGE105

M_D_CPU1_SB_CS_N<0> @S9S_MB_2U_LIB.S9S_MB_2U(SCH_1):M_D_CPU1_SB_CS_N(0)
    U1 AC41 DDR3_SB_CS_N0 SOCKET4677_AZIF0045P001C01CS-SA    I91 @S9S_MB_2U_LIB.S9S_MB_2U(SCH_1):PAGE54
   J23   84 CS0_B_N SCONN288_ADR50017P130CC-SCONN2A    I25 @S9S_MB_2U_LIB.S9S_MB_2U(SCH_1):PAGE104

M_D_CPU1_SB_CS_N<1> @S9S_MB_2U_LIB.S9S_MB_2U(SCH_1):M_D_CPU1_SB_CS_N(1)
    U1 AG41 DDR3_SB_CS_N1 SOCKET4677_AZIF0045P001C01CS-SA    I91 @S9S_MB_2U_LIB.S9S_MB_2U(SCH_1):PAGE54
   J23  229 CS1_B_N SCONN288_ADR50017P130CC-SCONN2A    I25 @S9S_MB_2U_LIB.S9S_MB_2U(SCH_1):PAGE104

M_D_CPU1_SB_CS_N<2> @S9S_MB_2U_LIB.S9S_MB_2U(SCH_1):M_D_CPU1_SB_CS_N(2)
    U1 AF40 DDR3_SB_CS_N2 SOCKET4677_AZIF0045P001C01CS-SA    I91 @S9S_MB_2U_LIB.S9S_MB_2U(SCH_1):PAGE54
   J24   84 CS0_B_N SCONN288_ADR50017P087CC-SCONN2A   I178 @S9S_MB_2U_LIB.S9S_MB_2U(SCH_1):PAGE105

M_D_CPU1_SB_CS_N<3> @S9S_MB_2U_LIB.S9S_MB_2U(SCH_1):M_D_CPU1_SB_CS_N(3)
    U1 AD40 DDR3_SB_CS_N3 SOCKET4677_AZIF0045P001C01CS-SA    I91 @S9S_MB_2U_LIB.S9S_MB_2U(SCH_1):PAGE54
   J24  229 CS1_B_N SCONN288_ADR50017P087CC-SCONN2A   I178 @S9S_MB_2U_LIB.S9S_MB_2U(SCH_1):PAGE105

M_D_CPU1_SB_DQ<0> @S9S_MB_2U_LIB.S9S_MB_2U(SCH_1):M_D_CPU1_SB_DQ(0)
    U1 AL35 DDR3_SB_DQ0 SOCKET4677_AZIF0045P001C01CS-SA    I91 @S9S_MB_2U_LIB.S9S_MB_2U(SCH_1):PAGE54
   J23  100  DQ0_B SCONN288_ADR50017P130CC-SCONN2A    I25 @S9S_MB_2U_LIB.S9S_MB_2U(SCH_1):PAGE104
   J24  100  DQ0_B SCONN288_ADR50017P087CC-SCONN2A   I178 @S9S_MB_2U_LIB.S9S_MB_2U(SCH_1):PAGE105

M_D_CPU1_SB_DQ<10> @S9S_MB_2U_LIB.S9S_MB_2U(SCH_1):M_D_CPU1_SB_DQ(10)
    U1 AN29 DDR3_SB_DQ10 SOCKET4677_AZIF0045P001C01CS-SA    I91 @S9S_MB_2U_LIB.S9S_MB_2U(SCH_1):PAGE54
   J23  256 DQ10_B SCONN288_ADR50017P130CC-SCONN2A    I25 @S9S_MB_2U_LIB.S9S_MB_2U(SCH_1):PAGE104
   J24  256 DQ10_B SCONN288_ADR50017P087CC-SCONN2A   I178 @S9S_MB_2U_LIB.S9S_MB_2U(SCH_1):PAGE105

M_D_CPU1_SB_DQ<11> @S9S_MB_2U_LIB.S9S_MB_2U(SCH_1):M_D_CPU1_SB_DQ(11)
    U1 AP28 DDR3_SB_DQ11 SOCKET4677_AZIF0045P001C01CS-SA    I91 @S9S_MB_2U_LIB.S9S_MB_2U(SCH_1):PAGE54
   J23  258 DQ11_B SCONN288_ADR50017P130CC-SCONN2A    I25 @S9S_MB_2U_LIB.S9S_MB_2U(SCH_1):PAGE104
   J24  258 DQ11_B SCONN288_ADR50017P087CC-SCONN2A   I178 @S9S_MB_2U_LIB.S9S_MB_2U(SCH_1):PAGE105

M_D_CPU1_SB_DQ<12> @S9S_MB_2U_LIB.S9S_MB_2U(SCH_1):M_D_CPU1_SB_DQ(12)
    U1 AK26 DDR3_SB_DQ12 SOCKET4677_AZIF0045P001C01CS-SA    I91 @S9S_MB_2U_LIB.S9S_MB_2U(SCH_1):PAGE54
   J23  118 DQ12_B SCONN288_ADR50017P130CC-SCONN2A    I25 @S9S_MB_2U_LIB.S9S_MB_2U(SCH_1):PAGE104
   J24  118 DQ12_B SCONN288_ADR50017P087CC-SCONN2A   I178 @S9S_MB_2U_LIB.S9S_MB_2U(SCH_1):PAGE105

M_D_CPU1_SB_DQ<13> @S9S_MB_2U_LIB.S9S_MB_2U(SCH_1):M_D_CPU1_SB_DQ(13)
    U1 AL25 DDR3_SB_DQ13 SOCKET4677_AZIF0045P001C01CS-SA    I91 @S9S_MB_2U_LIB.S9S_MB_2U(SCH_1):PAGE54
   J23  120 DQ13_B SCONN288_ADR50017P130CC-SCONN2A    I25 @S9S_MB_2U_LIB.S9S_MB_2U(SCH_1):PAGE104
   J24  120 DQ13_B SCONN288_ADR50017P087CC-SCONN2A   I178 @S9S_MB_2U_LIB.S9S_MB_2U(SCH_1):PAGE105

M_D_CPU1_SB_DQ<14> @S9S_MB_2U_LIB.S9S_MB_2U(SCH_1):M_D_CPU1_SB_DQ(14)
    U1 AP26 DDR3_SB_DQ14 SOCKET4677_AZIF0045P001C01CS-SA    I91 @S9S_MB_2U_LIB.S9S_MB_2U(SCH_1):PAGE54
   J23  263 DQ14_B SCONN288_ADR50017P130CC-SCONN2A    I25 @S9S_MB_2U_LIB.S9S_MB_2U(SCH_1):PAGE104
   J24  263 DQ14_B SCONN288_ADR50017P087CC-SCONN2A   I178 @S9S_MB_2U_LIB.S9S_MB_2U(SCH_1):PAGE105

M_D_CPU1_SB_DQ<15> @S9S_MB_2U_LIB.S9S_MB_2U(SCH_1):M_D_CPU1_SB_DQ(15)
    U1 AN25 DDR3_SB_DQ15 SOCKET4677_AZIF0045P001C01CS-SA    I91 @S9S_MB_2U_LIB.S9S_MB_2U(SCH_1):PAGE54
   J23  265 DQ15_B SCONN288_ADR50017P130CC-SCONN2A    I25 @S9S_MB_2U_LIB.S9S_MB_2U(SCH_1):PAGE104
   J24  265 DQ15_B SCONN288_ADR50017P087CC-SCONN2A   I178 @S9S_MB_2U_LIB.S9S_MB_2U(SCH_1):PAGE105

M_D_CPU1_SB_DQ<16> @S9S_MB_2U_LIB.S9S_MB_2U(SCH_1):M_D_CPU1_SB_DQ(16)
    U1 AD26 DDR3_SB_DQ16 SOCKET4677_AZIF0045P001C01CS-SA    I91 @S9S_MB_2U_LIB.S9S_MB_2U(SCH_1):PAGE54
   J23  122 DQ16_B SCONN288_ADR50017P130CC-SCONN2A    I25 @S9S_MB_2U_LIB.S9S_MB_2U(SCH_1):PAGE104
   J24  122 DQ16_B SCONN288_ADR50017P087CC-SCONN2A   I178 @S9S_MB_2U_LIB.S9S_MB_2U(SCH_1):PAGE105

M_D_CPU1_SB_DQ<17> @S9S_MB_2U_LIB.S9S_MB_2U(SCH_1):M_D_CPU1_SB_DQ(17)
    U1 AC25 DDR3_SB_DQ17 SOCKET4677_AZIF0045P001C01CS-SA    I91 @S9S_MB_2U_LIB.S9S_MB_2U(SCH_1):PAGE54
   J23  124 DQ17_B SCONN288_ADR50017P130CC-SCONN2A    I25 @S9S_MB_2U_LIB.S9S_MB_2U(SCH_1):PAGE104
   J24  124 DQ17_B SCONN288_ADR50017P087CC-SCONN2A   I178 @S9S_MB_2U_LIB.S9S_MB_2U(SCH_1):PAGE105

M_D_CPU1_SB_DQ<18> @S9S_MB_2U_LIB.S9S_MB_2U(SCH_1):M_D_CPU1_SB_DQ(18)
    U1 AF26 DDR3_SB_DQ18 SOCKET4677_AZIF0045P001C01CS-SA    I91 @S9S_MB_2U_LIB.S9S_MB_2U(SCH_1):PAGE54
   J23  267 DQ18_B SCONN288_ADR50017P130CC-SCONN2A    I25 @S9S_MB_2U_LIB.S9S_MB_2U(SCH_1):PAGE104
   J24  267 DQ18_B SCONN288_ADR50017P087CC-SCONN2A   I178 @S9S_MB_2U_LIB.S9S_MB_2U(SCH_1):PAGE105

M_D_CPU1_SB_DQ<19> @S9S_MB_2U_LIB.S9S_MB_2U(SCH_1):M_D_CPU1_SB_DQ(19)
    U1 AG25 DDR3_SB_DQ19 SOCKET4677_AZIF0045P001C01CS-SA    I91 @S9S_MB_2U_LIB.S9S_MB_2U(SCH_1):PAGE54
   J23  269 DQ19_B SCONN288_ADR50017P130CC-SCONN2A    I25 @S9S_MB_2U_LIB.S9S_MB_2U(SCH_1):PAGE104
   J24  269 DQ19_B SCONN288_ADR50017P087CC-SCONN2A   I178 @S9S_MB_2U_LIB.S9S_MB_2U(SCH_1):PAGE105

M_D_CPU1_SB_DQ<1> @S9S_MB_2U_LIB.S9S_MB_2U(SCH_1):M_D_CPU1_SB_DQ(1)
    U1 AK34 DDR3_SB_DQ1 SOCKET4677_AZIF0045P001C01CS-SA    I91 @S9S_MB_2U_LIB.S9S_MB_2U(SCH_1):PAGE54
   J23  102  DQ1_B SCONN288_ADR50017P130CC-SCONN2A    I25 @S9S_MB_2U_LIB.S9S_MB_2U(SCH_1):PAGE104
   J24  102  DQ1_B SCONN288_ADR50017P087CC-SCONN2A   I178 @S9S_MB_2U_LIB.S9S_MB_2U(SCH_1):PAGE105

M_D_CPU1_SB_DQ<20> @S9S_MB_2U_LIB.S9S_MB_2U(SCH_1):M_D_CPU1_SB_DQ(20)
    U1 AC23 DDR3_SB_DQ20 SOCKET4677_AZIF0045P001C01CS-SA    I91 @S9S_MB_2U_LIB.S9S_MB_2U(SCH_1):PAGE54
   J23  129 DQ20_B SCONN288_ADR50017P130CC-SCONN2A    I25 @S9S_MB_2U_LIB.S9S_MB_2U(SCH_1):PAGE104
   J24  129 DQ20_B SCONN288_ADR50017P087CC-SCONN2A   I178 @S9S_MB_2U_LIB.S9S_MB_2U(SCH_1):PAGE105

M_D_CPU1_SB_DQ<21> @S9S_MB_2U_LIB.S9S_MB_2U(SCH_1):M_D_CPU1_SB_DQ(21)
    U1 AD22 DDR3_SB_DQ21 SOCKET4677_AZIF0045P001C01CS-SA    I91 @S9S_MB_2U_LIB.S9S_MB_2U(SCH_1):PAGE54
   J23  131 DQ21_B SCONN288_ADR50017P130CC-SCONN2A    I25 @S9S_MB_2U_LIB.S9S_MB_2U(SCH_1):PAGE104
   J24  131 DQ21_B SCONN288_ADR50017P087CC-SCONN2A   I178 @S9S_MB_2U_LIB.S9S_MB_2U(SCH_1):PAGE105

M_D_CPU1_SB_DQ<22> @S9S_MB_2U_LIB.S9S_MB_2U(SCH_1):M_D_CPU1_SB_DQ(22)
    U1 AG23 DDR3_SB_DQ22 SOCKET4677_AZIF0045P001C01CS-SA    I91 @S9S_MB_2U_LIB.S9S_MB_2U(SCH_1):PAGE54
   J23  274 DQ22_B SCONN288_ADR50017P130CC-SCONN2A    I25 @S9S_MB_2U_LIB.S9S_MB_2U(SCH_1):PAGE104
   J24  274 DQ22_B SCONN288_ADR50017P087CC-SCONN2A   I178 @S9S_MB_2U_LIB.S9S_MB_2U(SCH_1):PAGE105

M_D_CPU1_SB_DQ<23> @S9S_MB_2U_LIB.S9S_MB_2U(SCH_1):M_D_CPU1_SB_DQ(23)
    U1 AF22 DDR3_SB_DQ23 SOCKET4677_AZIF0045P001C01CS-SA    I91 @S9S_MB_2U_LIB.S9S_MB_2U(SCH_1):PAGE54
   J23  276 DQ23_B SCONN288_ADR50017P130CC-SCONN2A    I25 @S9S_MB_2U_LIB.S9S_MB_2U(SCH_1):PAGE104
   J24  276 DQ23_B SCONN288_ADR50017P087CC-SCONN2A   I178 @S9S_MB_2U_LIB.S9S_MB_2U(SCH_1):PAGE105

M_D_CPU1_SB_DQ<24> @S9S_MB_2U_LIB.S9S_MB_2U(SCH_1):M_D_CPU1_SB_DQ(24)
    U1 AL23 DDR3_SB_DQ24 SOCKET4677_AZIF0045P001C01CS-SA    I91 @S9S_MB_2U_LIB.S9S_MB_2U(SCH_1):PAGE54
   J23  133 DQ24_B SCONN288_ADR50017P130CC-SCONN2A    I25 @S9S_MB_2U_LIB.S9S_MB_2U(SCH_1):PAGE104
   J24  133 DQ24_B SCONN288_ADR50017P087CC-SCONN2A   I178 @S9S_MB_2U_LIB.S9S_MB_2U(SCH_1):PAGE105

M_D_CPU1_SB_DQ<25> @S9S_MB_2U_LIB.S9S_MB_2U(SCH_1):M_D_CPU1_SB_DQ(25)
    U1 AK22 DDR3_SB_DQ25 SOCKET4677_AZIF0045P001C01CS-SA    I91 @S9S_MB_2U_LIB.S9S_MB_2U(SCH_1):PAGE54
   J23  135 DQ25_B SCONN288_ADR50017P130CC-SCONN2A    I25 @S9S_MB_2U_LIB.S9S_MB_2U(SCH_1):PAGE104
   J24  135 DQ25_B SCONN288_ADR50017P087CC-SCONN2A   I178 @S9S_MB_2U_LIB.S9S_MB_2U(SCH_1):PAGE105

M_D_CPU1_SB_DQ<26> @S9S_MB_2U_LIB.S9S_MB_2U(SCH_1):M_D_CPU1_SB_DQ(26)
    U1 AN23 DDR3_SB_DQ26 SOCKET4677_AZIF0045P001C01CS-SA    I91 @S9S_MB_2U_LIB.S9S_MB_2U(SCH_1):PAGE54
   J23  278 DQ26_B SCONN288_ADR50017P130CC-SCONN2A    I25 @S9S_MB_2U_LIB.S9S_MB_2U(SCH_1):PAGE104
   J24  278 DQ26_B SCONN288_ADR50017P087CC-SCONN2A   I178 @S9S_MB_2U_LIB.S9S_MB_2U(SCH_1):PAGE105

M_D_CPU1_SB_DQ<27> @S9S_MB_2U_LIB.S9S_MB_2U(SCH_1):M_D_CPU1_SB_DQ(27)
    U1 AP22 DDR3_SB_DQ27 SOCKET4677_AZIF0045P001C01CS-SA    I91 @S9S_MB_2U_LIB.S9S_MB_2U(SCH_1):PAGE54
   J23  280 DQ27_B SCONN288_ADR50017P130CC-SCONN2A    I25 @S9S_MB_2U_LIB.S9S_MB_2U(SCH_1):PAGE104
   J24  280 DQ27_B SCONN288_ADR50017P087CC-SCONN2A   I178 @S9S_MB_2U_LIB.S9S_MB_2U(SCH_1):PAGE105

M_D_CPU1_SB_DQ<28> @S9S_MB_2U_LIB.S9S_MB_2U(SCH_1):M_D_CPU1_SB_DQ(28)
    U1 AK20 DDR3_SB_DQ28 SOCKET4677_AZIF0045P001C01CS-SA    I91 @S9S_MB_2U_LIB.S9S_MB_2U(SCH_1):PAGE54
   J23  140 DQ28_B SCONN288_ADR50017P130CC-SCONN2A    I25 @S9S_MB_2U_LIB.S9S_MB_2U(SCH_1):PAGE104
   J24  140 DQ28_B SCONN288_ADR50017P087CC-SCONN2A   I178 @S9S_MB_2U_LIB.S9S_MB_2U(SCH_1):PAGE105

M_D_CPU1_SB_DQ<29> @S9S_MB_2U_LIB.S9S_MB_2U(SCH_1):M_D_CPU1_SB_DQ(29)
    U1 AL19 DDR3_SB_DQ29 SOCKET4677_AZIF0045P001C01CS-SA    I91 @S9S_MB_2U_LIB.S9S_MB_2U(SCH_1):PAGE54
   J23  142 DQ29_B SCONN288_ADR50017P130CC-SCONN2A    I25 @S9S_MB_2U_LIB.S9S_MB_2U(SCH_1):PAGE104
   J24  142 DQ29_B SCONN288_ADR50017P087CC-SCONN2A   I178 @S9S_MB_2U_LIB.S9S_MB_2U(SCH_1):PAGE105

M_D_CPU1_SB_DQ<2> @S9S_MB_2U_LIB.S9S_MB_2U(SCH_1):M_D_CPU1_SB_DQ(2)
    U1 AN35 DDR3_SB_DQ2 SOCKET4677_AZIF0045P001C01CS-SA    I91 @S9S_MB_2U_LIB.S9S_MB_2U(SCH_1):PAGE54
   J23  245  DQ2_B SCONN288_ADR50017P130CC-SCONN2A    I25 @S9S_MB_2U_LIB.S9S_MB_2U(SCH_1):PAGE104
   J24  245  DQ2_B SCONN288_ADR50017P087CC-SCONN2A   I178 @S9S_MB_2U_LIB.S9S_MB_2U(SCH_1):PAGE105

M_D_CPU1_SB_DQ<30> @S9S_MB_2U_LIB.S9S_MB_2U(SCH_1):M_D_CPU1_SB_DQ(30)
    U1 AP20 DDR3_SB_DQ30 SOCKET4677_AZIF0045P001C01CS-SA    I91 @S9S_MB_2U_LIB.S9S_MB_2U(SCH_1):PAGE54
   J23  285 DQ30_B SCONN288_ADR50017P130CC-SCONN2A    I25 @S9S_MB_2U_LIB.S9S_MB_2U(SCH_1):PAGE104
   J24  285 DQ30_B SCONN288_ADR50017P087CC-SCONN2A   I178 @S9S_MB_2U_LIB.S9S_MB_2U(SCH_1):PAGE105

M_D_CPU1_SB_DQ<31> @S9S_MB_2U_LIB.S9S_MB_2U(SCH_1):M_D_CPU1_SB_DQ(31)
    U1 AN19 DDR3_SB_DQ31 SOCKET4677_AZIF0045P001C01CS-SA    I91 @S9S_MB_2U_LIB.S9S_MB_2U(SCH_1):PAGE54
   J23  287 DQ31_B SCONN288_ADR50017P130CC-SCONN2A    I25 @S9S_MB_2U_LIB.S9S_MB_2U(SCH_1):PAGE104
   J24  287 DQ31_B SCONN288_ADR50017P087CC-SCONN2A   I178 @S9S_MB_2U_LIB.S9S_MB_2U(SCH_1):PAGE105

M_D_CPU1_SB_DQ<3> @S9S_MB_2U_LIB.S9S_MB_2U(SCH_1):M_D_CPU1_SB_DQ(3)
    U1 AP34 DDR3_SB_DQ3 SOCKET4677_AZIF0045P001C01CS-SA    I91 @S9S_MB_2U_LIB.S9S_MB_2U(SCH_1):PAGE54
   J23  247  DQ3_B SCONN288_ADR50017P130CC-SCONN2A    I25 @S9S_MB_2U_LIB.S9S_MB_2U(SCH_1):PAGE104
   J24  247  DQ3_B SCONN288_ADR50017P087CC-SCONN2A   I178 @S9S_MB_2U_LIB.S9S_MB_2U(SCH_1):PAGE105

M_D_CPU1_SB_DQ<4> @S9S_MB_2U_LIB.S9S_MB_2U(SCH_1):M_D_CPU1_SB_DQ(4)
    U1 AK32 DDR3_SB_DQ4 SOCKET4677_AZIF0045P001C01CS-SA    I91 @S9S_MB_2U_LIB.S9S_MB_2U(SCH_1):PAGE54
   J23  107  DQ4_B SCONN288_ADR50017P130CC-SCONN2A    I25 @S9S_MB_2U_LIB.S9S_MB_2U(SCH_1):PAGE104
   J24  107  DQ4_B SCONN288_ADR50017P087CC-SCONN2A   I178 @S9S_MB_2U_LIB.S9S_MB_2U(SCH_1):PAGE105

M_D_CPU1_SB_DQ<5> @S9S_MB_2U_LIB.S9S_MB_2U(SCH_1):M_D_CPU1_SB_DQ(5)
    U1 AL31 DDR3_SB_DQ5 SOCKET4677_AZIF0045P001C01CS-SA    I91 @S9S_MB_2U_LIB.S9S_MB_2U(SCH_1):PAGE54
   J23  109  DQ5_B SCONN288_ADR50017P130CC-SCONN2A    I25 @S9S_MB_2U_LIB.S9S_MB_2U(SCH_1):PAGE104
   J24  109  DQ5_B SCONN288_ADR50017P087CC-SCONN2A   I178 @S9S_MB_2U_LIB.S9S_MB_2U(SCH_1):PAGE105

M_D_CPU1_SB_DQ<6> @S9S_MB_2U_LIB.S9S_MB_2U(SCH_1):M_D_CPU1_SB_DQ(6)
    U1 AP32 DDR3_SB_DQ6 SOCKET4677_AZIF0045P001C01CS-SA    I91 @S9S_MB_2U_LIB.S9S_MB_2U(SCH_1):PAGE54
   J23  252  DQ6_B SCONN288_ADR50017P130CC-SCONN2A    I25 @S9S_MB_2U_LIB.S9S_MB_2U(SCH_1):PAGE104
   J24  252  DQ6_B SCONN288_ADR50017P087CC-SCONN2A   I178 @S9S_MB_2U_LIB.S9S_MB_2U(SCH_1):PAGE105

M_D_CPU1_SB_DQ<7> @S9S_MB_2U_LIB.S9S_MB_2U(SCH_1):M_D_CPU1_SB_DQ(7)
    U1 AN31 DDR3_SB_DQ7 SOCKET4677_AZIF0045P001C01CS-SA    I91 @S9S_MB_2U_LIB.S9S_MB_2U(SCH_1):PAGE54
   J23  254  DQ7_B SCONN288_ADR50017P130CC-SCONN2A    I25 @S9S_MB_2U_LIB.S9S_MB_2U(SCH_1):PAGE104
   J24  254  DQ7_B SCONN288_ADR50017P087CC-SCONN2A   I178 @S9S_MB_2U_LIB.S9S_MB_2U(SCH_1):PAGE105

M_D_CPU1_SB_DQ<8> @S9S_MB_2U_LIB.S9S_MB_2U(SCH_1):M_D_CPU1_SB_DQ(8)
    U1 AL29 DDR3_SB_DQ8 SOCKET4677_AZIF0045P001C01CS-SA    I91 @S9S_MB_2U_LIB.S9S_MB_2U(SCH_1):PAGE54
   J23  111  DQ8_B SCONN288_ADR50017P130CC-SCONN2A    I25 @S9S_MB_2U_LIB.S9S_MB_2U(SCH_1):PAGE104
   J24  111  DQ8_B SCONN288_ADR50017P087CC-SCONN2A   I178 @S9S_MB_2U_LIB.S9S_MB_2U(SCH_1):PAGE105

M_D_CPU1_SB_DQ<9> @S9S_MB_2U_LIB.S9S_MB_2U(SCH_1):M_D_CPU1_SB_DQ(9)
    U1 AK28 DDR3_SB_DQ9 SOCKET4677_AZIF0045P001C01CS-SA    I91 @S9S_MB_2U_LIB.S9S_MB_2U(SCH_1):PAGE54
   J23  113  DQ9_B SCONN288_ADR50017P130CC-SCONN2A    I25 @S9S_MB_2U_LIB.S9S_MB_2U(SCH_1):PAGE104
   J24  113  DQ9_B SCONN288_ADR50017P087CC-SCONN2A   I178 @S9S_MB_2U_LIB.S9S_MB_2U(SCH_1):PAGE105

M_D_CPU1_SB_DQS_DN<0> @S9S_MB_2U_LIB.S9S_MB_2U(SCH_1):M_D_CPU1_SB_DQS_DN(0)
    U1 AJ33 DDR3_SB_DQS_DN0 SOCKET4677_AZIF0045P001C01CS-SA    I91 @S9S_MB_2U_LIB.S9S_MB_2U(SCH_1):PAGE54
   J23  105 DQS0_B_C SCONN288_ADR50017P130CC-SCONN2A   I178 @S9S_MB_2U_LIB.S9S_MB_2U(SCH_1):PAGE104
   J24  105 DQS0_B_C SCONN288_ADR50017P087CC-SCONN2A   I181 @S9S_MB_2U_LIB.S9S_MB_2U(SCH_1):PAGE105

M_D_CPU1_SB_DQS_DN<1> @S9S_MB_2U_LIB.S9S_MB_2U(SCH_1):M_D_CPU1_SB_DQS_DN(1)
    U1 AJ27 DDR3_SB_DQS_DN1 SOCKET4677_AZIF0045P001C01CS-SA    I91 @S9S_MB_2U_LIB.S9S_MB_2U(SCH_1):PAGE54
   J23  116 DQS1_B_C SCONN288_ADR50017P130CC-SCONN2A   I178 @S9S_MB_2U_LIB.S9S_MB_2U(SCH_1):PAGE104
   J24  116 DQS1_B_C SCONN288_ADR50017P087CC-SCONN2A   I181 @S9S_MB_2U_LIB.S9S_MB_2U(SCH_1):PAGE105

M_D_CPU1_SB_DQS_DN<2> @S9S_MB_2U_LIB.S9S_MB_2U(SCH_1):M_D_CPU1_SB_DQS_DN(2)
    U1 AB24 DDR3_SB_DQS_DN2 SOCKET4677_AZIF0045P001C01CS-SA    I91 @S9S_MB_2U_LIB.S9S_MB_2U(SCH_1):PAGE54
   J23  127 DQS2_B_C SCONN288_ADR50017P130CC-SCONN2A   I178 @S9S_MB_2U_LIB.S9S_MB_2U(SCH_1):PAGE104
   J24  127 DQS2_B_C SCONN288_ADR50017P087CC-SCONN2A   I181 @S9S_MB_2U_LIB.S9S_MB_2U(SCH_1):PAGE105

M_D_CPU1_SB_DQS_DN<3> @S9S_MB_2U_LIB.S9S_MB_2U(SCH_1):M_D_CPU1_SB_DQS_DN(3)
    U1 AJ21 DDR3_SB_DQS_DN3 SOCKET4677_AZIF0045P001C01CS-SA    I91 @S9S_MB_2U_LIB.S9S_MB_2U(SCH_1):PAGE54
   J23  138 DQS3_B_C SCONN288_ADR50017P130CC-SCONN2A   I178 @S9S_MB_2U_LIB.S9S_MB_2U(SCH_1):PAGE104
   J24  138 DQS3_B_C SCONN288_ADR50017P087CC-SCONN2A   I181 @S9S_MB_2U_LIB.S9S_MB_2U(SCH_1):PAGE105

M_D_CPU1_SB_DQS_DN<4> @S9S_MB_2U_LIB.S9S_MB_2U(SCH_1):M_D_CPU1_SB_DQS_DN(4)
    U1 AR39 DDR3_SB_DQS_DN4 SOCKET4677_AZIF0045P001C01CS-SA    I91 @S9S_MB_2U_LIB.S9S_MB_2U(SCH_1):PAGE54
   J23  238 DQS4_B_C SCONN288_ADR50017P130CC-SCONN2A   I178 @S9S_MB_2U_LIB.S9S_MB_2U(SCH_1):PAGE104
   J24  238 DQS4_B_C SCONN288_ADR50017P087CC-SCONN2A   I181 @S9S_MB_2U_LIB.S9S_MB_2U(SCH_1):PAGE105

M_D_CPU1_SB_DQS_DN<5> @S9S_MB_2U_LIB.S9S_MB_2U(SCH_1):M_D_CPU1_SB_DQS_DN(5)
    U1 AN33 DDR3_SB_DQS_DN5 SOCKET4677_AZIF0045P001C01CS-SA    I91 @S9S_MB_2U_LIB.S9S_MB_2U(SCH_1):PAGE54
   J23  249 DQS5_B_C||TDQS5_B_C SCONN288_ADR50017P130CC-SCONN2A   I178 @S9S_MB_2U_LIB.S9S_MB_2U(SCH_1):PAGE104
   J24  249 DQS5_B_C||TDQS5_B_C SCONN288_ADR50017P087CC-SCONN2A   I181 @S9S_MB_2U_LIB.S9S_MB_2U(SCH_1):PAGE105

M_D_CPU1_SB_DQS_DN<6> @S9S_MB_2U_LIB.S9S_MB_2U(SCH_1):M_D_CPU1_SB_DQS_DN(6)
    U1 AN27 DDR3_SB_DQS_DN6 SOCKET4677_AZIF0045P001C01CS-SA    I91 @S9S_MB_2U_LIB.S9S_MB_2U(SCH_1):PAGE54
   J23  260 DQS6_B_C||TDQS6_B_C SCONN288_ADR50017P130CC-SCONN2A   I178 @S9S_MB_2U_LIB.S9S_MB_2U(SCH_1):PAGE104
   J24  260 DQS6_B_C||TDQS6_B_C SCONN288_ADR50017P087CC-SCONN2A   I181 @S9S_MB_2U_LIB.S9S_MB_2U(SCH_1):PAGE105

M_D_CPU1_SB_DQS_DN<7> @S9S_MB_2U_LIB.S9S_MB_2U(SCH_1):M_D_CPU1_SB_DQS_DN(7)
    U1 AF24 DDR3_SB_DQS_DN7 SOCKET4677_AZIF0045P001C01CS-SA    I91 @S9S_MB_2U_LIB.S9S_MB_2U(SCH_1):PAGE54
   J23  271 DQS7_B_C||TDQS7_B_C SCONN288_ADR50017P130CC-SCONN2A   I178 @S9S_MB_2U_LIB.S9S_MB_2U(SCH_1):PAGE104
   J24  271 DQS7_B_C||TDQS7_B_C SCONN288_ADR50017P087CC-SCONN2A   I181 @S9S_MB_2U_LIB.S9S_MB_2U(SCH_1):PAGE105

M_D_CPU1_SB_DQS_DN<8> @S9S_MB_2U_LIB.S9S_MB_2U(SCH_1):M_D_CPU1_SB_DQS_DN(8)
    U1 AN21 DDR3_SB_DQS_DN8 SOCKET4677_AZIF0045P001C01CS-SA    I91 @S9S_MB_2U_LIB.S9S_MB_2U(SCH_1):PAGE54
   J23  282 DQS8_B_C||TDQS8_B_C SCONN288_ADR50017P130CC-SCONN2A   I178 @S9S_MB_2U_LIB.S9S_MB_2U(SCH_1):PAGE104
   J24  282 DQS8_B_C||TDQS8_B_C SCONN288_ADR50017P087CC-SCONN2A   I181 @S9S_MB_2U_LIB.S9S_MB_2U(SCH_1):PAGE105

M_D_CPU1_SB_DQS_DN<9> @S9S_MB_2U_LIB.S9S_MB_2U(SCH_1):M_D_CPU1_SB_DQS_DN(9)
    U1 AJ39 DDR3_SB_DQS_DN9 SOCKET4677_AZIF0045P001C01CS-SA    I91 @S9S_MB_2U_LIB.S9S_MB_2U(SCH_1):PAGE54
   J23   94 DQS9_B_C||TDQS9_B_C SCONN288_ADR50017P130CC-SCONN2A   I178 @S9S_MB_2U_LIB.S9S_MB_2U(SCH_1):PAGE104
   J24   94 DQS9_B_C||TDQS9_B_C SCONN288_ADR50017P087CC-SCONN2A   I181 @S9S_MB_2U_LIB.S9S_MB_2U(SCH_1):PAGE105

M_D_CPU1_SB_DQS_DP<0> @S9S_MB_2U_LIB.S9S_MB_2U(SCH_1):M_D_CPU1_SB_DQS_DP(0)
    U1 AL33 DDR3_SB_DQS_DP0 SOCKET4677_AZIF0045P001C01CS-SA    I91 @S9S_MB_2U_LIB.S9S_MB_2U(SCH_1):PAGE54
   J23  104 DQS0_B_T SCONN288_ADR50017P130CC-SCONN2A   I178 @S9S_MB_2U_LIB.S9S_MB_2U(SCH_1):PAGE104
   J24  104 DQS0_B_T SCONN288_ADR50017P087CC-SCONN2A   I181 @S9S_MB_2U_LIB.S9S_MB_2U(SCH_1):PAGE105

M_D_CPU1_SB_DQS_DP<1> @S9S_MB_2U_LIB.S9S_MB_2U(SCH_1):M_D_CPU1_SB_DQS_DP(1)
    U1 AL27 DDR3_SB_DQS_DP1 SOCKET4677_AZIF0045P001C01CS-SA    I91 @S9S_MB_2U_LIB.S9S_MB_2U(SCH_1):PAGE54
   J23  115 DQS1_B_T SCONN288_ADR50017P130CC-SCONN2A   I178 @S9S_MB_2U_LIB.S9S_MB_2U(SCH_1):PAGE104
   J24  115 DQS1_B_T SCONN288_ADR50017P087CC-SCONN2A   I181 @S9S_MB_2U_LIB.S9S_MB_2U(SCH_1):PAGE105

M_D_CPU1_SB_DQS_DP<2> @S9S_MB_2U_LIB.S9S_MB_2U(SCH_1):M_D_CPU1_SB_DQS_DP(2)
    U1 AD24 DDR3_SB_DQS_DP2 SOCKET4677_AZIF0045P001C01CS-SA    I91 @S9S_MB_2U_LIB.S9S_MB_2U(SCH_1):PAGE54
   J23  126 DQS2_B_T SCONN288_ADR50017P130CC-SCONN2A   I178 @S9S_MB_2U_LIB.S9S_MB_2U(SCH_1):PAGE104
   J24  126 DQS2_B_T SCONN288_ADR50017P087CC-SCONN2A   I181 @S9S_MB_2U_LIB.S9S_MB_2U(SCH_1):PAGE105

M_D_CPU1_SB_DQS_DP<3> @S9S_MB_2U_LIB.S9S_MB_2U(SCH_1):M_D_CPU1_SB_DQS_DP(3)
    U1 AL21 DDR3_SB_DQS_DP3 SOCKET4677_AZIF0045P001C01CS-SA    I91 @S9S_MB_2U_LIB.S9S_MB_2U(SCH_1):PAGE54
   J23  137 DQS3_B_T SCONN288_ADR50017P130CC-SCONN2A   I178 @S9S_MB_2U_LIB.S9S_MB_2U(SCH_1):PAGE104
   J24  137 DQS3_B_T SCONN288_ADR50017P087CC-SCONN2A   I181 @S9S_MB_2U_LIB.S9S_MB_2U(SCH_1):PAGE105

M_D_CPU1_SB_DQS_DP<4> @S9S_MB_2U_LIB.S9S_MB_2U(SCH_1):M_D_CPU1_SB_DQS_DP(4)
    U1 AN39 DDR3_SB_DQS_DP4 SOCKET4677_AZIF0045P001C01CS-SA    I91 @S9S_MB_2U_LIB.S9S_MB_2U(SCH_1):PAGE54
   J23  239 DQS4_B_T SCONN288_ADR50017P130CC-SCONN2A   I178 @S9S_MB_2U_LIB.S9S_MB_2U(SCH_1):PAGE104
   J24  239 DQS4_B_T SCONN288_ADR50017P087CC-SCONN2A   I181 @S9S_MB_2U_LIB.S9S_MB_2U(SCH_1):PAGE105

M_D_CPU1_SB_DQS_DP<5> @S9S_MB_2U_LIB.S9S_MB_2U(SCH_1):M_D_CPU1_SB_DQS_DP(5)
    U1 AR33 DDR3_SB_DQS_DP5 SOCKET4677_AZIF0045P001C01CS-SA    I91 @S9S_MB_2U_LIB.S9S_MB_2U(SCH_1):PAGE54
   J23  250 DQS5_B_T||TDQS5_B_T SCONN288_ADR50017P130CC-SCONN2A   I178 @S9S_MB_2U_LIB.S9S_MB_2U(SCH_1):PAGE104
   J24  250 DQS5_B_T||TDQS5_B_T SCONN288_ADR50017P087CC-SCONN2A   I181 @S9S_MB_2U_LIB.S9S_MB_2U(SCH_1):PAGE105

M_D_CPU1_SB_DQS_DP<6> @S9S_MB_2U_LIB.S9S_MB_2U(SCH_1):M_D_CPU1_SB_DQS_DP(6)
    U1 AR27 DDR3_SB_DQS_DP6 SOCKET4677_AZIF0045P001C01CS-SA    I91 @S9S_MB_2U_LIB.S9S_MB_2U(SCH_1):PAGE54
   J23  261 DQS6_B_T||TDQS6_B_T SCONN288_ADR50017P130CC-SCONN2A   I178 @S9S_MB_2U_LIB.S9S_MB_2U(SCH_1):PAGE104
   J24  261 DQS6_B_T||TDQS6_B_T SCONN288_ADR50017P087CC-SCONN2A   I181 @S9S_MB_2U_LIB.S9S_MB_2U(SCH_1):PAGE105

M_D_CPU1_SB_DQS_DP<7> @S9S_MB_2U_LIB.S9S_MB_2U(SCH_1):M_D_CPU1_SB_DQS_DP(7)
    U1 AH24 DDR3_SB_DQS_DP7 SOCKET4677_AZIF0045P001C01CS-SA    I91 @S9S_MB_2U_LIB.S9S_MB_2U(SCH_1):PAGE54
   J23  272 DQS7_B_T||TDQS7_B_T SCONN288_ADR50017P130CC-SCONN2A   I178 @S9S_MB_2U_LIB.S9S_MB_2U(SCH_1):PAGE104
   J24  272 DQS7_B_T||TDQS7_B_T SCONN288_ADR50017P087CC-SCONN2A   I181 @S9S_MB_2U_LIB.S9S_MB_2U(SCH_1):PAGE105

M_D_CPU1_SB_DQS_DP<8> @S9S_MB_2U_LIB.S9S_MB_2U(SCH_1):M_D_CPU1_SB_DQS_DP(8)
    U1 AR21 DDR3_SB_DQS_DP8 SOCKET4677_AZIF0045P001C01CS-SA    I91 @S9S_MB_2U_LIB.S9S_MB_2U(SCH_1):PAGE54
   J23  283 DQS8_B_T||TDQS8_B_T SCONN288_ADR50017P130CC-SCONN2A   I178 @S9S_MB_2U_LIB.S9S_MB_2U(SCH_1):PAGE104
   J24  283 DQS8_B_T||TDQS8_B_T SCONN288_ADR50017P087CC-SCONN2A   I181 @S9S_MB_2U_LIB.S9S_MB_2U(SCH_1):PAGE105

M_D_CPU1_SB_DQS_DP<9> @S9S_MB_2U_LIB.S9S_MB_2U(SCH_1):M_D_CPU1_SB_DQS_DP(9)
    U1 AL39 DDR3_SB_DQS_DP9 SOCKET4677_AZIF0045P001C01CS-SA    I91 @S9S_MB_2U_LIB.S9S_MB_2U(SCH_1):PAGE54
   J23   93 DQS9_B_T||TDQS9_B_T||DBI4_B_N SCONN288_ADR50017P130CC-SCONN2A   I178 @S9S_MB_2U_LIB.S9S_MB_2U(SCH_1):PAGE104
   J24   93 DQS9_B_T||TDQS9_B_T||DBI4_B_N SCONN288_ADR50017P087CC-SCONN2A   I181 @S9S_MB_2U_LIB.S9S_MB_2U(SCH_1):PAGE105

M_D_CPU1_SB_PAR @S9S_MB_2U_LIB.S9S_MB_2U(SCH_1):M_D_CPU1_SB_PAR
    U1 AH42 DDR3_SB_PAR SOCKET4677_AZIF0045P001C01CS-SA    I91 @S9S_MB_2U_LIB.S9S_MB_2U(SCH_1):PAGE54
   J23  227  PAR_B SCONN288_ADR50017P130CC-SCONN2A    I25 @S9S_MB_2U_LIB.S9S_MB_2U(SCH_1):PAGE104
   J24  227  PAR_B SCONN288_ADR50017P087CC-SCONN2A   I178 @S9S_MB_2U_LIB.S9S_MB_2U(SCH_1):PAGE105

M_D_CPU1_SB_RSP<0> @S9S_MB_2U_LIB.S9S_MB_2U(SCH_1):M_D_CPU1_SB_RSP(0)
    U1 AF51 DDR3_B_RSP0 SOCKET4677_AZIF0045P001C01CS-SA    I91 @S9S_MB_2U_LIB.S9S_MB_2U(SCH_1):PAGE54
   J23   87 LBS||RSP_B_N SCONN288_ADR50017P130CC-SCONN2A    I25 @S9S_MB_2U_LIB.S9S_MB_2U(SCH_1):PAGE104

M_D_CPU1_SB_RSP<1> @S9S_MB_2U_LIB.S9S_MB_2U(SCH_1):M_D_CPU1_SB_RSP(1)
    U1 AG50 DDR3_B_RSP1 SOCKET4677_AZIF0045P001C01CS-SA    I91 @S9S_MB_2U_LIB.S9S_MB_2U(SCH_1):PAGE54
   J24   87 LBS||RSP_B_N SCONN288_ADR50017P087CC-SCONN2A   I178 @S9S_MB_2U_LIB.S9S_MB_2U(SCH_1):PAGE105

M_E_CPU0_ALERT_N @S9S_MB_2U_LIB.S9S_MB_2U(SCH_1):M_E_CPU0_ALERT_N
    U2 CY47 DDR4_ALERT_N SOCKET4677_AZIF0045P001C01CS-SA   I169 @S9S_MB_2U_LIB.S9S_MB_2U(SCH_1):PAGE24
    J9   62 ALERT_N SCONN288_ADR50017P130CC-SCONN2A    I12 @S9S_MB_2U_LIB.S9S_MB_2U(SCH_1):PAGE90
   J10   62 ALERT_N SCONN288_ADR50017P087CC-SCONN2A    I13 @S9S_MB_2U_LIB.S9S_MB_2U(SCH_1):PAGE91

M_E_CPU0_CLK_DN<0> @S9S_MB_2U_LIB.S9S_MB_2U(SCH_1):M_E_CPU0_CLK_DN(0)
    U2 EJ45 DDR4_CLK_DN0 SOCKET4677_AZIF0045P001C01CS-SA   I169 @S9S_MB_2U_LIB.S9S_MB_2U(SCH_1):PAGE24
    J9  218   CK_C SCONN288_ADR50017P130CC-SCONN2A    I12 @S9S_MB_2U_LIB.S9S_MB_2U(SCH_1):PAGE90

M_E_CPU0_CLK_DN<1> @S9S_MB_2U_LIB.S9S_MB_2U(SCH_1):M_E_CPU0_CLK_DN(1)
    U2 EE45 DDR4_CLK_DN1 SOCKET4677_AZIF0045P001C01CS-SA   I169 @S9S_MB_2U_LIB.S9S_MB_2U(SCH_1):PAGE24
   J10  218   CK_C SCONN288_ADR50017P087CC-SCONN2A    I13 @S9S_MB_2U_LIB.S9S_MB_2U(SCH_1):PAGE91

M_E_CPU0_CLK_DP<0> @S9S_MB_2U_LIB.S9S_MB_2U(SCH_1):M_E_CPU0_CLK_DP(0)
    U2 EG45 DDR4_CLK_DP0 SOCKET4677_AZIF0045P001C01CS-SA   I169 @S9S_MB_2U_LIB.S9S_MB_2U(SCH_1):PAGE24
    J9  217   CK_T SCONN288_ADR50017P130CC-SCONN2A    I12 @S9S_MB_2U_LIB.S9S_MB_2U(SCH_1):PAGE90

M_E_CPU0_CLK_DP<1> @S9S_MB_2U_LIB.S9S_MB_2U(SCH_1):M_E_CPU0_CLK_DP(1)
    U2 EC45 DDR4_CLK_DP1 SOCKET4677_AZIF0045P001C01CS-SA   I169 @S9S_MB_2U_LIB.S9S_MB_2U(SCH_1):PAGE24
   J10  217   CK_T SCONN288_ADR50017P087CC-SCONN2A    I13 @S9S_MB_2U_LIB.S9S_MB_2U(SCH_1):PAGE91

M_E_CPU0_SA_CA<0> @S9S_MB_2U_LIB.S9S_MB_2U(SCH_1):M_E_CPU0_SA_CA(0)
    U2 EP49 DDR4_SA_CA0 SOCKET4677_AZIF0045P001C01CS-SA   I169 @S9S_MB_2U_LIB.S9S_MB_2U(SCH_1):PAGE24
    J9   66  CA0_A SCONN288_ADR50017P130CC-SCONN2A    I12 @S9S_MB_2U_LIB.S9S_MB_2U(SCH_1):PAGE90
   J10   66  CA0_A SCONN288_ADR50017P087CC-SCONN2A    I13 @S9S_MB_2U_LIB.S9S_MB_2U(SCH_1):PAGE91

M_E_CPU0_SA_CA<1> @S9S_MB_2U_LIB.S9S_MB_2U(SCH_1):M_E_CPU0_SA_CA(1)
    U2 ET49 DDR4_SA_CA1 SOCKET4677_AZIF0045P001C01CS-SA   I169 @S9S_MB_2U_LIB.S9S_MB_2U(SCH_1):PAGE24
    J9  211  CA1_A SCONN288_ADR50017P130CC-SCONN2A    I12 @S9S_MB_2U_LIB.S9S_MB_2U(SCH_1):PAGE90
   J10  211  CA1_A SCONN288_ADR50017P087CC-SCONN2A    I13 @S9S_MB_2U_LIB.S9S_MB_2U(SCH_1):PAGE91

M_E_CPU0_SA_CA<2> @S9S_MB_2U_LIB.S9S_MB_2U(SCH_1):M_E_CPU0_SA_CA(2)
    U2 EK49 DDR4_SA_CA2 SOCKET4677_AZIF0045P001C01CS-SA   I169 @S9S_MB_2U_LIB.S9S_MB_2U(SCH_1):PAGE24
    J9   68  CA2_A SCONN288_ADR50017P130CC-SCONN2A    I12 @S9S_MB_2U_LIB.S9S_MB_2U(SCH_1):PAGE90
   J10   68  CA2_A SCONN288_ADR50017P087CC-SCONN2A    I13 @S9S_MB_2U_LIB.S9S_MB_2U(SCH_1):PAGE91

M_E_CPU0_SA_CA<3> @S9S_MB_2U_LIB.S9S_MB_2U(SCH_1):M_E_CPU0_SA_CA(3)
    U2 EL48 DDR4_SA_CA3 SOCKET4677_AZIF0045P001C01CS-SA   I169 @S9S_MB_2U_LIB.S9S_MB_2U(SCH_1):PAGE24
    J9  213  CA3_A SCONN288_ADR50017P130CC-SCONN2A    I12 @S9S_MB_2U_LIB.S9S_MB_2U(SCH_1):PAGE90
   J10  213  CA3_A SCONN288_ADR50017P087CC-SCONN2A    I13 @S9S_MB_2U_LIB.S9S_MB_2U(SCH_1):PAGE91

M_E_CPU0_SA_CA<4> @S9S_MB_2U_LIB.S9S_MB_2U(SCH_1):M_E_CPU0_SA_CA(4)
    U2 EM47 DDR4_SA_CA4 SOCKET4677_AZIF0045P001C01CS-SA   I169 @S9S_MB_2U_LIB.S9S_MB_2U(SCH_1):PAGE24
    J9   70  CA4_A SCONN288_ADR50017P130CC-SCONN2A    I12 @S9S_MB_2U_LIB.S9S_MB_2U(SCH_1):PAGE90
   J10   70  CA4_A SCONN288_ADR50017P087CC-SCONN2A    I13 @S9S_MB_2U_LIB.S9S_MB_2U(SCH_1):PAGE91

M_E_CPU0_SA_CA<5> @S9S_MB_2U_LIB.S9S_MB_2U(SCH_1):M_E_CPU0_SA_CA(5)
    U2 EP47 DDR4_SA_CA5 SOCKET4677_AZIF0045P001C01CS-SA   I169 @S9S_MB_2U_LIB.S9S_MB_2U(SCH_1):PAGE24
    J9  215  CA5_A SCONN288_ADR50017P130CC-SCONN2A    I12 @S9S_MB_2U_LIB.S9S_MB_2U(SCH_1):PAGE90
   J10  215  CA5_A SCONN288_ADR50017P087CC-SCONN2A    I13 @S9S_MB_2U_LIB.S9S_MB_2U(SCH_1):PAGE91

M_E_CPU0_SA_CA<6> @S9S_MB_2U_LIB.S9S_MB_2U(SCH_1):M_E_CPU0_SA_CA(6)
    U2 ED44 DDR4_SA_CA6 SOCKET4677_AZIF0045P001C01CS-SA   I169 @S9S_MB_2U_LIB.S9S_MB_2U(SCH_1):PAGE24
    J9   72  CA6_A SCONN288_ADR50017P130CC-SCONN2A    I12 @S9S_MB_2U_LIB.S9S_MB_2U(SCH_1):PAGE90
   J10   72  CA6_A SCONN288_ADR50017P087CC-SCONN2A    I13 @S9S_MB_2U_LIB.S9S_MB_2U(SCH_1):PAGE91

M_E_CPU0_SA_CB<0> @S9S_MB_2U_LIB.S9S_MB_2U(SCH_1):M_E_CPU0_SA_CB(0)
    U2 EM57 DDR4_SA_ECC0 SOCKET4677_AZIF0045P001C01CS-SA   I169 @S9S_MB_2U_LIB.S9S_MB_2U(SCH_1):PAGE24
    J9   51  CB0_A SCONN288_ADR50017P130CC-SCONN2A    I12 @S9S_MB_2U_LIB.S9S_MB_2U(SCH_1):PAGE90
   J10   51  CB0_A SCONN288_ADR50017P087CC-SCONN2A    I13 @S9S_MB_2U_LIB.S9S_MB_2U(SCH_1):PAGE91

M_E_CPU0_SA_CB<1> @S9S_MB_2U_LIB.S9S_MB_2U(SCH_1):M_E_CPU0_SA_CB(1)
    U2 EL56 DDR4_SA_ECC1 SOCKET4677_AZIF0045P001C01CS-SA   I169 @S9S_MB_2U_LIB.S9S_MB_2U(SCH_1):PAGE24
    J9   53  CB1_A SCONN288_ADR50017P130CC-SCONN2A    I12 @S9S_MB_2U_LIB.S9S_MB_2U(SCH_1):PAGE90
   J10   53  CB1_A SCONN288_ADR50017P087CC-SCONN2A    I13 @S9S_MB_2U_LIB.S9S_MB_2U(SCH_1):PAGE91

M_E_CPU0_SA_CB<2> @S9S_MB_2U_LIB.S9S_MB_2U(SCH_1):M_E_CPU0_SA_CB(2)
    U2 EP57 DDR4_SA_ECC2 SOCKET4677_AZIF0045P001C01CS-SA   I169 @S9S_MB_2U_LIB.S9S_MB_2U(SCH_1):PAGE24
    J9  196  CB2_A SCONN288_ADR50017P130CC-SCONN2A    I12 @S9S_MB_2U_LIB.S9S_MB_2U(SCH_1):PAGE90
   J10  196  CB2_A SCONN288_ADR50017P087CC-SCONN2A    I13 @S9S_MB_2U_LIB.S9S_MB_2U(SCH_1):PAGE91

M_E_CPU0_SA_CB<3> @S9S_MB_2U_LIB.S9S_MB_2U(SCH_1):M_E_CPU0_SA_CB(3)
    U2 ER56 DDR4_SA_ECC3 SOCKET4677_AZIF0045P001C01CS-SA   I169 @S9S_MB_2U_LIB.S9S_MB_2U(SCH_1):PAGE24
    J9  198  CB3_A SCONN288_ADR50017P130CC-SCONN2A    I12 @S9S_MB_2U_LIB.S9S_MB_2U(SCH_1):PAGE90
   J10  198  CB3_A SCONN288_ADR50017P087CC-SCONN2A    I13 @S9S_MB_2U_LIB.S9S_MB_2U(SCH_1):PAGE91

M_E_CPU0_SA_CB<4> @S9S_MB_2U_LIB.S9S_MB_2U(SCH_1):M_E_CPU0_SA_CB(4)
    U2 EL54 DDR4_SA_ECC4 SOCKET4677_AZIF0045P001C01CS-SA   I169 @S9S_MB_2U_LIB.S9S_MB_2U(SCH_1):PAGE24
    J9   58  CB4_A SCONN288_ADR50017P130CC-SCONN2A    I12 @S9S_MB_2U_LIB.S9S_MB_2U(SCH_1):PAGE90
   J10   58  CB4_A SCONN288_ADR50017P087CC-SCONN2A    I13 @S9S_MB_2U_LIB.S9S_MB_2U(SCH_1):PAGE91

M_E_CPU0_SA_CB<5> @S9S_MB_2U_LIB.S9S_MB_2U(SCH_1):M_E_CPU0_SA_CB(5)
    U2 EM53 DDR4_SA_ECC5 SOCKET4677_AZIF0045P001C01CS-SA   I169 @S9S_MB_2U_LIB.S9S_MB_2U(SCH_1):PAGE24
    J9   60  CB5_A SCONN288_ADR50017P130CC-SCONN2A    I12 @S9S_MB_2U_LIB.S9S_MB_2U(SCH_1):PAGE90
   J10   60  CB5_A SCONN288_ADR50017P087CC-SCONN2A    I13 @S9S_MB_2U_LIB.S9S_MB_2U(SCH_1):PAGE91

M_E_CPU0_SA_CB<6> @S9S_MB_2U_LIB.S9S_MB_2U(SCH_1):M_E_CPU0_SA_CB(6)
    U2 ER54 DDR4_SA_ECC6 SOCKET4677_AZIF0045P001C01CS-SA   I169 @S9S_MB_2U_LIB.S9S_MB_2U(SCH_1):PAGE24
    J9  203  CB6_A SCONN288_ADR50017P130CC-SCONN2A    I12 @S9S_MB_2U_LIB.S9S_MB_2U(SCH_1):PAGE90
   J10  203  CB6_A SCONN288_ADR50017P087CC-SCONN2A    I13 @S9S_MB_2U_LIB.S9S_MB_2U(SCH_1):PAGE91

M_E_CPU0_SA_CB<7> @S9S_MB_2U_LIB.S9S_MB_2U(SCH_1):M_E_CPU0_SA_CB(7)
    U2 EP53 DDR4_SA_ECC7 SOCKET4677_AZIF0045P001C01CS-SA   I169 @S9S_MB_2U_LIB.S9S_MB_2U(SCH_1):PAGE24
    J9  205  CB7_A SCONN288_ADR50017P130CC-SCONN2A    I12 @S9S_MB_2U_LIB.S9S_MB_2U(SCH_1):PAGE90
   J10  205  CB7_A SCONN288_ADR50017P087CC-SCONN2A    I13 @S9S_MB_2U_LIB.S9S_MB_2U(SCH_1):PAGE91

M_E_CPU0_SA_CS_N<0> @S9S_MB_2U_LIB.S9S_MB_2U(SCH_1):M_E_CPU0_SA_CS_N(0)
    U2 EP51 DDR4_SA_CS_N0 SOCKET4677_AZIF0045P001C01CS-SA   I169 @S9S_MB_2U_LIB.S9S_MB_2U(SCH_1):PAGE24
    J9   64 CS0_A_N SCONN288_ADR50017P130CC-SCONN2A    I12 @S9S_MB_2U_LIB.S9S_MB_2U(SCH_1):PAGE90

M_E_CPU0_SA_CS_N<1> @S9S_MB_2U_LIB.S9S_MB_2U(SCH_1):M_E_CPU0_SA_CS_N(1)
    U2 ET51 DDR4_SA_CS_N1 SOCKET4677_AZIF0045P001C01CS-SA   I169 @S9S_MB_2U_LIB.S9S_MB_2U(SCH_1):PAGE24
    J9  209 CS1_A_N SCONN288_ADR50017P130CC-SCONN2A    I12 @S9S_MB_2U_LIB.S9S_MB_2U(SCH_1):PAGE90

M_E_CPU0_SA_CS_N<2> @S9S_MB_2U_LIB.S9S_MB_2U(SCH_1):M_E_CPU0_SA_CS_N(2)
    U2 EM51 DDR4_SA_CS_N2 SOCKET4677_AZIF0045P001C01CS-SA   I169 @S9S_MB_2U_LIB.S9S_MB_2U(SCH_1):PAGE24
   J10   64 CS0_A_N SCONN288_ADR50017P087CC-SCONN2A    I13 @S9S_MB_2U_LIB.S9S_MB_2U(SCH_1):PAGE91

M_E_CPU0_SA_CS_N<3> @S9S_MB_2U_LIB.S9S_MB_2U(SCH_1):M_E_CPU0_SA_CS_N(3)
    U2 EL50 DDR4_SA_CS_N3 SOCKET4677_AZIF0045P001C01CS-SA   I169 @S9S_MB_2U_LIB.S9S_MB_2U(SCH_1):PAGE24
   J10  209 CS1_A_N SCONN288_ADR50017P087CC-SCONN2A    I13 @S9S_MB_2U_LIB.S9S_MB_2U(SCH_1):PAGE91

M_E_CPU0_SA_DQ<0> @S9S_MB_2U_LIB.S9S_MB_2U(SCH_1):M_E_CPU0_SA_DQ(0)
    U2 EL78 DDR4_SA_DQ0 SOCKET4677_AZIF0045P001C01CS-SA   I169 @S9S_MB_2U_LIB.S9S_MB_2U(SCH_1):PAGE24
    J9    7  DQ0_A SCONN288_ADR50017P130CC-SCONN2A    I12 @S9S_MB_2U_LIB.S9S_MB_2U(SCH_1):PAGE90
   J10    7  DQ0_A SCONN288_ADR50017P087CC-SCONN2A    I13 @S9S_MB_2U_LIB.S9S_MB_2U(SCH_1):PAGE91

M_E_CPU0_SA_DQ<10> @S9S_MB_2U_LIB.S9S_MB_2U(SCH_1):M_E_CPU0_SA_DQ(10)
    U2 EG72 DDR4_SA_DQ10 SOCKET4677_AZIF0045P001C01CS-SA   I169 @S9S_MB_2U_LIB.S9S_MB_2U(SCH_1):PAGE24
    J9  163 DQ10_A SCONN288_ADR50017P130CC-SCONN2A    I12 @S9S_MB_2U_LIB.S9S_MB_2U(SCH_1):PAGE90
   J10  163 DQ10_A SCONN288_ADR50017P087CC-SCONN2A    I13 @S9S_MB_2U_LIB.S9S_MB_2U(SCH_1):PAGE91

M_E_CPU0_SA_DQ<11> @S9S_MB_2U_LIB.S9S_MB_2U(SCH_1):M_E_CPU0_SA_DQ(11)
    U2 EH71 DDR4_SA_DQ11 SOCKET4677_AZIF0045P001C01CS-SA   I169 @S9S_MB_2U_LIB.S9S_MB_2U(SCH_1):PAGE24
    J9  165 DQ11_A SCONN288_ADR50017P130CC-SCONN2A    I12 @S9S_MB_2U_LIB.S9S_MB_2U(SCH_1):PAGE90
   J10  165 DQ11_A SCONN288_ADR50017P087CC-SCONN2A    I13 @S9S_MB_2U_LIB.S9S_MB_2U(SCH_1):PAGE91

M_E_CPU0_SA_DQ<12> @S9S_MB_2U_LIB.S9S_MB_2U(SCH_1):M_E_CPU0_SA_DQ(12)
    U2 ED69 DDR4_SA_DQ12 SOCKET4677_AZIF0045P001C01CS-SA   I169 @S9S_MB_2U_LIB.S9S_MB_2U(SCH_1):PAGE24
    J9   25 DQ12_A SCONN288_ADR50017P130CC-SCONN2A    I12 @S9S_MB_2U_LIB.S9S_MB_2U(SCH_1):PAGE90
   J10   25 DQ12_A SCONN288_ADR50017P087CC-SCONN2A    I13 @S9S_MB_2U_LIB.S9S_MB_2U(SCH_1):PAGE91

M_E_CPU0_SA_DQ<13> @S9S_MB_2U_LIB.S9S_MB_2U(SCH_1):M_E_CPU0_SA_DQ(13)
    U2 EE68 DDR4_SA_DQ13 SOCKET4677_AZIF0045P001C01CS-SA   I169 @S9S_MB_2U_LIB.S9S_MB_2U(SCH_1):PAGE24
    J9   27 DQ13_A SCONN288_ADR50017P130CC-SCONN2A    I12 @S9S_MB_2U_LIB.S9S_MB_2U(SCH_1):PAGE90
   J10   27 DQ13_A SCONN288_ADR50017P087CC-SCONN2A    I13 @S9S_MB_2U_LIB.S9S_MB_2U(SCH_1):PAGE91

M_E_CPU0_SA_DQ<14> @S9S_MB_2U_LIB.S9S_MB_2U(SCH_1):M_E_CPU0_SA_DQ(14)
    U2 EH69 DDR4_SA_DQ14 SOCKET4677_AZIF0045P001C01CS-SA   I169 @S9S_MB_2U_LIB.S9S_MB_2U(SCH_1):PAGE24
    J9  170 DQ14_A SCONN288_ADR50017P130CC-SCONN2A    I12 @S9S_MB_2U_LIB.S9S_MB_2U(SCH_1):PAGE90
   J10  170 DQ14_A SCONN288_ADR50017P087CC-SCONN2A    I13 @S9S_MB_2U_LIB.S9S_MB_2U(SCH_1):PAGE91

M_E_CPU0_SA_DQ<15> @S9S_MB_2U_LIB.S9S_MB_2U(SCH_1):M_E_CPU0_SA_DQ(15)
    U2 EG68 DDR4_SA_DQ15 SOCKET4677_AZIF0045P001C01CS-SA   I169 @S9S_MB_2U_LIB.S9S_MB_2U(SCH_1):PAGE24
    J9  172 DQ15_A SCONN288_ADR50017P130CC-SCONN2A    I12 @S9S_MB_2U_LIB.S9S_MB_2U(SCH_1):PAGE90
   J10  172 DQ15_A SCONN288_ADR50017P087CC-SCONN2A    I13 @S9S_MB_2U_LIB.S9S_MB_2U(SCH_1):PAGE91

M_E_CPU0_SA_DQ<16> @S9S_MB_2U_LIB.S9S_MB_2U(SCH_1):M_E_CPU0_SA_DQ(16)
    U2 EM71 DDR4_SA_DQ16 SOCKET4677_AZIF0045P001C01CS-SA   I169 @S9S_MB_2U_LIB.S9S_MB_2U(SCH_1):PAGE24
    J9   29 DQ16_A SCONN288_ADR50017P130CC-SCONN2A    I12 @S9S_MB_2U_LIB.S9S_MB_2U(SCH_1):PAGE90
   J10   29 DQ16_A SCONN288_ADR50017P087CC-SCONN2A    I13 @S9S_MB_2U_LIB.S9S_MB_2U(SCH_1):PAGE91

M_E_CPU0_SA_DQ<17> @S9S_MB_2U_LIB.S9S_MB_2U(SCH_1):M_E_CPU0_SA_DQ(17)
    U2 EM69 DDR4_SA_DQ17 SOCKET4677_AZIF0045P001C01CS-SA   I169 @S9S_MB_2U_LIB.S9S_MB_2U(SCH_1):PAGE24
    J9   31 DQ17_A SCONN288_ADR50017P130CC-SCONN2A    I12 @S9S_MB_2U_LIB.S9S_MB_2U(SCH_1):PAGE90
   J10   31 DQ17_A SCONN288_ADR50017P087CC-SCONN2A    I13 @S9S_MB_2U_LIB.S9S_MB_2U(SCH_1):PAGE91

M_E_CPU0_SA_DQ<18> @S9S_MB_2U_LIB.S9S_MB_2U(SCH_1):M_E_CPU0_SA_DQ(18)
    U2 EN70 DDR4_SA_DQ18 SOCKET4677_AZIF0045P001C01CS-SA   I169 @S9S_MB_2U_LIB.S9S_MB_2U(SCH_1):PAGE24
    J9  174 DQ18_A SCONN288_ADR50017P130CC-SCONN2A    I12 @S9S_MB_2U_LIB.S9S_MB_2U(SCH_1):PAGE90
   J10  174 DQ18_A SCONN288_ADR50017P087CC-SCONN2A    I13 @S9S_MB_2U_LIB.S9S_MB_2U(SCH_1):PAGE91

M_E_CPU0_SA_DQ<19> @S9S_MB_2U_LIB.S9S_MB_2U(SCH_1):M_E_CPU0_SA_DQ(19)
    U2 ER68 DDR4_SA_DQ19 SOCKET4677_AZIF0045P001C01CS-SA   I169 @S9S_MB_2U_LIB.S9S_MB_2U(SCH_1):PAGE24
    J9  176 DQ19_A SCONN288_ADR50017P130CC-SCONN2A    I12 @S9S_MB_2U_LIB.S9S_MB_2U(SCH_1):PAGE90
   J10  176 DQ19_A SCONN288_ADR50017P087CC-SCONN2A    I13 @S9S_MB_2U_LIB.S9S_MB_2U(SCH_1):PAGE91

M_E_CPU0_SA_DQ<1> @S9S_MB_2U_LIB.S9S_MB_2U(SCH_1):M_E_CPU0_SA_DQ(1)
    U2 EM77 DDR4_SA_DQ1 SOCKET4677_AZIF0045P001C01CS-SA   I169 @S9S_MB_2U_LIB.S9S_MB_2U(SCH_1):PAGE24
    J9    9  DQ1_A SCONN288_ADR50017P130CC-SCONN2A    I12 @S9S_MB_2U_LIB.S9S_MB_2U(SCH_1):PAGE90
   J10    9  DQ1_A SCONN288_ADR50017P087CC-SCONN2A    I13 @S9S_MB_2U_LIB.S9S_MB_2U(SCH_1):PAGE91

M_E_CPU0_SA_DQ<20> @S9S_MB_2U_LIB.S9S_MB_2U(SCH_1):M_E_CPU0_SA_DQ(20)
    U2 ER66 DDR4_SA_DQ20 SOCKET4677_AZIF0045P001C01CS-SA   I169 @S9S_MB_2U_LIB.S9S_MB_2U(SCH_1):PAGE24
    J9   36 DQ20_A SCONN288_ADR50017P130CC-SCONN2A    I12 @S9S_MB_2U_LIB.S9S_MB_2U(SCH_1):PAGE90
   J10   36 DQ20_A SCONN288_ADR50017P087CC-SCONN2A    I13 @S9S_MB_2U_LIB.S9S_MB_2U(SCH_1):PAGE91

M_E_CPU0_SA_DQ<21> @S9S_MB_2U_LIB.S9S_MB_2U(SCH_1):M_E_CPU0_SA_DQ(21)
    U2 EM65 DDR4_SA_DQ21 SOCKET4677_AZIF0045P001C01CS-SA   I169 @S9S_MB_2U_LIB.S9S_MB_2U(SCH_1):PAGE24
    J9   38 DQ21_A SCONN288_ADR50017P130CC-SCONN2A    I12 @S9S_MB_2U_LIB.S9S_MB_2U(SCH_1):PAGE90
   J10   38 DQ21_A SCONN288_ADR50017P087CC-SCONN2A    I13 @S9S_MB_2U_LIB.S9S_MB_2U(SCH_1):PAGE91

M_E_CPU0_SA_DQ<22> @S9S_MB_2U_LIB.S9S_MB_2U(SCH_1):M_E_CPU0_SA_DQ(22)
    U2 EL66 DDR4_SA_DQ22 SOCKET4677_AZIF0045P001C01CS-SA   I169 @S9S_MB_2U_LIB.S9S_MB_2U(SCH_1):PAGE24
    J9  181 DQ22_A SCONN288_ADR50017P130CC-SCONN2A    I12 @S9S_MB_2U_LIB.S9S_MB_2U(SCH_1):PAGE90
   J10  181 DQ22_A SCONN288_ADR50017P087CC-SCONN2A    I13 @S9S_MB_2U_LIB.S9S_MB_2U(SCH_1):PAGE91

M_E_CPU0_SA_DQ<23> @S9S_MB_2U_LIB.S9S_MB_2U(SCH_1):M_E_CPU0_SA_DQ(23)
    U2 EP65 DDR4_SA_DQ23 SOCKET4677_AZIF0045P001C01CS-SA   I169 @S9S_MB_2U_LIB.S9S_MB_2U(SCH_1):PAGE24
    J9  183 DQ23_A SCONN288_ADR50017P130CC-SCONN2A    I12 @S9S_MB_2U_LIB.S9S_MB_2U(SCH_1):PAGE90
   J10  183 DQ23_A SCONN288_ADR50017P087CC-SCONN2A    I13 @S9S_MB_2U_LIB.S9S_MB_2U(SCH_1):PAGE91

M_E_CPU0_SA_DQ<24> @S9S_MB_2U_LIB.S9S_MB_2U(SCH_1):M_E_CPU0_SA_DQ(24)
    U2 EM63 DDR4_SA_DQ24 SOCKET4677_AZIF0045P001C01CS-SA   I169 @S9S_MB_2U_LIB.S9S_MB_2U(SCH_1):PAGE24
    J9   40 DQ24_A SCONN288_ADR50017P130CC-SCONN2A    I12 @S9S_MB_2U_LIB.S9S_MB_2U(SCH_1):PAGE90
   J10   40 DQ24_A SCONN288_ADR50017P087CC-SCONN2A    I13 @S9S_MB_2U_LIB.S9S_MB_2U(SCH_1):PAGE91

M_E_CPU0_SA_DQ<25> @S9S_MB_2U_LIB.S9S_MB_2U(SCH_1):M_E_CPU0_SA_DQ(25)
    U2 EL62 DDR4_SA_DQ25 SOCKET4677_AZIF0045P001C01CS-SA   I169 @S9S_MB_2U_LIB.S9S_MB_2U(SCH_1):PAGE24
    J9   42 DQ25_A SCONN288_ADR50017P130CC-SCONN2A    I12 @S9S_MB_2U_LIB.S9S_MB_2U(SCH_1):PAGE90
   J10   42 DQ25_A SCONN288_ADR50017P087CC-SCONN2A    I13 @S9S_MB_2U_LIB.S9S_MB_2U(SCH_1):PAGE91

M_E_CPU0_SA_DQ<26> @S9S_MB_2U_LIB.S9S_MB_2U(SCH_1):M_E_CPU0_SA_DQ(26)
    U2 EP63 DDR4_SA_DQ26 SOCKET4677_AZIF0045P001C01CS-SA   I169 @S9S_MB_2U_LIB.S9S_MB_2U(SCH_1):PAGE24
    J9  185 DQ26_A SCONN288_ADR50017P130CC-SCONN2A    I12 @S9S_MB_2U_LIB.S9S_MB_2U(SCH_1):PAGE90
   J10  185 DQ26_A SCONN288_ADR50017P087CC-SCONN2A    I13 @S9S_MB_2U_LIB.S9S_MB_2U(SCH_1):PAGE91

M_E_CPU0_SA_DQ<27> @S9S_MB_2U_LIB.S9S_MB_2U(SCH_1):M_E_CPU0_SA_DQ(27)
    U2 ER62 DDR4_SA_DQ27 SOCKET4677_AZIF0045P001C01CS-SA   I169 @S9S_MB_2U_LIB.S9S_MB_2U(SCH_1):PAGE24
    J9  187 DQ27_A SCONN288_ADR50017P130CC-SCONN2A    I12 @S9S_MB_2U_LIB.S9S_MB_2U(SCH_1):PAGE90
   J10  187 DQ27_A SCONN288_ADR50017P087CC-SCONN2A    I13 @S9S_MB_2U_LIB.S9S_MB_2U(SCH_1):PAGE91

M_E_CPU0_SA_DQ<28> @S9S_MB_2U_LIB.S9S_MB_2U(SCH_1):M_E_CPU0_SA_DQ(28)
    U2 EL60 DDR4_SA_DQ28 SOCKET4677_AZIF0045P001C01CS-SA   I169 @S9S_MB_2U_LIB.S9S_MB_2U(SCH_1):PAGE24
    J9   47 DQ28_A SCONN288_ADR50017P130CC-SCONN2A    I12 @S9S_MB_2U_LIB.S9S_MB_2U(SCH_1):PAGE90
   J10   47 DQ28_A SCONN288_ADR50017P087CC-SCONN2A    I13 @S9S_MB_2U_LIB.S9S_MB_2U(SCH_1):PAGE91

M_E_CPU0_SA_DQ<29> @S9S_MB_2U_LIB.S9S_MB_2U(SCH_1):M_E_CPU0_SA_DQ(29)
    U2 EM59 DDR4_SA_DQ29 SOCKET4677_AZIF0045P001C01CS-SA   I169 @S9S_MB_2U_LIB.S9S_MB_2U(SCH_1):PAGE24
    J9   49 DQ29_A SCONN288_ADR50017P130CC-SCONN2A    I12 @S9S_MB_2U_LIB.S9S_MB_2U(SCH_1):PAGE90
   J10   49 DQ29_A SCONN288_ADR50017P087CC-SCONN2A    I13 @S9S_MB_2U_LIB.S9S_MB_2U(SCH_1):PAGE91

M_E_CPU0_SA_DQ<2> @S9S_MB_2U_LIB.S9S_MB_2U(SCH_1):M_E_CPU0_SA_DQ(2)
    U2 EP79 DDR4_SA_DQ2 SOCKET4677_AZIF0045P001C01CS-SA   I169 @S9S_MB_2U_LIB.S9S_MB_2U(SCH_1):PAGE24
    J9  152  DQ2_A SCONN288_ADR50017P130CC-SCONN2A    I12 @S9S_MB_2U_LIB.S9S_MB_2U(SCH_1):PAGE90
   J10  152  DQ2_A SCONN288_ADR50017P087CC-SCONN2A    I13 @S9S_MB_2U_LIB.S9S_MB_2U(SCH_1):PAGE91

M_E_CPU0_SA_DQ<30> @S9S_MB_2U_LIB.S9S_MB_2U(SCH_1):M_E_CPU0_SA_DQ(30)
    U2 ER60 DDR4_SA_DQ30 SOCKET4677_AZIF0045P001C01CS-SA   I169 @S9S_MB_2U_LIB.S9S_MB_2U(SCH_1):PAGE24
    J9  192 DQ30_A SCONN288_ADR50017P130CC-SCONN2A    I12 @S9S_MB_2U_LIB.S9S_MB_2U(SCH_1):PAGE90
   J10  192 DQ30_A SCONN288_ADR50017P087CC-SCONN2A    I13 @S9S_MB_2U_LIB.S9S_MB_2U(SCH_1):PAGE91

M_E_CPU0_SA_DQ<31> @S9S_MB_2U_LIB.S9S_MB_2U(SCH_1):M_E_CPU0_SA_DQ(31)
    U2 EP59 DDR4_SA_DQ31 SOCKET4677_AZIF0045P001C01CS-SA   I169 @S9S_MB_2U_LIB.S9S_MB_2U(SCH_1):PAGE24
    J9  194 DQ31_A SCONN288_ADR50017P130CC-SCONN2A    I12 @S9S_MB_2U_LIB.S9S_MB_2U(SCH_1):PAGE90
   J10  194 DQ31_A SCONN288_ADR50017P087CC-SCONN2A    I13 @S9S_MB_2U_LIB.S9S_MB_2U(SCH_1):PAGE91

M_E_CPU0_SA_DQ<3> @S9S_MB_2U_LIB.S9S_MB_2U(SCH_1):M_E_CPU0_SA_DQ(3)
    U2 ER76 DDR4_SA_DQ3 SOCKET4677_AZIF0045P001C01CS-SA   I169 @S9S_MB_2U_LIB.S9S_MB_2U(SCH_1):PAGE24
    J9  154  DQ3_A SCONN288_ADR50017P130CC-SCONN2A    I12 @S9S_MB_2U_LIB.S9S_MB_2U(SCH_1):PAGE90
   J10  154  DQ3_A SCONN288_ADR50017P087CC-SCONN2A    I13 @S9S_MB_2U_LIB.S9S_MB_2U(SCH_1):PAGE91

M_E_CPU0_SA_DQ<4> @S9S_MB_2U_LIB.S9S_MB_2U(SCH_1):M_E_CPU0_SA_DQ(4)
    U2 EL74 DDR4_SA_DQ4 SOCKET4677_AZIF0045P001C01CS-SA   I169 @S9S_MB_2U_LIB.S9S_MB_2U(SCH_1):PAGE24
    J9   14  DQ4_A SCONN288_ADR50017P130CC-SCONN2A    I12 @S9S_MB_2U_LIB.S9S_MB_2U(SCH_1):PAGE90
   J10   14  DQ4_A SCONN288_ADR50017P087CC-SCONN2A    I13 @S9S_MB_2U_LIB.S9S_MB_2U(SCH_1):PAGE91

M_E_CPU0_SA_DQ<5> @S9S_MB_2U_LIB.S9S_MB_2U(SCH_1):M_E_CPU0_SA_DQ(5)
    U2 EK73 DDR4_SA_DQ5 SOCKET4677_AZIF0045P001C01CS-SA   I169 @S9S_MB_2U_LIB.S9S_MB_2U(SCH_1):PAGE24
    J9   16  DQ5_A SCONN288_ADR50017P130CC-SCONN2A    I12 @S9S_MB_2U_LIB.S9S_MB_2U(SCH_1):PAGE90
   J10   16  DQ5_A SCONN288_ADR50017P087CC-SCONN2A    I13 @S9S_MB_2U_LIB.S9S_MB_2U(SCH_1):PAGE91

M_E_CPU0_SA_DQ<6> @S9S_MB_2U_LIB.S9S_MB_2U(SCH_1):M_E_CPU0_SA_DQ(6)
    U2 EP73 DDR4_SA_DQ6 SOCKET4677_AZIF0045P001C01CS-SA   I169 @S9S_MB_2U_LIB.S9S_MB_2U(SCH_1):PAGE24
    J9  159  DQ6_A SCONN288_ADR50017P130CC-SCONN2A    I12 @S9S_MB_2U_LIB.S9S_MB_2U(SCH_1):PAGE90
   J10  159  DQ6_A SCONN288_ADR50017P087CC-SCONN2A    I13 @S9S_MB_2U_LIB.S9S_MB_2U(SCH_1):PAGE91

M_E_CPU0_SA_DQ<7> @S9S_MB_2U_LIB.S9S_MB_2U(SCH_1):M_E_CPU0_SA_DQ(7)
    U2 ER72 DDR4_SA_DQ7 SOCKET4677_AZIF0045P001C01CS-SA   I169 @S9S_MB_2U_LIB.S9S_MB_2U(SCH_1):PAGE24
    J9  161  DQ7_A SCONN288_ADR50017P130CC-SCONN2A    I12 @S9S_MB_2U_LIB.S9S_MB_2U(SCH_1):PAGE90
   J10  161  DQ7_A SCONN288_ADR50017P087CC-SCONN2A    I13 @S9S_MB_2U_LIB.S9S_MB_2U(SCH_1):PAGE91

M_E_CPU0_SA_DQ<8> @S9S_MB_2U_LIB.S9S_MB_2U(SCH_1):M_E_CPU0_SA_DQ(8)
    U2 EE72 DDR4_SA_DQ8 SOCKET4677_AZIF0045P001C01CS-SA   I169 @S9S_MB_2U_LIB.S9S_MB_2U(SCH_1):PAGE24
    J9   18  DQ8_A SCONN288_ADR50017P130CC-SCONN2A    I12 @S9S_MB_2U_LIB.S9S_MB_2U(SCH_1):PAGE90
   J10   18  DQ8_A SCONN288_ADR50017P087CC-SCONN2A    I13 @S9S_MB_2U_LIB.S9S_MB_2U(SCH_1):PAGE91

M_E_CPU0_SA_DQ<9> @S9S_MB_2U_LIB.S9S_MB_2U(SCH_1):M_E_CPU0_SA_DQ(9)
    U2 ED71 DDR4_SA_DQ9 SOCKET4677_AZIF0045P001C01CS-SA   I169 @S9S_MB_2U_LIB.S9S_MB_2U(SCH_1):PAGE24
    J9   20  DQ9_A SCONN288_ADR50017P130CC-SCONN2A    I12 @S9S_MB_2U_LIB.S9S_MB_2U(SCH_1):PAGE90
   J10   20  DQ9_A SCONN288_ADR50017P087CC-SCONN2A    I13 @S9S_MB_2U_LIB.S9S_MB_2U(SCH_1):PAGE91

M_E_CPU0_SA_DQS_DN<0> @S9S_MB_2U_LIB.S9S_MB_2U(SCH_1):M_E_CPU0_SA_DQS_DN(0)
    U2 EP75 DDR4_SA_DQS_DN0 SOCKET4677_AZIF0045P001C01CS-SA   I169 @S9S_MB_2U_LIB.S9S_MB_2U(SCH_1):PAGE24
    J9   12 DQS0_A_C SCONN288_ADR50017P130CC-SCONN2A   I178 @S9S_MB_2U_LIB.S9S_MB_2U(SCH_1):PAGE90
   J10   12 DQS0_A_C SCONN288_ADR50017P087CC-SCONN2A   I178 @S9S_MB_2U_LIB.S9S_MB_2U(SCH_1):PAGE91

M_E_CPU0_SA_DQS_DN<1> @S9S_MB_2U_LIB.S9S_MB_2U(SCH_1):M_E_CPU0_SA_DQS_DN(1)
    U2 EC70 DDR4_SA_DQS_DN1 SOCKET4677_AZIF0045P001C01CS-SA   I169 @S9S_MB_2U_LIB.S9S_MB_2U(SCH_1):PAGE24
    J9   23 DQS1_A_C SCONN288_ADR50017P130CC-SCONN2A   I178 @S9S_MB_2U_LIB.S9S_MB_2U(SCH_1):PAGE90
   J10   23 DQS1_A_C SCONN288_ADR50017P087CC-SCONN2A   I178 @S9S_MB_2U_LIB.S9S_MB_2U(SCH_1):PAGE91

M_E_CPU0_SA_DQS_DN<2> @S9S_MB_2U_LIB.S9S_MB_2U(SCH_1):M_E_CPU0_SA_DQS_DN(2)
    U2 EK67 DDR4_SA_DQS_DN2 SOCKET4677_AZIF0045P001C01CS-SA   I169 @S9S_MB_2U_LIB.S9S_MB_2U(SCH_1):PAGE24
    J9   34 DQS2_A_C SCONN288_ADR50017P130CC-SCONN2A   I178 @S9S_MB_2U_LIB.S9S_MB_2U(SCH_1):PAGE90
   J10   34 DQS2_A_C SCONN288_ADR50017P087CC-SCONN2A   I178 @S9S_MB_2U_LIB.S9S_MB_2U(SCH_1):PAGE91

M_E_CPU0_SA_DQS_DN<3> @S9S_MB_2U_LIB.S9S_MB_2U(SCH_1):M_E_CPU0_SA_DQS_DN(3)
    U2 EK61 DDR4_SA_DQS_DN3 SOCKET4677_AZIF0045P001C01CS-SA   I169 @S9S_MB_2U_LIB.S9S_MB_2U(SCH_1):PAGE24
    J9   45 DQS3_A_C SCONN288_ADR50017P130CC-SCONN2A   I178 @S9S_MB_2U_LIB.S9S_MB_2U(SCH_1):PAGE90
   J10   45 DQS3_A_C SCONN288_ADR50017P087CC-SCONN2A   I178 @S9S_MB_2U_LIB.S9S_MB_2U(SCH_1):PAGE91

M_E_CPU0_SA_DQS_DN<4> @S9S_MB_2U_LIB.S9S_MB_2U(SCH_1):M_E_CPU0_SA_DQS_DN(4)
    U2 EM55 DDR4_SA_DQS_DN4 SOCKET4677_AZIF0045P001C01CS-SA   I169 @S9S_MB_2U_LIB.S9S_MB_2U(SCH_1):PAGE24
    J9   56 DQS4_A_C SCONN288_ADR50017P130CC-SCONN2A   I178 @S9S_MB_2U_LIB.S9S_MB_2U(SCH_1):PAGE90
   J10   56 DQS4_A_C SCONN288_ADR50017P087CC-SCONN2A   I178 @S9S_MB_2U_LIB.S9S_MB_2U(SCH_1):PAGE91

M_E_CPU0_SA_DQS_DN<5> @S9S_MB_2U_LIB.S9S_MB_2U(SCH_1):M_E_CPU0_SA_DQS_DN(5)
    U2 EM75 DDR4_SA_DQS_DN5 SOCKET4677_AZIF0045P001C01CS-SA   I169 @S9S_MB_2U_LIB.S9S_MB_2U(SCH_1):PAGE24
    J9  156 DQS5_A_C||TDQS5_A_C||DQS5_A_T||TDQS5_A_T SCONN288_ADR50017P130CC-SCONN2A   I178 @S9S_MB_2U_LIB.S9S_MB_2U(SCH_1):PAGE90
   J10  156 DQS5_A_C||TDQS5_A_C||DQS5_A_T||TDQS5_A_T SCONN288_ADR50017P087CC-SCONN2A   I178 @S9S_MB_2U_LIB.S9S_MB_2U(SCH_1):PAGE91

M_E_CPU0_SA_DQS_DN<6> @S9S_MB_2U_LIB.S9S_MB_2U(SCH_1):M_E_CPU0_SA_DQS_DN(6)
    U2 EJ70 DDR4_SA_DQS_DN6 SOCKET4677_AZIF0045P001C01CS-SA   I169 @S9S_MB_2U_LIB.S9S_MB_2U(SCH_1):PAGE24
    J9  167 DQS6_A_C||TDQS6_A_C||DQS6_A_T||TDQS6_A_T SCONN288_ADR50017P130CC-SCONN2A   I178 @S9S_MB_2U_LIB.S9S_MB_2U(SCH_1):PAGE90
   J10  167 DQS6_A_C||TDQS6_A_C||DQS6_A_T||TDQS6_A_T SCONN288_ADR50017P087CC-SCONN2A   I178 @S9S_MB_2U_LIB.S9S_MB_2U(SCH_1):PAGE91

M_E_CPU0_SA_DQS_DN<7> @S9S_MB_2U_LIB.S9S_MB_2U(SCH_1):M_E_CPU0_SA_DQS_DN(7)
    U2 EN68 DDR4_SA_DQS_DN7 SOCKET4677_AZIF0045P001C01CS-SA   I169 @S9S_MB_2U_LIB.S9S_MB_2U(SCH_1):PAGE24
    J9  178 DQS7_A_C||TDQS7_A_C SCONN288_ADR50017P130CC-SCONN2A   I178 @S9S_MB_2U_LIB.S9S_MB_2U(SCH_1):PAGE90
   J10  178 DQS7_A_C||TDQS7_A_C SCONN288_ADR50017P087CC-SCONN2A   I178 @S9S_MB_2U_LIB.S9S_MB_2U(SCH_1):PAGE91

M_E_CPU0_SA_DQS_DN<8> @S9S_MB_2U_LIB.S9S_MB_2U(SCH_1):M_E_CPU0_SA_DQS_DN(8)
    U2 ET61 DDR4_SA_DQS_DN8 SOCKET4677_AZIF0045P001C01CS-SA   I169 @S9S_MB_2U_LIB.S9S_MB_2U(SCH_1):PAGE24
    J9  189 DQS8_A_C||TDQS8_A_C SCONN288_ADR50017P130CC-SCONN2A   I178 @S9S_MB_2U_LIB.S9S_MB_2U(SCH_1):PAGE90
   J10  189 DQS8_A_C||TDQS8_A_C SCONN288_ADR50017P087CC-SCONN2A   I178 @S9S_MB_2U_LIB.S9S_MB_2U(SCH_1):PAGE91

M_E_CPU0_SA_DQS_DN<9> @S9S_MB_2U_LIB.S9S_MB_2U(SCH_1):M_E_CPU0_SA_DQS_DN(9)
    U2 ET55 DDR4_SA_DQS_DN9 SOCKET4677_AZIF0045P001C01CS-SA   I169 @S9S_MB_2U_LIB.S9S_MB_2U(SCH_1):PAGE24
    J9  200 DQS9_A_C||TDQS9_A_C SCONN288_ADR50017P130CC-SCONN2A   I178 @S9S_MB_2U_LIB.S9S_MB_2U(SCH_1):PAGE90
   J10  200 DQS9_A_C||TDQS9_A_C SCONN288_ADR50017P087CC-SCONN2A   I178 @S9S_MB_2U_LIB.S9S_MB_2U(SCH_1):PAGE91

M_E_CPU0_SA_DQS_DP<0> @S9S_MB_2U_LIB.S9S_MB_2U(SCH_1):M_E_CPU0_SA_DQS_DP(0)
    U2 EN76 DDR4_SA_DQS_DP0 SOCKET4677_AZIF0045P001C01CS-SA   I169 @S9S_MB_2U_LIB.S9S_MB_2U(SCH_1):PAGE24
    J9   11 DQS0_A_T SCONN288_ADR50017P130CC-SCONN2A   I178 @S9S_MB_2U_LIB.S9S_MB_2U(SCH_1):PAGE90
   J10   11 DQS0_A_T SCONN288_ADR50017P087CC-SCONN2A   I178 @S9S_MB_2U_LIB.S9S_MB_2U(SCH_1):PAGE91

M_E_CPU0_SA_DQS_DP<1> @S9S_MB_2U_LIB.S9S_MB_2U(SCH_1):M_E_CPU0_SA_DQS_DP(1)
    U2 EE70 DDR4_SA_DQS_DP1 SOCKET4677_AZIF0045P001C01CS-SA   I169 @S9S_MB_2U_LIB.S9S_MB_2U(SCH_1):PAGE24
    J9   22 DQS1_A_T SCONN288_ADR50017P130CC-SCONN2A   I178 @S9S_MB_2U_LIB.S9S_MB_2U(SCH_1):PAGE90
   J10   22 DQS1_A_T SCONN288_ADR50017P087CC-SCONN2A   I178 @S9S_MB_2U_LIB.S9S_MB_2U(SCH_1):PAGE91

M_E_CPU0_SA_DQS_DP<2> @S9S_MB_2U_LIB.S9S_MB_2U(SCH_1):M_E_CPU0_SA_DQS_DP(2)
    U2 EL68 DDR4_SA_DQS_DP2 SOCKET4677_AZIF0045P001C01CS-SA   I169 @S9S_MB_2U_LIB.S9S_MB_2U(SCH_1):PAGE24
    J9   33 DQS2_A_T SCONN288_ADR50017P130CC-SCONN2A   I178 @S9S_MB_2U_LIB.S9S_MB_2U(SCH_1):PAGE90
   J10   33 DQS2_A_T SCONN288_ADR50017P087CC-SCONN2A   I178 @S9S_MB_2U_LIB.S9S_MB_2U(SCH_1):PAGE91

M_E_CPU0_SA_DQS_DP<3> @S9S_MB_2U_LIB.S9S_MB_2U(SCH_1):M_E_CPU0_SA_DQS_DP(3)
    U2 EM61 DDR4_SA_DQS_DP3 SOCKET4677_AZIF0045P001C01CS-SA   I169 @S9S_MB_2U_LIB.S9S_MB_2U(SCH_1):PAGE24
    J9   44 DQS3_A_T SCONN288_ADR50017P130CC-SCONN2A   I178 @S9S_MB_2U_LIB.S9S_MB_2U(SCH_1):PAGE90
   J10   44 DQS3_A_T SCONN288_ADR50017P087CC-SCONN2A   I178 @S9S_MB_2U_LIB.S9S_MB_2U(SCH_1):PAGE91

M_E_CPU0_SA_DQS_DP<4> @S9S_MB_2U_LIB.S9S_MB_2U(SCH_1):M_E_CPU0_SA_DQS_DP(4)
    U2 EK55 DDR4_SA_DQS_DP4 SOCKET4677_AZIF0045P001C01CS-SA   I169 @S9S_MB_2U_LIB.S9S_MB_2U(SCH_1):PAGE24
    J9   55 DQS4_A_T SCONN288_ADR50017P130CC-SCONN2A   I178 @S9S_MB_2U_LIB.S9S_MB_2U(SCH_1):PAGE90
   J10   55 DQS4_A_T SCONN288_ADR50017P087CC-SCONN2A   I178 @S9S_MB_2U_LIB.S9S_MB_2U(SCH_1):PAGE91

M_E_CPU0_SA_DQS_DP<5> @S9S_MB_2U_LIB.S9S_MB_2U(SCH_1):M_E_CPU0_SA_DQS_DP(5)
    U2 EN74 DDR4_SA_DQS_DP5 SOCKET4677_AZIF0045P001C01CS-SA   I169 @S9S_MB_2U_LIB.S9S_MB_2U(SCH_1):PAGE24
    J9  157 DQS5_A_T||TDQS5_A_T SCONN288_ADR50017P130CC-SCONN2A   I178 @S9S_MB_2U_LIB.S9S_MB_2U(SCH_1):PAGE90
   J10  157 DQS5_A_T||TDQS5_A_T SCONN288_ADR50017P087CC-SCONN2A   I178 @S9S_MB_2U_LIB.S9S_MB_2U(SCH_1):PAGE91

M_E_CPU0_SA_DQS_DP<6> @S9S_MB_2U_LIB.S9S_MB_2U(SCH_1):M_E_CPU0_SA_DQS_DP(6)
    U2 EG70 DDR4_SA_DQS_DP6 SOCKET4677_AZIF0045P001C01CS-SA   I169 @S9S_MB_2U_LIB.S9S_MB_2U(SCH_1):PAGE24
    J9  168 DQS6_A_T||TDQS6_A_T SCONN288_ADR50017P130CC-SCONN2A   I178 @S9S_MB_2U_LIB.S9S_MB_2U(SCH_1):PAGE90
   J10  168 DQS6_A_T||TDQS6_A_T SCONN288_ADR50017P087CC-SCONN2A   I178 @S9S_MB_2U_LIB.S9S_MB_2U(SCH_1):PAGE91

M_E_CPU0_SA_DQS_DP<7> @S9S_MB_2U_LIB.S9S_MB_2U(SCH_1):M_E_CPU0_SA_DQS_DP(7)
    U2 EM67 DDR4_SA_DQS_DP7 SOCKET4677_AZIF0045P001C01CS-SA   I169 @S9S_MB_2U_LIB.S9S_MB_2U(SCH_1):PAGE24
    J9  179 DQS7_A_T||TDQS7_A_T SCONN288_ADR50017P130CC-SCONN2A   I178 @S9S_MB_2U_LIB.S9S_MB_2U(SCH_1):PAGE90
   J10  179 DQS7_A_T||TDQS7_A_T SCONN288_ADR50017P087CC-SCONN2A   I178 @S9S_MB_2U_LIB.S9S_MB_2U(SCH_1):PAGE91

M_E_CPU0_SA_DQS_DP<8> @S9S_MB_2U_LIB.S9S_MB_2U(SCH_1):M_E_CPU0_SA_DQS_DP(8)
    U2 EP61 DDR4_SA_DQS_DP8 SOCKET4677_AZIF0045P001C01CS-SA   I169 @S9S_MB_2U_LIB.S9S_MB_2U(SCH_1):PAGE24
    J9  190 DQS8_A_T||TDQS8_A_T SCONN288_ADR50017P130CC-SCONN2A   I178 @S9S_MB_2U_LIB.S9S_MB_2U(SCH_1):PAGE90
   J10  190 DQS8_A_T||TDQS8_A_T SCONN288_ADR50017P087CC-SCONN2A   I178 @S9S_MB_2U_LIB.S9S_MB_2U(SCH_1):PAGE91

M_E_CPU0_SA_DQS_DP<9> @S9S_MB_2U_LIB.S9S_MB_2U(SCH_1):M_E_CPU0_SA_DQS_DP(9)
    U2 EP55 DDR4_SA_DQS_DP9 SOCKET4677_AZIF0045P001C01CS-SA   I169 @S9S_MB_2U_LIB.S9S_MB_2U(SCH_1):PAGE24
    J9  201 DQS9_A_T||TDQS9_A_T SCONN288_ADR50017P130CC-SCONN2A   I178 @S9S_MB_2U_LIB.S9S_MB_2U(SCH_1):PAGE90
   J10  201 DQS9_A_T||TDQS9_A_T SCONN288_ADR50017P087CC-SCONN2A   I178 @S9S_MB_2U_LIB.S9S_MB_2U(SCH_1):PAGE91

M_E_CPU0_SA_PAR @S9S_MB_2U_LIB.S9S_MB_2U(SCH_1):M_E_CPU0_SA_PAR
    U2 EE43 DDR4_SA_PAR SOCKET4677_AZIF0045P001C01CS-SA   I169 @S9S_MB_2U_LIB.S9S_MB_2U(SCH_1):PAGE24
    J9   74  PAR_A SCONN288_ADR50017P130CC-SCONN2A    I12 @S9S_MB_2U_LIB.S9S_MB_2U(SCH_1):PAGE90
   J10   74  PAR_A SCONN288_ADR50017P087CC-SCONN2A    I13 @S9S_MB_2U_LIB.S9S_MB_2U(SCH_1):PAGE91

M_E_CPU0_SA_RSP<0> @S9S_MB_2U_LIB.S9S_MB_2U(SCH_1):M_E_CPU0_SA_RSP(0)
    U2 DD44 DDR4_A_RSP0 SOCKET4677_AZIF0045P001C01CS-SA   I169 @S9S_MB_2U_LIB.S9S_MB_2U(SCH_1):PAGE24
    J9   86 LBD||RSP_A_N SCONN288_ADR50017P130CC-SCONN2A    I12 @S9S_MB_2U_LIB.S9S_MB_2U(SCH_1):PAGE90

M_E_CPU0_SA_RSP<1> @S9S_MB_2U_LIB.S9S_MB_2U(SCH_1):M_E_CPU0_SA_RSP(1)
    U2 DC43 DDR4_A_RSP1 SOCKET4677_AZIF0045P001C01CS-SA   I169 @S9S_MB_2U_LIB.S9S_MB_2U(SCH_1):PAGE24
   J10   86 LBD||RSP_A_N SCONN288_ADR50017P087CC-SCONN2A    I13 @S9S_MB_2U_LIB.S9S_MB_2U(SCH_1):PAGE91

M_E_CPU0_SB_CA<0> @S9S_MB_2U_LIB.S9S_MB_2U(SCH_1):M_E_CPU0_SB_CA(0)
    U2 EG43 DDR4_SB_CA0 SOCKET4677_AZIF0045P001C01CS-SA   I169 @S9S_MB_2U_LIB.S9S_MB_2U(SCH_1):PAGE24
    J9   76  CA0_B SCONN288_ADR50017P130CC-SCONN2A    I12 @S9S_MB_2U_LIB.S9S_MB_2U(SCH_1):PAGE90
   J10   76  CA0_B SCONN288_ADR50017P087CC-SCONN2A    I13 @S9S_MB_2U_LIB.S9S_MB_2U(SCH_1):PAGE91

M_E_CPU0_SB_CA<1> @S9S_MB_2U_LIB.S9S_MB_2U(SCH_1):M_E_CPU0_SB_CA(1)
    U2 EH44 DDR4_SB_CA1 SOCKET4677_AZIF0045P001C01CS-SA   I169 @S9S_MB_2U_LIB.S9S_MB_2U(SCH_1):PAGE24
    J9  221  CA1_B SCONN288_ADR50017P130CC-SCONN2A    I12 @S9S_MB_2U_LIB.S9S_MB_2U(SCH_1):PAGE90
   J10  221  CA1_B SCONN288_ADR50017P087CC-SCONN2A    I13 @S9S_MB_2U_LIB.S9S_MB_2U(SCH_1):PAGE91

M_E_CPU0_SB_CA<2> @S9S_MB_2U_LIB.S9S_MB_2U(SCH_1):M_E_CPU0_SB_CA(2)
    U2 EM44 DDR4_SB_CA2 SOCKET4677_AZIF0045P001C01CS-SA   I169 @S9S_MB_2U_LIB.S9S_MB_2U(SCH_1):PAGE24
    J9   78  CA2_B SCONN288_ADR50017P130CC-SCONN2A    I12 @S9S_MB_2U_LIB.S9S_MB_2U(SCH_1):PAGE90
   J10   78  CA2_B SCONN288_ADR50017P087CC-SCONN2A    I13 @S9S_MB_2U_LIB.S9S_MB_2U(SCH_1):PAGE91

M_E_CPU0_SB_CA<3> @S9S_MB_2U_LIB.S9S_MB_2U(SCH_1):M_E_CPU0_SB_CA(3)
    U2 EP44 DDR4_SB_CA3 SOCKET4677_AZIF0045P001C01CS-SA   I169 @S9S_MB_2U_LIB.S9S_MB_2U(SCH_1):PAGE24
    J9  223  CA3_B SCONN288_ADR50017P130CC-SCONN2A    I12 @S9S_MB_2U_LIB.S9S_MB_2U(SCH_1):PAGE90
   J10  223  CA3_B SCONN288_ADR50017P087CC-SCONN2A    I13 @S9S_MB_2U_LIB.S9S_MB_2U(SCH_1):PAGE91

M_E_CPU0_SB_CA<4> @S9S_MB_2U_LIB.S9S_MB_2U(SCH_1):M_E_CPU0_SB_CA(4)
    U2 EL43 DDR4_SB_CA4 SOCKET4677_AZIF0045P001C01CS-SA   I169 @S9S_MB_2U_LIB.S9S_MB_2U(SCH_1):PAGE24
    J9   80  CA4_B SCONN288_ADR50017P130CC-SCONN2A    I12 @S9S_MB_2U_LIB.S9S_MB_2U(SCH_1):PAGE90
   J10   80  CA4_B SCONN288_ADR50017P087CC-SCONN2A    I13 @S9S_MB_2U_LIB.S9S_MB_2U(SCH_1):PAGE91

M_E_CPU0_SB_CA<5> @S9S_MB_2U_LIB.S9S_MB_2U(SCH_1):M_E_CPU0_SB_CA(5)
    U2 ET42 DDR4_SB_CA5 SOCKET4677_AZIF0045P001C01CS-SA   I169 @S9S_MB_2U_LIB.S9S_MB_2U(SCH_1):PAGE24
    J9  225  CA5_B SCONN288_ADR50017P130CC-SCONN2A    I12 @S9S_MB_2U_LIB.S9S_MB_2U(SCH_1):PAGE90
   J10  225  CA5_B SCONN288_ADR50017P087CC-SCONN2A    I13 @S9S_MB_2U_LIB.S9S_MB_2U(SCH_1):PAGE91

M_E_CPU0_SB_CA<6> @S9S_MB_2U_LIB.S9S_MB_2U(SCH_1):M_E_CPU0_SB_CA(6)
    U2 EK42 DDR4_SB_CA6 SOCKET4677_AZIF0045P001C01CS-SA   I169 @S9S_MB_2U_LIB.S9S_MB_2U(SCH_1):PAGE24
    J9   82  CA6_B SCONN288_ADR50017P130CC-SCONN2A    I12 @S9S_MB_2U_LIB.S9S_MB_2U(SCH_1):PAGE90
   J10   82  CA6_B SCONN288_ADR50017P087CC-SCONN2A    I13 @S9S_MB_2U_LIB.S9S_MB_2U(SCH_1):PAGE91

M_E_CPU0_SB_CB<0> @S9S_MB_2U_LIB.S9S_MB_2U(SCH_1):M_E_CPU0_SB_CB(0)
    U2 EL35 DDR4_SB_ECC0 SOCKET4677_AZIF0045P001C01CS-SA   I169 @S9S_MB_2U_LIB.S9S_MB_2U(SCH_1):PAGE24
    J9   96  CB0_B SCONN288_ADR50017P130CC-SCONN2A    I12 @S9S_MB_2U_LIB.S9S_MB_2U(SCH_1):PAGE90
   J10   96  CB0_B SCONN288_ADR50017P087CC-SCONN2A    I13 @S9S_MB_2U_LIB.S9S_MB_2U(SCH_1):PAGE91

M_E_CPU0_SB_CB<1> @S9S_MB_2U_LIB.S9S_MB_2U(SCH_1):M_E_CPU0_SB_CB(1)
    U2 EM34 DDR4_SB_ECC1 SOCKET4677_AZIF0045P001C01CS-SA   I169 @S9S_MB_2U_LIB.S9S_MB_2U(SCH_1):PAGE24
    J9   98  CB1_B SCONN288_ADR50017P130CC-SCONN2A    I12 @S9S_MB_2U_LIB.S9S_MB_2U(SCH_1):PAGE90
   J10   98  CB1_B SCONN288_ADR50017P087CC-SCONN2A    I13 @S9S_MB_2U_LIB.S9S_MB_2U(SCH_1):PAGE91

M_E_CPU0_SB_CB<2> @S9S_MB_2U_LIB.S9S_MB_2U(SCH_1):M_E_CPU0_SB_CB(2)
    U2 ER35 DDR4_SB_ECC2 SOCKET4677_AZIF0045P001C01CS-SA   I169 @S9S_MB_2U_LIB.S9S_MB_2U(SCH_1):PAGE24
    J9  241  CB2_B SCONN288_ADR50017P130CC-SCONN2A    I12 @S9S_MB_2U_LIB.S9S_MB_2U(SCH_1):PAGE90
   J10  241  CB2_B SCONN288_ADR50017P087CC-SCONN2A    I13 @S9S_MB_2U_LIB.S9S_MB_2U(SCH_1):PAGE91

M_E_CPU0_SB_CB<3> @S9S_MB_2U_LIB.S9S_MB_2U(SCH_1):M_E_CPU0_SB_CB(3)
    U2 EP34 DDR4_SB_ECC3 SOCKET4677_AZIF0045P001C01CS-SA   I169 @S9S_MB_2U_LIB.S9S_MB_2U(SCH_1):PAGE24
    J9  243  CB3_B SCONN288_ADR50017P130CC-SCONN2A    I12 @S9S_MB_2U_LIB.S9S_MB_2U(SCH_1):PAGE90
   J10  243  CB3_B SCONN288_ADR50017P087CC-SCONN2A    I13 @S9S_MB_2U_LIB.S9S_MB_2U(SCH_1):PAGE91

M_E_CPU0_SB_CB<4> @S9S_MB_2U_LIB.S9S_MB_2U(SCH_1):M_E_CPU0_SB_CB(4)
    U2 EM38 DDR4_SB_ECC4 SOCKET4677_AZIF0045P001C01CS-SA   I169 @S9S_MB_2U_LIB.S9S_MB_2U(SCH_1):PAGE24
    J9   89  CB4_B SCONN288_ADR50017P130CC-SCONN2A    I12 @S9S_MB_2U_LIB.S9S_MB_2U(SCH_1):PAGE90
   J10   89  CB4_B SCONN288_ADR50017P087CC-SCONN2A    I13 @S9S_MB_2U_LIB.S9S_MB_2U(SCH_1):PAGE91

M_E_CPU0_SB_CB<5> @S9S_MB_2U_LIB.S9S_MB_2U(SCH_1):M_E_CPU0_SB_CB(5)
    U2 EL37 DDR4_SB_ECC5 SOCKET4677_AZIF0045P001C01CS-SA   I169 @S9S_MB_2U_LIB.S9S_MB_2U(SCH_1):PAGE24
    J9   91  CB5_B SCONN288_ADR50017P130CC-SCONN2A    I12 @S9S_MB_2U_LIB.S9S_MB_2U(SCH_1):PAGE90
   J10   91  CB5_B SCONN288_ADR50017P087CC-SCONN2A    I13 @S9S_MB_2U_LIB.S9S_MB_2U(SCH_1):PAGE91

M_E_CPU0_SB_CB<6> @S9S_MB_2U_LIB.S9S_MB_2U(SCH_1):M_E_CPU0_SB_CB(6)
    U2 EP38 DDR4_SB_ECC6 SOCKET4677_AZIF0045P001C01CS-SA   I169 @S9S_MB_2U_LIB.S9S_MB_2U(SCH_1):PAGE24
    J9  234  CB6_B SCONN288_ADR50017P130CC-SCONN2A    I12 @S9S_MB_2U_LIB.S9S_MB_2U(SCH_1):PAGE90
   J10  234  CB6_B SCONN288_ADR50017P087CC-SCONN2A    I13 @S9S_MB_2U_LIB.S9S_MB_2U(SCH_1):PAGE91

M_E_CPU0_SB_CB<7> @S9S_MB_2U_LIB.S9S_MB_2U(SCH_1):M_E_CPU0_SB_CB(7)
    U2 ER37 DDR4_SB_ECC7 SOCKET4677_AZIF0045P001C01CS-SA   I169 @S9S_MB_2U_LIB.S9S_MB_2U(SCH_1):PAGE24
    J9  236  CB7_B SCONN288_ADR50017P130CC-SCONN2A    I12 @S9S_MB_2U_LIB.S9S_MB_2U(SCH_1):PAGE90
   J10  236  CB7_B SCONN288_ADR50017P087CC-SCONN2A    I13 @S9S_MB_2U_LIB.S9S_MB_2U(SCH_1):PAGE91

M_E_CPU0_SB_CS_N<0> @S9S_MB_2U_LIB.S9S_MB_2U(SCH_1):M_E_CPU0_SB_CS_N(0)
    U2 EP40 DDR4_SB_CS_N0 SOCKET4677_AZIF0045P001C01CS-SA   I169 @S9S_MB_2U_LIB.S9S_MB_2U(SCH_1):PAGE24
    J9   84 CS0_B_N SCONN288_ADR50017P130CC-SCONN2A    I12 @S9S_MB_2U_LIB.S9S_MB_2U(SCH_1):PAGE90

M_E_CPU0_SB_CS_N<1> @S9S_MB_2U_LIB.S9S_MB_2U(SCH_1):M_E_CPU0_SB_CS_N(1)
    U2 ET40 DDR4_SB_CS_N1 SOCKET4677_AZIF0045P001C01CS-SA   I169 @S9S_MB_2U_LIB.S9S_MB_2U(SCH_1):PAGE24
    J9  229 CS1_B_N SCONN288_ADR50017P130CC-SCONN2A    I12 @S9S_MB_2U_LIB.S9S_MB_2U(SCH_1):PAGE90

M_E_CPU0_SB_CS_N<2> @S9S_MB_2U_LIB.S9S_MB_2U(SCH_1):M_E_CPU0_SB_CS_N(2)
    U2 EM40 DDR4_SB_CS_N2 SOCKET4677_AZIF0045P001C01CS-SA   I169 @S9S_MB_2U_LIB.S9S_MB_2U(SCH_1):PAGE24
   J10   84 CS0_B_N SCONN288_ADR50017P087CC-SCONN2A    I13 @S9S_MB_2U_LIB.S9S_MB_2U(SCH_1):PAGE91

M_E_CPU0_SB_CS_N<3> @S9S_MB_2U_LIB.S9S_MB_2U(SCH_1):M_E_CPU0_SB_CS_N(3)
    U2 EL41 DDR4_SB_CS_N3 SOCKET4677_AZIF0045P001C01CS-SA   I169 @S9S_MB_2U_LIB.S9S_MB_2U(SCH_1):PAGE24
   J10  229 CS1_B_N SCONN288_ADR50017P087CC-SCONN2A    I13 @S9S_MB_2U_LIB.S9S_MB_2U(SCH_1):PAGE91

M_E_CPU0_SB_DQ<0> @S9S_MB_2U_LIB.S9S_MB_2U(SCH_1):M_E_CPU0_SB_DQ(0)
    U2 EE29 DDR4_SB_DQ0 SOCKET4677_AZIF0045P001C01CS-SA   I169 @S9S_MB_2U_LIB.S9S_MB_2U(SCH_1):PAGE24
    J9  100  DQ0_B SCONN288_ADR50017P130CC-SCONN2A    I12 @S9S_MB_2U_LIB.S9S_MB_2U(SCH_1):PAGE90
   J10  100  DQ0_B SCONN288_ADR50017P087CC-SCONN2A    I13 @S9S_MB_2U_LIB.S9S_MB_2U(SCH_1):PAGE91

M_E_CPU0_SB_DQ<10> @S9S_MB_2U_LIB.S9S_MB_2U(SCH_1):M_E_CPU0_SB_DQ(10)
    U2 EP32 DDR4_SB_DQ10 SOCKET4677_AZIF0045P001C01CS-SA   I169 @S9S_MB_2U_LIB.S9S_MB_2U(SCH_1):PAGE24
    J9  256 DQ10_B SCONN288_ADR50017P130CC-SCONN2A    I12 @S9S_MB_2U_LIB.S9S_MB_2U(SCH_1):PAGE90
   J10  256 DQ10_B SCONN288_ADR50017P087CC-SCONN2A    I13 @S9S_MB_2U_LIB.S9S_MB_2U(SCH_1):PAGE91

M_E_CPU0_SB_DQ<11> @S9S_MB_2U_LIB.S9S_MB_2U(SCH_1):M_E_CPU0_SB_DQ(11)
    U2 ER31 DDR4_SB_DQ11 SOCKET4677_AZIF0045P001C01CS-SA   I169 @S9S_MB_2U_LIB.S9S_MB_2U(SCH_1):PAGE24
    J9  258 DQ11_B SCONN288_ADR50017P130CC-SCONN2A    I12 @S9S_MB_2U_LIB.S9S_MB_2U(SCH_1):PAGE90
   J10  258 DQ11_B SCONN288_ADR50017P087CC-SCONN2A    I13 @S9S_MB_2U_LIB.S9S_MB_2U(SCH_1):PAGE91

M_E_CPU0_SB_DQ<12> @S9S_MB_2U_LIB.S9S_MB_2U(SCH_1):M_E_CPU0_SB_DQ(12)
    U2 EL29 DDR4_SB_DQ12 SOCKET4677_AZIF0045P001C01CS-SA   I169 @S9S_MB_2U_LIB.S9S_MB_2U(SCH_1):PAGE24
    J9  118 DQ12_B SCONN288_ADR50017P130CC-SCONN2A    I12 @S9S_MB_2U_LIB.S9S_MB_2U(SCH_1):PAGE90
   J10  118 DQ12_B SCONN288_ADR50017P087CC-SCONN2A    I13 @S9S_MB_2U_LIB.S9S_MB_2U(SCH_1):PAGE91

M_E_CPU0_SB_DQ<13> @S9S_MB_2U_LIB.S9S_MB_2U(SCH_1):M_E_CPU0_SB_DQ(13)
    U2 EM28 DDR4_SB_DQ13 SOCKET4677_AZIF0045P001C01CS-SA   I169 @S9S_MB_2U_LIB.S9S_MB_2U(SCH_1):PAGE24
    J9  120 DQ13_B SCONN288_ADR50017P130CC-SCONN2A    I12 @S9S_MB_2U_LIB.S9S_MB_2U(SCH_1):PAGE90
   J10  120 DQ13_B SCONN288_ADR50017P087CC-SCONN2A    I13 @S9S_MB_2U_LIB.S9S_MB_2U(SCH_1):PAGE91

M_E_CPU0_SB_DQ<14> @S9S_MB_2U_LIB.S9S_MB_2U(SCH_1):M_E_CPU0_SB_DQ(14)
    U2 ER29 DDR4_SB_DQ14 SOCKET4677_AZIF0045P001C01CS-SA   I169 @S9S_MB_2U_LIB.S9S_MB_2U(SCH_1):PAGE24
    J9  263 DQ14_B SCONN288_ADR50017P130CC-SCONN2A    I12 @S9S_MB_2U_LIB.S9S_MB_2U(SCH_1):PAGE90
   J10  263 DQ14_B SCONN288_ADR50017P087CC-SCONN2A    I13 @S9S_MB_2U_LIB.S9S_MB_2U(SCH_1):PAGE91

M_E_CPU0_SB_DQ<15> @S9S_MB_2U_LIB.S9S_MB_2U(SCH_1):M_E_CPU0_SB_DQ(15)
    U2 EP28 DDR4_SB_DQ15 SOCKET4677_AZIF0045P001C01CS-SA   I169 @S9S_MB_2U_LIB.S9S_MB_2U(SCH_1):PAGE24
    J9  265 DQ15_B SCONN288_ADR50017P130CC-SCONN2A    I12 @S9S_MB_2U_LIB.S9S_MB_2U(SCH_1):PAGE90
   J10  265 DQ15_B SCONN288_ADR50017P087CC-SCONN2A    I13 @S9S_MB_2U_LIB.S9S_MB_2U(SCH_1):PAGE91

M_E_CPU0_SB_DQ<16> @S9S_MB_2U_LIB.S9S_MB_2U(SCH_1):M_E_CPU0_SB_DQ(16)
    U2 EM26 DDR4_SB_DQ16 SOCKET4677_AZIF0045P001C01CS-SA   I169 @S9S_MB_2U_LIB.S9S_MB_2U(SCH_1):PAGE24
    J9  122 DQ16_B SCONN288_ADR50017P130CC-SCONN2A    I12 @S9S_MB_2U_LIB.S9S_MB_2U(SCH_1):PAGE90
   J10  122 DQ16_B SCONN288_ADR50017P087CC-SCONN2A    I13 @S9S_MB_2U_LIB.S9S_MB_2U(SCH_1):PAGE91

M_E_CPU0_SB_DQ<17> @S9S_MB_2U_LIB.S9S_MB_2U(SCH_1):M_E_CPU0_SB_DQ(17)
    U2 EL25 DDR4_SB_DQ17 SOCKET4677_AZIF0045P001C01CS-SA   I169 @S9S_MB_2U_LIB.S9S_MB_2U(SCH_1):PAGE24
    J9  124 DQ17_B SCONN288_ADR50017P130CC-SCONN2A    I12 @S9S_MB_2U_LIB.S9S_MB_2U(SCH_1):PAGE90
   J10  124 DQ17_B SCONN288_ADR50017P087CC-SCONN2A    I13 @S9S_MB_2U_LIB.S9S_MB_2U(SCH_1):PAGE91

M_E_CPU0_SB_DQ<18> @S9S_MB_2U_LIB.S9S_MB_2U(SCH_1):M_E_CPU0_SB_DQ(18)
    U2 EP26 DDR4_SB_DQ18 SOCKET4677_AZIF0045P001C01CS-SA   I169 @S9S_MB_2U_LIB.S9S_MB_2U(SCH_1):PAGE24
    J9  267 DQ18_B SCONN288_ADR50017P130CC-SCONN2A    I12 @S9S_MB_2U_LIB.S9S_MB_2U(SCH_1):PAGE90
   J10  267 DQ18_B SCONN288_ADR50017P087CC-SCONN2A    I13 @S9S_MB_2U_LIB.S9S_MB_2U(SCH_1):PAGE91

M_E_CPU0_SB_DQ<19> @S9S_MB_2U_LIB.S9S_MB_2U(SCH_1):M_E_CPU0_SB_DQ(19)
    U2 ER25 DDR4_SB_DQ19 SOCKET4677_AZIF0045P001C01CS-SA   I169 @S9S_MB_2U_LIB.S9S_MB_2U(SCH_1):PAGE24
    J9  269 DQ19_B SCONN288_ADR50017P130CC-SCONN2A    I12 @S9S_MB_2U_LIB.S9S_MB_2U(SCH_1):PAGE90
   J10  269 DQ19_B SCONN288_ADR50017P087CC-SCONN2A    I13 @S9S_MB_2U_LIB.S9S_MB_2U(SCH_1):PAGE91

M_E_CPU0_SB_DQ<1> @S9S_MB_2U_LIB.S9S_MB_2U(SCH_1):M_E_CPU0_SB_DQ(1)
    U2 ED28 DDR4_SB_DQ1 SOCKET4677_AZIF0045P001C01CS-SA   I169 @S9S_MB_2U_LIB.S9S_MB_2U(SCH_1):PAGE24
    J9  102  DQ1_B SCONN288_ADR50017P130CC-SCONN2A    I12 @S9S_MB_2U_LIB.S9S_MB_2U(SCH_1):PAGE90
   J10  102  DQ1_B SCONN288_ADR50017P087CC-SCONN2A    I13 @S9S_MB_2U_LIB.S9S_MB_2U(SCH_1):PAGE91

M_E_CPU0_SB_DQ<20> @S9S_MB_2U_LIB.S9S_MB_2U(SCH_1):M_E_CPU0_SB_DQ(20)
    U2 EL23 DDR4_SB_DQ20 SOCKET4677_AZIF0045P001C01CS-SA   I169 @S9S_MB_2U_LIB.S9S_MB_2U(SCH_1):PAGE24
    J9  129 DQ20_B SCONN288_ADR50017P130CC-SCONN2A    I12 @S9S_MB_2U_LIB.S9S_MB_2U(SCH_1):PAGE90
   J10  129 DQ20_B SCONN288_ADR50017P087CC-SCONN2A    I13 @S9S_MB_2U_LIB.S9S_MB_2U(SCH_1):PAGE91

M_E_CPU0_SB_DQ<21> @S9S_MB_2U_LIB.S9S_MB_2U(SCH_1):M_E_CPU0_SB_DQ(21)
    U2 EM22 DDR4_SB_DQ21 SOCKET4677_AZIF0045P001C01CS-SA   I169 @S9S_MB_2U_LIB.S9S_MB_2U(SCH_1):PAGE24
    J9  131 DQ21_B SCONN288_ADR50017P130CC-SCONN2A    I12 @S9S_MB_2U_LIB.S9S_MB_2U(SCH_1):PAGE90
   J10  131 DQ21_B SCONN288_ADR50017P087CC-SCONN2A    I13 @S9S_MB_2U_LIB.S9S_MB_2U(SCH_1):PAGE91

M_E_CPU0_SB_DQ<22> @S9S_MB_2U_LIB.S9S_MB_2U(SCH_1):M_E_CPU0_SB_DQ(22)
    U2 ER23 DDR4_SB_DQ22 SOCKET4677_AZIF0045P001C01CS-SA   I169 @S9S_MB_2U_LIB.S9S_MB_2U(SCH_1):PAGE24
    J9  274 DQ22_B SCONN288_ADR50017P130CC-SCONN2A    I12 @S9S_MB_2U_LIB.S9S_MB_2U(SCH_1):PAGE90
   J10  274 DQ22_B SCONN288_ADR50017P087CC-SCONN2A    I13 @S9S_MB_2U_LIB.S9S_MB_2U(SCH_1):PAGE91

M_E_CPU0_SB_DQ<23> @S9S_MB_2U_LIB.S9S_MB_2U(SCH_1):M_E_CPU0_SB_DQ(23)
    U2 EP22 DDR4_SB_DQ23 SOCKET4677_AZIF0045P001C01CS-SA   I169 @S9S_MB_2U_LIB.S9S_MB_2U(SCH_1):PAGE24
    J9  276 DQ23_B SCONN288_ADR50017P130CC-SCONN2A    I12 @S9S_MB_2U_LIB.S9S_MB_2U(SCH_1):PAGE90
   J10  276 DQ23_B SCONN288_ADR50017P087CC-SCONN2A    I13 @S9S_MB_2U_LIB.S9S_MB_2U(SCH_1):PAGE91

M_E_CPU0_SB_DQ<24> @S9S_MB_2U_LIB.S9S_MB_2U(SCH_1):M_E_CPU0_SB_DQ(24)
    U2 EM20 DDR4_SB_DQ24 SOCKET4677_AZIF0045P001C01CS-SA   I169 @S9S_MB_2U_LIB.S9S_MB_2U(SCH_1):PAGE24
    J9  133 DQ24_B SCONN288_ADR50017P130CC-SCONN2A    I12 @S9S_MB_2U_LIB.S9S_MB_2U(SCH_1):PAGE90
   J10  133 DQ24_B SCONN288_ADR50017P087CC-SCONN2A    I13 @S9S_MB_2U_LIB.S9S_MB_2U(SCH_1):PAGE91

M_E_CPU0_SB_DQ<25> @S9S_MB_2U_LIB.S9S_MB_2U(SCH_1):M_E_CPU0_SB_DQ(25)
    U2 EL19 DDR4_SB_DQ25 SOCKET4677_AZIF0045P001C01CS-SA   I169 @S9S_MB_2U_LIB.S9S_MB_2U(SCH_1):PAGE24
    J9  135 DQ25_B SCONN288_ADR50017P130CC-SCONN2A    I12 @S9S_MB_2U_LIB.S9S_MB_2U(SCH_1):PAGE90
   J10  135 DQ25_B SCONN288_ADR50017P087CC-SCONN2A    I13 @S9S_MB_2U_LIB.S9S_MB_2U(SCH_1):PAGE91

M_E_CPU0_SB_DQ<26> @S9S_MB_2U_LIB.S9S_MB_2U(SCH_1):M_E_CPU0_SB_DQ(26)
    U2 EP20 DDR4_SB_DQ26 SOCKET4677_AZIF0045P001C01CS-SA   I169 @S9S_MB_2U_LIB.S9S_MB_2U(SCH_1):PAGE24
    J9  278 DQ26_B SCONN288_ADR50017P130CC-SCONN2A    I12 @S9S_MB_2U_LIB.S9S_MB_2U(SCH_1):PAGE90
   J10  278 DQ26_B SCONN288_ADR50017P087CC-SCONN2A    I13 @S9S_MB_2U_LIB.S9S_MB_2U(SCH_1):PAGE91

M_E_CPU0_SB_DQ<27> @S9S_MB_2U_LIB.S9S_MB_2U(SCH_1):M_E_CPU0_SB_DQ(27)
    U2 ER19 DDR4_SB_DQ27 SOCKET4677_AZIF0045P001C01CS-SA   I169 @S9S_MB_2U_LIB.S9S_MB_2U(SCH_1):PAGE24
    J9  280 DQ27_B SCONN288_ADR50017P130CC-SCONN2A    I12 @S9S_MB_2U_LIB.S9S_MB_2U(SCH_1):PAGE90
   J10  280 DQ27_B SCONN288_ADR50017P087CC-SCONN2A    I13 @S9S_MB_2U_LIB.S9S_MB_2U(SCH_1):PAGE91

M_E_CPU0_SB_DQ<28> @S9S_MB_2U_LIB.S9S_MB_2U(SCH_1):M_E_CPU0_SB_DQ(28)
    U2 EL17 DDR4_SB_DQ28 SOCKET4677_AZIF0045P001C01CS-SA   I169 @S9S_MB_2U_LIB.S9S_MB_2U(SCH_1):PAGE24
    J9  140 DQ28_B SCONN288_ADR50017P130CC-SCONN2A    I12 @S9S_MB_2U_LIB.S9S_MB_2U(SCH_1):PAGE90
   J10  140 DQ28_B SCONN288_ADR50017P087CC-SCONN2A    I13 @S9S_MB_2U_LIB.S9S_MB_2U(SCH_1):PAGE91

M_E_CPU0_SB_DQ<29> @S9S_MB_2U_LIB.S9S_MB_2U(SCH_1):M_E_CPU0_SB_DQ(29)
    U2 EM16 DDR4_SB_DQ29 SOCKET4677_AZIF0045P001C01CS-SA   I169 @S9S_MB_2U_LIB.S9S_MB_2U(SCH_1):PAGE24
    J9  142 DQ29_B SCONN288_ADR50017P130CC-SCONN2A    I12 @S9S_MB_2U_LIB.S9S_MB_2U(SCH_1):PAGE90
   J10  142 DQ29_B SCONN288_ADR50017P087CC-SCONN2A    I13 @S9S_MB_2U_LIB.S9S_MB_2U(SCH_1):PAGE91

M_E_CPU0_SB_DQ<2> @S9S_MB_2U_LIB.S9S_MB_2U(SCH_1):M_E_CPU0_SB_DQ(2)
    U2 EG29 DDR4_SB_DQ2 SOCKET4677_AZIF0045P001C01CS-SA   I169 @S9S_MB_2U_LIB.S9S_MB_2U(SCH_1):PAGE24
    J9  245  DQ2_B SCONN288_ADR50017P130CC-SCONN2A    I12 @S9S_MB_2U_LIB.S9S_MB_2U(SCH_1):PAGE90
   J10  245  DQ2_B SCONN288_ADR50017P087CC-SCONN2A    I13 @S9S_MB_2U_LIB.S9S_MB_2U(SCH_1):PAGE91

M_E_CPU0_SB_DQ<30> @S9S_MB_2U_LIB.S9S_MB_2U(SCH_1):M_E_CPU0_SB_DQ(30)
    U2 ER17 DDR4_SB_DQ30 SOCKET4677_AZIF0045P001C01CS-SA   I169 @S9S_MB_2U_LIB.S9S_MB_2U(SCH_1):PAGE24
    J9  285 DQ30_B SCONN288_ADR50017P130CC-SCONN2A    I12 @S9S_MB_2U_LIB.S9S_MB_2U(SCH_1):PAGE90
   J10  285 DQ30_B SCONN288_ADR50017P087CC-SCONN2A    I13 @S9S_MB_2U_LIB.S9S_MB_2U(SCH_1):PAGE91

M_E_CPU0_SB_DQ<31> @S9S_MB_2U_LIB.S9S_MB_2U(SCH_1):M_E_CPU0_SB_DQ(31)
    U2 EP16 DDR4_SB_DQ31 SOCKET4677_AZIF0045P001C01CS-SA   I169 @S9S_MB_2U_LIB.S9S_MB_2U(SCH_1):PAGE24
    J9  287 DQ31_B SCONN288_ADR50017P130CC-SCONN2A    I12 @S9S_MB_2U_LIB.S9S_MB_2U(SCH_1):PAGE90
   J10  287 DQ31_B SCONN288_ADR50017P087CC-SCONN2A    I13 @S9S_MB_2U_LIB.S9S_MB_2U(SCH_1):PAGE91

M_E_CPU0_SB_DQ<3> @S9S_MB_2U_LIB.S9S_MB_2U(SCH_1):M_E_CPU0_SB_DQ(3)
    U2 EH28 DDR4_SB_DQ3 SOCKET4677_AZIF0045P001C01CS-SA   I169 @S9S_MB_2U_LIB.S9S_MB_2U(SCH_1):PAGE24
    J9  247  DQ3_B SCONN288_ADR50017P130CC-SCONN2A    I12 @S9S_MB_2U_LIB.S9S_MB_2U(SCH_1):PAGE90
   J10  247  DQ3_B SCONN288_ADR50017P087CC-SCONN2A    I13 @S9S_MB_2U_LIB.S9S_MB_2U(SCH_1):PAGE91

M_E_CPU0_SB_DQ<4> @S9S_MB_2U_LIB.S9S_MB_2U(SCH_1):M_E_CPU0_SB_DQ(4)
    U2 ED26 DDR4_SB_DQ4 SOCKET4677_AZIF0045P001C01CS-SA   I169 @S9S_MB_2U_LIB.S9S_MB_2U(SCH_1):PAGE24
    J9  107  DQ4_B SCONN288_ADR50017P130CC-SCONN2A    I12 @S9S_MB_2U_LIB.S9S_MB_2U(SCH_1):PAGE90
   J10  107  DQ4_B SCONN288_ADR50017P087CC-SCONN2A    I13 @S9S_MB_2U_LIB.S9S_MB_2U(SCH_1):PAGE91

M_E_CPU0_SB_DQ<5> @S9S_MB_2U_LIB.S9S_MB_2U(SCH_1):M_E_CPU0_SB_DQ(5)
    U2 EE25 DDR4_SB_DQ5 SOCKET4677_AZIF0045P001C01CS-SA   I169 @S9S_MB_2U_LIB.S9S_MB_2U(SCH_1):PAGE24
    J9  109  DQ5_B SCONN288_ADR50017P130CC-SCONN2A    I12 @S9S_MB_2U_LIB.S9S_MB_2U(SCH_1):PAGE90
   J10  109  DQ5_B SCONN288_ADR50017P087CC-SCONN2A    I13 @S9S_MB_2U_LIB.S9S_MB_2U(SCH_1):PAGE91

M_E_CPU0_SB_DQ<6> @S9S_MB_2U_LIB.S9S_MB_2U(SCH_1):M_E_CPU0_SB_DQ(6)
    U2 EH26 DDR4_SB_DQ6 SOCKET4677_AZIF0045P001C01CS-SA   I169 @S9S_MB_2U_LIB.S9S_MB_2U(SCH_1):PAGE24
    J9  252  DQ6_B SCONN288_ADR50017P130CC-SCONN2A    I12 @S9S_MB_2U_LIB.S9S_MB_2U(SCH_1):PAGE90
   J10  252  DQ6_B SCONN288_ADR50017P087CC-SCONN2A    I13 @S9S_MB_2U_LIB.S9S_MB_2U(SCH_1):PAGE91

M_E_CPU0_SB_DQ<7> @S9S_MB_2U_LIB.S9S_MB_2U(SCH_1):M_E_CPU0_SB_DQ(7)
    U2 EG25 DDR4_SB_DQ7 SOCKET4677_AZIF0045P001C01CS-SA   I169 @S9S_MB_2U_LIB.S9S_MB_2U(SCH_1):PAGE24
    J9  254  DQ7_B SCONN288_ADR50017P130CC-SCONN2A    I12 @S9S_MB_2U_LIB.S9S_MB_2U(SCH_1):PAGE90
   J10  254  DQ7_B SCONN288_ADR50017P087CC-SCONN2A    I13 @S9S_MB_2U_LIB.S9S_MB_2U(SCH_1):PAGE91

M_E_CPU0_SB_DQ<8> @S9S_MB_2U_LIB.S9S_MB_2U(SCH_1):M_E_CPU0_SB_DQ(8)
    U2 EM32 DDR4_SB_DQ8 SOCKET4677_AZIF0045P001C01CS-SA   I169 @S9S_MB_2U_LIB.S9S_MB_2U(SCH_1):PAGE24
    J9  111  DQ8_B SCONN288_ADR50017P130CC-SCONN2A    I12 @S9S_MB_2U_LIB.S9S_MB_2U(SCH_1):PAGE90
   J10  111  DQ8_B SCONN288_ADR50017P087CC-SCONN2A    I13 @S9S_MB_2U_LIB.S9S_MB_2U(SCH_1):PAGE91

M_E_CPU0_SB_DQ<9> @S9S_MB_2U_LIB.S9S_MB_2U(SCH_1):M_E_CPU0_SB_DQ(9)
    U2 EL31 DDR4_SB_DQ9 SOCKET4677_AZIF0045P001C01CS-SA   I169 @S9S_MB_2U_LIB.S9S_MB_2U(SCH_1):PAGE24
    J9  113  DQ9_B SCONN288_ADR50017P130CC-SCONN2A    I12 @S9S_MB_2U_LIB.S9S_MB_2U(SCH_1):PAGE90
   J10  113  DQ9_B SCONN288_ADR50017P087CC-SCONN2A    I13 @S9S_MB_2U_LIB.S9S_MB_2U(SCH_1):PAGE91

M_E_CPU0_SB_DQS_DN<0> @S9S_MB_2U_LIB.S9S_MB_2U(SCH_1):M_E_CPU0_SB_DQS_DN(0)
    U2 EE27 DDR4_SB_DQS_DN0 SOCKET4677_AZIF0045P001C01CS-SA   I169 @S9S_MB_2U_LIB.S9S_MB_2U(SCH_1):PAGE24
    J9  105 DQS0_B_C SCONN288_ADR50017P130CC-SCONN2A   I178 @S9S_MB_2U_LIB.S9S_MB_2U(SCH_1):PAGE90
   J10  105 DQS0_B_C SCONN288_ADR50017P087CC-SCONN2A   I178 @S9S_MB_2U_LIB.S9S_MB_2U(SCH_1):PAGE91

M_E_CPU0_SB_DQS_DN<1> @S9S_MB_2U_LIB.S9S_MB_2U(SCH_1):M_E_CPU0_SB_DQS_DN(1)
    U2 EK30 DDR4_SB_DQS_DN1 SOCKET4677_AZIF0045P001C01CS-SA   I169 @S9S_MB_2U_LIB.S9S_MB_2U(SCH_1):PAGE24
    J9  116 DQS1_B_C SCONN288_ADR50017P130CC-SCONN2A   I178 @S9S_MB_2U_LIB.S9S_MB_2U(SCH_1):PAGE90
   J10  116 DQS1_B_C SCONN288_ADR50017P087CC-SCONN2A   I178 @S9S_MB_2U_LIB.S9S_MB_2U(SCH_1):PAGE91

M_E_CPU0_SB_DQS_DN<2> @S9S_MB_2U_LIB.S9S_MB_2U(SCH_1):M_E_CPU0_SB_DQS_DN(2)
    U2 EK24 DDR4_SB_DQS_DN2 SOCKET4677_AZIF0045P001C01CS-SA   I169 @S9S_MB_2U_LIB.S9S_MB_2U(SCH_1):PAGE24
    J9  127 DQS2_B_C SCONN288_ADR50017P130CC-SCONN2A   I178 @S9S_MB_2U_LIB.S9S_MB_2U(SCH_1):PAGE90
   J10  127 DQS2_B_C SCONN288_ADR50017P087CC-SCONN2A   I178 @S9S_MB_2U_LIB.S9S_MB_2U(SCH_1):PAGE91

M_E_CPU0_SB_DQS_DN<3> @S9S_MB_2U_LIB.S9S_MB_2U(SCH_1):M_E_CPU0_SB_DQS_DN(3)
    U2 EK18 DDR4_SB_DQS_DN3 SOCKET4677_AZIF0045P001C01CS-SA   I169 @S9S_MB_2U_LIB.S9S_MB_2U(SCH_1):PAGE24
    J9  138 DQS3_B_C SCONN288_ADR50017P130CC-SCONN2A   I178 @S9S_MB_2U_LIB.S9S_MB_2U(SCH_1):PAGE90
   J10  138 DQS3_B_C SCONN288_ADR50017P087CC-SCONN2A   I178 @S9S_MB_2U_LIB.S9S_MB_2U(SCH_1):PAGE91

M_E_CPU0_SB_DQS_DN<4> @S9S_MB_2U_LIB.S9S_MB_2U(SCH_1):M_E_CPU0_SB_DQS_DN(4)
    U2 ET36 DDR4_SB_DQS_DN4 SOCKET4677_AZIF0045P001C01CS-SA   I169 @S9S_MB_2U_LIB.S9S_MB_2U(SCH_1):PAGE24
    J9  238 DQS4_B_C SCONN288_ADR50017P130CC-SCONN2A   I178 @S9S_MB_2U_LIB.S9S_MB_2U(SCH_1):PAGE90
   J10  238 DQS4_B_C SCONN288_ADR50017P087CC-SCONN2A   I178 @S9S_MB_2U_LIB.S9S_MB_2U(SCH_1):PAGE91

M_E_CPU0_SB_DQS_DN<5> @S9S_MB_2U_LIB.S9S_MB_2U(SCH_1):M_E_CPU0_SB_DQS_DN(5)
    U2 EJ27 DDR4_SB_DQS_DN5 SOCKET4677_AZIF0045P001C01CS-SA   I169 @S9S_MB_2U_LIB.S9S_MB_2U(SCH_1):PAGE24
    J9  249 DQS5_B_C||TDQS5_B_C SCONN288_ADR50017P130CC-SCONN2A   I178 @S9S_MB_2U_LIB.S9S_MB_2U(SCH_1):PAGE90
   J10  249 DQS5_B_C||TDQS5_B_C SCONN288_ADR50017P087CC-SCONN2A   I178 @S9S_MB_2U_LIB.S9S_MB_2U(SCH_1):PAGE91

M_E_CPU0_SB_DQS_DN<6> @S9S_MB_2U_LIB.S9S_MB_2U(SCH_1):M_E_CPU0_SB_DQS_DN(6)
    U2 ET30 DDR4_SB_DQS_DN6 SOCKET4677_AZIF0045P001C01CS-SA   I169 @S9S_MB_2U_LIB.S9S_MB_2U(SCH_1):PAGE24
    J9  260 DQS6_B_C||TDQS6_B_C SCONN288_ADR50017P130CC-SCONN2A   I178 @S9S_MB_2U_LIB.S9S_MB_2U(SCH_1):PAGE90
   J10  260 DQS6_B_C||TDQS6_B_C SCONN288_ADR50017P087CC-SCONN2A   I178 @S9S_MB_2U_LIB.S9S_MB_2U(SCH_1):PAGE91

M_E_CPU0_SB_DQS_DN<7> @S9S_MB_2U_LIB.S9S_MB_2U(SCH_1):M_E_CPU0_SB_DQS_DN(7)
    U2 ET24 DDR4_SB_DQS_DN7 SOCKET4677_AZIF0045P001C01CS-SA   I169 @S9S_MB_2U_LIB.S9S_MB_2U(SCH_1):PAGE24
    J9  271 DQS7_B_C||TDQS7_B_C SCONN288_ADR50017P130CC-SCONN2A   I178 @S9S_MB_2U_LIB.S9S_MB_2U(SCH_1):PAGE90
   J10  271 DQS7_B_C||TDQS7_B_C SCONN288_ADR50017P087CC-SCONN2A   I178 @S9S_MB_2U_LIB.S9S_MB_2U(SCH_1):PAGE91

M_E_CPU0_SB_DQS_DN<8> @S9S_MB_2U_LIB.S9S_MB_2U(SCH_1):M_E_CPU0_SB_DQS_DN(8)
    U2 ET18 DDR4_SB_DQS_DN8 SOCKET4677_AZIF0045P001C01CS-SA   I169 @S9S_MB_2U_LIB.S9S_MB_2U(SCH_1):PAGE24
    J9  282 DQS8_B_C||TDQS8_B_C SCONN288_ADR50017P130CC-SCONN2A   I178 @S9S_MB_2U_LIB.S9S_MB_2U(SCH_1):PAGE90
   J10  282 DQS8_B_C||TDQS8_B_C SCONN288_ADR50017P087CC-SCONN2A   I178 @S9S_MB_2U_LIB.S9S_MB_2U(SCH_1):PAGE91

M_E_CPU0_SB_DQS_DN<9> @S9S_MB_2U_LIB.S9S_MB_2U(SCH_1):M_E_CPU0_SB_DQS_DN(9)
    U2 EK36 DDR4_SB_DQS_DN9 SOCKET4677_AZIF0045P001C01CS-SA   I169 @S9S_MB_2U_LIB.S9S_MB_2U(SCH_1):PAGE24
    J9   94 DQS9_B_C||TDQS9_B_C SCONN288_ADR50017P130CC-SCONN2A   I178 @S9S_MB_2U_LIB.S9S_MB_2U(SCH_1):PAGE90
   J10   94 DQS9_B_C||TDQS9_B_C SCONN288_ADR50017P087CC-SCONN2A   I178 @S9S_MB_2U_LIB.S9S_MB_2U(SCH_1):PAGE91

M_E_CPU0_SB_DQS_DP<0> @S9S_MB_2U_LIB.S9S_MB_2U(SCH_1):M_E_CPU0_SB_DQS_DP(0)
    U2 EC27 DDR4_SB_DQS_DP0 SOCKET4677_AZIF0045P001C01CS-SA   I169 @S9S_MB_2U_LIB.S9S_MB_2U(SCH_1):PAGE24
    J9  104 DQS0_B_T SCONN288_ADR50017P130CC-SCONN2A   I178 @S9S_MB_2U_LIB.S9S_MB_2U(SCH_1):PAGE90
   J10  104 DQS0_B_T SCONN288_ADR50017P087CC-SCONN2A   I178 @S9S_MB_2U_LIB.S9S_MB_2U(SCH_1):PAGE91

M_E_CPU0_SB_DQS_DP<1> @S9S_MB_2U_LIB.S9S_MB_2U(SCH_1):M_E_CPU0_SB_DQS_DP(1)
    U2 EM30 DDR4_SB_DQS_DP1 SOCKET4677_AZIF0045P001C01CS-SA   I169 @S9S_MB_2U_LIB.S9S_MB_2U(SCH_1):PAGE24
    J9  115 DQS1_B_T SCONN288_ADR50017P130CC-SCONN2A   I178 @S9S_MB_2U_LIB.S9S_MB_2U(SCH_1):PAGE90
   J10  115 DQS1_B_T SCONN288_ADR50017P087CC-SCONN2A   I178 @S9S_MB_2U_LIB.S9S_MB_2U(SCH_1):PAGE91

M_E_CPU0_SB_DQS_DP<2> @S9S_MB_2U_LIB.S9S_MB_2U(SCH_1):M_E_CPU0_SB_DQS_DP(2)
    U2 EM24 DDR4_SB_DQS_DP2 SOCKET4677_AZIF0045P001C01CS-SA   I169 @S9S_MB_2U_LIB.S9S_MB_2U(SCH_1):PAGE24
    J9  126 DQS2_B_T SCONN288_ADR50017P130CC-SCONN2A   I178 @S9S_MB_2U_LIB.S9S_MB_2U(SCH_1):PAGE90
   J10  126 DQS2_B_T SCONN288_ADR50017P087CC-SCONN2A   I178 @S9S_MB_2U_LIB.S9S_MB_2U(SCH_1):PAGE91

M_E_CPU0_SB_DQS_DP<3> @S9S_MB_2U_LIB.S9S_MB_2U(SCH_1):M_E_CPU0_SB_DQS_DP(3)
    U2 EM18 DDR4_SB_DQS_DP3 SOCKET4677_AZIF0045P001C01CS-SA   I169 @S9S_MB_2U_LIB.S9S_MB_2U(SCH_1):PAGE24
    J9  137 DQS3_B_T SCONN288_ADR50017P130CC-SCONN2A   I178 @S9S_MB_2U_LIB.S9S_MB_2U(SCH_1):PAGE90
   J10  137 DQS3_B_T SCONN288_ADR50017P087CC-SCONN2A   I178 @S9S_MB_2U_LIB.S9S_MB_2U(SCH_1):PAGE91

M_E_CPU0_SB_DQS_DP<4> @S9S_MB_2U_LIB.S9S_MB_2U(SCH_1):M_E_CPU0_SB_DQS_DP(4)
    U2 EP36 DDR4_SB_DQS_DP4 SOCKET4677_AZIF0045P001C01CS-SA   I169 @S9S_MB_2U_LIB.S9S_MB_2U(SCH_1):PAGE24
    J9  239 DQS4_B_T SCONN288_ADR50017P130CC-SCONN2A   I178 @S9S_MB_2U_LIB.S9S_MB_2U(SCH_1):PAGE90
   J10  239 DQS4_B_T SCONN288_ADR50017P087CC-SCONN2A   I178 @S9S_MB_2U_LIB.S9S_MB_2U(SCH_1):PAGE91

M_E_CPU0_SB_DQS_DP<5> @S9S_MB_2U_LIB.S9S_MB_2U(SCH_1):M_E_CPU0_SB_DQS_DP(5)
    U2 EG27 DDR4_SB_DQS_DP5 SOCKET4677_AZIF0045P001C01CS-SA   I169 @S9S_MB_2U_LIB.S9S_MB_2U(SCH_1):PAGE24
    J9  250 DQS5_B_T||TDQS5_B_T SCONN288_ADR50017P130CC-SCONN2A   I178 @S9S_MB_2U_LIB.S9S_MB_2U(SCH_1):PAGE90
   J10  250 DQS5_B_T||TDQS5_B_T SCONN288_ADR50017P087CC-SCONN2A   I178 @S9S_MB_2U_LIB.S9S_MB_2U(SCH_1):PAGE91

M_E_CPU0_SB_DQS_DP<6> @S9S_MB_2U_LIB.S9S_MB_2U(SCH_1):M_E_CPU0_SB_DQS_DP(6)
    U2 EP30 DDR4_SB_DQS_DP6 SOCKET4677_AZIF0045P001C01CS-SA   I169 @S9S_MB_2U_LIB.S9S_MB_2U(SCH_1):PAGE24
    J9  261 DQS6_B_T||TDQS6_B_T SCONN288_ADR50017P130CC-SCONN2A   I178 @S9S_MB_2U_LIB.S9S_MB_2U(SCH_1):PAGE90
   J10  261 DQS6_B_T||TDQS6_B_T SCONN288_ADR50017P087CC-SCONN2A   I178 @S9S_MB_2U_LIB.S9S_MB_2U(SCH_1):PAGE91

M_E_CPU0_SB_DQS_DP<7> @S9S_MB_2U_LIB.S9S_MB_2U(SCH_1):M_E_CPU0_SB_DQS_DP(7)
    U2 EP24 DDR4_SB_DQS_DP7 SOCKET4677_AZIF0045P001C01CS-SA   I169 @S9S_MB_2U_LIB.S9S_MB_2U(SCH_1):PAGE24
    J9  272 DQS7_B_T||TDQS7_B_T SCONN288_ADR50017P130CC-SCONN2A   I178 @S9S_MB_2U_LIB.S9S_MB_2U(SCH_1):PAGE90
   J10  272 DQS7_B_T||TDQS7_B_T SCONN288_ADR50017P087CC-SCONN2A   I178 @S9S_MB_2U_LIB.S9S_MB_2U(SCH_1):PAGE91

M_E_CPU0_SB_DQS_DP<8> @S9S_MB_2U_LIB.S9S_MB_2U(SCH_1):M_E_CPU0_SB_DQS_DP(8)
    U2 EP18 DDR4_SB_DQS_DP8 SOCKET4677_AZIF0045P001C01CS-SA   I169 @S9S_MB_2U_LIB.S9S_MB_2U(SCH_1):PAGE24
    J9  283 DQS8_B_T||TDQS8_B_T SCONN288_ADR50017P130CC-SCONN2A   I178 @S9S_MB_2U_LIB.S9S_MB_2U(SCH_1):PAGE90
   J10  283 DQS8_B_T||TDQS8_B_T SCONN288_ADR50017P087CC-SCONN2A   I178 @S9S_MB_2U_LIB.S9S_MB_2U(SCH_1):PAGE91

M_E_CPU0_SB_DQS_DP<9> @S9S_MB_2U_LIB.S9S_MB_2U(SCH_1):M_E_CPU0_SB_DQS_DP(9)
    U2 EM36 DDR4_SB_DQS_DP9 SOCKET4677_AZIF0045P001C01CS-SA   I169 @S9S_MB_2U_LIB.S9S_MB_2U(SCH_1):PAGE24
    J9   93 DQS9_B_T||TDQS9_B_T||DBI4_B_N SCONN288_ADR50017P130CC-SCONN2A   I178 @S9S_MB_2U_LIB.S9S_MB_2U(SCH_1):PAGE90
   J10   93 DQS9_B_T||TDQS9_B_T||DBI4_B_N SCONN288_ADR50017P087CC-SCONN2A   I178 @S9S_MB_2U_LIB.S9S_MB_2U(SCH_1):PAGE91

M_E_CPU0_SB_PAR @S9S_MB_2U_LIB.S9S_MB_2U(SCH_1):M_E_CPU0_SB_PAR
    U2 EP42 DDR4_SB_PAR SOCKET4677_AZIF0045P001C01CS-SA   I169 @S9S_MB_2U_LIB.S9S_MB_2U(SCH_1):PAGE24
    J9  227  PAR_B SCONN288_ADR50017P130CC-SCONN2A    I12 @S9S_MB_2U_LIB.S9S_MB_2U(SCH_1):PAGE90
   J10  227  PAR_B SCONN288_ADR50017P087CC-SCONN2A    I13 @S9S_MB_2U_LIB.S9S_MB_2U(SCH_1):PAGE91

M_E_CPU0_SB_RSP<0> @S9S_MB_2U_LIB.S9S_MB_2U(SCH_1):M_E_CPU0_SB_RSP(0)
    U2 DF44 DDR4_B_RSP0 SOCKET4677_AZIF0045P001C01CS-SA   I169 @S9S_MB_2U_LIB.S9S_MB_2U(SCH_1):PAGE24
    J9   87 LBS||RSP_B_N SCONN288_ADR50017P130CC-SCONN2A    I12 @S9S_MB_2U_LIB.S9S_MB_2U(SCH_1):PAGE90

M_E_CPU0_SB_RSP<1> @S9S_MB_2U_LIB.S9S_MB_2U(SCH_1):M_E_CPU0_SB_RSP(1)
    U2 DG43 DDR4_B_RSP1 SOCKET4677_AZIF0045P001C01CS-SA   I169 @S9S_MB_2U_LIB.S9S_MB_2U(SCH_1):PAGE24
   J10   87 LBS||RSP_B_N SCONN288_ADR50017P087CC-SCONN2A    I13 @S9S_MB_2U_LIB.S9S_MB_2U(SCH_1):PAGE91

M_E_CPU1_ALERT_N @S9S_MB_2U_LIB.S9S_MB_2U(SCH_1):M_E_CPU1_ALERT_N
    U1 CY47 DDR4_ALERT_N SOCKET4677_AZIF0045P001C01CS-SA     I7 @S9S_MB_2U_LIB.S9S_MB_2U(SCH_1):PAGE55
   J25   62 ALERT_N SCONN288_ADR50017P130CC-SCONN2A   I180 @S9S_MB_2U_LIB.S9S_MB_2U(SCH_1):PAGE106
   J26   62 ALERT_N SCONN288_ADR50017P087CC-SCONN2A   I180 @S9S_MB_2U_LIB.S9S_MB_2U(SCH_1):PAGE107

M_E_CPU1_CLK_DN<0> @S9S_MB_2U_LIB.S9S_MB_2U(SCH_1):M_E_CPU1_CLK_DN(0)
    U1 EJ45 DDR4_CLK_DN0 SOCKET4677_AZIF0045P001C01CS-SA     I7 @S9S_MB_2U_LIB.S9S_MB_2U(SCH_1):PAGE55
   J25  218   CK_C SCONN288_ADR50017P130CC-SCONN2A   I180 @S9S_MB_2U_LIB.S9S_MB_2U(SCH_1):PAGE106

M_E_CPU1_CLK_DN<1> @S9S_MB_2U_LIB.S9S_MB_2U(SCH_1):M_E_CPU1_CLK_DN(1)
    U1 EE45 DDR4_CLK_DN1 SOCKET4677_AZIF0045P001C01CS-SA     I7 @S9S_MB_2U_LIB.S9S_MB_2U(SCH_1):PAGE55
   J26  218   CK_C SCONN288_ADR50017P087CC-SCONN2A   I180 @S9S_MB_2U_LIB.S9S_MB_2U(SCH_1):PAGE107

M_E_CPU1_CLK_DP<0> @S9S_MB_2U_LIB.S9S_MB_2U(SCH_1):M_E_CPU1_CLK_DP(0)
    U1 EG45 DDR4_CLK_DP0 SOCKET4677_AZIF0045P001C01CS-SA     I7 @S9S_MB_2U_LIB.S9S_MB_2U(SCH_1):PAGE55
   J25  217   CK_T SCONN288_ADR50017P130CC-SCONN2A   I180 @S9S_MB_2U_LIB.S9S_MB_2U(SCH_1):PAGE106

M_E_CPU1_CLK_DP<1> @S9S_MB_2U_LIB.S9S_MB_2U(SCH_1):M_E_CPU1_CLK_DP(1)
    U1 EC45 DDR4_CLK_DP1 SOCKET4677_AZIF0045P001C01CS-SA     I7 @S9S_MB_2U_LIB.S9S_MB_2U(SCH_1):PAGE55
   J26  217   CK_T SCONN288_ADR50017P087CC-SCONN2A   I180 @S9S_MB_2U_LIB.S9S_MB_2U(SCH_1):PAGE107

M_E_CPU1_SA_CA<0> @S9S_MB_2U_LIB.S9S_MB_2U(SCH_1):M_E_CPU1_SA_CA(0)
    U1 EP49 DDR4_SA_CA0 SOCKET4677_AZIF0045P001C01CS-SA     I7 @S9S_MB_2U_LIB.S9S_MB_2U(SCH_1):PAGE55
   J25   66  CA0_A SCONN288_ADR50017P130CC-SCONN2A   I180 @S9S_MB_2U_LIB.S9S_MB_2U(SCH_1):PAGE106
   J26   66  CA0_A SCONN288_ADR50017P087CC-SCONN2A   I180 @S9S_MB_2U_LIB.S9S_MB_2U(SCH_1):PAGE107

M_E_CPU1_SA_CA<1> @S9S_MB_2U_LIB.S9S_MB_2U(SCH_1):M_E_CPU1_SA_CA(1)
    U1 ET49 DDR4_SA_CA1 SOCKET4677_AZIF0045P001C01CS-SA     I7 @S9S_MB_2U_LIB.S9S_MB_2U(SCH_1):PAGE55
   J25  211  CA1_A SCONN288_ADR50017P130CC-SCONN2A   I180 @S9S_MB_2U_LIB.S9S_MB_2U(SCH_1):PAGE106
   J26  211  CA1_A SCONN288_ADR50017P087CC-SCONN2A   I180 @S9S_MB_2U_LIB.S9S_MB_2U(SCH_1):PAGE107

M_E_CPU1_SA_CA<2> @S9S_MB_2U_LIB.S9S_MB_2U(SCH_1):M_E_CPU1_SA_CA(2)
    U1 EK49 DDR4_SA_CA2 SOCKET4677_AZIF0045P001C01CS-SA     I7 @S9S_MB_2U_LIB.S9S_MB_2U(SCH_1):PAGE55
   J25   68  CA2_A SCONN288_ADR50017P130CC-SCONN2A   I180 @S9S_MB_2U_LIB.S9S_MB_2U(SCH_1):PAGE106
   J26   68  CA2_A SCONN288_ADR50017P087CC-SCONN2A   I180 @S9S_MB_2U_LIB.S9S_MB_2U(SCH_1):PAGE107

M_E_CPU1_SA_CA<3> @S9S_MB_2U_LIB.S9S_MB_2U(SCH_1):M_E_CPU1_SA_CA(3)
    U1 EL48 DDR4_SA_CA3 SOCKET4677_AZIF0045P001C01CS-SA     I7 @S9S_MB_2U_LIB.S9S_MB_2U(SCH_1):PAGE55
   J25  213  CA3_A SCONN288_ADR50017P130CC-SCONN2A   I180 @S9S_MB_2U_LIB.S9S_MB_2U(SCH_1):PAGE106
   J26  213  CA3_A SCONN288_ADR50017P087CC-SCONN2A   I180 @S9S_MB_2U_LIB.S9S_MB_2U(SCH_1):PAGE107

M_E_CPU1_SA_CA<4> @S9S_MB_2U_LIB.S9S_MB_2U(SCH_1):M_E_CPU1_SA_CA(4)
    U1 EM47 DDR4_SA_CA4 SOCKET4677_AZIF0045P001C01CS-SA     I7 @S9S_MB_2U_LIB.S9S_MB_2U(SCH_1):PAGE55
   J25   70  CA4_A SCONN288_ADR50017P130CC-SCONN2A   I180 @S9S_MB_2U_LIB.S9S_MB_2U(SCH_1):PAGE106
   J26   70  CA4_A SCONN288_ADR50017P087CC-SCONN2A   I180 @S9S_MB_2U_LIB.S9S_MB_2U(SCH_1):PAGE107

M_E_CPU1_SA_CA<5> @S9S_MB_2U_LIB.S9S_MB_2U(SCH_1):M_E_CPU1_SA_CA(5)
    U1 EP47 DDR4_SA_CA5 SOCKET4677_AZIF0045P001C01CS-SA     I7 @S9S_MB_2U_LIB.S9S_MB_2U(SCH_1):PAGE55
   J25  215  CA5_A SCONN288_ADR50017P130CC-SCONN2A   I180 @S9S_MB_2U_LIB.S9S_MB_2U(SCH_1):PAGE106
   J26  215  CA5_A SCONN288_ADR50017P087CC-SCONN2A   I180 @S9S_MB_2U_LIB.S9S_MB_2U(SCH_1):PAGE107

M_E_CPU1_SA_CA<6> @S9S_MB_2U_LIB.S9S_MB_2U(SCH_1):M_E_CPU1_SA_CA(6)
    U1 ED44 DDR4_SA_CA6 SOCKET4677_AZIF0045P001C01CS-SA     I7 @S9S_MB_2U_LIB.S9S_MB_2U(SCH_1):PAGE55
   J25   72  CA6_A SCONN288_ADR50017P130CC-SCONN2A   I180 @S9S_MB_2U_LIB.S9S_MB_2U(SCH_1):PAGE106
   J26   72  CA6_A SCONN288_ADR50017P087CC-SCONN2A   I180 @S9S_MB_2U_LIB.S9S_MB_2U(SCH_1):PAGE107

M_E_CPU1_SA_CB<0> @S9S_MB_2U_LIB.S9S_MB_2U(SCH_1):M_E_CPU1_SA_CB(0)
    U1 EM57 DDR4_SA_ECC0 SOCKET4677_AZIF0045P001C01CS-SA     I7 @S9S_MB_2U_LIB.S9S_MB_2U(SCH_1):PAGE55
   J25   51  CB0_A SCONN288_ADR50017P130CC-SCONN2A   I180 @S9S_MB_2U_LIB.S9S_MB_2U(SCH_1):PAGE106
   J26   51  CB0_A SCONN288_ADR50017P087CC-SCONN2A   I180 @S9S_MB_2U_LIB.S9S_MB_2U(SCH_1):PAGE107

M_E_CPU1_SA_CB<1> @S9S_MB_2U_LIB.S9S_MB_2U(SCH_1):M_E_CPU1_SA_CB(1)
    U1 EL56 DDR4_SA_ECC1 SOCKET4677_AZIF0045P001C01CS-SA     I7 @S9S_MB_2U_LIB.S9S_MB_2U(SCH_1):PAGE55
   J25   53  CB1_A SCONN288_ADR50017P130CC-SCONN2A   I180 @S9S_MB_2U_LIB.S9S_MB_2U(SCH_1):PAGE106
   J26   53  CB1_A SCONN288_ADR50017P087CC-SCONN2A   I180 @S9S_MB_2U_LIB.S9S_MB_2U(SCH_1):PAGE107

M_E_CPU1_SA_CB<2> @S9S_MB_2U_LIB.S9S_MB_2U(SCH_1):M_E_CPU1_SA_CB(2)
    U1 EP57 DDR4_SA_ECC2 SOCKET4677_AZIF0045P001C01CS-SA     I7 @S9S_MB_2U_LIB.S9S_MB_2U(SCH_1):PAGE55
   J25  196  CB2_A SCONN288_ADR50017P130CC-SCONN2A   I180 @S9S_MB_2U_LIB.S9S_MB_2U(SCH_1):PAGE106
   J26  196  CB2_A SCONN288_ADR50017P087CC-SCONN2A   I180 @S9S_MB_2U_LIB.S9S_MB_2U(SCH_1):PAGE107

M_E_CPU1_SA_CB<3> @S9S_MB_2U_LIB.S9S_MB_2U(SCH_1):M_E_CPU1_SA_CB(3)
    U1 ER56 DDR4_SA_ECC3 SOCKET4677_AZIF0045P001C01CS-SA     I7 @S9S_MB_2U_LIB.S9S_MB_2U(SCH_1):PAGE55
   J25  198  CB3_A SCONN288_ADR50017P130CC-SCONN2A   I180 @S9S_MB_2U_LIB.S9S_MB_2U(SCH_1):PAGE106
   J26  198  CB3_A SCONN288_ADR50017P087CC-SCONN2A   I180 @S9S_MB_2U_LIB.S9S_MB_2U(SCH_1):PAGE107

M_E_CPU1_SA_CB<4> @S9S_MB_2U_LIB.S9S_MB_2U(SCH_1):M_E_CPU1_SA_CB(4)
    U1 EL54 DDR4_SA_ECC4 SOCKET4677_AZIF0045P001C01CS-SA     I7 @S9S_MB_2U_LIB.S9S_MB_2U(SCH_1):PAGE55
   J25   58  CB4_A SCONN288_ADR50017P130CC-SCONN2A   I180 @S9S_MB_2U_LIB.S9S_MB_2U(SCH_1):PAGE106
   J26   58  CB4_A SCONN288_ADR50017P087CC-SCONN2A   I180 @S9S_MB_2U_LIB.S9S_MB_2U(SCH_1):PAGE107

M_E_CPU1_SA_CB<5> @S9S_MB_2U_LIB.S9S_MB_2U(SCH_1):M_E_CPU1_SA_CB(5)
    U1 EM53 DDR4_SA_ECC5 SOCKET4677_AZIF0045P001C01CS-SA     I7 @S9S_MB_2U_LIB.S9S_MB_2U(SCH_1):PAGE55
   J25   60  CB5_A SCONN288_ADR50017P130CC-SCONN2A   I180 @S9S_MB_2U_LIB.S9S_MB_2U(SCH_1):PAGE106
   J26   60  CB5_A SCONN288_ADR50017P087CC-SCONN2A   I180 @S9S_MB_2U_LIB.S9S_MB_2U(SCH_1):PAGE107

M_E_CPU1_SA_CB<6> @S9S_MB_2U_LIB.S9S_MB_2U(SCH_1):M_E_CPU1_SA_CB(6)
    U1 ER54 DDR4_SA_ECC6 SOCKET4677_AZIF0045P001C01CS-SA     I7 @S9S_MB_2U_LIB.S9S_MB_2U(SCH_1):PAGE55
   J25  203  CB6_A SCONN288_ADR50017P130CC-SCONN2A   I180 @S9S_MB_2U_LIB.S9S_MB_2U(SCH_1):PAGE106
   J26  203  CB6_A SCONN288_ADR50017P087CC-SCONN2A   I180 @S9S_MB_2U_LIB.S9S_MB_2U(SCH_1):PAGE107

M_E_CPU1_SA_CB<7> @S9S_MB_2U_LIB.S9S_MB_2U(SCH_1):M_E_CPU1_SA_CB(7)
    U1 EP53 DDR4_SA_ECC7 SOCKET4677_AZIF0045P001C01CS-SA     I7 @S9S_MB_2U_LIB.S9S_MB_2U(SCH_1):PAGE55
   J25  205  CB7_A SCONN288_ADR50017P130CC-SCONN2A   I180 @S9S_MB_2U_LIB.S9S_MB_2U(SCH_1):PAGE106
   J26  205  CB7_A SCONN288_ADR50017P087CC-SCONN2A   I180 @S9S_MB_2U_LIB.S9S_MB_2U(SCH_1):PAGE107

M_E_CPU1_SA_CS_N<0> @S9S_MB_2U_LIB.S9S_MB_2U(SCH_1):M_E_CPU1_SA_CS_N(0)
    U1 EP51 DDR4_SA_CS_N0 SOCKET4677_AZIF0045P001C01CS-SA     I7 @S9S_MB_2U_LIB.S9S_MB_2U(SCH_1):PAGE55
   J25   64 CS0_A_N SCONN288_ADR50017P130CC-SCONN2A   I180 @S9S_MB_2U_LIB.S9S_MB_2U(SCH_1):PAGE106

M_E_CPU1_SA_CS_N<1> @S9S_MB_2U_LIB.S9S_MB_2U(SCH_1):M_E_CPU1_SA_CS_N(1)
    U1 ET51 DDR4_SA_CS_N1 SOCKET4677_AZIF0045P001C01CS-SA     I7 @S9S_MB_2U_LIB.S9S_MB_2U(SCH_1):PAGE55
   J25  209 CS1_A_N SCONN288_ADR50017P130CC-SCONN2A   I180 @S9S_MB_2U_LIB.S9S_MB_2U(SCH_1):PAGE106

M_E_CPU1_SA_CS_N<2> @S9S_MB_2U_LIB.S9S_MB_2U(SCH_1):M_E_CPU1_SA_CS_N(2)
    U1 EM51 DDR4_SA_CS_N2 SOCKET4677_AZIF0045P001C01CS-SA     I7 @S9S_MB_2U_LIB.S9S_MB_2U(SCH_1):PAGE55
   J26   64 CS0_A_N SCONN288_ADR50017P087CC-SCONN2A   I180 @S9S_MB_2U_LIB.S9S_MB_2U(SCH_1):PAGE107

M_E_CPU1_SA_CS_N<3> @S9S_MB_2U_LIB.S9S_MB_2U(SCH_1):M_E_CPU1_SA_CS_N(3)
    U1 EL50 DDR4_SA_CS_N3 SOCKET4677_AZIF0045P001C01CS-SA     I7 @S9S_MB_2U_LIB.S9S_MB_2U(SCH_1):PAGE55
   J26  209 CS1_A_N SCONN288_ADR50017P087CC-SCONN2A   I180 @S9S_MB_2U_LIB.S9S_MB_2U(SCH_1):PAGE107

M_E_CPU1_SA_DQ<0> @S9S_MB_2U_LIB.S9S_MB_2U(SCH_1):M_E_CPU1_SA_DQ(0)
    U1 EL78 DDR4_SA_DQ0 SOCKET4677_AZIF0045P001C01CS-SA     I7 @S9S_MB_2U_LIB.S9S_MB_2U(SCH_1):PAGE55
   J25    7  DQ0_A SCONN288_ADR50017P130CC-SCONN2A   I180 @S9S_MB_2U_LIB.S9S_MB_2U(SCH_1):PAGE106
   J26    7  DQ0_A SCONN288_ADR50017P087CC-SCONN2A   I180 @S9S_MB_2U_LIB.S9S_MB_2U(SCH_1):PAGE107

M_E_CPU1_SA_DQ<10> @S9S_MB_2U_LIB.S9S_MB_2U(SCH_1):M_E_CPU1_SA_DQ(10)
    U1 EG72 DDR4_SA_DQ10 SOCKET4677_AZIF0045P001C01CS-SA     I7 @S9S_MB_2U_LIB.S9S_MB_2U(SCH_1):PAGE55
   J25  163 DQ10_A SCONN288_ADR50017P130CC-SCONN2A   I180 @S9S_MB_2U_LIB.S9S_MB_2U(SCH_1):PAGE106
   J26  163 DQ10_A SCONN288_ADR50017P087CC-SCONN2A   I180 @S9S_MB_2U_LIB.S9S_MB_2U(SCH_1):PAGE107

M_E_CPU1_SA_DQ<11> @S9S_MB_2U_LIB.S9S_MB_2U(SCH_1):M_E_CPU1_SA_DQ(11)
    U1 EH71 DDR4_SA_DQ11 SOCKET4677_AZIF0045P001C01CS-SA     I7 @S9S_MB_2U_LIB.S9S_MB_2U(SCH_1):PAGE55
   J25  165 DQ11_A SCONN288_ADR50017P130CC-SCONN2A   I180 @S9S_MB_2U_LIB.S9S_MB_2U(SCH_1):PAGE106
   J26  165 DQ11_A SCONN288_ADR50017P087CC-SCONN2A   I180 @S9S_MB_2U_LIB.S9S_MB_2U(SCH_1):PAGE107

M_E_CPU1_SA_DQ<12> @S9S_MB_2U_LIB.S9S_MB_2U(SCH_1):M_E_CPU1_SA_DQ(12)
    U1 ED69 DDR4_SA_DQ12 SOCKET4677_AZIF0045P001C01CS-SA     I7 @S9S_MB_2U_LIB.S9S_MB_2U(SCH_1):PAGE55
   J25   25 DQ12_A SCONN288_ADR50017P130CC-SCONN2A   I180 @S9S_MB_2U_LIB.S9S_MB_2U(SCH_1):PAGE106
   J26   25 DQ12_A SCONN288_ADR50017P087CC-SCONN2A   I180 @S9S_MB_2U_LIB.S9S_MB_2U(SCH_1):PAGE107

M_E_CPU1_SA_DQ<13> @S9S_MB_2U_LIB.S9S_MB_2U(SCH_1):M_E_CPU1_SA_DQ(13)
    U1 EE68 DDR4_SA_DQ13 SOCKET4677_AZIF0045P001C01CS-SA     I7 @S9S_MB_2U_LIB.S9S_MB_2U(SCH_1):PAGE55
   J25   27 DQ13_A SCONN288_ADR50017P130CC-SCONN2A   I180 @S9S_MB_2U_LIB.S9S_MB_2U(SCH_1):PAGE106
   J26   27 DQ13_A SCONN288_ADR50017P087CC-SCONN2A   I180 @S9S_MB_2U_LIB.S9S_MB_2U(SCH_1):PAGE107

M_E_CPU1_SA_DQ<14> @S9S_MB_2U_LIB.S9S_MB_2U(SCH_1):M_E_CPU1_SA_DQ(14)
    U1 EH69 DDR4_SA_DQ14 SOCKET4677_AZIF0045P001C01CS-SA     I7 @S9S_MB_2U_LIB.S9S_MB_2U(SCH_1):PAGE55
   J25  170 DQ14_A SCONN288_ADR50017P130CC-SCONN2A   I180 @S9S_MB_2U_LIB.S9S_MB_2U(SCH_1):PAGE106
   J26  170 DQ14_A SCONN288_ADR50017P087CC-SCONN2A   I180 @S9S_MB_2U_LIB.S9S_MB_2U(SCH_1):PAGE107

M_E_CPU1_SA_DQ<15> @S9S_MB_2U_LIB.S9S_MB_2U(SCH_1):M_E_CPU1_SA_DQ(15)
    U1 EG68 DDR4_SA_DQ15 SOCKET4677_AZIF0045P001C01CS-SA     I7 @S9S_MB_2U_LIB.S9S_MB_2U(SCH_1):PAGE55
   J25  172 DQ15_A SCONN288_ADR50017P130CC-SCONN2A   I180 @S9S_MB_2U_LIB.S9S_MB_2U(SCH_1):PAGE106
   J26  172 DQ15_A SCONN288_ADR50017P087CC-SCONN2A   I180 @S9S_MB_2U_LIB.S9S_MB_2U(SCH_1):PAGE107

M_E_CPU1_SA_DQ<16> @S9S_MB_2U_LIB.S9S_MB_2U(SCH_1):M_E_CPU1_SA_DQ(16)
    U1 EM71 DDR4_SA_DQ16 SOCKET4677_AZIF0045P001C01CS-SA     I7 @S9S_MB_2U_LIB.S9S_MB_2U(SCH_1):PAGE55
   J25   29 DQ16_A SCONN288_ADR50017P130CC-SCONN2A   I180 @S9S_MB_2U_LIB.S9S_MB_2U(SCH_1):PAGE106
   J26   29 DQ16_A SCONN288_ADR50017P087CC-SCONN2A   I180 @S9S_MB_2U_LIB.S9S_MB_2U(SCH_1):PAGE107

M_E_CPU1_SA_DQ<17> @S9S_MB_2U_LIB.S9S_MB_2U(SCH_1):M_E_CPU1_SA_DQ(17)
    U1 EM69 DDR4_SA_DQ17 SOCKET4677_AZIF0045P001C01CS-SA     I7 @S9S_MB_2U_LIB.S9S_MB_2U(SCH_1):PAGE55
   J25   31 DQ17_A SCONN288_ADR50017P130CC-SCONN2A   I180 @S9S_MB_2U_LIB.S9S_MB_2U(SCH_1):PAGE106
   J26   31 DQ17_A SCONN288_ADR50017P087CC-SCONN2A   I180 @S9S_MB_2U_LIB.S9S_MB_2U(SCH_1):PAGE107

M_E_CPU1_SA_DQ<18> @S9S_MB_2U_LIB.S9S_MB_2U(SCH_1):M_E_CPU1_SA_DQ(18)
    U1 EN70 DDR4_SA_DQ18 SOCKET4677_AZIF0045P001C01CS-SA     I7 @S9S_MB_2U_LIB.S9S_MB_2U(SCH_1):PAGE55
   J25  174 DQ18_A SCONN288_ADR50017P130CC-SCONN2A   I180 @S9S_MB_2U_LIB.S9S_MB_2U(SCH_1):PAGE106
   J26  174 DQ18_A SCONN288_ADR50017P087CC-SCONN2A   I180 @S9S_MB_2U_LIB.S9S_MB_2U(SCH_1):PAGE107

M_E_CPU1_SA_DQ<19> @S9S_MB_2U_LIB.S9S_MB_2U(SCH_1):M_E_CPU1_SA_DQ(19)
    U1 ER68 DDR4_SA_DQ19 SOCKET4677_AZIF0045P001C01CS-SA     I7 @S9S_MB_2U_LIB.S9S_MB_2U(SCH_1):PAGE55
   J25  176 DQ19_A SCONN288_ADR50017P130CC-SCONN2A   I180 @S9S_MB_2U_LIB.S9S_MB_2U(SCH_1):PAGE106
   J26  176 DQ19_A SCONN288_ADR50017P087CC-SCONN2A   I180 @S9S_MB_2U_LIB.S9S_MB_2U(SCH_1):PAGE107

M_E_CPU1_SA_DQ<1> @S9S_MB_2U_LIB.S9S_MB_2U(SCH_1):M_E_CPU1_SA_DQ(1)
    U1 EM77 DDR4_SA_DQ1 SOCKET4677_AZIF0045P001C01CS-SA     I7 @S9S_MB_2U_LIB.S9S_MB_2U(SCH_1):PAGE55
   J25    9  DQ1_A SCONN288_ADR50017P130CC-SCONN2A   I180 @S9S_MB_2U_LIB.S9S_MB_2U(SCH_1):PAGE106
   J26    9  DQ1_A SCONN288_ADR50017P087CC-SCONN2A   I180 @S9S_MB_2U_LIB.S9S_MB_2U(SCH_1):PAGE107

M_E_CPU1_SA_DQ<20> @S9S_MB_2U_LIB.S9S_MB_2U(SCH_1):M_E_CPU1_SA_DQ(20)
    U1 ER66 DDR4_SA_DQ20 SOCKET4677_AZIF0045P001C01CS-SA     I7 @S9S_MB_2U_LIB.S9S_MB_2U(SCH_1):PAGE55
   J25   36 DQ20_A SCONN288_ADR50017P130CC-SCONN2A   I180 @S9S_MB_2U_LIB.S9S_MB_2U(SCH_1):PAGE106
   J26   36 DQ20_A SCONN288_ADR50017P087CC-SCONN2A   I180 @S9S_MB_2U_LIB.S9S_MB_2U(SCH_1):PAGE107

M_E_CPU1_SA_DQ<21> @S9S_MB_2U_LIB.S9S_MB_2U(SCH_1):M_E_CPU1_SA_DQ(21)
    U1 EM65 DDR4_SA_DQ21 SOCKET4677_AZIF0045P001C01CS-SA     I7 @S9S_MB_2U_LIB.S9S_MB_2U(SCH_1):PAGE55
   J25   38 DQ21_A SCONN288_ADR50017P130CC-SCONN2A   I180 @S9S_MB_2U_LIB.S9S_MB_2U(SCH_1):PAGE106
   J26   38 DQ21_A SCONN288_ADR50017P087CC-SCONN2A   I180 @S9S_MB_2U_LIB.S9S_MB_2U(SCH_1):PAGE107

M_E_CPU1_SA_DQ<22> @S9S_MB_2U_LIB.S9S_MB_2U(SCH_1):M_E_CPU1_SA_DQ(22)
    U1 EL66 DDR4_SA_DQ22 SOCKET4677_AZIF0045P001C01CS-SA     I7 @S9S_MB_2U_LIB.S9S_MB_2U(SCH_1):PAGE55
   J25  181 DQ22_A SCONN288_ADR50017P130CC-SCONN2A   I180 @S9S_MB_2U_LIB.S9S_MB_2U(SCH_1):PAGE106
   J26  181 DQ22_A SCONN288_ADR50017P087CC-SCONN2A   I180 @S9S_MB_2U_LIB.S9S_MB_2U(SCH_1):PAGE107

M_E_CPU1_SA_DQ<23> @S9S_MB_2U_LIB.S9S_MB_2U(SCH_1):M_E_CPU1_SA_DQ(23)
    U1 EP65 DDR4_SA_DQ23 SOCKET4677_AZIF0045P001C01CS-SA     I7 @S9S_MB_2U_LIB.S9S_MB_2U(SCH_1):PAGE55
   J25  183 DQ23_A SCONN288_ADR50017P130CC-SCONN2A   I180 @S9S_MB_2U_LIB.S9S_MB_2U(SCH_1):PAGE106
   J26  183 DQ23_A SCONN288_ADR50017P087CC-SCONN2A   I180 @S9S_MB_2U_LIB.S9S_MB_2U(SCH_1):PAGE107

M_E_CPU1_SA_DQ<24> @S9S_MB_2U_LIB.S9S_MB_2U(SCH_1):M_E_CPU1_SA_DQ(24)
    U1 EM63 DDR4_SA_DQ24 SOCKET4677_AZIF0045P001C01CS-SA     I7 @S9S_MB_2U_LIB.S9S_MB_2U(SCH_1):PAGE55
   J25   40 DQ24_A SCONN288_ADR50017P130CC-SCONN2A   I180 @S9S_MB_2U_LIB.S9S_MB_2U(SCH_1):PAGE106
   J26   40 DQ24_A SCONN288_ADR50017P087CC-SCONN2A   I180 @S9S_MB_2U_LIB.S9S_MB_2U(SCH_1):PAGE107

M_E_CPU1_SA_DQ<25> @S9S_MB_2U_LIB.S9S_MB_2U(SCH_1):M_E_CPU1_SA_DQ(25)
    U1 EL62 DDR4_SA_DQ25 SOCKET4677_AZIF0045P001C01CS-SA     I7 @S9S_MB_2U_LIB.S9S_MB_2U(SCH_1):PAGE55
   J25   42 DQ25_A SCONN288_ADR50017P130CC-SCONN2A   I180 @S9S_MB_2U_LIB.S9S_MB_2U(SCH_1):PAGE106
   J26   42 DQ25_A SCONN288_ADR50017P087CC-SCONN2A   I180 @S9S_MB_2U_LIB.S9S_MB_2U(SCH_1):PAGE107

M_E_CPU1_SA_DQ<26> @S9S_MB_2U_LIB.S9S_MB_2U(SCH_1):M_E_CPU1_SA_DQ(26)
    U1 EP63 DDR4_SA_DQ26 SOCKET4677_AZIF0045P001C01CS-SA     I7 @S9S_MB_2U_LIB.S9S_MB_2U(SCH_1):PAGE55
   J25  185 DQ26_A SCONN288_ADR50017P130CC-SCONN2A   I180 @S9S_MB_2U_LIB.S9S_MB_2U(SCH_1):PAGE106
   J26  185 DQ26_A SCONN288_ADR50017P087CC-SCONN2A   I180 @S9S_MB_2U_LIB.S9S_MB_2U(SCH_1):PAGE107

M_E_CPU1_SA_DQ<27> @S9S_MB_2U_LIB.S9S_MB_2U(SCH_1):M_E_CPU1_SA_DQ(27)
    U1 ER62 DDR4_SA_DQ27 SOCKET4677_AZIF0045P001C01CS-SA     I7 @S9S_MB_2U_LIB.S9S_MB_2U(SCH_1):PAGE55
   J25  187 DQ27_A SCONN288_ADR50017P130CC-SCONN2A   I180 @S9S_MB_2U_LIB.S9S_MB_2U(SCH_1):PAGE106
   J26  187 DQ27_A SCONN288_ADR50017P087CC-SCONN2A   I180 @S9S_MB_2U_LIB.S9S_MB_2U(SCH_1):PAGE107

M_E_CPU1_SA_DQ<28> @S9S_MB_2U_LIB.S9S_MB_2U(SCH_1):M_E_CPU1_SA_DQ(28)
    U1 EL60 DDR4_SA_DQ28 SOCKET4677_AZIF0045P001C01CS-SA     I7 @S9S_MB_2U_LIB.S9S_MB_2U(SCH_1):PAGE55
   J25   47 DQ28_A SCONN288_ADR50017P130CC-SCONN2A   I180 @S9S_MB_2U_LIB.S9S_MB_2U(SCH_1):PAGE106
   J26   47 DQ28_A SCONN288_ADR50017P087CC-SCONN2A   I180 @S9S_MB_2U_LIB.S9S_MB_2U(SCH_1):PAGE107

M_E_CPU1_SA_DQ<29> @S9S_MB_2U_LIB.S9S_MB_2U(SCH_1):M_E_CPU1_SA_DQ(29)
    U1 EM59 DDR4_SA_DQ29 SOCKET4677_AZIF0045P001C01CS-SA     I7 @S9S_MB_2U_LIB.S9S_MB_2U(SCH_1):PAGE55
   J25   49 DQ29_A SCONN288_ADR50017P130CC-SCONN2A   I180 @S9S_MB_2U_LIB.S9S_MB_2U(SCH_1):PAGE106
   J26   49 DQ29_A SCONN288_ADR50017P087CC-SCONN2A   I180 @S9S_MB_2U_LIB.S9S_MB_2U(SCH_1):PAGE107

M_E_CPU1_SA_DQ<2> @S9S_MB_2U_LIB.S9S_MB_2U(SCH_1):M_E_CPU1_SA_DQ(2)
    U1 EP79 DDR4_SA_DQ2 SOCKET4677_AZIF0045P001C01CS-SA     I7 @S9S_MB_2U_LIB.S9S_MB_2U(SCH_1):PAGE55
   J25  152  DQ2_A SCONN288_ADR50017P130CC-SCONN2A   I180 @S9S_MB_2U_LIB.S9S_MB_2U(SCH_1):PAGE106
   J26  152  DQ2_A SCONN288_ADR50017P087CC-SCONN2A   I180 @S9S_MB_2U_LIB.S9S_MB_2U(SCH_1):PAGE107

M_E_CPU1_SA_DQ<30> @S9S_MB_2U_LIB.S9S_MB_2U(SCH_1):M_E_CPU1_SA_DQ(30)
    U1 ER60 DDR4_SA_DQ30 SOCKET4677_AZIF0045P001C01CS-SA     I7 @S9S_MB_2U_LIB.S9S_MB_2U(SCH_1):PAGE55
   J25  192 DQ30_A SCONN288_ADR50017P130CC-SCONN2A   I180 @S9S_MB_2U_LIB.S9S_MB_2U(SCH_1):PAGE106
   J26  192 DQ30_A SCONN288_ADR50017P087CC-SCONN2A   I180 @S9S_MB_2U_LIB.S9S_MB_2U(SCH_1):PAGE107

M_E_CPU1_SA_DQ<31> @S9S_MB_2U_LIB.S9S_MB_2U(SCH_1):M_E_CPU1_SA_DQ(31)
    U1 EP59 DDR4_SA_DQ31 SOCKET4677_AZIF0045P001C01CS-SA     I7 @S9S_MB_2U_LIB.S9S_MB_2U(SCH_1):PAGE55
   J25  194 DQ31_A SCONN288_ADR50017P130CC-SCONN2A   I180 @S9S_MB_2U_LIB.S9S_MB_2U(SCH_1):PAGE106
   J26  194 DQ31_A SCONN288_ADR50017P087CC-SCONN2A   I180 @S9S_MB_2U_LIB.S9S_MB_2U(SCH_1):PAGE107

M_E_CPU1_SA_DQ<3> @S9S_MB_2U_LIB.S9S_MB_2U(SCH_1):M_E_CPU1_SA_DQ(3)
    U1 ER76 DDR4_SA_DQ3 SOCKET4677_AZIF0045P001C01CS-SA     I7 @S9S_MB_2U_LIB.S9S_MB_2U(SCH_1):PAGE55
   J25  154  DQ3_A SCONN288_ADR50017P130CC-SCONN2A   I180 @S9S_MB_2U_LIB.S9S_MB_2U(SCH_1):PAGE106
   J26  154  DQ3_A SCONN288_ADR50017P087CC-SCONN2A   I180 @S9S_MB_2U_LIB.S9S_MB_2U(SCH_1):PAGE107

M_E_CPU1_SA_DQ<4> @S9S_MB_2U_LIB.S9S_MB_2U(SCH_1):M_E_CPU1_SA_DQ(4)
    U1 EL74 DDR4_SA_DQ4 SOCKET4677_AZIF0045P001C01CS-SA     I7 @S9S_MB_2U_LIB.S9S_MB_2U(SCH_1):PAGE55
   J25   14  DQ4_A SCONN288_ADR50017P130CC-SCONN2A   I180 @S9S_MB_2U_LIB.S9S_MB_2U(SCH_1):PAGE106
   J26   14  DQ4_A SCONN288_ADR50017P087CC-SCONN2A   I180 @S9S_MB_2U_LIB.S9S_MB_2U(SCH_1):PAGE107

M_E_CPU1_SA_DQ<5> @S9S_MB_2U_LIB.S9S_MB_2U(SCH_1):M_E_CPU1_SA_DQ(5)
    U1 EK73 DDR4_SA_DQ5 SOCKET4677_AZIF0045P001C01CS-SA     I7 @S9S_MB_2U_LIB.S9S_MB_2U(SCH_1):PAGE55
   J25   16  DQ5_A SCONN288_ADR50017P130CC-SCONN2A   I180 @S9S_MB_2U_LIB.S9S_MB_2U(SCH_1):PAGE106
   J26   16  DQ5_A SCONN288_ADR50017P087CC-SCONN2A   I180 @S9S_MB_2U_LIB.S9S_MB_2U(SCH_1):PAGE107

M_E_CPU1_SA_DQ<6> @S9S_MB_2U_LIB.S9S_MB_2U(SCH_1):M_E_CPU1_SA_DQ(6)
    U1 EP73 DDR4_SA_DQ6 SOCKET4677_AZIF0045P001C01CS-SA     I7 @S9S_MB_2U_LIB.S9S_MB_2U(SCH_1):PAGE55
   J25  159  DQ6_A SCONN288_ADR50017P130CC-SCONN2A   I180 @S9S_MB_2U_LIB.S9S_MB_2U(SCH_1):PAGE106
   J26  159  DQ6_A SCONN288_ADR50017P087CC-SCONN2A   I180 @S9S_MB_2U_LIB.S9S_MB_2U(SCH_1):PAGE107

M_E_CPU1_SA_DQ<7> @S9S_MB_2U_LIB.S9S_MB_2U(SCH_1):M_E_CPU1_SA_DQ(7)
    U1 ER72 DDR4_SA_DQ7 SOCKET4677_AZIF0045P001C01CS-SA     I7 @S9S_MB_2U_LIB.S9S_MB_2U(SCH_1):PAGE55
   J25  161  DQ7_A SCONN288_ADR50017P130CC-SCONN2A   I180 @S9S_MB_2U_LIB.S9S_MB_2U(SCH_1):PAGE106
   J26  161  DQ7_A SCONN288_ADR50017P087CC-SCONN2A   I180 @S9S_MB_2U_LIB.S9S_MB_2U(SCH_1):PAGE107

M_E_CPU1_SA_DQ<8> @S9S_MB_2U_LIB.S9S_MB_2U(SCH_1):M_E_CPU1_SA_DQ(8)
    U1 EE72 DDR4_SA_DQ8 SOCKET4677_AZIF0045P001C01CS-SA     I7 @S9S_MB_2U_LIB.S9S_MB_2U(SCH_1):PAGE55
   J25   18  DQ8_A SCONN288_ADR50017P130CC-SCONN2A   I180 @S9S_MB_2U_LIB.S9S_MB_2U(SCH_1):PAGE106
   J26   18  DQ8_A SCONN288_ADR50017P087CC-SCONN2A   I180 @S9S_MB_2U_LIB.S9S_MB_2U(SCH_1):PAGE107

M_E_CPU1_SA_DQ<9> @S9S_MB_2U_LIB.S9S_MB_2U(SCH_1):M_E_CPU1_SA_DQ(9)
    U1 ED71 DDR4_SA_DQ9 SOCKET4677_AZIF0045P001C01CS-SA     I7 @S9S_MB_2U_LIB.S9S_MB_2U(SCH_1):PAGE55
   J25   20  DQ9_A SCONN288_ADR50017P130CC-SCONN2A   I180 @S9S_MB_2U_LIB.S9S_MB_2U(SCH_1):PAGE106
   J26   20  DQ9_A SCONN288_ADR50017P087CC-SCONN2A   I180 @S9S_MB_2U_LIB.S9S_MB_2U(SCH_1):PAGE107

M_E_CPU1_SA_DQS_DN<0> @S9S_MB_2U_LIB.S9S_MB_2U(SCH_1):M_E_CPU1_SA_DQS_DN(0)
    U1 EP75 DDR4_SA_DQS_DN0 SOCKET4677_AZIF0045P001C01CS-SA     I7 @S9S_MB_2U_LIB.S9S_MB_2U(SCH_1):PAGE55
   J25   12 DQS0_A_C SCONN288_ADR50017P130CC-SCONN2A   I181 @S9S_MB_2U_LIB.S9S_MB_2U(SCH_1):PAGE106
   J26   12 DQS0_A_C SCONN288_ADR50017P087CC-SCONN2A   I181 @S9S_MB_2U_LIB.S9S_MB_2U(SCH_1):PAGE107

M_E_CPU1_SA_DQS_DN<1> @S9S_MB_2U_LIB.S9S_MB_2U(SCH_1):M_E_CPU1_SA_DQS_DN(1)
    U1 EC70 DDR4_SA_DQS_DN1 SOCKET4677_AZIF0045P001C01CS-SA     I7 @S9S_MB_2U_LIB.S9S_MB_2U(SCH_1):PAGE55
   J25   23 DQS1_A_C SCONN288_ADR50017P130CC-SCONN2A   I181 @S9S_MB_2U_LIB.S9S_MB_2U(SCH_1):PAGE106
   J26   23 DQS1_A_C SCONN288_ADR50017P087CC-SCONN2A   I181 @S9S_MB_2U_LIB.S9S_MB_2U(SCH_1):PAGE107

M_E_CPU1_SA_DQS_DN<2> @S9S_MB_2U_LIB.S9S_MB_2U(SCH_1):M_E_CPU1_SA_DQS_DN(2)
    U1 EK67 DDR4_SA_DQS_DN2 SOCKET4677_AZIF0045P001C01CS-SA     I7 @S9S_MB_2U_LIB.S9S_MB_2U(SCH_1):PAGE55
   J25   34 DQS2_A_C SCONN288_ADR50017P130CC-SCONN2A   I181 @S9S_MB_2U_LIB.S9S_MB_2U(SCH_1):PAGE106
   J26   34 DQS2_A_C SCONN288_ADR50017P087CC-SCONN2A   I181 @S9S_MB_2U_LIB.S9S_MB_2U(SCH_1):PAGE107

M_E_CPU1_SA_DQS_DN<3> @S9S_MB_2U_LIB.S9S_MB_2U(SCH_1):M_E_CPU1_SA_DQS_DN(3)
    U1 EK61 DDR4_SA_DQS_DN3 SOCKET4677_AZIF0045P001C01CS-SA     I7 @S9S_MB_2U_LIB.S9S_MB_2U(SCH_1):PAGE55
   J25   45 DQS3_A_C SCONN288_ADR50017P130CC-SCONN2A   I181 @S9S_MB_2U_LIB.S9S_MB_2U(SCH_1):PAGE106
   J26   45 DQS3_A_C SCONN288_ADR50017P087CC-SCONN2A   I181 @S9S_MB_2U_LIB.S9S_MB_2U(SCH_1):PAGE107

M_E_CPU1_SA_DQS_DN<4> @S9S_MB_2U_LIB.S9S_MB_2U(SCH_1):M_E_CPU1_SA_DQS_DN(4)
    U1 EM55 DDR4_SA_DQS_DN4 SOCKET4677_AZIF0045P001C01CS-SA     I7 @S9S_MB_2U_LIB.S9S_MB_2U(SCH_1):PAGE55
   J25   56 DQS4_A_C SCONN288_ADR50017P130CC-SCONN2A   I181 @S9S_MB_2U_LIB.S9S_MB_2U(SCH_1):PAGE106
   J26   56 DQS4_A_C SCONN288_ADR50017P087CC-SCONN2A   I181 @S9S_MB_2U_LIB.S9S_MB_2U(SCH_1):PAGE107

M_E_CPU1_SA_DQS_DN<5> @S9S_MB_2U_LIB.S9S_MB_2U(SCH_1):M_E_CPU1_SA_DQS_DN(5)
    U1 EM75 DDR4_SA_DQS_DN5 SOCKET4677_AZIF0045P001C01CS-SA     I7 @S9S_MB_2U_LIB.S9S_MB_2U(SCH_1):PAGE55
   J25  156 DQS5_A_C||TDQS5_A_C||DQS5_A_T||TDQS5_A_T SCONN288_ADR50017P130CC-SCONN2A   I181 @S9S_MB_2U_LIB.S9S_MB_2U(SCH_1):PAGE106
   J26  156 DQS5_A_C||TDQS5_A_C||DQS5_A_T||TDQS5_A_T SCONN288_ADR50017P087CC-SCONN2A   I181 @S9S_MB_2U_LIB.S9S_MB_2U(SCH_1):PAGE107

M_E_CPU1_SA_DQS_DN<6> @S9S_MB_2U_LIB.S9S_MB_2U(SCH_1):M_E_CPU1_SA_DQS_DN(6)
    U1 EJ70 DDR4_SA_DQS_DN6 SOCKET4677_AZIF0045P001C01CS-SA     I7 @S9S_MB_2U_LIB.S9S_MB_2U(SCH_1):PAGE55
   J25  167 DQS6_A_C||TDQS6_A_C||DQS6_A_T||TDQS6_A_T SCONN288_ADR50017P130CC-SCONN2A   I181 @S9S_MB_2U_LIB.S9S_MB_2U(SCH_1):PAGE106
   J26  167 DQS6_A_C||TDQS6_A_C||DQS6_A_T||TDQS6_A_T SCONN288_ADR50017P087CC-SCONN2A   I181 @S9S_MB_2U_LIB.S9S_MB_2U(SCH_1):PAGE107

M_E_CPU1_SA_DQS_DN<7> @S9S_MB_2U_LIB.S9S_MB_2U(SCH_1):M_E_CPU1_SA_DQS_DN(7)
    U1 EN68 DDR4_SA_DQS_DN7 SOCKET4677_AZIF0045P001C01CS-SA     I7 @S9S_MB_2U_LIB.S9S_MB_2U(SCH_1):PAGE55
   J25  178 DQS7_A_C||TDQS7_A_C SCONN288_ADR50017P130CC-SCONN2A   I181 @S9S_MB_2U_LIB.S9S_MB_2U(SCH_1):PAGE106
   J26  178 DQS7_A_C||TDQS7_A_C SCONN288_ADR50017P087CC-SCONN2A   I181 @S9S_MB_2U_LIB.S9S_MB_2U(SCH_1):PAGE107

M_E_CPU1_SA_DQS_DN<8> @S9S_MB_2U_LIB.S9S_MB_2U(SCH_1):M_E_CPU1_SA_DQS_DN(8)
    U1 ET61 DDR4_SA_DQS_DN8 SOCKET4677_AZIF0045P001C01CS-SA     I7 @S9S_MB_2U_LIB.S9S_MB_2U(SCH_1):PAGE55
   J25  189 DQS8_A_C||TDQS8_A_C SCONN288_ADR50017P130CC-SCONN2A   I181 @S9S_MB_2U_LIB.S9S_MB_2U(SCH_1):PAGE106
   J26  189 DQS8_A_C||TDQS8_A_C SCONN288_ADR50017P087CC-SCONN2A   I181 @S9S_MB_2U_LIB.S9S_MB_2U(SCH_1):PAGE107

M_E_CPU1_SA_DQS_DN<9> @S9S_MB_2U_LIB.S9S_MB_2U(SCH_1):M_E_CPU1_SA_DQS_DN(9)
    U1 ET55 DDR4_SA_DQS_DN9 SOCKET4677_AZIF0045P001C01CS-SA     I7 @S9S_MB_2U_LIB.S9S_MB_2U(SCH_1):PAGE55
   J25  200 DQS9_A_C||TDQS9_A_C SCONN288_ADR50017P130CC-SCONN2A   I181 @S9S_MB_2U_LIB.S9S_MB_2U(SCH_1):PAGE106
   J26  200 DQS9_A_C||TDQS9_A_C SCONN288_ADR50017P087CC-SCONN2A   I181 @S9S_MB_2U_LIB.S9S_MB_2U(SCH_1):PAGE107

M_E_CPU1_SA_DQS_DP<0> @S9S_MB_2U_LIB.S9S_MB_2U(SCH_1):M_E_CPU1_SA_DQS_DP(0)
    U1 EN76 DDR4_SA_DQS_DP0 SOCKET4677_AZIF0045P001C01CS-SA     I7 @S9S_MB_2U_LIB.S9S_MB_2U(SCH_1):PAGE55
   J25   11 DQS0_A_T SCONN288_ADR50017P130CC-SCONN2A   I181 @S9S_MB_2U_LIB.S9S_MB_2U(SCH_1):PAGE106
   J26   11 DQS0_A_T SCONN288_ADR50017P087CC-SCONN2A   I181 @S9S_MB_2U_LIB.S9S_MB_2U(SCH_1):PAGE107

M_E_CPU1_SA_DQS_DP<1> @S9S_MB_2U_LIB.S9S_MB_2U(SCH_1):M_E_CPU1_SA_DQS_DP(1)
    U1 EE70 DDR4_SA_DQS_DP1 SOCKET4677_AZIF0045P001C01CS-SA     I7 @S9S_MB_2U_LIB.S9S_MB_2U(SCH_1):PAGE55
   J25   22 DQS1_A_T SCONN288_ADR50017P130CC-SCONN2A   I181 @S9S_MB_2U_LIB.S9S_MB_2U(SCH_1):PAGE106
   J26   22 DQS1_A_T SCONN288_ADR50017P087CC-SCONN2A   I181 @S9S_MB_2U_LIB.S9S_MB_2U(SCH_1):PAGE107

M_E_CPU1_SA_DQS_DP<2> @S9S_MB_2U_LIB.S9S_MB_2U(SCH_1):M_E_CPU1_SA_DQS_DP(2)
    U1 EL68 DDR4_SA_DQS_DP2 SOCKET4677_AZIF0045P001C01CS-SA     I7 @S9S_MB_2U_LIB.S9S_MB_2U(SCH_1):PAGE55
   J25   33 DQS2_A_T SCONN288_ADR50017P130CC-SCONN2A   I181 @S9S_MB_2U_LIB.S9S_MB_2U(SCH_1):PAGE106
   J26   33 DQS2_A_T SCONN288_ADR50017P087CC-SCONN2A   I181 @S9S_MB_2U_LIB.S9S_MB_2U(SCH_1):PAGE107

M_E_CPU1_SA_DQS_DP<3> @S9S_MB_2U_LIB.S9S_MB_2U(SCH_1):M_E_CPU1_SA_DQS_DP(3)
    U1 EM61 DDR4_SA_DQS_DP3 SOCKET4677_AZIF0045P001C01CS-SA     I7 @S9S_MB_2U_LIB.S9S_MB_2U(SCH_1):PAGE55
   J25   44 DQS3_A_T SCONN288_ADR50017P130CC-SCONN2A   I181 @S9S_MB_2U_LIB.S9S_MB_2U(SCH_1):PAGE106
   J26   44 DQS3_A_T SCONN288_ADR50017P087CC-SCONN2A   I181 @S9S_MB_2U_LIB.S9S_MB_2U(SCH_1):PAGE107

M_E_CPU1_SA_DQS_DP<4> @S9S_MB_2U_LIB.S9S_MB_2U(SCH_1):M_E_CPU1_SA_DQS_DP(4)
    U1 EK55 DDR4_SA_DQS_DP4 SOCKET4677_AZIF0045P001C01CS-SA     I7 @S9S_MB_2U_LIB.S9S_MB_2U(SCH_1):PAGE55
   J25   55 DQS4_A_T SCONN288_ADR50017P130CC-SCONN2A   I181 @S9S_MB_2U_LIB.S9S_MB_2U(SCH_1):PAGE106
   J26   55 DQS4_A_T SCONN288_ADR50017P087CC-SCONN2A   I181 @S9S_MB_2U_LIB.S9S_MB_2U(SCH_1):PAGE107

M_E_CPU1_SA_DQS_DP<5> @S9S_MB_2U_LIB.S9S_MB_2U(SCH_1):M_E_CPU1_SA_DQS_DP(5)
    U1 EN74 DDR4_SA_DQS_DP5 SOCKET4677_AZIF0045P001C01CS-SA     I7 @S9S_MB_2U_LIB.S9S_MB_2U(SCH_1):PAGE55
   J25  157 DQS5_A_T||TDQS5_A_T SCONN288_ADR50017P130CC-SCONN2A   I181 @S9S_MB_2U_LIB.S9S_MB_2U(SCH_1):PAGE106
   J26  157 DQS5_A_T||TDQS5_A_T SCONN288_ADR50017P087CC-SCONN2A   I181 @S9S_MB_2U_LIB.S9S_MB_2U(SCH_1):PAGE107

M_E_CPU1_SA_DQS_DP<6> @S9S_MB_2U_LIB.S9S_MB_2U(SCH_1):M_E_CPU1_SA_DQS_DP(6)
    U1 EG70 DDR4_SA_DQS_DP6 SOCKET4677_AZIF0045P001C01CS-SA     I7 @S9S_MB_2U_LIB.S9S_MB_2U(SCH_1):PAGE55
   J25  168 DQS6_A_T||TDQS6_A_T SCONN288_ADR50017P130CC-SCONN2A   I181 @S9S_MB_2U_LIB.S9S_MB_2U(SCH_1):PAGE106
   J26  168 DQS6_A_T||TDQS6_A_T SCONN288_ADR50017P087CC-SCONN2A   I181 @S9S_MB_2U_LIB.S9S_MB_2U(SCH_1):PAGE107

M_E_CPU1_SA_DQS_DP<7> @S9S_MB_2U_LIB.S9S_MB_2U(SCH_1):M_E_CPU1_SA_DQS_DP(7)
    U1 EM67 DDR4_SA_DQS_DP7 SOCKET4677_AZIF0045P001C01CS-SA     I7 @S9S_MB_2U_LIB.S9S_MB_2U(SCH_1):PAGE55
   J25  179 DQS7_A_T||TDQS7_A_T SCONN288_ADR50017P130CC-SCONN2A   I181 @S9S_MB_2U_LIB.S9S_MB_2U(SCH_1):PAGE106
   J26  179 DQS7_A_T||TDQS7_A_T SCONN288_ADR50017P087CC-SCONN2A   I181 @S9S_MB_2U_LIB.S9S_MB_2U(SCH_1):PAGE107

M_E_CPU1_SA_DQS_DP<8> @S9S_MB_2U_LIB.S9S_MB_2U(SCH_1):M_E_CPU1_SA_DQS_DP(8)
    U1 EP61 DDR4_SA_DQS_DP8 SOCKET4677_AZIF0045P001C01CS-SA     I7 @S9S_MB_2U_LIB.S9S_MB_2U(SCH_1):PAGE55
   J25  190 DQS8_A_T||TDQS8_A_T SCONN288_ADR50017P130CC-SCONN2A   I181 @S9S_MB_2U_LIB.S9S_MB_2U(SCH_1):PAGE106
   J26  190 DQS8_A_T||TDQS8_A_T SCONN288_ADR50017P087CC-SCONN2A   I181 @S9S_MB_2U_LIB.S9S_MB_2U(SCH_1):PAGE107

M_E_CPU1_SA_DQS_DP<9> @S9S_MB_2U_LIB.S9S_MB_2U(SCH_1):M_E_CPU1_SA_DQS_DP(9)
    U1 EP55 DDR4_SA_DQS_DP9 SOCKET4677_AZIF0045P001C01CS-SA     I7 @S9S_MB_2U_LIB.S9S_MB_2U(SCH_1):PAGE55
   J25  201 DQS9_A_T||TDQS9_A_T SCONN288_ADR50017P130CC-SCONN2A   I181 @S9S_MB_2U_LIB.S9S_MB_2U(SCH_1):PAGE106
   J26  201 DQS9_A_T||TDQS9_A_T SCONN288_ADR50017P087CC-SCONN2A   I181 @S9S_MB_2U_LIB.S9S_MB_2U(SCH_1):PAGE107

M_E_CPU1_SA_PAR @S9S_MB_2U_LIB.S9S_MB_2U(SCH_1):M_E_CPU1_SA_PAR
    U1 EE43 DDR4_SA_PAR SOCKET4677_AZIF0045P001C01CS-SA     I7 @S9S_MB_2U_LIB.S9S_MB_2U(SCH_1):PAGE55
   J25   74  PAR_A SCONN288_ADR50017P130CC-SCONN2A   I180 @S9S_MB_2U_LIB.S9S_MB_2U(SCH_1):PAGE106
   J26   74  PAR_A SCONN288_ADR50017P087CC-SCONN2A   I180 @S9S_MB_2U_LIB.S9S_MB_2U(SCH_1):PAGE107

M_E_CPU1_SA_RSP<0> @S9S_MB_2U_LIB.S9S_MB_2U(SCH_1):M_E_CPU1_SA_RSP(0)
    U1 DD44 DDR4_A_RSP0 SOCKET4677_AZIF0045P001C01CS-SA     I7 @S9S_MB_2U_LIB.S9S_MB_2U(SCH_1):PAGE55
   J25   86 LBD||RSP_A_N SCONN288_ADR50017P130CC-SCONN2A   I180 @S9S_MB_2U_LIB.S9S_MB_2U(SCH_1):PAGE106

M_E_CPU1_SA_RSP<1> @S9S_MB_2U_LIB.S9S_MB_2U(SCH_1):M_E_CPU1_SA_RSP(1)
    U1 DC43 DDR4_A_RSP1 SOCKET4677_AZIF0045P001C01CS-SA     I7 @S9S_MB_2U_LIB.S9S_MB_2U(SCH_1):PAGE55
   J26   86 LBD||RSP_A_N SCONN288_ADR50017P087CC-SCONN2A   I180 @S9S_MB_2U_LIB.S9S_MB_2U(SCH_1):PAGE107

M_E_CPU1_SB_CA<0> @S9S_MB_2U_LIB.S9S_MB_2U(SCH_1):M_E_CPU1_SB_CA(0)
    U1 EG43 DDR4_SB_CA0 SOCKET4677_AZIF0045P001C01CS-SA     I7 @S9S_MB_2U_LIB.S9S_MB_2U(SCH_1):PAGE55
   J25   76  CA0_B SCONN288_ADR50017P130CC-SCONN2A   I180 @S9S_MB_2U_LIB.S9S_MB_2U(SCH_1):PAGE106
   J26   76  CA0_B SCONN288_ADR50017P087CC-SCONN2A   I180 @S9S_MB_2U_LIB.S9S_MB_2U(SCH_1):PAGE107

M_E_CPU1_SB_CA<1> @S9S_MB_2U_LIB.S9S_MB_2U(SCH_1):M_E_CPU1_SB_CA(1)
    U1 EH44 DDR4_SB_CA1 SOCKET4677_AZIF0045P001C01CS-SA     I7 @S9S_MB_2U_LIB.S9S_MB_2U(SCH_1):PAGE55
   J25  221  CA1_B SCONN288_ADR50017P130CC-SCONN2A   I180 @S9S_MB_2U_LIB.S9S_MB_2U(SCH_1):PAGE106
   J26  221  CA1_B SCONN288_ADR50017P087CC-SCONN2A   I180 @S9S_MB_2U_LIB.S9S_MB_2U(SCH_1):PAGE107

M_E_CPU1_SB_CA<2> @S9S_MB_2U_LIB.S9S_MB_2U(SCH_1):M_E_CPU1_SB_CA(2)
    U1 EM44 DDR4_SB_CA2 SOCKET4677_AZIF0045P001C01CS-SA     I7 @S9S_MB_2U_LIB.S9S_MB_2U(SCH_1):PAGE55
   J25   78  CA2_B SCONN288_ADR50017P130CC-SCONN2A   I180 @S9S_MB_2U_LIB.S9S_MB_2U(SCH_1):PAGE106
   J26   78  CA2_B SCONN288_ADR50017P087CC-SCONN2A   I180 @S9S_MB_2U_LIB.S9S_MB_2U(SCH_1):PAGE107

M_E_CPU1_SB_CA<3> @S9S_MB_2U_LIB.S9S_MB_2U(SCH_1):M_E_CPU1_SB_CA(3)
    U1 EP44 DDR4_SB_CA3 SOCKET4677_AZIF0045P001C01CS-SA     I7 @S9S_MB_2U_LIB.S9S_MB_2U(SCH_1):PAGE55
   J25  223  CA3_B SCONN288_ADR50017P130CC-SCONN2A   I180 @S9S_MB_2U_LIB.S9S_MB_2U(SCH_1):PAGE106
   J26  223  CA3_B SCONN288_ADR50017P087CC-SCONN2A   I180 @S9S_MB_2U_LIB.S9S_MB_2U(SCH_1):PAGE107

M_E_CPU1_SB_CA<4> @S9S_MB_2U_LIB.S9S_MB_2U(SCH_1):M_E_CPU1_SB_CA(4)
    U1 EL43 DDR4_SB_CA4 SOCKET4677_AZIF0045P001C01CS-SA     I7 @S9S_MB_2U_LIB.S9S_MB_2U(SCH_1):PAGE55
   J25   80  CA4_B SCONN288_ADR50017P130CC-SCONN2A   I180 @S9S_MB_2U_LIB.S9S_MB_2U(SCH_1):PAGE106
   J26   80  CA4_B SCONN288_ADR50017P087CC-SCONN2A   I180 @S9S_MB_2U_LIB.S9S_MB_2U(SCH_1):PAGE107

M_E_CPU1_SB_CA<5> @S9S_MB_2U_LIB.S9S_MB_2U(SCH_1):M_E_CPU1_SB_CA(5)
    U1 ET42 DDR4_SB_CA5 SOCKET4677_AZIF0045P001C01CS-SA     I7 @S9S_MB_2U_LIB.S9S_MB_2U(SCH_1):PAGE55
   J25  225  CA5_B SCONN288_ADR50017P130CC-SCONN2A   I180 @S9S_MB_2U_LIB.S9S_MB_2U(SCH_1):PAGE106
   J26  225  CA5_B SCONN288_ADR50017P087CC-SCONN2A   I180 @S9S_MB_2U_LIB.S9S_MB_2U(SCH_1):PAGE107

M_E_CPU1_SB_CA<6> @S9S_MB_2U_LIB.S9S_MB_2U(SCH_1):M_E_CPU1_SB_CA(6)
    U1 EK42 DDR4_SB_CA6 SOCKET4677_AZIF0045P001C01CS-SA     I7 @S9S_MB_2U_LIB.S9S_MB_2U(SCH_1):PAGE55
   J25   82  CA6_B SCONN288_ADR50017P130CC-SCONN2A   I180 @S9S_MB_2U_LIB.S9S_MB_2U(SCH_1):PAGE106
   J26   82  CA6_B SCONN288_ADR50017P087CC-SCONN2A   I180 @S9S_MB_2U_LIB.S9S_MB_2U(SCH_1):PAGE107

M_E_CPU1_SB_CB<0> @S9S_MB_2U_LIB.S9S_MB_2U(SCH_1):M_E_CPU1_SB_CB(0)
    U1 EL35 DDR4_SB_ECC0 SOCKET4677_AZIF0045P001C01CS-SA     I7 @S9S_MB_2U_LIB.S9S_MB_2U(SCH_1):PAGE55
   J25   96  CB0_B SCONN288_ADR50017P130CC-SCONN2A   I180 @S9S_MB_2U_LIB.S9S_MB_2U(SCH_1):PAGE106
   J26   96  CB0_B SCONN288_ADR50017P087CC-SCONN2A   I180 @S9S_MB_2U_LIB.S9S_MB_2U(SCH_1):PAGE107

M_E_CPU1_SB_CB<1> @S9S_MB_2U_LIB.S9S_MB_2U(SCH_1):M_E_CPU1_SB_CB(1)
    U1 EM34 DDR4_SB_ECC1 SOCKET4677_AZIF0045P001C01CS-SA     I7 @S9S_MB_2U_LIB.S9S_MB_2U(SCH_1):PAGE55
   J25   98  CB1_B SCONN288_ADR50017P130CC-SCONN2A   I180 @S9S_MB_2U_LIB.S9S_MB_2U(SCH_1):PAGE106
   J26   98  CB1_B SCONN288_ADR50017P087CC-SCONN2A   I180 @S9S_MB_2U_LIB.S9S_MB_2U(SCH_1):PAGE107

M_E_CPU1_SB_CB<2> @S9S_MB_2U_LIB.S9S_MB_2U(SCH_1):M_E_CPU1_SB_CB(2)
    U1 ER35 DDR4_SB_ECC2 SOCKET4677_AZIF0045P001C01CS-SA     I7 @S9S_MB_2U_LIB.S9S_MB_2U(SCH_1):PAGE55
   J25  241  CB2_B SCONN288_ADR50017P130CC-SCONN2A   I180 @S9S_MB_2U_LIB.S9S_MB_2U(SCH_1):PAGE106
   J26  241  CB2_B SCONN288_ADR50017P087CC-SCONN2A   I180 @S9S_MB_2U_LIB.S9S_MB_2U(SCH_1):PAGE107

M_E_CPU1_SB_CB<3> @S9S_MB_2U_LIB.S9S_MB_2U(SCH_1):M_E_CPU1_SB_CB(3)
    U1 EP34 DDR4_SB_ECC3 SOCKET4677_AZIF0045P001C01CS-SA     I7 @S9S_MB_2U_LIB.S9S_MB_2U(SCH_1):PAGE55
   J25  243  CB3_B SCONN288_ADR50017P130CC-SCONN2A   I180 @S9S_MB_2U_LIB.S9S_MB_2U(SCH_1):PAGE106
   J26  243  CB3_B SCONN288_ADR50017P087CC-SCONN2A   I180 @S9S_MB_2U_LIB.S9S_MB_2U(SCH_1):PAGE107

M_E_CPU1_SB_CB<4> @S9S_MB_2U_LIB.S9S_MB_2U(SCH_1):M_E_CPU1_SB_CB(4)
    U1 EM38 DDR4_SB_ECC4 SOCKET4677_AZIF0045P001C01CS-SA     I7 @S9S_MB_2U_LIB.S9S_MB_2U(SCH_1):PAGE55
   J25   89  CB4_B SCONN288_ADR50017P130CC-SCONN2A   I180 @S9S_MB_2U_LIB.S9S_MB_2U(SCH_1):PAGE106
   J26   89  CB4_B SCONN288_ADR50017P087CC-SCONN2A   I180 @S9S_MB_2U_LIB.S9S_MB_2U(SCH_1):PAGE107

M_E_CPU1_SB_CB<5> @S9S_MB_2U_LIB.S9S_MB_2U(SCH_1):M_E_CPU1_SB_CB(5)
    U1 EL37 DDR4_SB_ECC5 SOCKET4677_AZIF0045P001C01CS-SA     I7 @S9S_MB_2U_LIB.S9S_MB_2U(SCH_1):PAGE55
   J25   91  CB5_B SCONN288_ADR50017P130CC-SCONN2A   I180 @S9S_MB_2U_LIB.S9S_MB_2U(SCH_1):PAGE106
   J26   91  CB5_B SCONN288_ADR50017P087CC-SCONN2A   I180 @S9S_MB_2U_LIB.S9S_MB_2U(SCH_1):PAGE107

M_E_CPU1_SB_CB<6> @S9S_MB_2U_LIB.S9S_MB_2U(SCH_1):M_E_CPU1_SB_CB(6)
    U1 EP38 DDR4_SB_ECC6 SOCKET4677_AZIF0045P001C01CS-SA     I7 @S9S_MB_2U_LIB.S9S_MB_2U(SCH_1):PAGE55
   J25  234  CB6_B SCONN288_ADR50017P130CC-SCONN2A   I180 @S9S_MB_2U_LIB.S9S_MB_2U(SCH_1):PAGE106
   J26  234  CB6_B SCONN288_ADR50017P087CC-SCONN2A   I180 @S9S_MB_2U_LIB.S9S_MB_2U(SCH_1):PAGE107

M_E_CPU1_SB_CB<7> @S9S_MB_2U_LIB.S9S_MB_2U(SCH_1):M_E_CPU1_SB_CB(7)
    U1 ER37 DDR4_SB_ECC7 SOCKET4677_AZIF0045P001C01CS-SA     I7 @S9S_MB_2U_LIB.S9S_MB_2U(SCH_1):PAGE55
   J25  236  CB7_B SCONN288_ADR50017P130CC-SCONN2A   I180 @S9S_MB_2U_LIB.S9S_MB_2U(SCH_1):PAGE106
   J26  236  CB7_B SCONN288_ADR50017P087CC-SCONN2A   I180 @S9S_MB_2U_LIB.S9S_MB_2U(SCH_1):PAGE107

M_E_CPU1_SB_CS_N<0> @S9S_MB_2U_LIB.S9S_MB_2U(SCH_1):M_E_CPU1_SB_CS_N(0)
    U1 EP40 DDR4_SB_CS_N0 SOCKET4677_AZIF0045P001C01CS-SA     I7 @S9S_MB_2U_LIB.S9S_MB_2U(SCH_1):PAGE55
   J25   84 CS0_B_N SCONN288_ADR50017P130CC-SCONN2A   I180 @S9S_MB_2U_LIB.S9S_MB_2U(SCH_1):PAGE106

M_E_CPU1_SB_CS_N<1> @S9S_MB_2U_LIB.S9S_MB_2U(SCH_1):M_E_CPU1_SB_CS_N(1)
    U1 ET40 DDR4_SB_CS_N1 SOCKET4677_AZIF0045P001C01CS-SA     I7 @S9S_MB_2U_LIB.S9S_MB_2U(SCH_1):PAGE55
   J25  229 CS1_B_N SCONN288_ADR50017P130CC-SCONN2A   I180 @S9S_MB_2U_LIB.S9S_MB_2U(SCH_1):PAGE106

M_E_CPU1_SB_CS_N<2> @S9S_MB_2U_LIB.S9S_MB_2U(SCH_1):M_E_CPU1_SB_CS_N(2)
    U1 EM40 DDR4_SB_CS_N2 SOCKET4677_AZIF0045P001C01CS-SA     I7 @S9S_MB_2U_LIB.S9S_MB_2U(SCH_1):PAGE55
   J26   84 CS0_B_N SCONN288_ADR50017P087CC-SCONN2A   I180 @S9S_MB_2U_LIB.S9S_MB_2U(SCH_1):PAGE107

M_E_CPU1_SB_CS_N<3> @S9S_MB_2U_LIB.S9S_MB_2U(SCH_1):M_E_CPU1_SB_CS_N(3)
    U1 EL41 DDR4_SB_CS_N3 SOCKET4677_AZIF0045P001C01CS-SA     I7 @S9S_MB_2U_LIB.S9S_MB_2U(SCH_1):PAGE55
   J26  229 CS1_B_N SCONN288_ADR50017P087CC-SCONN2A   I180 @S9S_MB_2U_LIB.S9S_MB_2U(SCH_1):PAGE107

M_E_CPU1_SB_DQ<0> @S9S_MB_2U_LIB.S9S_MB_2U(SCH_1):M_E_CPU1_SB_DQ(0)
    U1 EE29 DDR4_SB_DQ0 SOCKET4677_AZIF0045P001C01CS-SA     I7 @S9S_MB_2U_LIB.S9S_MB_2U(SCH_1):PAGE55
   J25  100  DQ0_B SCONN288_ADR50017P130CC-SCONN2A   I180 @S9S_MB_2U_LIB.S9S_MB_2U(SCH_1):PAGE106
   J26  100  DQ0_B SCONN288_ADR50017P087CC-SCONN2A   I180 @S9S_MB_2U_LIB.S9S_MB_2U(SCH_1):PAGE107

M_E_CPU1_SB_DQ<10> @S9S_MB_2U_LIB.S9S_MB_2U(SCH_1):M_E_CPU1_SB_DQ(10)
    U1 EP32 DDR4_SB_DQ10 SOCKET4677_AZIF0045P001C01CS-SA     I7 @S9S_MB_2U_LIB.S9S_MB_2U(SCH_1):PAGE55
   J25  256 DQ10_B SCONN288_ADR50017P130CC-SCONN2A   I180 @S9S_MB_2U_LIB.S9S_MB_2U(SCH_1):PAGE106
   J26  256 DQ10_B SCONN288_ADR50017P087CC-SCONN2A   I180 @S9S_MB_2U_LIB.S9S_MB_2U(SCH_1):PAGE107

M_E_CPU1_SB_DQ<11> @S9S_MB_2U_LIB.S9S_MB_2U(SCH_1):M_E_CPU1_SB_DQ(11)
    U1 ER31 DDR4_SB_DQ11 SOCKET4677_AZIF0045P001C01CS-SA     I7 @S9S_MB_2U_LIB.S9S_MB_2U(SCH_1):PAGE55
   J25  258 DQ11_B SCONN288_ADR50017P130CC-SCONN2A   I180 @S9S_MB_2U_LIB.S9S_MB_2U(SCH_1):PAGE106
   J26  258 DQ11_B SCONN288_ADR50017P087CC-SCONN2A   I180 @S9S_MB_2U_LIB.S9S_MB_2U(SCH_1):PAGE107

M_E_CPU1_SB_DQ<12> @S9S_MB_2U_LIB.S9S_MB_2U(SCH_1):M_E_CPU1_SB_DQ(12)
    U1 EL29 DDR4_SB_DQ12 SOCKET4677_AZIF0045P001C01CS-SA     I7 @S9S_MB_2U_LIB.S9S_MB_2U(SCH_1):PAGE55
   J25  118 DQ12_B SCONN288_ADR50017P130CC-SCONN2A   I180 @S9S_MB_2U_LIB.S9S_MB_2U(SCH_1):PAGE106
   J26  118 DQ12_B SCONN288_ADR50017P087CC-SCONN2A   I180 @S9S_MB_2U_LIB.S9S_MB_2U(SCH_1):PAGE107

M_E_CPU1_SB_DQ<13> @S9S_MB_2U_LIB.S9S_MB_2U(SCH_1):M_E_CPU1_SB_DQ(13)
    U1 EM28 DDR4_SB_DQ13 SOCKET4677_AZIF0045P001C01CS-SA     I7 @S9S_MB_2U_LIB.S9S_MB_2U(SCH_1):PAGE55
   J25  120 DQ13_B SCONN288_ADR50017P130CC-SCONN2A   I180 @S9S_MB_2U_LIB.S9S_MB_2U(SCH_1):PAGE106
   J26  120 DQ13_B SCONN288_ADR50017P087CC-SCONN2A   I180 @S9S_MB_2U_LIB.S9S_MB_2U(SCH_1):PAGE107

M_E_CPU1_SB_DQ<14> @S9S_MB_2U_LIB.S9S_MB_2U(SCH_1):M_E_CPU1_SB_DQ(14)
    U1 ER29 DDR4_SB_DQ14 SOCKET4677_AZIF0045P001C01CS-SA     I7 @S9S_MB_2U_LIB.S9S_MB_2U(SCH_1):PAGE55
   J25  263 DQ14_B SCONN288_ADR50017P130CC-SCONN2A   I180 @S9S_MB_2U_LIB.S9S_MB_2U(SCH_1):PAGE106
   J26  263 DQ14_B SCONN288_ADR50017P087CC-SCONN2A   I180 @S9S_MB_2U_LIB.S9S_MB_2U(SCH_1):PAGE107

M_E_CPU1_SB_DQ<15> @S9S_MB_2U_LIB.S9S_MB_2U(SCH_1):M_E_CPU1_SB_DQ(15)
    U1 EP28 DDR4_SB_DQ15 SOCKET4677_AZIF0045P001C01CS-SA     I7 @S9S_MB_2U_LIB.S9S_MB_2U(SCH_1):PAGE55
   J25  265 DQ15_B SCONN288_ADR50017P130CC-SCONN2A   I180 @S9S_MB_2U_LIB.S9S_MB_2U(SCH_1):PAGE106
   J26  265 DQ15_B SCONN288_ADR50017P087CC-SCONN2A   I180 @S9S_MB_2U_LIB.S9S_MB_2U(SCH_1):PAGE107

M_E_CPU1_SB_DQ<16> @S9S_MB_2U_LIB.S9S_MB_2U(SCH_1):M_E_CPU1_SB_DQ(16)
    U1 EM26 DDR4_SB_DQ16 SOCKET4677_AZIF0045P001C01CS-SA     I7 @S9S_MB_2U_LIB.S9S_MB_2U(SCH_1):PAGE55
   J25  122 DQ16_B SCONN288_ADR50017P130CC-SCONN2A   I180 @S9S_MB_2U_LIB.S9S_MB_2U(SCH_1):PAGE106
   J26  122 DQ16_B SCONN288_ADR50017P087CC-SCONN2A   I180 @S9S_MB_2U_LIB.S9S_MB_2U(SCH_1):PAGE107

M_E_CPU1_SB_DQ<17> @S9S_MB_2U_LIB.S9S_MB_2U(SCH_1):M_E_CPU1_SB_DQ(17)
    U1 EL25 DDR4_SB_DQ17 SOCKET4677_AZIF0045P001C01CS-SA     I7 @S9S_MB_2U_LIB.S9S_MB_2U(SCH_1):PAGE55
   J25  124 DQ17_B SCONN288_ADR50017P130CC-SCONN2A   I180 @S9S_MB_2U_LIB.S9S_MB_2U(SCH_1):PAGE106
   J26  124 DQ17_B SCONN288_ADR50017P087CC-SCONN2A   I180 @S9S_MB_2U_LIB.S9S_MB_2U(SCH_1):PAGE107

M_E_CPU1_SB_DQ<18> @S9S_MB_2U_LIB.S9S_MB_2U(SCH_1):M_E_CPU1_SB_DQ(18)
    U1 EP26 DDR4_SB_DQ18 SOCKET4677_AZIF0045P001C01CS-SA     I7 @S9S_MB_2U_LIB.S9S_MB_2U(SCH_1):PAGE55
   J25  267 DQ18_B SCONN288_ADR50017P130CC-SCONN2A   I180 @S9S_MB_2U_LIB.S9S_MB_2U(SCH_1):PAGE106
   J26  267 DQ18_B SCONN288_ADR50017P087CC-SCONN2A   I180 @S9S_MB_2U_LIB.S9S_MB_2U(SCH_1):PAGE107

M_E_CPU1_SB_DQ<19> @S9S_MB_2U_LIB.S9S_MB_2U(SCH_1):M_E_CPU1_SB_DQ(19)
    U1 ER25 DDR4_SB_DQ19 SOCKET4677_AZIF0045P001C01CS-SA     I7 @S9S_MB_2U_LIB.S9S_MB_2U(SCH_1):PAGE55
   J25  269 DQ19_B SCONN288_ADR50017P130CC-SCONN2A   I180 @S9S_MB_2U_LIB.S9S_MB_2U(SCH_1):PAGE106
   J26  269 DQ19_B SCONN288_ADR50017P087CC-SCONN2A   I180 @S9S_MB_2U_LIB.S9S_MB_2U(SCH_1):PAGE107

M_E_CPU1_SB_DQ<1> @S9S_MB_2U_LIB.S9S_MB_2U(SCH_1):M_E_CPU1_SB_DQ(1)
    U1 ED28 DDR4_SB_DQ1 SOCKET4677_AZIF0045P001C01CS-SA     I7 @S9S_MB_2U_LIB.S9S_MB_2U(SCH_1):PAGE55
   J25  102  DQ1_B SCONN288_ADR50017P130CC-SCONN2A   I180 @S9S_MB_2U_LIB.S9S_MB_2U(SCH_1):PAGE106
   J26  102  DQ1_B SCONN288_ADR50017P087CC-SCONN2A   I180 @S9S_MB_2U_LIB.S9S_MB_2U(SCH_1):PAGE107

M_E_CPU1_SB_DQ<20> @S9S_MB_2U_LIB.S9S_MB_2U(SCH_1):M_E_CPU1_SB_DQ(20)
    U1 EL23 DDR4_SB_DQ20 SOCKET4677_AZIF0045P001C01CS-SA     I7 @S9S_MB_2U_LIB.S9S_MB_2U(SCH_1):PAGE55
   J25  129 DQ20_B SCONN288_ADR50017P130CC-SCONN2A   I180 @S9S_MB_2U_LIB.S9S_MB_2U(SCH_1):PAGE106
   J26  129 DQ20_B SCONN288_ADR50017P087CC-SCONN2A   I180 @S9S_MB_2U_LIB.S9S_MB_2U(SCH_1):PAGE107

M_E_CPU1_SB_DQ<21> @S9S_MB_2U_LIB.S9S_MB_2U(SCH_1):M_E_CPU1_SB_DQ(21)
    U1 EM22 DDR4_SB_DQ21 SOCKET4677_AZIF0045P001C01CS-SA     I7 @S9S_MB_2U_LIB.S9S_MB_2U(SCH_1):PAGE55
   J25  131 DQ21_B SCONN288_ADR50017P130CC-SCONN2A   I180 @S9S_MB_2U_LIB.S9S_MB_2U(SCH_1):PAGE106
   J26  131 DQ21_B SCONN288_ADR50017P087CC-SCONN2A   I180 @S9S_MB_2U_LIB.S9S_MB_2U(SCH_1):PAGE107

M_E_CPU1_SB_DQ<22> @S9S_MB_2U_LIB.S9S_MB_2U(SCH_1):M_E_CPU1_SB_DQ(22)
    U1 ER23 DDR4_SB_DQ22 SOCKET4677_AZIF0045P001C01CS-SA     I7 @S9S_MB_2U_LIB.S9S_MB_2U(SCH_1):PAGE55
   J25  274 DQ22_B SCONN288_ADR50017P130CC-SCONN2A   I180 @S9S_MB_2U_LIB.S9S_MB_2U(SCH_1):PAGE106
   J26  274 DQ22_B SCONN288_ADR50017P087CC-SCONN2A   I180 @S9S_MB_2U_LIB.S9S_MB_2U(SCH_1):PAGE107

M_E_CPU1_SB_DQ<23> @S9S_MB_2U_LIB.S9S_MB_2U(SCH_1):M_E_CPU1_SB_DQ(23)
    U1 EP22 DDR4_SB_DQ23 SOCKET4677_AZIF0045P001C01CS-SA     I7 @S9S_MB_2U_LIB.S9S_MB_2U(SCH_1):PAGE55
   J25  276 DQ23_B SCONN288_ADR50017P130CC-SCONN2A   I180 @S9S_MB_2U_LIB.S9S_MB_2U(SCH_1):PAGE106
   J26  276 DQ23_B SCONN288_ADR50017P087CC-SCONN2A   I180 @S9S_MB_2U_LIB.S9S_MB_2U(SCH_1):PAGE107

M_E_CPU1_SB_DQ<24> @S9S_MB_2U_LIB.S9S_MB_2U(SCH_1):M_E_CPU1_SB_DQ(24)
    U1 EM20 DDR4_SB_DQ24 SOCKET4677_AZIF0045P001C01CS-SA     I7 @S9S_MB_2U_LIB.S9S_MB_2U(SCH_1):PAGE55
   J25  133 DQ24_B SCONN288_ADR50017P130CC-SCONN2A   I180 @S9S_MB_2U_LIB.S9S_MB_2U(SCH_1):PAGE106
   J26  133 DQ24_B SCONN288_ADR50017P087CC-SCONN2A   I180 @S9S_MB_2U_LIB.S9S_MB_2U(SCH_1):PAGE107

M_E_CPU1_SB_DQ<25> @S9S_MB_2U_LIB.S9S_MB_2U(SCH_1):M_E_CPU1_SB_DQ(25)
    U1 EL19 DDR4_SB_DQ25 SOCKET4677_AZIF0045P001C01CS-SA     I7 @S9S_MB_2U_LIB.S9S_MB_2U(SCH_1):PAGE55
   J25  135 DQ25_B SCONN288_ADR50017P130CC-SCONN2A   I180 @S9S_MB_2U_LIB.S9S_MB_2U(SCH_1):PAGE106
   J26  135 DQ25_B SCONN288_ADR50017P087CC-SCONN2A   I180 @S9S_MB_2U_LIB.S9S_MB_2U(SCH_1):PAGE107

M_E_CPU1_SB_DQ<26> @S9S_MB_2U_LIB.S9S_MB_2U(SCH_1):M_E_CPU1_SB_DQ(26)
    U1 EP20 DDR4_SB_DQ26 SOCKET4677_AZIF0045P001C01CS-SA     I7 @S9S_MB_2U_LIB.S9S_MB_2U(SCH_1):PAGE55
   J25  278 DQ26_B SCONN288_ADR50017P130CC-SCONN2A   I180 @S9S_MB_2U_LIB.S9S_MB_2U(SCH_1):PAGE106
   J26  278 DQ26_B SCONN288_ADR50017P087CC-SCONN2A   I180 @S9S_MB_2U_LIB.S9S_MB_2U(SCH_1):PAGE107

M_E_CPU1_SB_DQ<27> @S9S_MB_2U_LIB.S9S_MB_2U(SCH_1):M_E_CPU1_SB_DQ(27)
    U1 ER19 DDR4_SB_DQ27 SOCKET4677_AZIF0045P001C01CS-SA     I7 @S9S_MB_2U_LIB.S9S_MB_2U(SCH_1):PAGE55
   J25  280 DQ27_B SCONN288_ADR50017P130CC-SCONN2A   I180 @S9S_MB_2U_LIB.S9S_MB_2U(SCH_1):PAGE106
   J26  280 DQ27_B SCONN288_ADR50017P087CC-SCONN2A   I180 @S9S_MB_2U_LIB.S9S_MB_2U(SCH_1):PAGE107

M_E_CPU1_SB_DQ<28> @S9S_MB_2U_LIB.S9S_MB_2U(SCH_1):M_E_CPU1_SB_DQ(28)
    U1 EL17 DDR4_SB_DQ28 SOCKET4677_AZIF0045P001C01CS-SA     I7 @S9S_MB_2U_LIB.S9S_MB_2U(SCH_1):PAGE55
   J25  140 DQ28_B SCONN288_ADR50017P130CC-SCONN2A   I180 @S9S_MB_2U_LIB.S9S_MB_2U(SCH_1):PAGE106
   J26  140 DQ28_B SCONN288_ADR50017P087CC-SCONN2A   I180 @S9S_MB_2U_LIB.S9S_MB_2U(SCH_1):PAGE107

M_E_CPU1_SB_DQ<29> @S9S_MB_2U_LIB.S9S_MB_2U(SCH_1):M_E_CPU1_SB_DQ(29)
    U1 EM16 DDR4_SB_DQ29 SOCKET4677_AZIF0045P001C01CS-SA     I7 @S9S_MB_2U_LIB.S9S_MB_2U(SCH_1):PAGE55
   J25  142 DQ29_B SCONN288_ADR50017P130CC-SCONN2A   I180 @S9S_MB_2U_LIB.S9S_MB_2U(SCH_1):PAGE106
   J26  142 DQ29_B SCONN288_ADR50017P087CC-SCONN2A   I180 @S9S_MB_2U_LIB.S9S_MB_2U(SCH_1):PAGE107

M_E_CPU1_SB_DQ<2> @S9S_MB_2U_LIB.S9S_MB_2U(SCH_1):M_E_CPU1_SB_DQ(2)
    U1 EG29 DDR4_SB_DQ2 SOCKET4677_AZIF0045P001C01CS-SA     I7 @S9S_MB_2U_LIB.S9S_MB_2U(SCH_1):PAGE55
   J25  245  DQ2_B SCONN288_ADR50017P130CC-SCONN2A   I180 @S9S_MB_2U_LIB.S9S_MB_2U(SCH_1):PAGE106
   J26  245  DQ2_B SCONN288_ADR50017P087CC-SCONN2A   I180 @S9S_MB_2U_LIB.S9S_MB_2U(SCH_1):PAGE107

M_E_CPU1_SB_DQ<30> @S9S_MB_2U_LIB.S9S_MB_2U(SCH_1):M_E_CPU1_SB_DQ(30)
    U1 ER17 DDR4_SB_DQ30 SOCKET4677_AZIF0045P001C01CS-SA     I7 @S9S_MB_2U_LIB.S9S_MB_2U(SCH_1):PAGE55
   J25  285 DQ30_B SCONN288_ADR50017P130CC-SCONN2A   I180 @S9S_MB_2U_LIB.S9S_MB_2U(SCH_1):PAGE106
   J26  285 DQ30_B SCONN288_ADR50017P087CC-SCONN2A   I180 @S9S_MB_2U_LIB.S9S_MB_2U(SCH_1):PAGE107

M_E_CPU1_SB_DQ<31> @S9S_MB_2U_LIB.S9S_MB_2U(SCH_1):M_E_CPU1_SB_DQ(31)
    U1 EP16 DDR4_SB_DQ31 SOCKET4677_AZIF0045P001C01CS-SA     I7 @S9S_MB_2U_LIB.S9S_MB_2U(SCH_1):PAGE55
   J25  287 DQ31_B SCONN288_ADR50017P130CC-SCONN2A   I180 @S9S_MB_2U_LIB.S9S_MB_2U(SCH_1):PAGE106
   J26  287 DQ31_B SCONN288_ADR50017P087CC-SCONN2A   I180 @S9S_MB_2U_LIB.S9S_MB_2U(SCH_1):PAGE107

M_E_CPU1_SB_DQ<3> @S9S_MB_2U_LIB.S9S_MB_2U(SCH_1):M_E_CPU1_SB_DQ(3)
    U1 EH28 DDR4_SB_DQ3 SOCKET4677_AZIF0045P001C01CS-SA     I7 @S9S_MB_2U_LIB.S9S_MB_2U(SCH_1):PAGE55
   J25  247  DQ3_B SCONN288_ADR50017P130CC-SCONN2A   I180 @S9S_MB_2U_LIB.S9S_MB_2U(SCH_1):PAGE106
   J26  247  DQ3_B SCONN288_ADR50017P087CC-SCONN2A   I180 @S9S_MB_2U_LIB.S9S_MB_2U(SCH_1):PAGE107

M_E_CPU1_SB_DQ<4> @S9S_MB_2U_LIB.S9S_MB_2U(SCH_1):M_E_CPU1_SB_DQ(4)
    U1 ED26 DDR4_SB_DQ4 SOCKET4677_AZIF0045P001C01CS-SA     I7 @S9S_MB_2U_LIB.S9S_MB_2U(SCH_1):PAGE55
   J25  107  DQ4_B SCONN288_ADR50017P130CC-SCONN2A   I180 @S9S_MB_2U_LIB.S9S_MB_2U(SCH_1):PAGE106
   J26  107  DQ4_B SCONN288_ADR50017P087CC-SCONN2A   I180 @S9S_MB_2U_LIB.S9S_MB_2U(SCH_1):PAGE107

M_E_CPU1_SB_DQ<5> @S9S_MB_2U_LIB.S9S_MB_2U(SCH_1):M_E_CPU1_SB_DQ(5)
    U1 EE25 DDR4_SB_DQ5 SOCKET4677_AZIF0045P001C01CS-SA     I7 @S9S_MB_2U_LIB.S9S_MB_2U(SCH_1):PAGE55
   J25  109  DQ5_B SCONN288_ADR50017P130CC-SCONN2A   I180 @S9S_MB_2U_LIB.S9S_MB_2U(SCH_1):PAGE106
   J26  109  DQ5_B SCONN288_ADR50017P087CC-SCONN2A   I180 @S9S_MB_2U_LIB.S9S_MB_2U(SCH_1):PAGE107

M_E_CPU1_SB_DQ<6> @S9S_MB_2U_LIB.S9S_MB_2U(SCH_1):M_E_CPU1_SB_DQ(6)
    U1 EH26 DDR4_SB_DQ6 SOCKET4677_AZIF0045P001C01CS-SA     I7 @S9S_MB_2U_LIB.S9S_MB_2U(SCH_1):PAGE55
   J25  252  DQ6_B SCONN288_ADR50017P130CC-SCONN2A   I180 @S9S_MB_2U_LIB.S9S_MB_2U(SCH_1):PAGE106
   J26  252  DQ6_B SCONN288_ADR50017P087CC-SCONN2A   I180 @S9S_MB_2U_LIB.S9S_MB_2U(SCH_1):PAGE107

M_E_CPU1_SB_DQ<7> @S9S_MB_2U_LIB.S9S_MB_2U(SCH_1):M_E_CPU1_SB_DQ(7)
    U1 EG25 DDR4_SB_DQ7 SOCKET4677_AZIF0045P001C01CS-SA     I7 @S9S_MB_2U_LIB.S9S_MB_2U(SCH_1):PAGE55
   J25  254  DQ7_B SCONN288_ADR50017P130CC-SCONN2A   I180 @S9S_MB_2U_LIB.S9S_MB_2U(SCH_1):PAGE106
   J26  254  DQ7_B SCONN288_ADR50017P087CC-SCONN2A   I180 @S9S_MB_2U_LIB.S9S_MB_2U(SCH_1):PAGE107

M_E_CPU1_SB_DQ<8> @S9S_MB_2U_LIB.S9S_MB_2U(SCH_1):M_E_CPU1_SB_DQ(8)
    U1 EM32 DDR4_SB_DQ8 SOCKET4677_AZIF0045P001C01CS-SA     I7 @S9S_MB_2U_LIB.S9S_MB_2U(SCH_1):PAGE55
   J25  111  DQ8_B SCONN288_ADR50017P130CC-SCONN2A   I180 @S9S_MB_2U_LIB.S9S_MB_2U(SCH_1):PAGE106
   J26  111  DQ8_B SCONN288_ADR50017P087CC-SCONN2A   I180 @S9S_MB_2U_LIB.S9S_MB_2U(SCH_1):PAGE107

M_E_CPU1_SB_DQ<9> @S9S_MB_2U_LIB.S9S_MB_2U(SCH_1):M_E_CPU1_SB_DQ(9)
    U1 EL31 DDR4_SB_DQ9 SOCKET4677_AZIF0045P001C01CS-SA     I7 @S9S_MB_2U_LIB.S9S_MB_2U(SCH_1):PAGE55
   J25  113  DQ9_B SCONN288_ADR50017P130CC-SCONN2A   I180 @S9S_MB_2U_LIB.S9S_MB_2U(SCH_1):PAGE106
   J26  113  DQ9_B SCONN288_ADR50017P087CC-SCONN2A   I180 @S9S_MB_2U_LIB.S9S_MB_2U(SCH_1):PAGE107

M_E_CPU1_SB_DQS_DN<0> @S9S_MB_2U_LIB.S9S_MB_2U(SCH_1):M_E_CPU1_SB_DQS_DN(0)
    U1 EE27 DDR4_SB_DQS_DN0 SOCKET4677_AZIF0045P001C01CS-SA     I7 @S9S_MB_2U_LIB.S9S_MB_2U(SCH_1):PAGE55
   J25  105 DQS0_B_C SCONN288_ADR50017P130CC-SCONN2A   I181 @S9S_MB_2U_LIB.S9S_MB_2U(SCH_1):PAGE106
   J26  105 DQS0_B_C SCONN288_ADR50017P087CC-SCONN2A   I181 @S9S_MB_2U_LIB.S9S_MB_2U(SCH_1):PAGE107

M_E_CPU1_SB_DQS_DN<1> @S9S_MB_2U_LIB.S9S_MB_2U(SCH_1):M_E_CPU1_SB_DQS_DN(1)
    U1 EK30 DDR4_SB_DQS_DN1 SOCKET4677_AZIF0045P001C01CS-SA     I7 @S9S_MB_2U_LIB.S9S_MB_2U(SCH_1):PAGE55
   J25  116 DQS1_B_C SCONN288_ADR50017P130CC-SCONN2A   I181 @S9S_MB_2U_LIB.S9S_MB_2U(SCH_1):PAGE106
   J26  116 DQS1_B_C SCONN288_ADR50017P087CC-SCONN2A   I181 @S9S_MB_2U_LIB.S9S_MB_2U(SCH_1):PAGE107

M_E_CPU1_SB_DQS_DN<2> @S9S_MB_2U_LIB.S9S_MB_2U(SCH_1):M_E_CPU1_SB_DQS_DN(2)
    U1 EK24 DDR4_SB_DQS_DN2 SOCKET4677_AZIF0045P001C01CS-SA     I7 @S9S_MB_2U_LIB.S9S_MB_2U(SCH_1):PAGE55
   J25  127 DQS2_B_C SCONN288_ADR50017P130CC-SCONN2A   I181 @S9S_MB_2U_LIB.S9S_MB_2U(SCH_1):PAGE106
   J26  127 DQS2_B_C SCONN288_ADR50017P087CC-SCONN2A   I181 @S9S_MB_2U_LIB.S9S_MB_2U(SCH_1):PAGE107

M_E_CPU1_SB_DQS_DN<3> @S9S_MB_2U_LIB.S9S_MB_2U(SCH_1):M_E_CPU1_SB_DQS_DN(3)
    U1 EK18 DDR4_SB_DQS_DN3 SOCKET4677_AZIF0045P001C01CS-SA     I7 @S9S_MB_2U_LIB.S9S_MB_2U(SCH_1):PAGE55
   J25  138 DQS3_B_C SCONN288_ADR50017P130CC-SCONN2A   I181 @S9S_MB_2U_LIB.S9S_MB_2U(SCH_1):PAGE106
   J26  138 DQS3_B_C SCONN288_ADR50017P087CC-SCONN2A   I181 @S9S_MB_2U_LIB.S9S_MB_2U(SCH_1):PAGE107

M_E_CPU1_SB_DQS_DN<4> @S9S_MB_2U_LIB.S9S_MB_2U(SCH_1):M_E_CPU1_SB_DQS_DN(4)
    U1 ET36 DDR4_SB_DQS_DN4 SOCKET4677_AZIF0045P001C01CS-SA     I7 @S9S_MB_2U_LIB.S9S_MB_2U(SCH_1):PAGE55
   J25  238 DQS4_B_C SCONN288_ADR50017P130CC-SCONN2A   I181 @S9S_MB_2U_LIB.S9S_MB_2U(SCH_1):PAGE106
   J26  238 DQS4_B_C SCONN288_ADR50017P087CC-SCONN2A   I181 @S9S_MB_2U_LIB.S9S_MB_2U(SCH_1):PAGE107

M_E_CPU1_SB_DQS_DN<5> @S9S_MB_2U_LIB.S9S_MB_2U(SCH_1):M_E_CPU1_SB_DQS_DN(5)
    U1 EJ27 DDR4_SB_DQS_DN5 SOCKET4677_AZIF0045P001C01CS-SA     I7 @S9S_MB_2U_LIB.S9S_MB_2U(SCH_1):PAGE55
   J25  249 DQS5_B_C||TDQS5_B_C SCONN288_ADR50017P130CC-SCONN2A   I181 @S9S_MB_2U_LIB.S9S_MB_2U(SCH_1):PAGE106
   J26  249 DQS5_B_C||TDQS5_B_C SCONN288_ADR50017P087CC-SCONN2A   I181 @S9S_MB_2U_LIB.S9S_MB_2U(SCH_1):PAGE107

M_E_CPU1_SB_DQS_DN<6> @S9S_MB_2U_LIB.S9S_MB_2U(SCH_1):M_E_CPU1_SB_DQS_DN(6)
    U1 ET30 DDR4_SB_DQS_DN6 SOCKET4677_AZIF0045P001C01CS-SA     I7 @S9S_MB_2U_LIB.S9S_MB_2U(SCH_1):PAGE55
   J25  260 DQS6_B_C||TDQS6_B_C SCONN288_ADR50017P130CC-SCONN2A   I181 @S9S_MB_2U_LIB.S9S_MB_2U(SCH_1):PAGE106
   J26  260 DQS6_B_C||TDQS6_B_C SCONN288_ADR50017P087CC-SCONN2A   I181 @S9S_MB_2U_LIB.S9S_MB_2U(SCH_1):PAGE107

M_E_CPU1_SB_DQS_DN<7> @S9S_MB_2U_LIB.S9S_MB_2U(SCH_1):M_E_CPU1_SB_DQS_DN(7)
    U1 ET24 DDR4_SB_DQS_DN7 SOCKET4677_AZIF0045P001C01CS-SA     I7 @S9S_MB_2U_LIB.S9S_MB_2U(SCH_1):PAGE55
   J25  271 DQS7_B_C||TDQS7_B_C SCONN288_ADR50017P130CC-SCONN2A   I181 @S9S_MB_2U_LIB.S9S_MB_2U(SCH_1):PAGE106
   J26  271 DQS7_B_C||TDQS7_B_C SCONN288_ADR50017P087CC-SCONN2A   I181 @S9S_MB_2U_LIB.S9S_MB_2U(SCH_1):PAGE107

M_E_CPU1_SB_DQS_DN<8> @S9S_MB_2U_LIB.S9S_MB_2U(SCH_1):M_E_CPU1_SB_DQS_DN(8)
    U1 ET18 DDR4_SB_DQS_DN8 SOCKET4677_AZIF0045P001C01CS-SA     I7 @S9S_MB_2U_LIB.S9S_MB_2U(SCH_1):PAGE55
   J25  282 DQS8_B_C||TDQS8_B_C SCONN288_ADR50017P130CC-SCONN2A   I181 @S9S_MB_2U_LIB.S9S_MB_2U(SCH_1):PAGE106
   J26  282 DQS8_B_C||TDQS8_B_C SCONN288_ADR50017P087CC-SCONN2A   I181 @S9S_MB_2U_LIB.S9S_MB_2U(SCH_1):PAGE107

M_E_CPU1_SB_DQS_DN<9> @S9S_MB_2U_LIB.S9S_MB_2U(SCH_1):M_E_CPU1_SB_DQS_DN(9)
    U1 EK36 DDR4_SB_DQS_DN9 SOCKET4677_AZIF0045P001C01CS-SA     I7 @S9S_MB_2U_LIB.S9S_MB_2U(SCH_1):PAGE55
   J25   94 DQS9_B_C||TDQS9_B_C SCONN288_ADR50017P130CC-SCONN2A   I181 @S9S_MB_2U_LIB.S9S_MB_2U(SCH_1):PAGE106
   J26   94 DQS9_B_C||TDQS9_B_C SCONN288_ADR50017P087CC-SCONN2A   I181 @S9S_MB_2U_LIB.S9S_MB_2U(SCH_1):PAGE107

M_E_CPU1_SB_DQS_DP<0> @S9S_MB_2U_LIB.S9S_MB_2U(SCH_1):M_E_CPU1_SB_DQS_DP(0)
    U1 EC27 DDR4_SB_DQS_DP0 SOCKET4677_AZIF0045P001C01CS-SA     I7 @S9S_MB_2U_LIB.S9S_MB_2U(SCH_1):PAGE55
   J25  104 DQS0_B_T SCONN288_ADR50017P130CC-SCONN2A   I181 @S9S_MB_2U_LIB.S9S_MB_2U(SCH_1):PAGE106
   J26  104 DQS0_B_T SCONN288_ADR50017P087CC-SCONN2A   I181 @S9S_MB_2U_LIB.S9S_MB_2U(SCH_1):PAGE107

M_E_CPU1_SB_DQS_DP<1> @S9S_MB_2U_LIB.S9S_MB_2U(SCH_1):M_E_CPU1_SB_DQS_DP(1)
    U1 EM30 DDR4_SB_DQS_DP1 SOCKET4677_AZIF0045P001C01CS-SA     I7 @S9S_MB_2U_LIB.S9S_MB_2U(SCH_1):PAGE55
   J25  115 DQS1_B_T SCONN288_ADR50017P130CC-SCONN2A   I181 @S9S_MB_2U_LIB.S9S_MB_2U(SCH_1):PAGE106
   J26  115 DQS1_B_T SCONN288_ADR50017P087CC-SCONN2A   I181 @S9S_MB_2U_LIB.S9S_MB_2U(SCH_1):PAGE107

M_E_CPU1_SB_DQS_DP<2> @S9S_MB_2U_LIB.S9S_MB_2U(SCH_1):M_E_CPU1_SB_DQS_DP(2)
    U1 EM24 DDR4_SB_DQS_DP2 SOCKET4677_AZIF0045P001C01CS-SA     I7 @S9S_MB_2U_LIB.S9S_MB_2U(SCH_1):PAGE55
   J25  126 DQS2_B_T SCONN288_ADR50017P130CC-SCONN2A   I181 @S9S_MB_2U_LIB.S9S_MB_2U(SCH_1):PAGE106
   J26  126 DQS2_B_T SCONN288_ADR50017P087CC-SCONN2A   I181 @S9S_MB_2U_LIB.S9S_MB_2U(SCH_1):PAGE107

M_E_CPU1_SB_DQS_DP<3> @S9S_MB_2U_LIB.S9S_MB_2U(SCH_1):M_E_CPU1_SB_DQS_DP(3)
    U1 EM18 DDR4_SB_DQS_DP3 SOCKET4677_AZIF0045P001C01CS-SA     I7 @S9S_MB_2U_LIB.S9S_MB_2U(SCH_1):PAGE55
   J25  137 DQS3_B_T SCONN288_ADR50017P130CC-SCONN2A   I181 @S9S_MB_2U_LIB.S9S_MB_2U(SCH_1):PAGE106
   J26  137 DQS3_B_T SCONN288_ADR50017P087CC-SCONN2A   I181 @S9S_MB_2U_LIB.S9S_MB_2U(SCH_1):PAGE107

M_E_CPU1_SB_DQS_DP<4> @S9S_MB_2U_LIB.S9S_MB_2U(SCH_1):M_E_CPU1_SB_DQS_DP(4)
    U1 EP36 DDR4_SB_DQS_DP4 SOCKET4677_AZIF0045P001C01CS-SA     I7 @S9S_MB_2U_LIB.S9S_MB_2U(SCH_1):PAGE55
   J25  239 DQS4_B_T SCONN288_ADR50017P130CC-SCONN2A   I181 @S9S_MB_2U_LIB.S9S_MB_2U(SCH_1):PAGE106
   J26  239 DQS4_B_T SCONN288_ADR50017P087CC-SCONN2A   I181 @S9S_MB_2U_LIB.S9S_MB_2U(SCH_1):PAGE107

M_E_CPU1_SB_DQS_DP<5> @S9S_MB_2U_LIB.S9S_MB_2U(SCH_1):M_E_CPU1_SB_DQS_DP(5)
    U1 EG27 DDR4_SB_DQS_DP5 SOCKET4677_AZIF0045P001C01CS-SA     I7 @S9S_MB_2U_LIB.S9S_MB_2U(SCH_1):PAGE55
   J25  250 DQS5_B_T||TDQS5_B_T SCONN288_ADR50017P130CC-SCONN2A   I181 @S9S_MB_2U_LIB.S9S_MB_2U(SCH_1):PAGE106
   J26  250 DQS5_B_T||TDQS5_B_T SCONN288_ADR50017P087CC-SCONN2A   I181 @S9S_MB_2U_LIB.S9S_MB_2U(SCH_1):PAGE107

M_E_CPU1_SB_DQS_DP<6> @S9S_MB_2U_LIB.S9S_MB_2U(SCH_1):M_E_CPU1_SB_DQS_DP(6)
    U1 EP30 DDR4_SB_DQS_DP6 SOCKET4677_AZIF0045P001C01CS-SA     I7 @S9S_MB_2U_LIB.S9S_MB_2U(SCH_1):PAGE55
   J25  261 DQS6_B_T||TDQS6_B_T SCONN288_ADR50017P130CC-SCONN2A   I181 @S9S_MB_2U_LIB.S9S_MB_2U(SCH_1):PAGE106
   J26  261 DQS6_B_T||TDQS6_B_T SCONN288_ADR50017P087CC-SCONN2A   I181 @S9S_MB_2U_LIB.S9S_MB_2U(SCH_1):PAGE107

M_E_CPU1_SB_DQS_DP<7> @S9S_MB_2U_LIB.S9S_MB_2U(SCH_1):M_E_CPU1_SB_DQS_DP(7)
    U1 EP24 DDR4_SB_DQS_DP7 SOCKET4677_AZIF0045P001C01CS-SA     I7 @S9S_MB_2U_LIB.S9S_MB_2U(SCH_1):PAGE55
   J25  272 DQS7_B_T||TDQS7_B_T SCONN288_ADR50017P130CC-SCONN2A   I181 @S9S_MB_2U_LIB.S9S_MB_2U(SCH_1):PAGE106
   J26  272 DQS7_B_T||TDQS7_B_T SCONN288_ADR50017P087CC-SCONN2A   I181 @S9S_MB_2U_LIB.S9S_MB_2U(SCH_1):PAGE107

M_E_CPU1_SB_DQS_DP<8> @S9S_MB_2U_LIB.S9S_MB_2U(SCH_1):M_E_CPU1_SB_DQS_DP(8)
    U1 EP18 DDR4_SB_DQS_DP8 SOCKET4677_AZIF0045P001C01CS-SA     I7 @S9S_MB_2U_LIB.S9S_MB_2U(SCH_1):PAGE55
   J25  283 DQS8_B_T||TDQS8_B_T SCONN288_ADR50017P130CC-SCONN2A   I181 @S9S_MB_2U_LIB.S9S_MB_2U(SCH_1):PAGE106
   J26  283 DQS8_B_T||TDQS8_B_T SCONN288_ADR50017P087CC-SCONN2A   I181 @S9S_MB_2U_LIB.S9S_MB_2U(SCH_1):PAGE107

M_E_CPU1_SB_DQS_DP<9> @S9S_MB_2U_LIB.S9S_MB_2U(SCH_1):M_E_CPU1_SB_DQS_DP(9)
    U1 EM36 DDR4_SB_DQS_DP9 SOCKET4677_AZIF0045P001C01CS-SA     I7 @S9S_MB_2U_LIB.S9S_MB_2U(SCH_1):PAGE55
   J25   93 DQS9_B_T||TDQS9_B_T||DBI4_B_N SCONN288_ADR50017P130CC-SCONN2A   I181 @S9S_MB_2U_LIB.S9S_MB_2U(SCH_1):PAGE106
   J26   93 DQS9_B_T||TDQS9_B_T||DBI4_B_N SCONN288_ADR50017P087CC-SCONN2A   I181 @S9S_MB_2U_LIB.S9S_MB_2U(SCH_1):PAGE107

M_E_CPU1_SB_PAR @S9S_MB_2U_LIB.S9S_MB_2U(SCH_1):M_E_CPU1_SB_PAR
    U1 EP42 DDR4_SB_PAR SOCKET4677_AZIF0045P001C01CS-SA     I7 @S9S_MB_2U_LIB.S9S_MB_2U(SCH_1):PAGE55
   J25  227  PAR_B SCONN288_ADR50017P130CC-SCONN2A   I180 @S9S_MB_2U_LIB.S9S_MB_2U(SCH_1):PAGE106
   J26  227  PAR_B SCONN288_ADR50017P087CC-SCONN2A   I180 @S9S_MB_2U_LIB.S9S_MB_2U(SCH_1):PAGE107

M_E_CPU1_SB_RSP<0> @S9S_MB_2U_LIB.S9S_MB_2U(SCH_1):M_E_CPU1_SB_RSP(0)
    U1 DF44 DDR4_B_RSP0 SOCKET4677_AZIF0045P001C01CS-SA     I7 @S9S_MB_2U_LIB.S9S_MB_2U(SCH_1):PAGE55
   J25   87 LBS||RSP_B_N SCONN288_ADR50017P130CC-SCONN2A   I180 @S9S_MB_2U_LIB.S9S_MB_2U(SCH_1):PAGE106

M_E_CPU1_SB_RSP<1> @S9S_MB_2U_LIB.S9S_MB_2U(SCH_1):M_E_CPU1_SB_RSP(1)
    U1 DG43 DDR4_B_RSP1 SOCKET4677_AZIF0045P001C01CS-SA     I7 @S9S_MB_2U_LIB.S9S_MB_2U(SCH_1):PAGE55
   J26   87 LBS||RSP_B_N SCONN288_ADR50017P087CC-SCONN2A   I180 @S9S_MB_2U_LIB.S9S_MB_2U(SCH_1):PAGE107

M_F_CPU0_ALERT_N @S9S_MB_2U_LIB.S9S_MB_2U(SCH_1):M_F_CPU0_ALERT_N
    U2 CW48 DDR5_ALERT_N SOCKET4677_AZIF0045P001C01CS-SA   I169 @S9S_MB_2U_LIB.S9S_MB_2U(SCH_1):PAGE25
   J11   62 ALERT_N SCONN288_ADR50017P130CC-SCONN2A    I25 @S9S_MB_2U_LIB.S9S_MB_2U(SCH_1):PAGE92
   J12   62 ALERT_N SCONN288_ADR50017P087CC-SCONN2A    I24 @S9S_MB_2U_LIB.S9S_MB_2U(SCH_1):PAGE93

M_F_CPU0_CLK_DN<0> @S9S_MB_2U_LIB.S9S_MB_2U(SCH_1):M_F_CPU0_CLK_DN(0)
    U2 DY49 DDR5_CLK_DN0 SOCKET4677_AZIF0045P001C01CS-SA   I169 @S9S_MB_2U_LIB.S9S_MB_2U(SCH_1):PAGE25
   J11  218   CK_C SCONN288_ADR50017P130CC-SCONN2A    I25 @S9S_MB_2U_LIB.S9S_MB_2U(SCH_1):PAGE92

M_F_CPU0_CLK_DN<1> @S9S_MB_2U_LIB.S9S_MB_2U(SCH_1):M_F_CPU0_CLK_DN(1)
    U2 DV49 DDR5_CLK_DN1 SOCKET4677_AZIF0045P001C01CS-SA   I169 @S9S_MB_2U_LIB.S9S_MB_2U(SCH_1):PAGE25
   J12  218   CK_C SCONN288_ADR50017P087CC-SCONN2A    I24 @S9S_MB_2U_LIB.S9S_MB_2U(SCH_1):PAGE93

M_F_CPU0_CLK_DP<0> @S9S_MB_2U_LIB.S9S_MB_2U(SCH_1):M_F_CPU0_CLK_DP(0)
    U2 EB49 DDR5_CLK_DP0 SOCKET4677_AZIF0045P001C01CS-SA   I169 @S9S_MB_2U_LIB.S9S_MB_2U(SCH_1):PAGE25
   J11  217   CK_T SCONN288_ADR50017P130CC-SCONN2A    I25 @S9S_MB_2U_LIB.S9S_MB_2U(SCH_1):PAGE92

M_F_CPU0_CLK_DP<1> @S9S_MB_2U_LIB.S9S_MB_2U(SCH_1):M_F_CPU0_CLK_DP(1)
    U2 DT49 DDR5_CLK_DP1 SOCKET4677_AZIF0045P001C01CS-SA   I169 @S9S_MB_2U_LIB.S9S_MB_2U(SCH_1):PAGE25
   J12  217   CK_T SCONN288_ADR50017P087CC-SCONN2A    I24 @S9S_MB_2U_LIB.S9S_MB_2U(SCH_1):PAGE93

M_F_CPU0_SA_CA<0> @S9S_MB_2U_LIB.S9S_MB_2U(SCH_1):M_F_CPU0_SA_CA(0)
    U2 EC52 DDR5_SA_CA0 SOCKET4677_AZIF0045P001C01CS-SA   I169 @S9S_MB_2U_LIB.S9S_MB_2U(SCH_1):PAGE25
   J11   66  CA0_A SCONN288_ADR50017P130CC-SCONN2A    I25 @S9S_MB_2U_LIB.S9S_MB_2U(SCH_1):PAGE92
   J12   66  CA0_A SCONN288_ADR50017P087CC-SCONN2A    I24 @S9S_MB_2U_LIB.S9S_MB_2U(SCH_1):PAGE93

M_F_CPU0_SA_CA<1> @S9S_MB_2U_LIB.S9S_MB_2U(SCH_1):M_F_CPU0_SA_CA(1)
    U2 EJ52 DDR5_SA_CA1 SOCKET4677_AZIF0045P001C01CS-SA   I169 @S9S_MB_2U_LIB.S9S_MB_2U(SCH_1):PAGE25
   J11  211  CA1_A SCONN288_ADR50017P130CC-SCONN2A    I25 @S9S_MB_2U_LIB.S9S_MB_2U(SCH_1):PAGE92
   J12  211  CA1_A SCONN288_ADR50017P087CC-SCONN2A    I24 @S9S_MB_2U_LIB.S9S_MB_2U(SCH_1):PAGE93

M_F_CPU0_SA_CA<2> @S9S_MB_2U_LIB.S9S_MB_2U(SCH_1):M_F_CPU0_SA_CA(2)
    U2 ED51 DDR5_SA_CA2 SOCKET4677_AZIF0045P001C01CS-SA   I169 @S9S_MB_2U_LIB.S9S_MB_2U(SCH_1):PAGE25
   J11   68  CA2_A SCONN288_ADR50017P130CC-SCONN2A    I25 @S9S_MB_2U_LIB.S9S_MB_2U(SCH_1):PAGE92
   J12   68  CA2_A SCONN288_ADR50017P087CC-SCONN2A    I24 @S9S_MB_2U_LIB.S9S_MB_2U(SCH_1):PAGE93

M_F_CPU0_SA_CA<3> @S9S_MB_2U_LIB.S9S_MB_2U(SCH_1):M_F_CPU0_SA_CA(3)
    U2 EH51 DDR5_SA_CA3 SOCKET4677_AZIF0045P001C01CS-SA   I169 @S9S_MB_2U_LIB.S9S_MB_2U(SCH_1):PAGE25
   J11  213  CA3_A SCONN288_ADR50017P130CC-SCONN2A    I25 @S9S_MB_2U_LIB.S9S_MB_2U(SCH_1):PAGE92
   J12  213  CA3_A SCONN288_ADR50017P087CC-SCONN2A    I24 @S9S_MB_2U_LIB.S9S_MB_2U(SCH_1):PAGE93

M_F_CPU0_SA_CA<4> @S9S_MB_2U_LIB.S9S_MB_2U(SCH_1):M_F_CPU0_SA_CA(4)
    U2 EE50 DDR5_SA_CA4 SOCKET4677_AZIF0045P001C01CS-SA   I169 @S9S_MB_2U_LIB.S9S_MB_2U(SCH_1):PAGE25
   J11   70  CA4_A SCONN288_ADR50017P130CC-SCONN2A    I25 @S9S_MB_2U_LIB.S9S_MB_2U(SCH_1):PAGE92
   J12   70  CA4_A SCONN288_ADR50017P087CC-SCONN2A    I24 @S9S_MB_2U_LIB.S9S_MB_2U(SCH_1):PAGE93

M_F_CPU0_SA_CA<5> @S9S_MB_2U_LIB.S9S_MB_2U(SCH_1):M_F_CPU0_SA_CA(5)
    U2 EG50 DDR5_SA_CA5 SOCKET4677_AZIF0045P001C01CS-SA   I169 @S9S_MB_2U_LIB.S9S_MB_2U(SCH_1):PAGE25
   J11  215  CA5_A SCONN288_ADR50017P130CC-SCONN2A    I25 @S9S_MB_2U_LIB.S9S_MB_2U(SCH_1):PAGE92
   J12  215  CA5_A SCONN288_ADR50017P087CC-SCONN2A    I24 @S9S_MB_2U_LIB.S9S_MB_2U(SCH_1):PAGE93

M_F_CPU0_SA_CA<6> @S9S_MB_2U_LIB.S9S_MB_2U(SCH_1):M_F_CPU0_SA_CA(6)
    U2 DY51 DDR5_SA_CA6 SOCKET4677_AZIF0045P001C01CS-SA   I169 @S9S_MB_2U_LIB.S9S_MB_2U(SCH_1):PAGE25
   J11   72  CA6_A SCONN288_ADR50017P130CC-SCONN2A    I25 @S9S_MB_2U_LIB.S9S_MB_2U(SCH_1):PAGE92
   J12   72  CA6_A SCONN288_ADR50017P087CC-SCONN2A    I24 @S9S_MB_2U_LIB.S9S_MB_2U(SCH_1):PAGE93

M_F_CPU0_SA_CB<0> @S9S_MB_2U_LIB.S9S_MB_2U(SCH_1):M_F_CPU0_SA_CB(0)
    U2 EE60 DDR5_SA_ECC0 SOCKET4677_AZIF0045P001C01CS-SA   I169 @S9S_MB_2U_LIB.S9S_MB_2U(SCH_1):PAGE25
   J11   51  CB0_A SCONN288_ADR50017P130CC-SCONN2A    I25 @S9S_MB_2U_LIB.S9S_MB_2U(SCH_1):PAGE92
   J12   51  CB0_A SCONN288_ADR50017P087CC-SCONN2A    I24 @S9S_MB_2U_LIB.S9S_MB_2U(SCH_1):PAGE93

M_F_CPU0_SA_CB<1> @S9S_MB_2U_LIB.S9S_MB_2U(SCH_1):M_F_CPU0_SA_CB(1)
    U2 ED59 DDR5_SA_ECC1 SOCKET4677_AZIF0045P001C01CS-SA   I169 @S9S_MB_2U_LIB.S9S_MB_2U(SCH_1):PAGE25
   J11   53  CB1_A SCONN288_ADR50017P130CC-SCONN2A    I25 @S9S_MB_2U_LIB.S9S_MB_2U(SCH_1):PAGE92
   J12   53  CB1_A SCONN288_ADR50017P087CC-SCONN2A    I24 @S9S_MB_2U_LIB.S9S_MB_2U(SCH_1):PAGE93

M_F_CPU0_SA_CB<2> @S9S_MB_2U_LIB.S9S_MB_2U(SCH_1):M_F_CPU0_SA_CB(2)
    U2 EG60 DDR5_SA_ECC2 SOCKET4677_AZIF0045P001C01CS-SA   I169 @S9S_MB_2U_LIB.S9S_MB_2U(SCH_1):PAGE25
   J11  196  CB2_A SCONN288_ADR50017P130CC-SCONN2A    I25 @S9S_MB_2U_LIB.S9S_MB_2U(SCH_1):PAGE92
   J12  196  CB2_A SCONN288_ADR50017P087CC-SCONN2A    I24 @S9S_MB_2U_LIB.S9S_MB_2U(SCH_1):PAGE93

M_F_CPU0_SA_CB<3> @S9S_MB_2U_LIB.S9S_MB_2U(SCH_1):M_F_CPU0_SA_CB(3)
    U2 EH59 DDR5_SA_ECC3 SOCKET4677_AZIF0045P001C01CS-SA   I169 @S9S_MB_2U_LIB.S9S_MB_2U(SCH_1):PAGE25
   J11  198  CB3_A SCONN288_ADR50017P130CC-SCONN2A    I25 @S9S_MB_2U_LIB.S9S_MB_2U(SCH_1):PAGE92
   J12  198  CB3_A SCONN288_ADR50017P087CC-SCONN2A    I24 @S9S_MB_2U_LIB.S9S_MB_2U(SCH_1):PAGE93

M_F_CPU0_SA_CB<4> @S9S_MB_2U_LIB.S9S_MB_2U(SCH_1):M_F_CPU0_SA_CB(4)
    U2 ED57 DDR5_SA_ECC4 SOCKET4677_AZIF0045P001C01CS-SA   I169 @S9S_MB_2U_LIB.S9S_MB_2U(SCH_1):PAGE25
   J11   58  CB4_A SCONN288_ADR50017P130CC-SCONN2A    I25 @S9S_MB_2U_LIB.S9S_MB_2U(SCH_1):PAGE92
   J12   58  CB4_A SCONN288_ADR50017P087CC-SCONN2A    I24 @S9S_MB_2U_LIB.S9S_MB_2U(SCH_1):PAGE93

M_F_CPU0_SA_CB<5> @S9S_MB_2U_LIB.S9S_MB_2U(SCH_1):M_F_CPU0_SA_CB(5)
    U2 EE56 DDR5_SA_ECC5 SOCKET4677_AZIF0045P001C01CS-SA   I169 @S9S_MB_2U_LIB.S9S_MB_2U(SCH_1):PAGE25
   J11   60  CB5_A SCONN288_ADR50017P130CC-SCONN2A    I25 @S9S_MB_2U_LIB.S9S_MB_2U(SCH_1):PAGE92
   J12   60  CB5_A SCONN288_ADR50017P087CC-SCONN2A    I24 @S9S_MB_2U_LIB.S9S_MB_2U(SCH_1):PAGE93

M_F_CPU0_SA_CB<6> @S9S_MB_2U_LIB.S9S_MB_2U(SCH_1):M_F_CPU0_SA_CB(6)
    U2 EH57 DDR5_SA_ECC6 SOCKET4677_AZIF0045P001C01CS-SA   I169 @S9S_MB_2U_LIB.S9S_MB_2U(SCH_1):PAGE25
   J11  203  CB6_A SCONN288_ADR50017P130CC-SCONN2A    I25 @S9S_MB_2U_LIB.S9S_MB_2U(SCH_1):PAGE92
   J12  203  CB6_A SCONN288_ADR50017P087CC-SCONN2A    I24 @S9S_MB_2U_LIB.S9S_MB_2U(SCH_1):PAGE93

M_F_CPU0_SA_CB<7> @S9S_MB_2U_LIB.S9S_MB_2U(SCH_1):M_F_CPU0_SA_CB(7)
    U2 EG56 DDR5_SA_ECC7 SOCKET4677_AZIF0045P001C01CS-SA   I169 @S9S_MB_2U_LIB.S9S_MB_2U(SCH_1):PAGE25
   J11  205  CB7_A SCONN288_ADR50017P130CC-SCONN2A    I25 @S9S_MB_2U_LIB.S9S_MB_2U(SCH_1):PAGE92
   J12  205  CB7_A SCONN288_ADR50017P087CC-SCONN2A    I24 @S9S_MB_2U_LIB.S9S_MB_2U(SCH_1):PAGE93

M_F_CPU0_SA_CS_N<0> @S9S_MB_2U_LIB.S9S_MB_2U(SCH_1):M_F_CPU0_SA_CS_N(0)
    U2 EG54 DDR5_SA_CS_N0 SOCKET4677_AZIF0045P001C01CS-SA   I169 @S9S_MB_2U_LIB.S9S_MB_2U(SCH_1):PAGE25
   J11   64 CS0_A_N SCONN288_ADR50017P130CC-SCONN2A    I25 @S9S_MB_2U_LIB.S9S_MB_2U(SCH_1):PAGE92

M_F_CPU0_SA_CS_N<1> @S9S_MB_2U_LIB.S9S_MB_2U(SCH_1):M_F_CPU0_SA_CS_N(1)
    U2 EH53 DDR5_SA_CS_N1 SOCKET4677_AZIF0045P001C01CS-SA   I169 @S9S_MB_2U_LIB.S9S_MB_2U(SCH_1):PAGE25
   J11  209 CS1_A_N SCONN288_ADR50017P130CC-SCONN2A    I25 @S9S_MB_2U_LIB.S9S_MB_2U(SCH_1):PAGE92

M_F_CPU0_SA_CS_N<2> @S9S_MB_2U_LIB.S9S_MB_2U(SCH_1):M_F_CPU0_SA_CS_N(2)
    U2 EE54 DDR5_SA_CS_N2 SOCKET4677_AZIF0045P001C01CS-SA   I169 @S9S_MB_2U_LIB.S9S_MB_2U(SCH_1):PAGE25
   J12   64 CS0_A_N SCONN288_ADR50017P087CC-SCONN2A    I24 @S9S_MB_2U_LIB.S9S_MB_2U(SCH_1):PAGE93

M_F_CPU0_SA_CS_N<3> @S9S_MB_2U_LIB.S9S_MB_2U(SCH_1):M_F_CPU0_SA_CS_N(3)
    U2 ED53 DDR5_SA_CS_N3 SOCKET4677_AZIF0045P001C01CS-SA   I169 @S9S_MB_2U_LIB.S9S_MB_2U(SCH_1):PAGE25
   J12  209 CS1_A_N SCONN288_ADR50017P087CC-SCONN2A    I24 @S9S_MB_2U_LIB.S9S_MB_2U(SCH_1):PAGE93

M_F_CPU0_SA_DQ<0> @S9S_MB_2U_LIB.S9S_MB_2U(SCH_1):M_F_CPU0_SA_DQ(0)
    U2 EB77 DDR5_SA_DQ0 SOCKET4677_AZIF0045P001C01CS-SA   I169 @S9S_MB_2U_LIB.S9S_MB_2U(SCH_1):PAGE25
   J11    7  DQ0_A SCONN288_ADR50017P130CC-SCONN2A    I25 @S9S_MB_2U_LIB.S9S_MB_2U(SCH_1):PAGE92
   J12    7  DQ0_A SCONN288_ADR50017P087CC-SCONN2A    I24 @S9S_MB_2U_LIB.S9S_MB_2U(SCH_1):PAGE93

M_F_CPU0_SA_DQ<10> @S9S_MB_2U_LIB.S9S_MB_2U(SCH_1):M_F_CPU0_SA_DQ(10)
    U2 DY69 DDR5_SA_DQ10 SOCKET4677_AZIF0045P001C01CS-SA   I169 @S9S_MB_2U_LIB.S9S_MB_2U(SCH_1):PAGE25
   J11  163 DQ10_A SCONN288_ADR50017P130CC-SCONN2A    I25 @S9S_MB_2U_LIB.S9S_MB_2U(SCH_1):PAGE92
   J12  163 DQ10_A SCONN288_ADR50017P087CC-SCONN2A    I24 @S9S_MB_2U_LIB.S9S_MB_2U(SCH_1):PAGE93

M_F_CPU0_SA_DQ<11> @S9S_MB_2U_LIB.S9S_MB_2U(SCH_1):M_F_CPU0_SA_DQ(11)
    U2 EA68 DDR5_SA_DQ11 SOCKET4677_AZIF0045P001C01CS-SA   I169 @S9S_MB_2U_LIB.S9S_MB_2U(SCH_1):PAGE25
   J11  165 DQ11_A SCONN288_ADR50017P130CC-SCONN2A    I25 @S9S_MB_2U_LIB.S9S_MB_2U(SCH_1):PAGE92
   J12  165 DQ11_A SCONN288_ADR50017P087CC-SCONN2A    I24 @S9S_MB_2U_LIB.S9S_MB_2U(SCH_1):PAGE93

M_F_CPU0_SA_DQ<12> @S9S_MB_2U_LIB.S9S_MB_2U(SCH_1):M_F_CPU0_SA_DQ(12)
    U2 DU66 DDR5_SA_DQ12 SOCKET4677_AZIF0045P001C01CS-SA   I169 @S9S_MB_2U_LIB.S9S_MB_2U(SCH_1):PAGE25
   J11   25 DQ12_A SCONN288_ADR50017P130CC-SCONN2A    I25 @S9S_MB_2U_LIB.S9S_MB_2U(SCH_1):PAGE92
   J12   25 DQ12_A SCONN288_ADR50017P087CC-SCONN2A    I24 @S9S_MB_2U_LIB.S9S_MB_2U(SCH_1):PAGE93

M_F_CPU0_SA_DQ<13> @S9S_MB_2U_LIB.S9S_MB_2U(SCH_1):M_F_CPU0_SA_DQ(13)
    U2 DV65 DDR5_SA_DQ13 SOCKET4677_AZIF0045P001C01CS-SA   I169 @S9S_MB_2U_LIB.S9S_MB_2U(SCH_1):PAGE25
   J11   27 DQ13_A SCONN288_ADR50017P130CC-SCONN2A    I25 @S9S_MB_2U_LIB.S9S_MB_2U(SCH_1):PAGE92
   J12   27 DQ13_A SCONN288_ADR50017P087CC-SCONN2A    I24 @S9S_MB_2U_LIB.S9S_MB_2U(SCH_1):PAGE93

M_F_CPU0_SA_DQ<14> @S9S_MB_2U_LIB.S9S_MB_2U(SCH_1):M_F_CPU0_SA_DQ(14)
    U2 EA66 DDR5_SA_DQ14 SOCKET4677_AZIF0045P001C01CS-SA   I169 @S9S_MB_2U_LIB.S9S_MB_2U(SCH_1):PAGE25
   J11  170 DQ14_A SCONN288_ADR50017P130CC-SCONN2A    I25 @S9S_MB_2U_LIB.S9S_MB_2U(SCH_1):PAGE92
   J12  170 DQ14_A SCONN288_ADR50017P087CC-SCONN2A    I24 @S9S_MB_2U_LIB.S9S_MB_2U(SCH_1):PAGE93

M_F_CPU0_SA_DQ<15> @S9S_MB_2U_LIB.S9S_MB_2U(SCH_1):M_F_CPU0_SA_DQ(15)
    U2 DY65 DDR5_SA_DQ15 SOCKET4677_AZIF0045P001C01CS-SA   I169 @S9S_MB_2U_LIB.S9S_MB_2U(SCH_1):PAGE25
   J11  172 DQ15_A SCONN288_ADR50017P130CC-SCONN2A    I25 @S9S_MB_2U_LIB.S9S_MB_2U(SCH_1):PAGE92
   J12  172 DQ15_A SCONN288_ADR50017P087CC-SCONN2A    I24 @S9S_MB_2U_LIB.S9S_MB_2U(SCH_1):PAGE93

M_F_CPU0_SA_DQ<16> @S9S_MB_2U_LIB.S9S_MB_2U(SCH_1):M_F_CPU0_SA_DQ(16)
    U2 EE66 DDR5_SA_DQ16 SOCKET4677_AZIF0045P001C01CS-SA   I169 @S9S_MB_2U_LIB.S9S_MB_2U(SCH_1):PAGE25
   J11   29 DQ16_A SCONN288_ADR50017P130CC-SCONN2A    I25 @S9S_MB_2U_LIB.S9S_MB_2U(SCH_1):PAGE92
   J12   29 DQ16_A SCONN288_ADR50017P087CC-SCONN2A    I24 @S9S_MB_2U_LIB.S9S_MB_2U(SCH_1):PAGE93

M_F_CPU0_SA_DQ<17> @S9S_MB_2U_LIB.S9S_MB_2U(SCH_1):M_F_CPU0_SA_DQ(17)
    U2 ED65 DDR5_SA_DQ17 SOCKET4677_AZIF0045P001C01CS-SA   I169 @S9S_MB_2U_LIB.S9S_MB_2U(SCH_1):PAGE25
   J11   31 DQ17_A SCONN288_ADR50017P130CC-SCONN2A    I25 @S9S_MB_2U_LIB.S9S_MB_2U(SCH_1):PAGE92
   J12   31 DQ17_A SCONN288_ADR50017P087CC-SCONN2A    I24 @S9S_MB_2U_LIB.S9S_MB_2U(SCH_1):PAGE93

M_F_CPU0_SA_DQ<18> @S9S_MB_2U_LIB.S9S_MB_2U(SCH_1):M_F_CPU0_SA_DQ(18)
    U2 EG66 DDR5_SA_DQ18 SOCKET4677_AZIF0045P001C01CS-SA   I169 @S9S_MB_2U_LIB.S9S_MB_2U(SCH_1):PAGE25
   J11  174 DQ18_A SCONN288_ADR50017P130CC-SCONN2A    I25 @S9S_MB_2U_LIB.S9S_MB_2U(SCH_1):PAGE92
   J12  174 DQ18_A SCONN288_ADR50017P087CC-SCONN2A    I24 @S9S_MB_2U_LIB.S9S_MB_2U(SCH_1):PAGE93

M_F_CPU0_SA_DQ<19> @S9S_MB_2U_LIB.S9S_MB_2U(SCH_1):M_F_CPU0_SA_DQ(19)
    U2 EH65 DDR5_SA_DQ19 SOCKET4677_AZIF0045P001C01CS-SA   I169 @S9S_MB_2U_LIB.S9S_MB_2U(SCH_1):PAGE25
   J11  176 DQ19_A SCONN288_ADR50017P130CC-SCONN2A    I25 @S9S_MB_2U_LIB.S9S_MB_2U(SCH_1):PAGE92
   J12  176 DQ19_A SCONN288_ADR50017P087CC-SCONN2A    I24 @S9S_MB_2U_LIB.S9S_MB_2U(SCH_1):PAGE93

M_F_CPU0_SA_DQ<1> @S9S_MB_2U_LIB.S9S_MB_2U(SCH_1):M_F_CPU0_SA_DQ(1)
    U2 EH77 DDR5_SA_DQ1 SOCKET4677_AZIF0045P001C01CS-SA   I169 @S9S_MB_2U_LIB.S9S_MB_2U(SCH_1):PAGE25
   J11    9  DQ1_A SCONN288_ADR50017P130CC-SCONN2A    I25 @S9S_MB_2U_LIB.S9S_MB_2U(SCH_1):PAGE92
   J12    9  DQ1_A SCONN288_ADR50017P087CC-SCONN2A    I24 @S9S_MB_2U_LIB.S9S_MB_2U(SCH_1):PAGE93

M_F_CPU0_SA_DQ<20> @S9S_MB_2U_LIB.S9S_MB_2U(SCH_1):M_F_CPU0_SA_DQ(20)
    U2 ED63 DDR5_SA_DQ20 SOCKET4677_AZIF0045P001C01CS-SA   I169 @S9S_MB_2U_LIB.S9S_MB_2U(SCH_1):PAGE25
   J11   36 DQ20_A SCONN288_ADR50017P130CC-SCONN2A    I25 @S9S_MB_2U_LIB.S9S_MB_2U(SCH_1):PAGE92
   J12   36 DQ20_A SCONN288_ADR50017P087CC-SCONN2A    I24 @S9S_MB_2U_LIB.S9S_MB_2U(SCH_1):PAGE93

M_F_CPU0_SA_DQ<21> @S9S_MB_2U_LIB.S9S_MB_2U(SCH_1):M_F_CPU0_SA_DQ(21)
    U2 EE62 DDR5_SA_DQ21 SOCKET4677_AZIF0045P001C01CS-SA   I169 @S9S_MB_2U_LIB.S9S_MB_2U(SCH_1):PAGE25
   J11   38 DQ21_A SCONN288_ADR50017P130CC-SCONN2A    I25 @S9S_MB_2U_LIB.S9S_MB_2U(SCH_1):PAGE92
   J12   38 DQ21_A SCONN288_ADR50017P087CC-SCONN2A    I24 @S9S_MB_2U_LIB.S9S_MB_2U(SCH_1):PAGE93

M_F_CPU0_SA_DQ<22> @S9S_MB_2U_LIB.S9S_MB_2U(SCH_1):M_F_CPU0_SA_DQ(22)
    U2 EH63 DDR5_SA_DQ22 SOCKET4677_AZIF0045P001C01CS-SA   I169 @S9S_MB_2U_LIB.S9S_MB_2U(SCH_1):PAGE25
   J11  181 DQ22_A SCONN288_ADR50017P130CC-SCONN2A    I25 @S9S_MB_2U_LIB.S9S_MB_2U(SCH_1):PAGE92
   J12  181 DQ22_A SCONN288_ADR50017P087CC-SCONN2A    I24 @S9S_MB_2U_LIB.S9S_MB_2U(SCH_1):PAGE93

M_F_CPU0_SA_DQ<23> @S9S_MB_2U_LIB.S9S_MB_2U(SCH_1):M_F_CPU0_SA_DQ(23)
    U2 EG62 DDR5_SA_DQ23 SOCKET4677_AZIF0045P001C01CS-SA   I169 @S9S_MB_2U_LIB.S9S_MB_2U(SCH_1):PAGE25
   J11  183 DQ23_A SCONN288_ADR50017P130CC-SCONN2A    I25 @S9S_MB_2U_LIB.S9S_MB_2U(SCH_1):PAGE92
   J12  183 DQ23_A SCONN288_ADR50017P087CC-SCONN2A    I24 @S9S_MB_2U_LIB.S9S_MB_2U(SCH_1):PAGE93

M_F_CPU0_SA_DQ<24> @S9S_MB_2U_LIB.S9S_MB_2U(SCH_1):M_F_CPU0_SA_DQ(24)
    U2 DV57 DDR5_SA_DQ24 SOCKET4677_AZIF0045P001C01CS-SA   I169 @S9S_MB_2U_LIB.S9S_MB_2U(SCH_1):PAGE25
   J11   40 DQ24_A SCONN288_ADR50017P130CC-SCONN2A    I25 @S9S_MB_2U_LIB.S9S_MB_2U(SCH_1):PAGE92
   J12   40 DQ24_A SCONN288_ADR50017P087CC-SCONN2A    I24 @S9S_MB_2U_LIB.S9S_MB_2U(SCH_1):PAGE93

M_F_CPU0_SA_DQ<25> @S9S_MB_2U_LIB.S9S_MB_2U(SCH_1):M_F_CPU0_SA_DQ(25)
    U2 DU56 DDR5_SA_DQ25 SOCKET4677_AZIF0045P001C01CS-SA   I169 @S9S_MB_2U_LIB.S9S_MB_2U(SCH_1):PAGE25
   J11   42 DQ25_A SCONN288_ADR50017P130CC-SCONN2A    I25 @S9S_MB_2U_LIB.S9S_MB_2U(SCH_1):PAGE92
   J12   42 DQ25_A SCONN288_ADR50017P087CC-SCONN2A    I24 @S9S_MB_2U_LIB.S9S_MB_2U(SCH_1):PAGE93

M_F_CPU0_SA_DQ<26> @S9S_MB_2U_LIB.S9S_MB_2U(SCH_1):M_F_CPU0_SA_DQ(26)
    U2 DY57 DDR5_SA_DQ26 SOCKET4677_AZIF0045P001C01CS-SA   I169 @S9S_MB_2U_LIB.S9S_MB_2U(SCH_1):PAGE25
   J11  185 DQ26_A SCONN288_ADR50017P130CC-SCONN2A    I25 @S9S_MB_2U_LIB.S9S_MB_2U(SCH_1):PAGE92
   J12  185 DQ26_A SCONN288_ADR50017P087CC-SCONN2A    I24 @S9S_MB_2U_LIB.S9S_MB_2U(SCH_1):PAGE93

M_F_CPU0_SA_DQ<27> @S9S_MB_2U_LIB.S9S_MB_2U(SCH_1):M_F_CPU0_SA_DQ(27)
    U2 EA56 DDR5_SA_DQ27 SOCKET4677_AZIF0045P001C01CS-SA   I169 @S9S_MB_2U_LIB.S9S_MB_2U(SCH_1):PAGE25
   J11  187 DQ27_A SCONN288_ADR50017P130CC-SCONN2A    I25 @S9S_MB_2U_LIB.S9S_MB_2U(SCH_1):PAGE92
   J12  187 DQ27_A SCONN288_ADR50017P087CC-SCONN2A    I24 @S9S_MB_2U_LIB.S9S_MB_2U(SCH_1):PAGE93

M_F_CPU0_SA_DQ<28> @S9S_MB_2U_LIB.S9S_MB_2U(SCH_1):M_F_CPU0_SA_DQ(28)
    U2 DU54 DDR5_SA_DQ28 SOCKET4677_AZIF0045P001C01CS-SA   I169 @S9S_MB_2U_LIB.S9S_MB_2U(SCH_1):PAGE25
   J11   47 DQ28_A SCONN288_ADR50017P130CC-SCONN2A    I25 @S9S_MB_2U_LIB.S9S_MB_2U(SCH_1):PAGE92
   J12   47 DQ28_A SCONN288_ADR50017P087CC-SCONN2A    I24 @S9S_MB_2U_LIB.S9S_MB_2U(SCH_1):PAGE93

M_F_CPU0_SA_DQ<29> @S9S_MB_2U_LIB.S9S_MB_2U(SCH_1):M_F_CPU0_SA_DQ(29)
    U2 DV53 DDR5_SA_DQ29 SOCKET4677_AZIF0045P001C01CS-SA   I169 @S9S_MB_2U_LIB.S9S_MB_2U(SCH_1):PAGE25
   J11   49 DQ29_A SCONN288_ADR50017P130CC-SCONN2A    I25 @S9S_MB_2U_LIB.S9S_MB_2U(SCH_1):PAGE92
   J12   49 DQ29_A SCONN288_ADR50017P087CC-SCONN2A    I24 @S9S_MB_2U_LIB.S9S_MB_2U(SCH_1):PAGE93

M_F_CPU0_SA_DQ<2> @S9S_MB_2U_LIB.S9S_MB_2U(SCH_1):M_F_CPU0_SA_DQ(2)
    U2 ED77 DDR5_SA_DQ2 SOCKET4677_AZIF0045P001C01CS-SA   I169 @S9S_MB_2U_LIB.S9S_MB_2U(SCH_1):PAGE25
   J11  152  DQ2_A SCONN288_ADR50017P130CC-SCONN2A    I25 @S9S_MB_2U_LIB.S9S_MB_2U(SCH_1):PAGE92
   J12  152  DQ2_A SCONN288_ADR50017P087CC-SCONN2A    I24 @S9S_MB_2U_LIB.S9S_MB_2U(SCH_1):PAGE93

M_F_CPU0_SA_DQ<30> @S9S_MB_2U_LIB.S9S_MB_2U(SCH_1):M_F_CPU0_SA_DQ(30)
    U2 EA54 DDR5_SA_DQ30 SOCKET4677_AZIF0045P001C01CS-SA   I169 @S9S_MB_2U_LIB.S9S_MB_2U(SCH_1):PAGE25
   J11  192 DQ30_A SCONN288_ADR50017P130CC-SCONN2A    I25 @S9S_MB_2U_LIB.S9S_MB_2U(SCH_1):PAGE92
   J12  192 DQ30_A SCONN288_ADR50017P087CC-SCONN2A    I24 @S9S_MB_2U_LIB.S9S_MB_2U(SCH_1):PAGE93

M_F_CPU0_SA_DQ<31> @S9S_MB_2U_LIB.S9S_MB_2U(SCH_1):M_F_CPU0_SA_DQ(31)
    U2 DY53 DDR5_SA_DQ31 SOCKET4677_AZIF0045P001C01CS-SA   I169 @S9S_MB_2U_LIB.S9S_MB_2U(SCH_1):PAGE25
   J11  194 DQ31_A SCONN288_ADR50017P130CC-SCONN2A    I25 @S9S_MB_2U_LIB.S9S_MB_2U(SCH_1):PAGE92
   J12  194 DQ31_A SCONN288_ADR50017P087CC-SCONN2A    I24 @S9S_MB_2U_LIB.S9S_MB_2U(SCH_1):PAGE93

M_F_CPU0_SA_DQ<3> @S9S_MB_2U_LIB.S9S_MB_2U(SCH_1):M_F_CPU0_SA_DQ(3)
    U2 EG78 DDR5_SA_DQ3 SOCKET4677_AZIF0045P001C01CS-SA   I169 @S9S_MB_2U_LIB.S9S_MB_2U(SCH_1):PAGE25
   J11  154  DQ3_A SCONN288_ADR50017P130CC-SCONN2A    I25 @S9S_MB_2U_LIB.S9S_MB_2U(SCH_1):PAGE92
   J12  154  DQ3_A SCONN288_ADR50017P087CC-SCONN2A    I24 @S9S_MB_2U_LIB.S9S_MB_2U(SCH_1):PAGE93

M_F_CPU0_SA_DQ<4> @S9S_MB_2U_LIB.S9S_MB_2U(SCH_1):M_F_CPU0_SA_DQ(4)
    U2 ED75 DDR5_SA_DQ4 SOCKET4677_AZIF0045P001C01CS-SA   I169 @S9S_MB_2U_LIB.S9S_MB_2U(SCH_1):PAGE25
   J11   14  DQ4_A SCONN288_ADR50017P130CC-SCONN2A    I25 @S9S_MB_2U_LIB.S9S_MB_2U(SCH_1):PAGE92
   J12   14  DQ4_A SCONN288_ADR50017P087CC-SCONN2A    I24 @S9S_MB_2U_LIB.S9S_MB_2U(SCH_1):PAGE93

M_F_CPU0_SA_DQ<5> @S9S_MB_2U_LIB.S9S_MB_2U(SCH_1):M_F_CPU0_SA_DQ(5)
    U2 EE74 DDR5_SA_DQ5 SOCKET4677_AZIF0045P001C01CS-SA   I169 @S9S_MB_2U_LIB.S9S_MB_2U(SCH_1):PAGE25
   J11   16  DQ5_A SCONN288_ADR50017P130CC-SCONN2A    I25 @S9S_MB_2U_LIB.S9S_MB_2U(SCH_1):PAGE92
   J12   16  DQ5_A SCONN288_ADR50017P087CC-SCONN2A    I24 @S9S_MB_2U_LIB.S9S_MB_2U(SCH_1):PAGE93

M_F_CPU0_SA_DQ<6> @S9S_MB_2U_LIB.S9S_MB_2U(SCH_1):M_F_CPU0_SA_DQ(6)
    U2 EH75 DDR5_SA_DQ6 SOCKET4677_AZIF0045P001C01CS-SA   I169 @S9S_MB_2U_LIB.S9S_MB_2U(SCH_1):PAGE25
   J11  159  DQ6_A SCONN288_ADR50017P130CC-SCONN2A    I25 @S9S_MB_2U_LIB.S9S_MB_2U(SCH_1):PAGE92
   J12  159  DQ6_A SCONN288_ADR50017P087CC-SCONN2A    I24 @S9S_MB_2U_LIB.S9S_MB_2U(SCH_1):PAGE93

M_F_CPU0_SA_DQ<7> @S9S_MB_2U_LIB.S9S_MB_2U(SCH_1):M_F_CPU0_SA_DQ(7)
    U2 EG74 DDR5_SA_DQ7 SOCKET4677_AZIF0045P001C01CS-SA   I169 @S9S_MB_2U_LIB.S9S_MB_2U(SCH_1):PAGE25
   J11  161  DQ7_A SCONN288_ADR50017P130CC-SCONN2A    I25 @S9S_MB_2U_LIB.S9S_MB_2U(SCH_1):PAGE92
   J12  161  DQ7_A SCONN288_ADR50017P087CC-SCONN2A    I24 @S9S_MB_2U_LIB.S9S_MB_2U(SCH_1):PAGE93

M_F_CPU0_SA_DQ<8> @S9S_MB_2U_LIB.S9S_MB_2U(SCH_1):M_F_CPU0_SA_DQ(8)
    U2 DV69 DDR5_SA_DQ8 SOCKET4677_AZIF0045P001C01CS-SA   I169 @S9S_MB_2U_LIB.S9S_MB_2U(SCH_1):PAGE25
   J11   18  DQ8_A SCONN288_ADR50017P130CC-SCONN2A    I25 @S9S_MB_2U_LIB.S9S_MB_2U(SCH_1):PAGE92
   J12   18  DQ8_A SCONN288_ADR50017P087CC-SCONN2A    I24 @S9S_MB_2U_LIB.S9S_MB_2U(SCH_1):PAGE93

M_F_CPU0_SA_DQ<9> @S9S_MB_2U_LIB.S9S_MB_2U(SCH_1):M_F_CPU0_SA_DQ(9)
    U2 DU68 DDR5_SA_DQ9 SOCKET4677_AZIF0045P001C01CS-SA   I169 @S9S_MB_2U_LIB.S9S_MB_2U(SCH_1):PAGE25
   J11   20  DQ9_A SCONN288_ADR50017P130CC-SCONN2A    I25 @S9S_MB_2U_LIB.S9S_MB_2U(SCH_1):PAGE92
   J12   20  DQ9_A SCONN288_ADR50017P087CC-SCONN2A    I24 @S9S_MB_2U_LIB.S9S_MB_2U(SCH_1):PAGE93

M_F_CPU0_SA_DQS_DN<0> @S9S_MB_2U_LIB.S9S_MB_2U(SCH_1):M_F_CPU0_SA_DQS_DN(0)
    U2 EE76 DDR5_SA_DQS_DN0 SOCKET4677_AZIF0045P001C01CS-SA   I169 @S9S_MB_2U_LIB.S9S_MB_2U(SCH_1):PAGE25
   J11   12 DQS0_A_C SCONN288_ADR50017P130CC-SCONN2A   I178 @S9S_MB_2U_LIB.S9S_MB_2U(SCH_1):PAGE92
   J12   12 DQS0_A_C SCONN288_ADR50017P087CC-SCONN2A   I178 @S9S_MB_2U_LIB.S9S_MB_2U(SCH_1):PAGE93

M_F_CPU0_SA_DQS_DN<1> @S9S_MB_2U_LIB.S9S_MB_2U(SCH_1):M_F_CPU0_SA_DQS_DN(1)
    U2 DT67 DDR5_SA_DQS_DN1 SOCKET4677_AZIF0045P001C01CS-SA   I169 @S9S_MB_2U_LIB.S9S_MB_2U(SCH_1):PAGE25
   J11   23 DQS1_A_C SCONN288_ADR50017P130CC-SCONN2A   I178 @S9S_MB_2U_LIB.S9S_MB_2U(SCH_1):PAGE92
   J12   23 DQS1_A_C SCONN288_ADR50017P087CC-SCONN2A   I178 @S9S_MB_2U_LIB.S9S_MB_2U(SCH_1):PAGE93

M_F_CPU0_SA_DQS_DN<2> @S9S_MB_2U_LIB.S9S_MB_2U(SCH_1):M_F_CPU0_SA_DQS_DN(2)
    U2 EC64 DDR5_SA_DQS_DN2 SOCKET4677_AZIF0045P001C01CS-SA   I169 @S9S_MB_2U_LIB.S9S_MB_2U(SCH_1):PAGE25
   J11   34 DQS2_A_C SCONN288_ADR50017P130CC-SCONN2A   I178 @S9S_MB_2U_LIB.S9S_MB_2U(SCH_1):PAGE92
   J12   34 DQS2_A_C SCONN288_ADR50017P087CC-SCONN2A   I178 @S9S_MB_2U_LIB.S9S_MB_2U(SCH_1):PAGE93

M_F_CPU0_SA_DQS_DN<3> @S9S_MB_2U_LIB.S9S_MB_2U(SCH_1):M_F_CPU0_SA_DQS_DN(3)
    U2 DV55 DDR5_SA_DQS_DN3 SOCKET4677_AZIF0045P001C01CS-SA   I169 @S9S_MB_2U_LIB.S9S_MB_2U(SCH_1):PAGE25
   J11   45 DQS3_A_C SCONN288_ADR50017P130CC-SCONN2A   I178 @S9S_MB_2U_LIB.S9S_MB_2U(SCH_1):PAGE92
   J12   45 DQS3_A_C SCONN288_ADR50017P087CC-SCONN2A   I178 @S9S_MB_2U_LIB.S9S_MB_2U(SCH_1):PAGE93

M_F_CPU0_SA_DQS_DN<4> @S9S_MB_2U_LIB.S9S_MB_2U(SCH_1):M_F_CPU0_SA_DQS_DN(4)
    U2 EE58 DDR5_SA_DQS_DN4 SOCKET4677_AZIF0045P001C01CS-SA   I169 @S9S_MB_2U_LIB.S9S_MB_2U(SCH_1):PAGE25
   J11   56 DQS4_A_C SCONN288_ADR50017P130CC-SCONN2A   I178 @S9S_MB_2U_LIB.S9S_MB_2U(SCH_1):PAGE92
   J12   56 DQS4_A_C SCONN288_ADR50017P087CC-SCONN2A   I178 @S9S_MB_2U_LIB.S9S_MB_2U(SCH_1):PAGE93

M_F_CPU0_SA_DQS_DN<5> @S9S_MB_2U_LIB.S9S_MB_2U(SCH_1):M_F_CPU0_SA_DQS_DN(5)
    U2 EJ76 DDR5_SA_DQS_DN5 SOCKET4677_AZIF0045P001C01CS-SA   I169 @S9S_MB_2U_LIB.S9S_MB_2U(SCH_1):PAGE25
   J11  156 DQS5_A_C||TDQS5_A_C||DQS5_A_T||TDQS5_A_T SCONN288_ADR50017P130CC-SCONN2A   I178 @S9S_MB_2U_LIB.S9S_MB_2U(SCH_1):PAGE92
   J12  156 DQS5_A_C||TDQS5_A_C||DQS5_A_T||TDQS5_A_T SCONN288_ADR50017P087CC-SCONN2A   I178 @S9S_MB_2U_LIB.S9S_MB_2U(SCH_1):PAGE93

M_F_CPU0_SA_DQS_DN<6> @S9S_MB_2U_LIB.S9S_MB_2U(SCH_1):M_F_CPU0_SA_DQS_DN(6)
    U2 EB67 DDR5_SA_DQS_DN6 SOCKET4677_AZIF0045P001C01CS-SA   I169 @S9S_MB_2U_LIB.S9S_MB_2U(SCH_1):PAGE25
   J11  167 DQS6_A_C||TDQS6_A_C||DQS6_A_T||TDQS6_A_T SCONN288_ADR50017P130CC-SCONN2A   I178 @S9S_MB_2U_LIB.S9S_MB_2U(SCH_1):PAGE92
   J12  167 DQS6_A_C||TDQS6_A_C||DQS6_A_T||TDQS6_A_T SCONN288_ADR50017P087CC-SCONN2A   I178 @S9S_MB_2U_LIB.S9S_MB_2U(SCH_1):PAGE93

M_F_CPU0_SA_DQS_DN<7> @S9S_MB_2U_LIB.S9S_MB_2U(SCH_1):M_F_CPU0_SA_DQS_DN(7)
    U2 EJ64 DDR5_SA_DQS_DN7 SOCKET4677_AZIF0045P001C01CS-SA   I169 @S9S_MB_2U_LIB.S9S_MB_2U(SCH_1):PAGE25
   J11  178 DQS7_A_C||TDQS7_A_C SCONN288_ADR50017P130CC-SCONN2A   I178 @S9S_MB_2U_LIB.S9S_MB_2U(SCH_1):PAGE92
   J12  178 DQS7_A_C||TDQS7_A_C SCONN288_ADR50017P087CC-SCONN2A   I178 @S9S_MB_2U_LIB.S9S_MB_2U(SCH_1):PAGE93

M_F_CPU0_SA_DQS_DN<8> @S9S_MB_2U_LIB.S9S_MB_2U(SCH_1):M_F_CPU0_SA_DQS_DN(8)
    U2 EB55 DDR5_SA_DQS_DN8 SOCKET4677_AZIF0045P001C01CS-SA   I169 @S9S_MB_2U_LIB.S9S_MB_2U(SCH_1):PAGE25
   J11  189 DQS8_A_C||TDQS8_A_C SCONN288_ADR50017P130CC-SCONN2A   I178 @S9S_MB_2U_LIB.S9S_MB_2U(SCH_1):PAGE92
   J12  189 DQS8_A_C||TDQS8_A_C SCONN288_ADR50017P087CC-SCONN2A   I178 @S9S_MB_2U_LIB.S9S_MB_2U(SCH_1):PAGE93

M_F_CPU0_SA_DQS_DN<9> @S9S_MB_2U_LIB.S9S_MB_2U(SCH_1):M_F_CPU0_SA_DQS_DN(9)
    U2 EJ58 DDR5_SA_DQS_DN9 SOCKET4677_AZIF0045P001C01CS-SA   I169 @S9S_MB_2U_LIB.S9S_MB_2U(SCH_1):PAGE25
   J11  200 DQS9_A_C||TDQS9_A_C SCONN288_ADR50017P130CC-SCONN2A   I178 @S9S_MB_2U_LIB.S9S_MB_2U(SCH_1):PAGE92
   J12  200 DQS9_A_C||TDQS9_A_C SCONN288_ADR50017P087CC-SCONN2A   I178 @S9S_MB_2U_LIB.S9S_MB_2U(SCH_1):PAGE93

M_F_CPU0_SA_DQS_DP<0> @S9S_MB_2U_LIB.S9S_MB_2U(SCH_1):M_F_CPU0_SA_DQS_DP(0)
    U2 EC76 DDR5_SA_DQS_DP0 SOCKET4677_AZIF0045P001C01CS-SA   I169 @S9S_MB_2U_LIB.S9S_MB_2U(SCH_1):PAGE25
   J11   11 DQS0_A_T SCONN288_ADR50017P130CC-SCONN2A   I178 @S9S_MB_2U_LIB.S9S_MB_2U(SCH_1):PAGE92
   J12   11 DQS0_A_T SCONN288_ADR50017P087CC-SCONN2A   I178 @S9S_MB_2U_LIB.S9S_MB_2U(SCH_1):PAGE93

M_F_CPU0_SA_DQS_DP<1> @S9S_MB_2U_LIB.S9S_MB_2U(SCH_1):M_F_CPU0_SA_DQS_DP(1)
    U2 DV67 DDR5_SA_DQS_DP1 SOCKET4677_AZIF0045P001C01CS-SA   I169 @S9S_MB_2U_LIB.S9S_MB_2U(SCH_1):PAGE25
   J11   22 DQS1_A_T SCONN288_ADR50017P130CC-SCONN2A   I178 @S9S_MB_2U_LIB.S9S_MB_2U(SCH_1):PAGE92
   J12   22 DQS1_A_T SCONN288_ADR50017P087CC-SCONN2A   I178 @S9S_MB_2U_LIB.S9S_MB_2U(SCH_1):PAGE93

M_F_CPU0_SA_DQS_DP<2> @S9S_MB_2U_LIB.S9S_MB_2U(SCH_1):M_F_CPU0_SA_DQS_DP(2)
    U2 EE64 DDR5_SA_DQS_DP2 SOCKET4677_AZIF0045P001C01CS-SA   I169 @S9S_MB_2U_LIB.S9S_MB_2U(SCH_1):PAGE25
   J11   33 DQS2_A_T SCONN288_ADR50017P130CC-SCONN2A   I178 @S9S_MB_2U_LIB.S9S_MB_2U(SCH_1):PAGE92
   J12   33 DQS2_A_T SCONN288_ADR50017P087CC-SCONN2A   I178 @S9S_MB_2U_LIB.S9S_MB_2U(SCH_1):PAGE93

M_F_CPU0_SA_DQS_DP<3> @S9S_MB_2U_LIB.S9S_MB_2U(SCH_1):M_F_CPU0_SA_DQS_DP(3)
    U2 DT55 DDR5_SA_DQS_DP3 SOCKET4677_AZIF0045P001C01CS-SA   I169 @S9S_MB_2U_LIB.S9S_MB_2U(SCH_1):PAGE25
   J11   44 DQS3_A_T SCONN288_ADR50017P130CC-SCONN2A   I178 @S9S_MB_2U_LIB.S9S_MB_2U(SCH_1):PAGE92
   J12   44 DQS3_A_T SCONN288_ADR50017P087CC-SCONN2A   I178 @S9S_MB_2U_LIB.S9S_MB_2U(SCH_1):PAGE93

M_F_CPU0_SA_DQS_DP<4> @S9S_MB_2U_LIB.S9S_MB_2U(SCH_1):M_F_CPU0_SA_DQS_DP(4)
    U2 EC58 DDR5_SA_DQS_DP4 SOCKET4677_AZIF0045P001C01CS-SA   I169 @S9S_MB_2U_LIB.S9S_MB_2U(SCH_1):PAGE25
   J11   55 DQS4_A_T SCONN288_ADR50017P130CC-SCONN2A   I178 @S9S_MB_2U_LIB.S9S_MB_2U(SCH_1):PAGE92
   J12   55 DQS4_A_T SCONN288_ADR50017P087CC-SCONN2A   I178 @S9S_MB_2U_LIB.S9S_MB_2U(SCH_1):PAGE93

M_F_CPU0_SA_DQS_DP<5> @S9S_MB_2U_LIB.S9S_MB_2U(SCH_1):M_F_CPU0_SA_DQS_DP(5)
    U2 EG76 DDR5_SA_DQS_DP5 SOCKET4677_AZIF0045P001C01CS-SA   I169 @S9S_MB_2U_LIB.S9S_MB_2U(SCH_1):PAGE25
   J11  157 DQS5_A_T||TDQS5_A_T SCONN288_ADR50017P130CC-SCONN2A   I178 @S9S_MB_2U_LIB.S9S_MB_2U(SCH_1):PAGE92
   J12  157 DQS5_A_T||TDQS5_A_T SCONN288_ADR50017P087CC-SCONN2A   I178 @S9S_MB_2U_LIB.S9S_MB_2U(SCH_1):PAGE93

M_F_CPU0_SA_DQS_DP<6> @S9S_MB_2U_LIB.S9S_MB_2U(SCH_1):M_F_CPU0_SA_DQS_DP(6)
    U2 DY67 DDR5_SA_DQS_DP6 SOCKET4677_AZIF0045P001C01CS-SA   I169 @S9S_MB_2U_LIB.S9S_MB_2U(SCH_1):PAGE25
   J11  168 DQS6_A_T||TDQS6_A_T SCONN288_ADR50017P130CC-SCONN2A   I178 @S9S_MB_2U_LIB.S9S_MB_2U(SCH_1):PAGE92
   J12  168 DQS6_A_T||TDQS6_A_T SCONN288_ADR50017P087CC-SCONN2A   I178 @S9S_MB_2U_LIB.S9S_MB_2U(SCH_1):PAGE93

M_F_CPU0_SA_DQS_DP<7> @S9S_MB_2U_LIB.S9S_MB_2U(SCH_1):M_F_CPU0_SA_DQS_DP(7)
    U2 EG64 DDR5_SA_DQS_DP7 SOCKET4677_AZIF0045P001C01CS-SA   I169 @S9S_MB_2U_LIB.S9S_MB_2U(SCH_1):PAGE25
   J11  179 DQS7_A_T||TDQS7_A_T SCONN288_ADR50017P130CC-SCONN2A   I178 @S9S_MB_2U_LIB.S9S_MB_2U(SCH_1):PAGE92
   J12  179 DQS7_A_T||TDQS7_A_T SCONN288_ADR50017P087CC-SCONN2A   I178 @S9S_MB_2U_LIB.S9S_MB_2U(SCH_1):PAGE93

M_F_CPU0_SA_DQS_DP<8> @S9S_MB_2U_LIB.S9S_MB_2U(SCH_1):M_F_CPU0_SA_DQS_DP(8)
    U2 DY55 DDR5_SA_DQS_DP8 SOCKET4677_AZIF0045P001C01CS-SA   I169 @S9S_MB_2U_LIB.S9S_MB_2U(SCH_1):PAGE25
   J11  190 DQS8_A_T||TDQS8_A_T SCONN288_ADR50017P130CC-SCONN2A   I178 @S9S_MB_2U_LIB.S9S_MB_2U(SCH_1):PAGE92
   J12  190 DQS8_A_T||TDQS8_A_T SCONN288_ADR50017P087CC-SCONN2A   I178 @S9S_MB_2U_LIB.S9S_MB_2U(SCH_1):PAGE93

M_F_CPU0_SA_DQS_DP<9> @S9S_MB_2U_LIB.S9S_MB_2U(SCH_1):M_F_CPU0_SA_DQS_DP(9)
    U2 EG58 DDR5_SA_DQS_DP9 SOCKET4677_AZIF0045P001C01CS-SA   I169 @S9S_MB_2U_LIB.S9S_MB_2U(SCH_1):PAGE25
   J11  201 DQS9_A_T||TDQS9_A_T SCONN288_ADR50017P130CC-SCONN2A   I178 @S9S_MB_2U_LIB.S9S_MB_2U(SCH_1):PAGE92
   J12  201 DQS9_A_T||TDQS9_A_T SCONN288_ADR50017P087CC-SCONN2A   I178 @S9S_MB_2U_LIB.S9S_MB_2U(SCH_1):PAGE93

M_F_CPU0_SA_PAR @S9S_MB_2U_LIB.S9S_MB_2U(SCH_1):M_F_CPU0_SA_PAR
    U2 EA50 DDR5_SA_PAR SOCKET4677_AZIF0045P001C01CS-SA   I169 @S9S_MB_2U_LIB.S9S_MB_2U(SCH_1):PAGE25
   J11   74  PAR_A SCONN288_ADR50017P130CC-SCONN2A    I25 @S9S_MB_2U_LIB.S9S_MB_2U(SCH_1):PAGE92
   J12   74  PAR_A SCONN288_ADR50017P087CC-SCONN2A    I24 @S9S_MB_2U_LIB.S9S_MB_2U(SCH_1):PAGE93

M_F_CPU0_SA_RSP<0> @S9S_MB_2U_LIB.S9S_MB_2U(SCH_1):M_F_CPU0_SA_RSP(0)
    U2 DN48 DDR5_A_RSP0 SOCKET4677_AZIF0045P001C01CS-SA   I169 @S9S_MB_2U_LIB.S9S_MB_2U(SCH_1):PAGE25
   J11   86 LBD||RSP_A_N SCONN288_ADR50017P130CC-SCONN2A    I25 @S9S_MB_2U_LIB.S9S_MB_2U(SCH_1):PAGE92

M_F_CPU0_SA_RSP<1> @S9S_MB_2U_LIB.S9S_MB_2U(SCH_1):M_F_CPU0_SA_RSP(1)
    U2 DP47 DDR5_A_RSP1 SOCKET4677_AZIF0045P001C01CS-SA   I169 @S9S_MB_2U_LIB.S9S_MB_2U(SCH_1):PAGE25
   J12   86 LBD||RSP_A_N SCONN288_ADR50017P087CC-SCONN2A    I24 @S9S_MB_2U_LIB.S9S_MB_2U(SCH_1):PAGE93

M_F_CPU0_SB_CA<0> @S9S_MB_2U_LIB.S9S_MB_2U(SCH_1):M_F_CPU0_SB_CA(0)
    U2 DV51 DDR5_SB_CA0 SOCKET4677_AZIF0045P001C01CS-SA   I169 @S9S_MB_2U_LIB.S9S_MB_2U(SCH_1):PAGE25
   J11   76  CA0_B SCONN288_ADR50017P130CC-SCONN2A    I25 @S9S_MB_2U_LIB.S9S_MB_2U(SCH_1):PAGE92
   J12   76  CA0_B SCONN288_ADR50017P087CC-SCONN2A    I24 @S9S_MB_2U_LIB.S9S_MB_2U(SCH_1):PAGE93

M_F_CPU0_SB_CA<1> @S9S_MB_2U_LIB.S9S_MB_2U(SCH_1):M_F_CPU0_SB_CA(1)
    U2 DU50 DDR5_SB_CA1 SOCKET4677_AZIF0045P001C01CS-SA   I169 @S9S_MB_2U_LIB.S9S_MB_2U(SCH_1):PAGE25
   J11  221  CA1_B SCONN288_ADR50017P130CC-SCONN2A    I25 @S9S_MB_2U_LIB.S9S_MB_2U(SCH_1):PAGE92
   J12  221  CA1_B SCONN288_ADR50017P087CC-SCONN2A    I24 @S9S_MB_2U_LIB.S9S_MB_2U(SCH_1):PAGE93

M_F_CPU0_SB_CA<2> @S9S_MB_2U_LIB.S9S_MB_2U(SCH_1):M_F_CPU0_SB_CA(2)
    U2 EE41 DDR5_SB_CA2 SOCKET4677_AZIF0045P001C01CS-SA   I169 @S9S_MB_2U_LIB.S9S_MB_2U(SCH_1):PAGE25
   J11   78  CA2_B SCONN288_ADR50017P130CC-SCONN2A    I25 @S9S_MB_2U_LIB.S9S_MB_2U(SCH_1):PAGE92
   J12   78  CA2_B SCONN288_ADR50017P087CC-SCONN2A    I24 @S9S_MB_2U_LIB.S9S_MB_2U(SCH_1):PAGE93

M_F_CPU0_SB_CA<3> @S9S_MB_2U_LIB.S9S_MB_2U(SCH_1):M_F_CPU0_SB_CA(3)
    U2 EG41 DDR5_SB_CA3 SOCKET4677_AZIF0045P001C01CS-SA   I169 @S9S_MB_2U_LIB.S9S_MB_2U(SCH_1):PAGE25
   J11  223  CA3_B SCONN288_ADR50017P130CC-SCONN2A    I25 @S9S_MB_2U_LIB.S9S_MB_2U(SCH_1):PAGE92
   J12  223  CA3_B SCONN288_ADR50017P087CC-SCONN2A    I24 @S9S_MB_2U_LIB.S9S_MB_2U(SCH_1):PAGE93

M_F_CPU0_SB_CA<4> @S9S_MB_2U_LIB.S9S_MB_2U(SCH_1):M_F_CPU0_SB_CA(4)
    U2 ED40 DDR5_SB_CA4 SOCKET4677_AZIF0045P001C01CS-SA   I169 @S9S_MB_2U_LIB.S9S_MB_2U(SCH_1):PAGE25
   J11   80  CA4_B SCONN288_ADR50017P130CC-SCONN2A    I25 @S9S_MB_2U_LIB.S9S_MB_2U(SCH_1):PAGE92
   J12   80  CA4_B SCONN288_ADR50017P087CC-SCONN2A    I24 @S9S_MB_2U_LIB.S9S_MB_2U(SCH_1):PAGE93

M_F_CPU0_SB_CA<5> @S9S_MB_2U_LIB.S9S_MB_2U(SCH_1):M_F_CPU0_SB_CA(5)
    U2 EH40 DDR5_SB_CA5 SOCKET4677_AZIF0045P001C01CS-SA   I169 @S9S_MB_2U_LIB.S9S_MB_2U(SCH_1):PAGE25
   J11  225  CA5_B SCONN288_ADR50017P130CC-SCONN2A    I25 @S9S_MB_2U_LIB.S9S_MB_2U(SCH_1):PAGE92
   J12  225  CA5_B SCONN288_ADR50017P087CC-SCONN2A    I24 @S9S_MB_2U_LIB.S9S_MB_2U(SCH_1):PAGE93

M_F_CPU0_SB_CA<6> @S9S_MB_2U_LIB.S9S_MB_2U(SCH_1):M_F_CPU0_SB_CA(6)
    U2 EC39 DDR5_SB_CA6 SOCKET4677_AZIF0045P001C01CS-SA   I169 @S9S_MB_2U_LIB.S9S_MB_2U(SCH_1):PAGE25
   J11   82  CA6_B SCONN288_ADR50017P130CC-SCONN2A    I25 @S9S_MB_2U_LIB.S9S_MB_2U(SCH_1):PAGE92
   J12   82  CA6_B SCONN288_ADR50017P087CC-SCONN2A    I24 @S9S_MB_2U_LIB.S9S_MB_2U(SCH_1):PAGE93

M_F_CPU0_SB_CB<0> @S9S_MB_2U_LIB.S9S_MB_2U(SCH_1):M_F_CPU0_SB_CB(0)
    U2 ED32 DDR5_SB_ECC0 SOCKET4677_AZIF0045P001C01CS-SA   I169 @S9S_MB_2U_LIB.S9S_MB_2U(SCH_1):PAGE25
   J11   96  CB0_B SCONN288_ADR50017P130CC-SCONN2A    I25 @S9S_MB_2U_LIB.S9S_MB_2U(SCH_1):PAGE92
   J12   96  CB0_B SCONN288_ADR50017P087CC-SCONN2A    I24 @S9S_MB_2U_LIB.S9S_MB_2U(SCH_1):PAGE93

M_F_CPU0_SB_CB<1> @S9S_MB_2U_LIB.S9S_MB_2U(SCH_1):M_F_CPU0_SB_CB(1)
    U2 EE31 DDR5_SB_ECC1 SOCKET4677_AZIF0045P001C01CS-SA   I169 @S9S_MB_2U_LIB.S9S_MB_2U(SCH_1):PAGE25
   J11   98  CB1_B SCONN288_ADR50017P130CC-SCONN2A    I25 @S9S_MB_2U_LIB.S9S_MB_2U(SCH_1):PAGE92
   J12   98  CB1_B SCONN288_ADR50017P087CC-SCONN2A    I24 @S9S_MB_2U_LIB.S9S_MB_2U(SCH_1):PAGE93

M_F_CPU0_SB_CB<2> @S9S_MB_2U_LIB.S9S_MB_2U(SCH_1):M_F_CPU0_SB_CB(2)
    U2 EH32 DDR5_SB_ECC2 SOCKET4677_AZIF0045P001C01CS-SA   I169 @S9S_MB_2U_LIB.S9S_MB_2U(SCH_1):PAGE25
   J11  241  CB2_B SCONN288_ADR50017P130CC-SCONN2A    I25 @S9S_MB_2U_LIB.S9S_MB_2U(SCH_1):PAGE92
   J12  241  CB2_B SCONN288_ADR50017P087CC-SCONN2A    I24 @S9S_MB_2U_LIB.S9S_MB_2U(SCH_1):PAGE93

M_F_CPU0_SB_CB<3> @S9S_MB_2U_LIB.S9S_MB_2U(SCH_1):M_F_CPU0_SB_CB(3)
    U2 EG31 DDR5_SB_ECC3 SOCKET4677_AZIF0045P001C01CS-SA   I169 @S9S_MB_2U_LIB.S9S_MB_2U(SCH_1):PAGE25
   J11  243  CB3_B SCONN288_ADR50017P130CC-SCONN2A    I25 @S9S_MB_2U_LIB.S9S_MB_2U(SCH_1):PAGE92
   J12  243  CB3_B SCONN288_ADR50017P087CC-SCONN2A    I24 @S9S_MB_2U_LIB.S9S_MB_2U(SCH_1):PAGE93

M_F_CPU0_SB_CB<4> @S9S_MB_2U_LIB.S9S_MB_2U(SCH_1):M_F_CPU0_SB_CB(4)
    U2 EE35 DDR5_SB_ECC4 SOCKET4677_AZIF0045P001C01CS-SA   I169 @S9S_MB_2U_LIB.S9S_MB_2U(SCH_1):PAGE25
   J11   89  CB4_B SCONN288_ADR50017P130CC-SCONN2A    I25 @S9S_MB_2U_LIB.S9S_MB_2U(SCH_1):PAGE92
   J12   89  CB4_B SCONN288_ADR50017P087CC-SCONN2A    I24 @S9S_MB_2U_LIB.S9S_MB_2U(SCH_1):PAGE93

M_F_CPU0_SB_CB<5> @S9S_MB_2U_LIB.S9S_MB_2U(SCH_1):M_F_CPU0_SB_CB(5)
    U2 ED34 DDR5_SB_ECC5 SOCKET4677_AZIF0045P001C01CS-SA   I169 @S9S_MB_2U_LIB.S9S_MB_2U(SCH_1):PAGE25
   J11   91  CB5_B SCONN288_ADR50017P130CC-SCONN2A    I25 @S9S_MB_2U_LIB.S9S_MB_2U(SCH_1):PAGE92
   J12   91  CB5_B SCONN288_ADR50017P087CC-SCONN2A    I24 @S9S_MB_2U_LIB.S9S_MB_2U(SCH_1):PAGE93

M_F_CPU0_SB_CB<6> @S9S_MB_2U_LIB.S9S_MB_2U(SCH_1):M_F_CPU0_SB_CB(6)
    U2 EG35 DDR5_SB_ECC6 SOCKET4677_AZIF0045P001C01CS-SA   I169 @S9S_MB_2U_LIB.S9S_MB_2U(SCH_1):PAGE25
   J11  234  CB6_B SCONN288_ADR50017P130CC-SCONN2A    I25 @S9S_MB_2U_LIB.S9S_MB_2U(SCH_1):PAGE92
   J12  234  CB6_B SCONN288_ADR50017P087CC-SCONN2A    I24 @S9S_MB_2U_LIB.S9S_MB_2U(SCH_1):PAGE93

M_F_CPU0_SB_CB<7> @S9S_MB_2U_LIB.S9S_MB_2U(SCH_1):M_F_CPU0_SB_CB(7)
    U2 EH34 DDR5_SB_ECC7 SOCKET4677_AZIF0045P001C01CS-SA   I169 @S9S_MB_2U_LIB.S9S_MB_2U(SCH_1):PAGE25
   J11  236  CB7_B SCONN288_ADR50017P130CC-SCONN2A    I25 @S9S_MB_2U_LIB.S9S_MB_2U(SCH_1):PAGE92
   J12  236  CB7_B SCONN288_ADR50017P087CC-SCONN2A    I24 @S9S_MB_2U_LIB.S9S_MB_2U(SCH_1):PAGE93

M_F_CPU0_SB_CS_N<0> @S9S_MB_2U_LIB.S9S_MB_2U(SCH_1):M_F_CPU0_SB_CS_N(0)
    U2 EH38 DDR5_SB_CS_N0 SOCKET4677_AZIF0045P001C01CS-SA   I169 @S9S_MB_2U_LIB.S9S_MB_2U(SCH_1):PAGE25
   J11   84 CS0_B_N SCONN288_ADR50017P130CC-SCONN2A    I25 @S9S_MB_2U_LIB.S9S_MB_2U(SCH_1):PAGE92

M_F_CPU0_SB_CS_N<1> @S9S_MB_2U_LIB.S9S_MB_2U(SCH_1):M_F_CPU0_SB_CS_N(1)
    U2 EG37 DDR5_SB_CS_N1 SOCKET4677_AZIF0045P001C01CS-SA   I169 @S9S_MB_2U_LIB.S9S_MB_2U(SCH_1):PAGE25
   J11  229 CS1_B_N SCONN288_ADR50017P130CC-SCONN2A    I25 @S9S_MB_2U_LIB.S9S_MB_2U(SCH_1):PAGE92

M_F_CPU0_SB_CS_N<2> @S9S_MB_2U_LIB.S9S_MB_2U(SCH_1):M_F_CPU0_SB_CS_N(2)
    U2 ED38 DDR5_SB_CS_N2 SOCKET4677_AZIF0045P001C01CS-SA   I169 @S9S_MB_2U_LIB.S9S_MB_2U(SCH_1):PAGE25
   J12   84 CS0_B_N SCONN288_ADR50017P087CC-SCONN2A    I24 @S9S_MB_2U_LIB.S9S_MB_2U(SCH_1):PAGE93

M_F_CPU0_SB_CS_N<3> @S9S_MB_2U_LIB.S9S_MB_2U(SCH_1):M_F_CPU0_SB_CS_N(3)
    U2 EE37 DDR5_SB_CS_N3 SOCKET4677_AZIF0045P001C01CS-SA   I169 @S9S_MB_2U_LIB.S9S_MB_2U(SCH_1):PAGE25
   J12  229 CS1_B_N SCONN288_ADR50017P087CC-SCONN2A    I24 @S9S_MB_2U_LIB.S9S_MB_2U(SCH_1):PAGE93

M_F_CPU0_SB_DQ<0> @S9S_MB_2U_LIB.S9S_MB_2U(SCH_1):M_F_CPU0_SB_DQ(0)
    U2 DV32 DDR5_SB_DQ0 SOCKET4677_AZIF0045P001C01CS-SA   I169 @S9S_MB_2U_LIB.S9S_MB_2U(SCH_1):PAGE25
   J11  100  DQ0_B SCONN288_ADR50017P130CC-SCONN2A    I25 @S9S_MB_2U_LIB.S9S_MB_2U(SCH_1):PAGE92
   J12  100  DQ0_B SCONN288_ADR50017P087CC-SCONN2A    I24 @S9S_MB_2U_LIB.S9S_MB_2U(SCH_1):PAGE93

M_F_CPU0_SB_DQ<10> @S9S_MB_2U_LIB.S9S_MB_2U(SCH_1):M_F_CPU0_SB_DQ(10)
    U2 EG23 DDR5_SB_DQ10 SOCKET4677_AZIF0045P001C01CS-SA   I169 @S9S_MB_2U_LIB.S9S_MB_2U(SCH_1):PAGE25
   J11  256 DQ10_B SCONN288_ADR50017P130CC-SCONN2A    I25 @S9S_MB_2U_LIB.S9S_MB_2U(SCH_1):PAGE92
   J12  256 DQ10_B SCONN288_ADR50017P087CC-SCONN2A    I24 @S9S_MB_2U_LIB.S9S_MB_2U(SCH_1):PAGE93

M_F_CPU0_SB_DQ<11> @S9S_MB_2U_LIB.S9S_MB_2U(SCH_1):M_F_CPU0_SB_DQ(11)
    U2 EH22 DDR5_SB_DQ11 SOCKET4677_AZIF0045P001C01CS-SA   I169 @S9S_MB_2U_LIB.S9S_MB_2U(SCH_1):PAGE25
   J11  258 DQ11_B SCONN288_ADR50017P130CC-SCONN2A    I25 @S9S_MB_2U_LIB.S9S_MB_2U(SCH_1):PAGE92
   J12  258 DQ11_B SCONN288_ADR50017P087CC-SCONN2A    I24 @S9S_MB_2U_LIB.S9S_MB_2U(SCH_1):PAGE93

M_F_CPU0_SB_DQ<12> @S9S_MB_2U_LIB.S9S_MB_2U(SCH_1):M_F_CPU0_SB_DQ(12)
    U2 ED20 DDR5_SB_DQ12 SOCKET4677_AZIF0045P001C01CS-SA   I169 @S9S_MB_2U_LIB.S9S_MB_2U(SCH_1):PAGE25
   J11  118 DQ12_B SCONN288_ADR50017P130CC-SCONN2A    I25 @S9S_MB_2U_LIB.S9S_MB_2U(SCH_1):PAGE92
   J12  118 DQ12_B SCONN288_ADR50017P087CC-SCONN2A    I24 @S9S_MB_2U_LIB.S9S_MB_2U(SCH_1):PAGE93

M_F_CPU0_SB_DQ<13> @S9S_MB_2U_LIB.S9S_MB_2U(SCH_1):M_F_CPU0_SB_DQ(13)
    U2 EE19 DDR5_SB_DQ13 SOCKET4677_AZIF0045P001C01CS-SA   I169 @S9S_MB_2U_LIB.S9S_MB_2U(SCH_1):PAGE25
   J11  120 DQ13_B SCONN288_ADR50017P130CC-SCONN2A    I25 @S9S_MB_2U_LIB.S9S_MB_2U(SCH_1):PAGE92
   J12  120 DQ13_B SCONN288_ADR50017P087CC-SCONN2A    I24 @S9S_MB_2U_LIB.S9S_MB_2U(SCH_1):PAGE93

M_F_CPU0_SB_DQ<14> @S9S_MB_2U_LIB.S9S_MB_2U(SCH_1):M_F_CPU0_SB_DQ(14)
    U2 EH20 DDR5_SB_DQ14 SOCKET4677_AZIF0045P001C01CS-SA   I169 @S9S_MB_2U_LIB.S9S_MB_2U(SCH_1):PAGE25
   J11  263 DQ14_B SCONN288_ADR50017P130CC-SCONN2A    I25 @S9S_MB_2U_LIB.S9S_MB_2U(SCH_1):PAGE92
   J12  263 DQ14_B SCONN288_ADR50017P087CC-SCONN2A    I24 @S9S_MB_2U_LIB.S9S_MB_2U(SCH_1):PAGE93

M_F_CPU0_SB_DQ<15> @S9S_MB_2U_LIB.S9S_MB_2U(SCH_1):M_F_CPU0_SB_DQ(15)
    U2 EG19 DDR5_SB_DQ15 SOCKET4677_AZIF0045P001C01CS-SA   I169 @S9S_MB_2U_LIB.S9S_MB_2U(SCH_1):PAGE25
   J11  265 DQ15_B SCONN288_ADR50017P130CC-SCONN2A    I25 @S9S_MB_2U_LIB.S9S_MB_2U(SCH_1):PAGE92
   J12  265 DQ15_B SCONN288_ADR50017P087CC-SCONN2A    I24 @S9S_MB_2U_LIB.S9S_MB_2U(SCH_1):PAGE93

M_F_CPU0_SB_DQ<16> @S9S_MB_2U_LIB.S9S_MB_2U(SCH_1):M_F_CPU0_SB_DQ(16)
    U2 EM14 DDR5_SB_DQ16 SOCKET4677_AZIF0045P001C01CS-SA   I169 @S9S_MB_2U_LIB.S9S_MB_2U(SCH_1):PAGE25
   J11  122 DQ16_B SCONN288_ADR50017P130CC-SCONN2A    I25 @S9S_MB_2U_LIB.S9S_MB_2U(SCH_1):PAGE92
   J12  122 DQ16_B SCONN288_ADR50017P087CC-SCONN2A    I24 @S9S_MB_2U_LIB.S9S_MB_2U(SCH_1):PAGE93

M_F_CPU0_SB_DQ<17> @S9S_MB_2U_LIB.S9S_MB_2U(SCH_1):M_F_CPU0_SB_DQ(17)
    U2 EL13 DDR5_SB_DQ17 SOCKET4677_AZIF0045P001C01CS-SA   I169 @S9S_MB_2U_LIB.S9S_MB_2U(SCH_1):PAGE25
   J11  124 DQ17_B SCONN288_ADR50017P130CC-SCONN2A    I25 @S9S_MB_2U_LIB.S9S_MB_2U(SCH_1):PAGE92
   J12  124 DQ17_B SCONN288_ADR50017P087CC-SCONN2A    I24 @S9S_MB_2U_LIB.S9S_MB_2U(SCH_1):PAGE93

M_F_CPU0_SB_DQ<18> @S9S_MB_2U_LIB.S9S_MB_2U(SCH_1):M_F_CPU0_SB_DQ(18)
    U2 EP14 DDR5_SB_DQ18 SOCKET4677_AZIF0045P001C01CS-SA   I169 @S9S_MB_2U_LIB.S9S_MB_2U(SCH_1):PAGE25
   J11  267 DQ18_B SCONN288_ADR50017P130CC-SCONN2A    I25 @S9S_MB_2U_LIB.S9S_MB_2U(SCH_1):PAGE92
   J12  267 DQ18_B SCONN288_ADR50017P087CC-SCONN2A    I24 @S9S_MB_2U_LIB.S9S_MB_2U(SCH_1):PAGE93

M_F_CPU0_SB_DQ<19> @S9S_MB_2U_LIB.S9S_MB_2U(SCH_1):M_F_CPU0_SB_DQ(19)
    U2 ER13 DDR5_SB_DQ19 SOCKET4677_AZIF0045P001C01CS-SA   I169 @S9S_MB_2U_LIB.S9S_MB_2U(SCH_1):PAGE25
   J11  269 DQ19_B SCONN288_ADR50017P130CC-SCONN2A    I25 @S9S_MB_2U_LIB.S9S_MB_2U(SCH_1):PAGE92
   J12  269 DQ19_B SCONN288_ADR50017P087CC-SCONN2A    I24 @S9S_MB_2U_LIB.S9S_MB_2U(SCH_1):PAGE93

M_F_CPU0_SB_DQ<1> @S9S_MB_2U_LIB.S9S_MB_2U(SCH_1):M_F_CPU0_SB_DQ(1)
    U2 DU31 DDR5_SB_DQ1 SOCKET4677_AZIF0045P001C01CS-SA   I169 @S9S_MB_2U_LIB.S9S_MB_2U(SCH_1):PAGE25
   J11  102  DQ1_B SCONN288_ADR50017P130CC-SCONN2A    I25 @S9S_MB_2U_LIB.S9S_MB_2U(SCH_1):PAGE92
   J12  102  DQ1_B SCONN288_ADR50017P087CC-SCONN2A    I24 @S9S_MB_2U_LIB.S9S_MB_2U(SCH_1):PAGE93

M_F_CPU0_SB_DQ<20> @S9S_MB_2U_LIB.S9S_MB_2U(SCH_1):M_F_CPU0_SB_DQ(20)
    U2 EL11 DDR5_SB_DQ20 SOCKET4677_AZIF0045P001C01CS-SA   I169 @S9S_MB_2U_LIB.S9S_MB_2U(SCH_1):PAGE25
   J11  129 DQ20_B SCONN288_ADR50017P130CC-SCONN2A    I25 @S9S_MB_2U_LIB.S9S_MB_2U(SCH_1):PAGE92
   J12  129 DQ20_B SCONN288_ADR50017P087CC-SCONN2A    I24 @S9S_MB_2U_LIB.S9S_MB_2U(SCH_1):PAGE93

M_F_CPU0_SB_DQ<21> @S9S_MB_2U_LIB.S9S_MB_2U(SCH_1):M_F_CPU0_SB_DQ(21)
    U2 EM10 DDR5_SB_DQ21 SOCKET4677_AZIF0045P001C01CS-SA   I169 @S9S_MB_2U_LIB.S9S_MB_2U(SCH_1):PAGE25
   J11  131 DQ21_B SCONN288_ADR50017P130CC-SCONN2A    I25 @S9S_MB_2U_LIB.S9S_MB_2U(SCH_1):PAGE92
   J12  131 DQ21_B SCONN288_ADR50017P087CC-SCONN2A    I24 @S9S_MB_2U_LIB.S9S_MB_2U(SCH_1):PAGE93

M_F_CPU0_SB_DQ<22> @S9S_MB_2U_LIB.S9S_MB_2U(SCH_1):M_F_CPU0_SB_DQ(22)
    U2 ER11 DDR5_SB_DQ22 SOCKET4677_AZIF0045P001C01CS-SA   I169 @S9S_MB_2U_LIB.S9S_MB_2U(SCH_1):PAGE25
   J11  274 DQ22_B SCONN288_ADR50017P130CC-SCONN2A    I25 @S9S_MB_2U_LIB.S9S_MB_2U(SCH_1):PAGE92
   J12  274 DQ22_B SCONN288_ADR50017P087CC-SCONN2A    I24 @S9S_MB_2U_LIB.S9S_MB_2U(SCH_1):PAGE93

M_F_CPU0_SB_DQ<23> @S9S_MB_2U_LIB.S9S_MB_2U(SCH_1):M_F_CPU0_SB_DQ(23)
    U2 EP10 DDR5_SB_DQ23 SOCKET4677_AZIF0045P001C01CS-SA   I169 @S9S_MB_2U_LIB.S9S_MB_2U(SCH_1):PAGE25
   J11  276 DQ23_B SCONN288_ADR50017P130CC-SCONN2A    I25 @S9S_MB_2U_LIB.S9S_MB_2U(SCH_1):PAGE92
   J12  276 DQ23_B SCONN288_ADR50017P087CC-SCONN2A    I24 @S9S_MB_2U_LIB.S9S_MB_2U(SCH_1):PAGE93

M_F_CPU0_SB_DQ<24> @S9S_MB_2U_LIB.S9S_MB_2U(SCH_1):M_F_CPU0_SB_DQ(24)
    U2 DV20 DDR5_SB_DQ24 SOCKET4677_AZIF0045P001C01CS-SA   I169 @S9S_MB_2U_LIB.S9S_MB_2U(SCH_1):PAGE25
   J11  133 DQ24_B SCONN288_ADR50017P130CC-SCONN2A    I25 @S9S_MB_2U_LIB.S9S_MB_2U(SCH_1):PAGE92
   J12  133 DQ24_B SCONN288_ADR50017P087CC-SCONN2A    I24 @S9S_MB_2U_LIB.S9S_MB_2U(SCH_1):PAGE93

M_F_CPU0_SB_DQ<25> @S9S_MB_2U_LIB.S9S_MB_2U(SCH_1):M_F_CPU0_SB_DQ(25)
    U2 DU19 DDR5_SB_DQ25 SOCKET4677_AZIF0045P001C01CS-SA   I169 @S9S_MB_2U_LIB.S9S_MB_2U(SCH_1):PAGE25
   J11  135 DQ25_B SCONN288_ADR50017P130CC-SCONN2A    I25 @S9S_MB_2U_LIB.S9S_MB_2U(SCH_1):PAGE92
   J12  135 DQ25_B SCONN288_ADR50017P087CC-SCONN2A    I24 @S9S_MB_2U_LIB.S9S_MB_2U(SCH_1):PAGE93

M_F_CPU0_SB_DQ<26> @S9S_MB_2U_LIB.S9S_MB_2U(SCH_1):M_F_CPU0_SB_DQ(26)
    U2 DY20 DDR5_SB_DQ26 SOCKET4677_AZIF0045P001C01CS-SA   I169 @S9S_MB_2U_LIB.S9S_MB_2U(SCH_1):PAGE25
   J11  278 DQ26_B SCONN288_ADR50017P130CC-SCONN2A    I25 @S9S_MB_2U_LIB.S9S_MB_2U(SCH_1):PAGE92
   J12  278 DQ26_B SCONN288_ADR50017P087CC-SCONN2A    I24 @S9S_MB_2U_LIB.S9S_MB_2U(SCH_1):PAGE93

M_F_CPU0_SB_DQ<27> @S9S_MB_2U_LIB.S9S_MB_2U(SCH_1):M_F_CPU0_SB_DQ(27)
    U2 EA19 DDR5_SB_DQ27 SOCKET4677_AZIF0045P001C01CS-SA   I169 @S9S_MB_2U_LIB.S9S_MB_2U(SCH_1):PAGE25
   J11  280 DQ27_B SCONN288_ADR50017P130CC-SCONN2A    I25 @S9S_MB_2U_LIB.S9S_MB_2U(SCH_1):PAGE92
   J12  280 DQ27_B SCONN288_ADR50017P087CC-SCONN2A    I24 @S9S_MB_2U_LIB.S9S_MB_2U(SCH_1):PAGE93

M_F_CPU0_SB_DQ<28> @S9S_MB_2U_LIB.S9S_MB_2U(SCH_1):M_F_CPU0_SB_DQ(28)
    U2 EA17 DDR5_SB_DQ28 SOCKET4677_AZIF0045P001C01CS-SA   I169 @S9S_MB_2U_LIB.S9S_MB_2U(SCH_1):PAGE25
   J11  140 DQ28_B SCONN288_ADR50017P130CC-SCONN2A    I25 @S9S_MB_2U_LIB.S9S_MB_2U(SCH_1):PAGE92
   J12  140 DQ28_B SCONN288_ADR50017P087CC-SCONN2A    I24 @S9S_MB_2U_LIB.S9S_MB_2U(SCH_1):PAGE93

M_F_CPU0_SB_DQ<29> @S9S_MB_2U_LIB.S9S_MB_2U(SCH_1):M_F_CPU0_SB_DQ(29)
    U2 DU17 DDR5_SB_DQ29 SOCKET4677_AZIF0045P001C01CS-SA   I169 @S9S_MB_2U_LIB.S9S_MB_2U(SCH_1):PAGE25
   J11  142 DQ29_B SCONN288_ADR50017P130CC-SCONN2A    I25 @S9S_MB_2U_LIB.S9S_MB_2U(SCH_1):PAGE92
   J12  142 DQ29_B SCONN288_ADR50017P087CC-SCONN2A    I24 @S9S_MB_2U_LIB.S9S_MB_2U(SCH_1):PAGE93

M_F_CPU0_SB_DQ<2> @S9S_MB_2U_LIB.S9S_MB_2U(SCH_1):M_F_CPU0_SB_DQ(2)
    U2 DY32 DDR5_SB_DQ2 SOCKET4677_AZIF0045P001C01CS-SA   I169 @S9S_MB_2U_LIB.S9S_MB_2U(SCH_1):PAGE25
   J11  245  DQ2_B SCONN288_ADR50017P130CC-SCONN2A    I25 @S9S_MB_2U_LIB.S9S_MB_2U(SCH_1):PAGE92
   J12  245  DQ2_B SCONN288_ADR50017P087CC-SCONN2A    I24 @S9S_MB_2U_LIB.S9S_MB_2U(SCH_1):PAGE93

M_F_CPU0_SB_DQ<30> @S9S_MB_2U_LIB.S9S_MB_2U(SCH_1):M_F_CPU0_SB_DQ(30)
    U2 EC17 DDR5_SB_DQ30 SOCKET4677_AZIF0045P001C01CS-SA   I169 @S9S_MB_2U_LIB.S9S_MB_2U(SCH_1):PAGE25
   J11  285 DQ30_B SCONN288_ADR50017P130CC-SCONN2A    I25 @S9S_MB_2U_LIB.S9S_MB_2U(SCH_1):PAGE92
   J12  285 DQ30_B SCONN288_ADR50017P087CC-SCONN2A    I24 @S9S_MB_2U_LIB.S9S_MB_2U(SCH_1):PAGE93

M_F_CPU0_SB_DQ<31> @S9S_MB_2U_LIB.S9S_MB_2U(SCH_1):M_F_CPU0_SB_DQ(31)
    U2 DR17 DDR5_SB_DQ31 SOCKET4677_AZIF0045P001C01CS-SA   I169 @S9S_MB_2U_LIB.S9S_MB_2U(SCH_1):PAGE25
   J11  287 DQ31_B SCONN288_ADR50017P130CC-SCONN2A    I25 @S9S_MB_2U_LIB.S9S_MB_2U(SCH_1):PAGE92
   J12  287 DQ31_B SCONN288_ADR50017P087CC-SCONN2A    I24 @S9S_MB_2U_LIB.S9S_MB_2U(SCH_1):PAGE93

M_F_CPU0_SB_DQ<3> @S9S_MB_2U_LIB.S9S_MB_2U(SCH_1):M_F_CPU0_SB_DQ(3)
    U2 EA31 DDR5_SB_DQ3 SOCKET4677_AZIF0045P001C01CS-SA   I169 @S9S_MB_2U_LIB.S9S_MB_2U(SCH_1):PAGE25
   J11  247  DQ3_B SCONN288_ADR50017P130CC-SCONN2A    I25 @S9S_MB_2U_LIB.S9S_MB_2U(SCH_1):PAGE92
   J12  247  DQ3_B SCONN288_ADR50017P087CC-SCONN2A    I24 @S9S_MB_2U_LIB.S9S_MB_2U(SCH_1):PAGE93

M_F_CPU0_SB_DQ<4> @S9S_MB_2U_LIB.S9S_MB_2U(SCH_1):M_F_CPU0_SB_DQ(4)
    U2 DU29 DDR5_SB_DQ4 SOCKET4677_AZIF0045P001C01CS-SA   I169 @S9S_MB_2U_LIB.S9S_MB_2U(SCH_1):PAGE25
   J11  107  DQ4_B SCONN288_ADR50017P130CC-SCONN2A    I25 @S9S_MB_2U_LIB.S9S_MB_2U(SCH_1):PAGE92
   J12  107  DQ4_B SCONN288_ADR50017P087CC-SCONN2A    I24 @S9S_MB_2U_LIB.S9S_MB_2U(SCH_1):PAGE93

M_F_CPU0_SB_DQ<5> @S9S_MB_2U_LIB.S9S_MB_2U(SCH_1):M_F_CPU0_SB_DQ(5)
    U2 DV28 DDR5_SB_DQ5 SOCKET4677_AZIF0045P001C01CS-SA   I169 @S9S_MB_2U_LIB.S9S_MB_2U(SCH_1):PAGE25
   J11  109  DQ5_B SCONN288_ADR50017P130CC-SCONN2A    I25 @S9S_MB_2U_LIB.S9S_MB_2U(SCH_1):PAGE92
   J12  109  DQ5_B SCONN288_ADR50017P087CC-SCONN2A    I24 @S9S_MB_2U_LIB.S9S_MB_2U(SCH_1):PAGE93

M_F_CPU0_SB_DQ<6> @S9S_MB_2U_LIB.S9S_MB_2U(SCH_1):M_F_CPU0_SB_DQ(6)
    U2 EA29 DDR5_SB_DQ6 SOCKET4677_AZIF0045P001C01CS-SA   I169 @S9S_MB_2U_LIB.S9S_MB_2U(SCH_1):PAGE25
   J11  252  DQ6_B SCONN288_ADR50017P130CC-SCONN2A    I25 @S9S_MB_2U_LIB.S9S_MB_2U(SCH_1):PAGE92
   J12  252  DQ6_B SCONN288_ADR50017P087CC-SCONN2A    I24 @S9S_MB_2U_LIB.S9S_MB_2U(SCH_1):PAGE93

M_F_CPU0_SB_DQ<7> @S9S_MB_2U_LIB.S9S_MB_2U(SCH_1):M_F_CPU0_SB_DQ(7)
    U2 DY28 DDR5_SB_DQ7 SOCKET4677_AZIF0045P001C01CS-SA   I169 @S9S_MB_2U_LIB.S9S_MB_2U(SCH_1):PAGE25
   J11  254  DQ7_B SCONN288_ADR50017P130CC-SCONN2A    I25 @S9S_MB_2U_LIB.S9S_MB_2U(SCH_1):PAGE92
   J12  254  DQ7_B SCONN288_ADR50017P087CC-SCONN2A    I24 @S9S_MB_2U_LIB.S9S_MB_2U(SCH_1):PAGE93

M_F_CPU0_SB_DQ<8> @S9S_MB_2U_LIB.S9S_MB_2U(SCH_1):M_F_CPU0_SB_DQ(8)
    U2 EE23 DDR5_SB_DQ8 SOCKET4677_AZIF0045P001C01CS-SA   I169 @S9S_MB_2U_LIB.S9S_MB_2U(SCH_1):PAGE25
   J11  111  DQ8_B SCONN288_ADR50017P130CC-SCONN2A    I25 @S9S_MB_2U_LIB.S9S_MB_2U(SCH_1):PAGE92
   J12  111  DQ8_B SCONN288_ADR50017P087CC-SCONN2A    I24 @S9S_MB_2U_LIB.S9S_MB_2U(SCH_1):PAGE93

M_F_CPU0_SB_DQ<9> @S9S_MB_2U_LIB.S9S_MB_2U(SCH_1):M_F_CPU0_SB_DQ(9)
    U2 ED22 DDR5_SB_DQ9 SOCKET4677_AZIF0045P001C01CS-SA   I169 @S9S_MB_2U_LIB.S9S_MB_2U(SCH_1):PAGE25
   J11  113  DQ9_B SCONN288_ADR50017P130CC-SCONN2A    I25 @S9S_MB_2U_LIB.S9S_MB_2U(SCH_1):PAGE92
   J12  113  DQ9_B SCONN288_ADR50017P087CC-SCONN2A    I24 @S9S_MB_2U_LIB.S9S_MB_2U(SCH_1):PAGE93

M_F_CPU0_SB_DQS_DN<0> @S9S_MB_2U_LIB.S9S_MB_2U(SCH_1):M_F_CPU0_SB_DQS_DN(0)
    U2 DV30 DDR5_SB_DQS_DN0 SOCKET4677_AZIF0045P001C01CS-SA   I169 @S9S_MB_2U_LIB.S9S_MB_2U(SCH_1):PAGE25
   J11  105 DQS0_B_C SCONN288_ADR50017P130CC-SCONN2A   I178 @S9S_MB_2U_LIB.S9S_MB_2U(SCH_1):PAGE92
   J12  105 DQS0_B_C SCONN288_ADR50017P087CC-SCONN2A   I178 @S9S_MB_2U_LIB.S9S_MB_2U(SCH_1):PAGE93

M_F_CPU0_SB_DQS_DN<1> @S9S_MB_2U_LIB.S9S_MB_2U(SCH_1):M_F_CPU0_SB_DQS_DN(1)
    U2 EE21 DDR5_SB_DQS_DN1 SOCKET4677_AZIF0045P001C01CS-SA   I169 @S9S_MB_2U_LIB.S9S_MB_2U(SCH_1):PAGE25
   J11  116 DQS1_B_C SCONN288_ADR50017P130CC-SCONN2A   I178 @S9S_MB_2U_LIB.S9S_MB_2U(SCH_1):PAGE92
   J12  116 DQS1_B_C SCONN288_ADR50017P087CC-SCONN2A   I178 @S9S_MB_2U_LIB.S9S_MB_2U(SCH_1):PAGE93

M_F_CPU0_SB_DQS_DN<2> @S9S_MB_2U_LIB.S9S_MB_2U(SCH_1):M_F_CPU0_SB_DQS_DN(2)
    U2 EM12 DDR5_SB_DQS_DN2 SOCKET4677_AZIF0045P001C01CS-SA   I169 @S9S_MB_2U_LIB.S9S_MB_2U(SCH_1):PAGE25
   J11  127 DQS2_B_C SCONN288_ADR50017P130CC-SCONN2A   I178 @S9S_MB_2U_LIB.S9S_MB_2U(SCH_1):PAGE92
   J12  127 DQS2_B_C SCONN288_ADR50017P087CC-SCONN2A   I178 @S9S_MB_2U_LIB.S9S_MB_2U(SCH_1):PAGE93

M_F_CPU0_SB_DQS_DN<3> @S9S_MB_2U_LIB.S9S_MB_2U(SCH_1):M_F_CPU0_SB_DQS_DN(3)
    U2 DT18 DDR5_SB_DQS_DN3 SOCKET4677_AZIF0045P001C01CS-SA   I169 @S9S_MB_2U_LIB.S9S_MB_2U(SCH_1):PAGE25
   J11  138 DQS3_B_C SCONN288_ADR50017P130CC-SCONN2A   I178 @S9S_MB_2U_LIB.S9S_MB_2U(SCH_1):PAGE92
   J12  138 DQS3_B_C SCONN288_ADR50017P087CC-SCONN2A   I178 @S9S_MB_2U_LIB.S9S_MB_2U(SCH_1):PAGE93

M_F_CPU0_SB_DQS_DN<4> @S9S_MB_2U_LIB.S9S_MB_2U(SCH_1):M_F_CPU0_SB_DQS_DN(4)
    U2 EJ33 DDR5_SB_DQS_DN4 SOCKET4677_AZIF0045P001C01CS-SA   I169 @S9S_MB_2U_LIB.S9S_MB_2U(SCH_1):PAGE25
   J11  238 DQS4_B_C SCONN288_ADR50017P130CC-SCONN2A   I178 @S9S_MB_2U_LIB.S9S_MB_2U(SCH_1):PAGE92
   J12  238 DQS4_B_C SCONN288_ADR50017P087CC-SCONN2A   I178 @S9S_MB_2U_LIB.S9S_MB_2U(SCH_1):PAGE93

M_F_CPU0_SB_DQS_DN<5> @S9S_MB_2U_LIB.S9S_MB_2U(SCH_1):M_F_CPU0_SB_DQS_DN(5)
    U2 EB30 DDR5_SB_DQS_DN5 SOCKET4677_AZIF0045P001C01CS-SA   I169 @S9S_MB_2U_LIB.S9S_MB_2U(SCH_1):PAGE25
   J11  249 DQS5_B_C||TDQS5_B_C SCONN288_ADR50017P130CC-SCONN2A   I178 @S9S_MB_2U_LIB.S9S_MB_2U(SCH_1):PAGE92
   J12  249 DQS5_B_C||TDQS5_B_C SCONN288_ADR50017P087CC-SCONN2A   I178 @S9S_MB_2U_LIB.S9S_MB_2U(SCH_1):PAGE93

M_F_CPU0_SB_DQS_DN<6> @S9S_MB_2U_LIB.S9S_MB_2U(SCH_1):M_F_CPU0_SB_DQS_DN(6)
    U2 EJ21 DDR5_SB_DQS_DN6 SOCKET4677_AZIF0045P001C01CS-SA   I169 @S9S_MB_2U_LIB.S9S_MB_2U(SCH_1):PAGE25
   J11  260 DQS6_B_C||TDQS6_B_C SCONN288_ADR50017P130CC-SCONN2A   I178 @S9S_MB_2U_LIB.S9S_MB_2U(SCH_1):PAGE92
   J12  260 DQS6_B_C||TDQS6_B_C SCONN288_ADR50017P087CC-SCONN2A   I178 @S9S_MB_2U_LIB.S9S_MB_2U(SCH_1):PAGE93

M_F_CPU0_SB_DQS_DN<7> @S9S_MB_2U_LIB.S9S_MB_2U(SCH_1):M_F_CPU0_SB_DQS_DN(7)
    U2 ET12 DDR5_SB_DQS_DN7 SOCKET4677_AZIF0045P001C01CS-SA   I169 @S9S_MB_2U_LIB.S9S_MB_2U(SCH_1):PAGE25
   J11  271 DQS7_B_C||TDQS7_B_C SCONN288_ADR50017P130CC-SCONN2A   I178 @S9S_MB_2U_LIB.S9S_MB_2U(SCH_1):PAGE92
   J12  271 DQS7_B_C||TDQS7_B_C SCONN288_ADR50017P087CC-SCONN2A   I178 @S9S_MB_2U_LIB.S9S_MB_2U(SCH_1):PAGE93

M_F_CPU0_SB_DQS_DN<8> @S9S_MB_2U_LIB.S9S_MB_2U(SCH_1):M_F_CPU0_SB_DQS_DN(8)
    U2 DY18 DDR5_SB_DQS_DN8 SOCKET4677_AZIF0045P001C01CS-SA   I169 @S9S_MB_2U_LIB.S9S_MB_2U(SCH_1):PAGE25
   J11  282 DQS8_B_C||TDQS8_B_C SCONN288_ADR50017P130CC-SCONN2A   I178 @S9S_MB_2U_LIB.S9S_MB_2U(SCH_1):PAGE92
   J12  282 DQS8_B_C||TDQS8_B_C SCONN288_ADR50017P087CC-SCONN2A   I178 @S9S_MB_2U_LIB.S9S_MB_2U(SCH_1):PAGE93

M_F_CPU0_SB_DQS_DN<9> @S9S_MB_2U_LIB.S9S_MB_2U(SCH_1):M_F_CPU0_SB_DQS_DN(9)
    U2 EE33 DDR5_SB_DQS_DN9 SOCKET4677_AZIF0045P001C01CS-SA   I169 @S9S_MB_2U_LIB.S9S_MB_2U(SCH_1):PAGE25
   J11   94 DQS9_B_C||TDQS9_B_C SCONN288_ADR50017P130CC-SCONN2A   I178 @S9S_MB_2U_LIB.S9S_MB_2U(SCH_1):PAGE92
   J12   94 DQS9_B_C||TDQS9_B_C SCONN288_ADR50017P087CC-SCONN2A   I178 @S9S_MB_2U_LIB.S9S_MB_2U(SCH_1):PAGE93

M_F_CPU0_SB_DQS_DP<0> @S9S_MB_2U_LIB.S9S_MB_2U(SCH_1):M_F_CPU0_SB_DQS_DP(0)
    U2 DT30 DDR5_SB_DQS_DP0 SOCKET4677_AZIF0045P001C01CS-SA   I169 @S9S_MB_2U_LIB.S9S_MB_2U(SCH_1):PAGE25
   J11  104 DQS0_B_T SCONN288_ADR50017P130CC-SCONN2A   I178 @S9S_MB_2U_LIB.S9S_MB_2U(SCH_1):PAGE92
   J12  104 DQS0_B_T SCONN288_ADR50017P087CC-SCONN2A   I178 @S9S_MB_2U_LIB.S9S_MB_2U(SCH_1):PAGE93

M_F_CPU0_SB_DQS_DP<1> @S9S_MB_2U_LIB.S9S_MB_2U(SCH_1):M_F_CPU0_SB_DQS_DP(1)
    U2 EC21 DDR5_SB_DQS_DP1 SOCKET4677_AZIF0045P001C01CS-SA   I169 @S9S_MB_2U_LIB.S9S_MB_2U(SCH_1):PAGE25
   J11  115 DQS1_B_T SCONN288_ADR50017P130CC-SCONN2A   I178 @S9S_MB_2U_LIB.S9S_MB_2U(SCH_1):PAGE92
   J12  115 DQS1_B_T SCONN288_ADR50017P087CC-SCONN2A   I178 @S9S_MB_2U_LIB.S9S_MB_2U(SCH_1):PAGE93

M_F_CPU0_SB_DQS_DP<2> @S9S_MB_2U_LIB.S9S_MB_2U(SCH_1):M_F_CPU0_SB_DQS_DP(2)
    U2 EK12 DDR5_SB_DQS_DP2 SOCKET4677_AZIF0045P001C01CS-SA   I169 @S9S_MB_2U_LIB.S9S_MB_2U(SCH_1):PAGE25
   J11  126 DQS2_B_T SCONN288_ADR50017P130CC-SCONN2A   I178 @S9S_MB_2U_LIB.S9S_MB_2U(SCH_1):PAGE92
   J12  126 DQS2_B_T SCONN288_ADR50017P087CC-SCONN2A   I178 @S9S_MB_2U_LIB.S9S_MB_2U(SCH_1):PAGE93

M_F_CPU0_SB_DQS_DP<3> @S9S_MB_2U_LIB.S9S_MB_2U(SCH_1):M_F_CPU0_SB_DQS_DP(3)
    U2 DV18 DDR5_SB_DQS_DP3 SOCKET4677_AZIF0045P001C01CS-SA   I169 @S9S_MB_2U_LIB.S9S_MB_2U(SCH_1):PAGE25
   J11  137 DQS3_B_T SCONN288_ADR50017P130CC-SCONN2A   I178 @S9S_MB_2U_LIB.S9S_MB_2U(SCH_1):PAGE92
   J12  137 DQS3_B_T SCONN288_ADR50017P087CC-SCONN2A   I178 @S9S_MB_2U_LIB.S9S_MB_2U(SCH_1):PAGE93

M_F_CPU0_SB_DQS_DP<4> @S9S_MB_2U_LIB.S9S_MB_2U(SCH_1):M_F_CPU0_SB_DQS_DP(4)
    U2 EG33 DDR5_SB_DQS_DP4 SOCKET4677_AZIF0045P001C01CS-SA   I169 @S9S_MB_2U_LIB.S9S_MB_2U(SCH_1):PAGE25
   J11  239 DQS4_B_T SCONN288_ADR50017P130CC-SCONN2A   I178 @S9S_MB_2U_LIB.S9S_MB_2U(SCH_1):PAGE92
   J12  239 DQS4_B_T SCONN288_ADR50017P087CC-SCONN2A   I178 @S9S_MB_2U_LIB.S9S_MB_2U(SCH_1):PAGE93

M_F_CPU0_SB_DQS_DP<5> @S9S_MB_2U_LIB.S9S_MB_2U(SCH_1):M_F_CPU0_SB_DQS_DP(5)
    U2 DY30 DDR5_SB_DQS_DP5 SOCKET4677_AZIF0045P001C01CS-SA   I169 @S9S_MB_2U_LIB.S9S_MB_2U(SCH_1):PAGE25
   J11  250 DQS5_B_T||TDQS5_B_T SCONN288_ADR50017P130CC-SCONN2A   I178 @S9S_MB_2U_LIB.S9S_MB_2U(SCH_1):PAGE92
   J12  250 DQS5_B_T||TDQS5_B_T SCONN288_ADR50017P087CC-SCONN2A   I178 @S9S_MB_2U_LIB.S9S_MB_2U(SCH_1):PAGE93

M_F_CPU0_SB_DQS_DP<6> @S9S_MB_2U_LIB.S9S_MB_2U(SCH_1):M_F_CPU0_SB_DQS_DP(6)
    U2 EG21 DDR5_SB_DQS_DP6 SOCKET4677_AZIF0045P001C01CS-SA   I169 @S9S_MB_2U_LIB.S9S_MB_2U(SCH_1):PAGE25
   J11  261 DQS6_B_T||TDQS6_B_T SCONN288_ADR50017P130CC-SCONN2A   I178 @S9S_MB_2U_LIB.S9S_MB_2U(SCH_1):PAGE92
   J12  261 DQS6_B_T||TDQS6_B_T SCONN288_ADR50017P087CC-SCONN2A   I178 @S9S_MB_2U_LIB.S9S_MB_2U(SCH_1):PAGE93

M_F_CPU0_SB_DQS_DP<7> @S9S_MB_2U_LIB.S9S_MB_2U(SCH_1):M_F_CPU0_SB_DQS_DP(7)
    U2 EP12 DDR5_SB_DQS_DP7 SOCKET4677_AZIF0045P001C01CS-SA   I169 @S9S_MB_2U_LIB.S9S_MB_2U(SCH_1):PAGE25
   J11  272 DQS7_B_T||TDQS7_B_T SCONN288_ADR50017P130CC-SCONN2A   I178 @S9S_MB_2U_LIB.S9S_MB_2U(SCH_1):PAGE92
   J12  272 DQS7_B_T||TDQS7_B_T SCONN288_ADR50017P087CC-SCONN2A   I178 @S9S_MB_2U_LIB.S9S_MB_2U(SCH_1):PAGE93

M_F_CPU0_SB_DQS_DP<8> @S9S_MB_2U_LIB.S9S_MB_2U(SCH_1):M_F_CPU0_SB_DQS_DP(8)
    U2 EB18 DDR5_SB_DQS_DP8 SOCKET4677_AZIF0045P001C01CS-SA   I169 @S9S_MB_2U_LIB.S9S_MB_2U(SCH_1):PAGE25
   J11  283 DQS8_B_T||TDQS8_B_T SCONN288_ADR50017P130CC-SCONN2A   I178 @S9S_MB_2U_LIB.S9S_MB_2U(SCH_1):PAGE92
   J12  283 DQS8_B_T||TDQS8_B_T SCONN288_ADR50017P087CC-SCONN2A   I178 @S9S_MB_2U_LIB.S9S_MB_2U(SCH_1):PAGE93

M_F_CPU0_SB_DQS_DP<9> @S9S_MB_2U_LIB.S9S_MB_2U(SCH_1):M_F_CPU0_SB_DQS_DP(9)
    U2 EC33 DDR5_SB_DQS_DP9 SOCKET4677_AZIF0045P001C01CS-SA   I169 @S9S_MB_2U_LIB.S9S_MB_2U(SCH_1):PAGE25
   J11   93 DQS9_B_T||TDQS9_B_T||DBI4_B_N SCONN288_ADR50017P130CC-SCONN2A   I178 @S9S_MB_2U_LIB.S9S_MB_2U(SCH_1):PAGE92
   J12   93 DQS9_B_T||TDQS9_B_T||DBI4_B_N SCONN288_ADR50017P087CC-SCONN2A   I178 @S9S_MB_2U_LIB.S9S_MB_2U(SCH_1):PAGE93

M_F_CPU0_SB_PAR @S9S_MB_2U_LIB.S9S_MB_2U(SCH_1):M_F_CPU0_SB_PAR
    U2 EJ39 DDR5_SB_PAR SOCKET4677_AZIF0045P001C01CS-SA   I169 @S9S_MB_2U_LIB.S9S_MB_2U(SCH_1):PAGE25
   J11  227  PAR_B SCONN288_ADR50017P130CC-SCONN2A    I25 @S9S_MB_2U_LIB.S9S_MB_2U(SCH_1):PAGE92
   J12  227  PAR_B SCONN288_ADR50017P087CC-SCONN2A    I24 @S9S_MB_2U_LIB.S9S_MB_2U(SCH_1):PAGE93

M_F_CPU0_SB_RSP<0> @S9S_MB_2U_LIB.S9S_MB_2U(SCH_1):M_F_CPU0_SB_RSP(0)
    U2 DL48 DDR5_B_RSP0 SOCKET4677_AZIF0045P001C01CS-SA   I169 @S9S_MB_2U_LIB.S9S_MB_2U(SCH_1):PAGE25
   J11   87 LBS||RSP_B_N SCONN288_ADR50017P130CC-SCONN2A    I25 @S9S_MB_2U_LIB.S9S_MB_2U(SCH_1):PAGE92

M_F_CPU0_SB_RSP<1> @S9S_MB_2U_LIB.S9S_MB_2U(SCH_1):M_F_CPU0_SB_RSP(1)
    U2 DK47 DDR5_B_RSP1 SOCKET4677_AZIF0045P001C01CS-SA   I169 @S9S_MB_2U_LIB.S9S_MB_2U(SCH_1):PAGE25
   J12   87 LBS||RSP_B_N SCONN288_ADR50017P087CC-SCONN2A    I24 @S9S_MB_2U_LIB.S9S_MB_2U(SCH_1):PAGE93

M_F_CPU1_ALERT_N @S9S_MB_2U_LIB.S9S_MB_2U(SCH_1):M_F_CPU1_ALERT_N
    U1 CW48 DDR5_ALERT_N SOCKET4677_AZIF0045P001C01CS-SA   I168 @S9S_MB_2U_LIB.S9S_MB_2U(SCH_1):PAGE56
   J27   62 ALERT_N SCONN288_ADR50017P130CC-SCONN2A   I179 @S9S_MB_2U_LIB.S9S_MB_2U(SCH_1):PAGE108
   J28   62 ALERT_N SCONN288_ADR50017P087CC-SCONN2A    I47 @S9S_MB_2U_LIB.S9S_MB_2U(SCH_1):PAGE109

M_F_CPU1_CLK_DN<0> @S9S_MB_2U_LIB.S9S_MB_2U(SCH_1):M_F_CPU1_CLK_DN(0)
    U1 DY49 DDR5_CLK_DN0 SOCKET4677_AZIF0045P001C01CS-SA   I168 @S9S_MB_2U_LIB.S9S_MB_2U(SCH_1):PAGE56
   J27  218   CK_C SCONN288_ADR50017P130CC-SCONN2A   I179 @S9S_MB_2U_LIB.S9S_MB_2U(SCH_1):PAGE108

M_F_CPU1_CLK_DN<1> @S9S_MB_2U_LIB.S9S_MB_2U(SCH_1):M_F_CPU1_CLK_DN(1)
    U1 DV49 DDR5_CLK_DN1 SOCKET4677_AZIF0045P001C01CS-SA   I168 @S9S_MB_2U_LIB.S9S_MB_2U(SCH_1):PAGE56
   J28  218   CK_C SCONN288_ADR50017P087CC-SCONN2A    I47 @S9S_MB_2U_LIB.S9S_MB_2U(SCH_1):PAGE109

M_F_CPU1_CLK_DP<0> @S9S_MB_2U_LIB.S9S_MB_2U(SCH_1):M_F_CPU1_CLK_DP(0)
    U1 EB49 DDR5_CLK_DP0 SOCKET4677_AZIF0045P001C01CS-SA   I168 @S9S_MB_2U_LIB.S9S_MB_2U(SCH_1):PAGE56
   J27  217   CK_T SCONN288_ADR50017P130CC-SCONN2A   I179 @S9S_MB_2U_LIB.S9S_MB_2U(SCH_1):PAGE108

M_F_CPU1_CLK_DP<1> @S9S_MB_2U_LIB.S9S_MB_2U(SCH_1):M_F_CPU1_CLK_DP(1)
    U1 DT49 DDR5_CLK_DP1 SOCKET4677_AZIF0045P001C01CS-SA   I168 @S9S_MB_2U_LIB.S9S_MB_2U(SCH_1):PAGE56
   J28  217   CK_T SCONN288_ADR50017P087CC-SCONN2A    I47 @S9S_MB_2U_LIB.S9S_MB_2U(SCH_1):PAGE109

M_F_CPU1_SA_CA<0> @S9S_MB_2U_LIB.S9S_MB_2U(SCH_1):M_F_CPU1_SA_CA(0)
    U1 EC52 DDR5_SA_CA0 SOCKET4677_AZIF0045P001C01CS-SA   I168 @S9S_MB_2U_LIB.S9S_MB_2U(SCH_1):PAGE56
   J27   66  CA0_A SCONN288_ADR50017P130CC-SCONN2A   I179 @S9S_MB_2U_LIB.S9S_MB_2U(SCH_1):PAGE108
   J28   66  CA0_A SCONN288_ADR50017P087CC-SCONN2A    I47 @S9S_MB_2U_LIB.S9S_MB_2U(SCH_1):PAGE109

M_F_CPU1_SA_CA<1> @S9S_MB_2U_LIB.S9S_MB_2U(SCH_1):M_F_CPU1_SA_CA(1)
    U1 EJ52 DDR5_SA_CA1 SOCKET4677_AZIF0045P001C01CS-SA   I168 @S9S_MB_2U_LIB.S9S_MB_2U(SCH_1):PAGE56
   J27  211  CA1_A SCONN288_ADR50017P130CC-SCONN2A   I179 @S9S_MB_2U_LIB.S9S_MB_2U(SCH_1):PAGE108
   J28  211  CA1_A SCONN288_ADR50017P087CC-SCONN2A    I47 @S9S_MB_2U_LIB.S9S_MB_2U(SCH_1):PAGE109

M_F_CPU1_SA_CA<2> @S9S_MB_2U_LIB.S9S_MB_2U(SCH_1):M_F_CPU1_SA_CA(2)
    U1 ED51 DDR5_SA_CA2 SOCKET4677_AZIF0045P001C01CS-SA   I168 @S9S_MB_2U_LIB.S9S_MB_2U(SCH_1):PAGE56
   J27   68  CA2_A SCONN288_ADR50017P130CC-SCONN2A   I179 @S9S_MB_2U_LIB.S9S_MB_2U(SCH_1):PAGE108
   J28   68  CA2_A SCONN288_ADR50017P087CC-SCONN2A    I47 @S9S_MB_2U_LIB.S9S_MB_2U(SCH_1):PAGE109

M_F_CPU1_SA_CA<3> @S9S_MB_2U_LIB.S9S_MB_2U(SCH_1):M_F_CPU1_SA_CA(3)
    U1 EH51 DDR5_SA_CA3 SOCKET4677_AZIF0045P001C01CS-SA   I168 @S9S_MB_2U_LIB.S9S_MB_2U(SCH_1):PAGE56
   J27  213  CA3_A SCONN288_ADR50017P130CC-SCONN2A   I179 @S9S_MB_2U_LIB.S9S_MB_2U(SCH_1):PAGE108
   J28  213  CA3_A SCONN288_ADR50017P087CC-SCONN2A    I47 @S9S_MB_2U_LIB.S9S_MB_2U(SCH_1):PAGE109

M_F_CPU1_SA_CA<4> @S9S_MB_2U_LIB.S9S_MB_2U(SCH_1):M_F_CPU1_SA_CA(4)
    U1 EE50 DDR5_SA_CA4 SOCKET4677_AZIF0045P001C01CS-SA   I168 @S9S_MB_2U_LIB.S9S_MB_2U(SCH_1):PAGE56
   J27   70  CA4_A SCONN288_ADR50017P130CC-SCONN2A   I179 @S9S_MB_2U_LIB.S9S_MB_2U(SCH_1):PAGE108
   J28   70  CA4_A SCONN288_ADR50017P087CC-SCONN2A    I47 @S9S_MB_2U_LIB.S9S_MB_2U(SCH_1):PAGE109

M_F_CPU1_SA_CA<5> @S9S_MB_2U_LIB.S9S_MB_2U(SCH_1):M_F_CPU1_SA_CA(5)
    U1 EG50 DDR5_SA_CA5 SOCKET4677_AZIF0045P001C01CS-SA   I168 @S9S_MB_2U_LIB.S9S_MB_2U(SCH_1):PAGE56
   J27  215  CA5_A SCONN288_ADR50017P130CC-SCONN2A   I179 @S9S_MB_2U_LIB.S9S_MB_2U(SCH_1):PAGE108
   J28  215  CA5_A SCONN288_ADR50017P087CC-SCONN2A    I47 @S9S_MB_2U_LIB.S9S_MB_2U(SCH_1):PAGE109

M_F_CPU1_SA_CA<6> @S9S_MB_2U_LIB.S9S_MB_2U(SCH_1):M_F_CPU1_SA_CA(6)
    U1 DY51 DDR5_SA_CA6 SOCKET4677_AZIF0045P001C01CS-SA   I168 @S9S_MB_2U_LIB.S9S_MB_2U(SCH_1):PAGE56
   J27   72  CA6_A SCONN288_ADR50017P130CC-SCONN2A   I179 @S9S_MB_2U_LIB.S9S_MB_2U(SCH_1):PAGE108
   J28   72  CA6_A SCONN288_ADR50017P087CC-SCONN2A    I47 @S9S_MB_2U_LIB.S9S_MB_2U(SCH_1):PAGE109

M_F_CPU1_SA_CB<0> @S9S_MB_2U_LIB.S9S_MB_2U(SCH_1):M_F_CPU1_SA_CB(0)
    U1 EE60 DDR5_SA_ECC0 SOCKET4677_AZIF0045P001C01CS-SA   I168 @S9S_MB_2U_LIB.S9S_MB_2U(SCH_1):PAGE56
   J27   51  CB0_A SCONN288_ADR50017P130CC-SCONN2A   I179 @S9S_MB_2U_LIB.S9S_MB_2U(SCH_1):PAGE108
   J28   51  CB0_A SCONN288_ADR50017P087CC-SCONN2A    I47 @S9S_MB_2U_LIB.S9S_MB_2U(SCH_1):PAGE109

M_F_CPU1_SA_CB<1> @S9S_MB_2U_LIB.S9S_MB_2U(SCH_1):M_F_CPU1_SA_CB(1)
    U1 ED59 DDR5_SA_ECC1 SOCKET4677_AZIF0045P001C01CS-SA   I168 @S9S_MB_2U_LIB.S9S_MB_2U(SCH_1):PAGE56
   J27   53  CB1_A SCONN288_ADR50017P130CC-SCONN2A   I179 @S9S_MB_2U_LIB.S9S_MB_2U(SCH_1):PAGE108
   J28   53  CB1_A SCONN288_ADR50017P087CC-SCONN2A    I47 @S9S_MB_2U_LIB.S9S_MB_2U(SCH_1):PAGE109

M_F_CPU1_SA_CB<2> @S9S_MB_2U_LIB.S9S_MB_2U(SCH_1):M_F_CPU1_SA_CB(2)
    U1 EG60 DDR5_SA_ECC2 SOCKET4677_AZIF0045P001C01CS-SA   I168 @S9S_MB_2U_LIB.S9S_MB_2U(SCH_1):PAGE56
   J27  196  CB2_A SCONN288_ADR50017P130CC-SCONN2A   I179 @S9S_MB_2U_LIB.S9S_MB_2U(SCH_1):PAGE108
   J28  196  CB2_A SCONN288_ADR50017P087CC-SCONN2A    I47 @S9S_MB_2U_LIB.S9S_MB_2U(SCH_1):PAGE109

M_F_CPU1_SA_CB<3> @S9S_MB_2U_LIB.S9S_MB_2U(SCH_1):M_F_CPU1_SA_CB(3)
    U1 EH59 DDR5_SA_ECC3 SOCKET4677_AZIF0045P001C01CS-SA   I168 @S9S_MB_2U_LIB.S9S_MB_2U(SCH_1):PAGE56
   J27  198  CB3_A SCONN288_ADR50017P130CC-SCONN2A   I179 @S9S_MB_2U_LIB.S9S_MB_2U(SCH_1):PAGE108
   J28  198  CB3_A SCONN288_ADR50017P087CC-SCONN2A    I47 @S9S_MB_2U_LIB.S9S_MB_2U(SCH_1):PAGE109

M_F_CPU1_SA_CB<4> @S9S_MB_2U_LIB.S9S_MB_2U(SCH_1):M_F_CPU1_SA_CB(4)
    U1 ED57 DDR5_SA_ECC4 SOCKET4677_AZIF0045P001C01CS-SA   I168 @S9S_MB_2U_LIB.S9S_MB_2U(SCH_1):PAGE56
   J27   58  CB4_A SCONN288_ADR50017P130CC-SCONN2A   I179 @S9S_MB_2U_LIB.S9S_MB_2U(SCH_1):PAGE108
   J28   58  CB4_A SCONN288_ADR50017P087CC-SCONN2A    I47 @S9S_MB_2U_LIB.S9S_MB_2U(SCH_1):PAGE109

M_F_CPU1_SA_CB<5> @S9S_MB_2U_LIB.S9S_MB_2U(SCH_1):M_F_CPU1_SA_CB(5)
    U1 EE56 DDR5_SA_ECC5 SOCKET4677_AZIF0045P001C01CS-SA   I168 @S9S_MB_2U_LIB.S9S_MB_2U(SCH_1):PAGE56
   J27   60  CB5_A SCONN288_ADR50017P130CC-SCONN2A   I179 @S9S_MB_2U_LIB.S9S_MB_2U(SCH_1):PAGE108
   J28   60  CB5_A SCONN288_ADR50017P087CC-SCONN2A    I47 @S9S_MB_2U_LIB.S9S_MB_2U(SCH_1):PAGE109

M_F_CPU1_SA_CB<6> @S9S_MB_2U_LIB.S9S_MB_2U(SCH_1):M_F_CPU1_SA_CB(6)
    U1 EH57 DDR5_SA_ECC6 SOCKET4677_AZIF0045P001C01CS-SA   I168 @S9S_MB_2U_LIB.S9S_MB_2U(SCH_1):PAGE56
   J27  203  CB6_A SCONN288_ADR50017P130CC-SCONN2A   I179 @S9S_MB_2U_LIB.S9S_MB_2U(SCH_1):PAGE108
   J28  203  CB6_A SCONN288_ADR50017P087CC-SCONN2A    I47 @S9S_MB_2U_LIB.S9S_MB_2U(SCH_1):PAGE109

M_F_CPU1_SA_CB<7> @S9S_MB_2U_LIB.S9S_MB_2U(SCH_1):M_F_CPU1_SA_CB(7)
    U1 EG56 DDR5_SA_ECC7 SOCKET4677_AZIF0045P001C01CS-SA   I168 @S9S_MB_2U_LIB.S9S_MB_2U(SCH_1):PAGE56
   J27  205  CB7_A SCONN288_ADR50017P130CC-SCONN2A   I179 @S9S_MB_2U_LIB.S9S_MB_2U(SCH_1):PAGE108
   J28  205  CB7_A SCONN288_ADR50017P087CC-SCONN2A    I47 @S9S_MB_2U_LIB.S9S_MB_2U(SCH_1):PAGE109

M_F_CPU1_SA_CS_N<0> @S9S_MB_2U_LIB.S9S_MB_2U(SCH_1):M_F_CPU1_SA_CS_N(0)
    U1 EG54 DDR5_SA_CS_N0 SOCKET4677_AZIF0045P001C01CS-SA   I168 @S9S_MB_2U_LIB.S9S_MB_2U(SCH_1):PAGE56
   J27   64 CS0_A_N SCONN288_ADR50017P130CC-SCONN2A   I179 @S9S_MB_2U_LIB.S9S_MB_2U(SCH_1):PAGE108

M_F_CPU1_SA_CS_N<1> @S9S_MB_2U_LIB.S9S_MB_2U(SCH_1):M_F_CPU1_SA_CS_N(1)
    U1 EH53 DDR5_SA_CS_N1 SOCKET4677_AZIF0045P001C01CS-SA   I168 @S9S_MB_2U_LIB.S9S_MB_2U(SCH_1):PAGE56
   J27  209 CS1_A_N SCONN288_ADR50017P130CC-SCONN2A   I179 @S9S_MB_2U_LIB.S9S_MB_2U(SCH_1):PAGE108

M_F_CPU1_SA_CS_N<2> @S9S_MB_2U_LIB.S9S_MB_2U(SCH_1):M_F_CPU1_SA_CS_N(2)
    U1 EE54 DDR5_SA_CS_N2 SOCKET4677_AZIF0045P001C01CS-SA   I168 @S9S_MB_2U_LIB.S9S_MB_2U(SCH_1):PAGE56
   J28   64 CS0_A_N SCONN288_ADR50017P087CC-SCONN2A    I47 @S9S_MB_2U_LIB.S9S_MB_2U(SCH_1):PAGE109

M_F_CPU1_SA_CS_N<3> @S9S_MB_2U_LIB.S9S_MB_2U(SCH_1):M_F_CPU1_SA_CS_N(3)
    U1 ED53 DDR5_SA_CS_N3 SOCKET4677_AZIF0045P001C01CS-SA   I168 @S9S_MB_2U_LIB.S9S_MB_2U(SCH_1):PAGE56
   J28  209 CS1_A_N SCONN288_ADR50017P087CC-SCONN2A    I47 @S9S_MB_2U_LIB.S9S_MB_2U(SCH_1):PAGE109

M_F_CPU1_SA_DQ<0> @S9S_MB_2U_LIB.S9S_MB_2U(SCH_1):M_F_CPU1_SA_DQ(0)
    U1 EB77 DDR5_SA_DQ0 SOCKET4677_AZIF0045P001C01CS-SA   I168 @S9S_MB_2U_LIB.S9S_MB_2U(SCH_1):PAGE56
   J27    7  DQ0_A SCONN288_ADR50017P130CC-SCONN2A   I179 @S9S_MB_2U_LIB.S9S_MB_2U(SCH_1):PAGE108
   J28    7  DQ0_A SCONN288_ADR50017P087CC-SCONN2A    I47 @S9S_MB_2U_LIB.S9S_MB_2U(SCH_1):PAGE109

M_F_CPU1_SA_DQ<10> @S9S_MB_2U_LIB.S9S_MB_2U(SCH_1):M_F_CPU1_SA_DQ(10)
    U1 DY69 DDR5_SA_DQ10 SOCKET4677_AZIF0045P001C01CS-SA   I168 @S9S_MB_2U_LIB.S9S_MB_2U(SCH_1):PAGE56
   J27  163 DQ10_A SCONN288_ADR50017P130CC-SCONN2A   I179 @S9S_MB_2U_LIB.S9S_MB_2U(SCH_1):PAGE108
   J28  163 DQ10_A SCONN288_ADR50017P087CC-SCONN2A    I47 @S9S_MB_2U_LIB.S9S_MB_2U(SCH_1):PAGE109

M_F_CPU1_SA_DQ<11> @S9S_MB_2U_LIB.S9S_MB_2U(SCH_1):M_F_CPU1_SA_DQ(11)
    U1 EA68 DDR5_SA_DQ11 SOCKET4677_AZIF0045P001C01CS-SA   I168 @S9S_MB_2U_LIB.S9S_MB_2U(SCH_1):PAGE56
   J27  165 DQ11_A SCONN288_ADR50017P130CC-SCONN2A   I179 @S9S_MB_2U_LIB.S9S_MB_2U(SCH_1):PAGE108
   J28  165 DQ11_A SCONN288_ADR50017P087CC-SCONN2A    I47 @S9S_MB_2U_LIB.S9S_MB_2U(SCH_1):PAGE109

M_F_CPU1_SA_DQ<12> @S9S_MB_2U_LIB.S9S_MB_2U(SCH_1):M_F_CPU1_SA_DQ(12)
    U1 DU66 DDR5_SA_DQ12 SOCKET4677_AZIF0045P001C01CS-SA   I168 @S9S_MB_2U_LIB.S9S_MB_2U(SCH_1):PAGE56
   J27   25 DQ12_A SCONN288_ADR50017P130CC-SCONN2A   I179 @S9S_MB_2U_LIB.S9S_MB_2U(SCH_1):PAGE108
   J28   25 DQ12_A SCONN288_ADR50017P087CC-SCONN2A    I47 @S9S_MB_2U_LIB.S9S_MB_2U(SCH_1):PAGE109

M_F_CPU1_SA_DQ<13> @S9S_MB_2U_LIB.S9S_MB_2U(SCH_1):M_F_CPU1_SA_DQ(13)
    U1 DV65 DDR5_SA_DQ13 SOCKET4677_AZIF0045P001C01CS-SA   I168 @S9S_MB_2U_LIB.S9S_MB_2U(SCH_1):PAGE56
   J27   27 DQ13_A SCONN288_ADR50017P130CC-SCONN2A   I179 @S9S_MB_2U_LIB.S9S_MB_2U(SCH_1):PAGE108
   J28   27 DQ13_A SCONN288_ADR50017P087CC-SCONN2A    I47 @S9S_MB_2U_LIB.S9S_MB_2U(SCH_1):PAGE109

M_F_CPU1_SA_DQ<14> @S9S_MB_2U_LIB.S9S_MB_2U(SCH_1):M_F_CPU1_SA_DQ(14)
    U1 EA66 DDR5_SA_DQ14 SOCKET4677_AZIF0045P001C01CS-SA   I168 @S9S_MB_2U_LIB.S9S_MB_2U(SCH_1):PAGE56
   J27  170 DQ14_A SCONN288_ADR50017P130CC-SCONN2A   I179 @S9S_MB_2U_LIB.S9S_MB_2U(SCH_1):PAGE108
   J28  170 DQ14_A SCONN288_ADR50017P087CC-SCONN2A    I47 @S9S_MB_2U_LIB.S9S_MB_2U(SCH_1):PAGE109

M_F_CPU1_SA_DQ<15> @S9S_MB_2U_LIB.S9S_MB_2U(SCH_1):M_F_CPU1_SA_DQ(15)
    U1 DY65 DDR5_SA_DQ15 SOCKET4677_AZIF0045P001C01CS-SA   I168 @S9S_MB_2U_LIB.S9S_MB_2U(SCH_1):PAGE56
   J27  172 DQ15_A SCONN288_ADR50017P130CC-SCONN2A   I179 @S9S_MB_2U_LIB.S9S_MB_2U(SCH_1):PAGE108
   J28  172 DQ15_A SCONN288_ADR50017P087CC-SCONN2A    I47 @S9S_MB_2U_LIB.S9S_MB_2U(SCH_1):PAGE109

M_F_CPU1_SA_DQ<16> @S9S_MB_2U_LIB.S9S_MB_2U(SCH_1):M_F_CPU1_SA_DQ(16)
    U1 EE66 DDR5_SA_DQ16 SOCKET4677_AZIF0045P001C01CS-SA   I168 @S9S_MB_2U_LIB.S9S_MB_2U(SCH_1):PAGE56
   J27   29 DQ16_A SCONN288_ADR50017P130CC-SCONN2A   I179 @S9S_MB_2U_LIB.S9S_MB_2U(SCH_1):PAGE108
   J28   29 DQ16_A SCONN288_ADR50017P087CC-SCONN2A    I47 @S9S_MB_2U_LIB.S9S_MB_2U(SCH_1):PAGE109

M_F_CPU1_SA_DQ<17> @S9S_MB_2U_LIB.S9S_MB_2U(SCH_1):M_F_CPU1_SA_DQ(17)
    U1 ED65 DDR5_SA_DQ17 SOCKET4677_AZIF0045P001C01CS-SA   I168 @S9S_MB_2U_LIB.S9S_MB_2U(SCH_1):PAGE56
   J27   31 DQ17_A SCONN288_ADR50017P130CC-SCONN2A   I179 @S9S_MB_2U_LIB.S9S_MB_2U(SCH_1):PAGE108
   J28   31 DQ17_A SCONN288_ADR50017P087CC-SCONN2A    I47 @S9S_MB_2U_LIB.S9S_MB_2U(SCH_1):PAGE109

M_F_CPU1_SA_DQ<18> @S9S_MB_2U_LIB.S9S_MB_2U(SCH_1):M_F_CPU1_SA_DQ(18)
    U1 EG66 DDR5_SA_DQ18 SOCKET4677_AZIF0045P001C01CS-SA   I168 @S9S_MB_2U_LIB.S9S_MB_2U(SCH_1):PAGE56
   J27  174 DQ18_A SCONN288_ADR50017P130CC-SCONN2A   I179 @S9S_MB_2U_LIB.S9S_MB_2U(SCH_1):PAGE108
   J28  174 DQ18_A SCONN288_ADR50017P087CC-SCONN2A    I47 @S9S_MB_2U_LIB.S9S_MB_2U(SCH_1):PAGE109

M_F_CPU1_SA_DQ<19> @S9S_MB_2U_LIB.S9S_MB_2U(SCH_1):M_F_CPU1_SA_DQ(19)
    U1 EH65 DDR5_SA_DQ19 SOCKET4677_AZIF0045P001C01CS-SA   I168 @S9S_MB_2U_LIB.S9S_MB_2U(SCH_1):PAGE56
   J27  176 DQ19_A SCONN288_ADR50017P130CC-SCONN2A   I179 @S9S_MB_2U_LIB.S9S_MB_2U(SCH_1):PAGE108
   J28  176 DQ19_A SCONN288_ADR50017P087CC-SCONN2A    I47 @S9S_MB_2U_LIB.S9S_MB_2U(SCH_1):PAGE109

M_F_CPU1_SA_DQ<1> @S9S_MB_2U_LIB.S9S_MB_2U(SCH_1):M_F_CPU1_SA_DQ(1)
    U1 EH77 DDR5_SA_DQ1 SOCKET4677_AZIF0045P001C01CS-SA   I168 @S9S_MB_2U_LIB.S9S_MB_2U(SCH_1):PAGE56
   J27    9  DQ1_A SCONN288_ADR50017P130CC-SCONN2A   I179 @S9S_MB_2U_LIB.S9S_MB_2U(SCH_1):PAGE108
   J28    9  DQ1_A SCONN288_ADR50017P087CC-SCONN2A    I47 @S9S_MB_2U_LIB.S9S_MB_2U(SCH_1):PAGE109

M_F_CPU1_SA_DQ<20> @S9S_MB_2U_LIB.S9S_MB_2U(SCH_1):M_F_CPU1_SA_DQ(20)
    U1 ED63 DDR5_SA_DQ20 SOCKET4677_AZIF0045P001C01CS-SA   I168 @S9S_MB_2U_LIB.S9S_MB_2U(SCH_1):PAGE56
   J27   36 DQ20_A SCONN288_ADR50017P130CC-SCONN2A   I179 @S9S_MB_2U_LIB.S9S_MB_2U(SCH_1):PAGE108
   J28   36 DQ20_A SCONN288_ADR50017P087CC-SCONN2A    I47 @S9S_MB_2U_LIB.S9S_MB_2U(SCH_1):PAGE109

M_F_CPU1_SA_DQ<21> @S9S_MB_2U_LIB.S9S_MB_2U(SCH_1):M_F_CPU1_SA_DQ(21)
    U1 EE62 DDR5_SA_DQ21 SOCKET4677_AZIF0045P001C01CS-SA   I168 @S9S_MB_2U_LIB.S9S_MB_2U(SCH_1):PAGE56
   J27   38 DQ21_A SCONN288_ADR50017P130CC-SCONN2A   I179 @S9S_MB_2U_LIB.S9S_MB_2U(SCH_1):PAGE108
   J28   38 DQ21_A SCONN288_ADR50017P087CC-SCONN2A    I47 @S9S_MB_2U_LIB.S9S_MB_2U(SCH_1):PAGE109

M_F_CPU1_SA_DQ<22> @S9S_MB_2U_LIB.S9S_MB_2U(SCH_1):M_F_CPU1_SA_DQ(22)
    U1 EH63 DDR5_SA_DQ22 SOCKET4677_AZIF0045P001C01CS-SA   I168 @S9S_MB_2U_LIB.S9S_MB_2U(SCH_1):PAGE56
   J27  181 DQ22_A SCONN288_ADR50017P130CC-SCONN2A   I179 @S9S_MB_2U_LIB.S9S_MB_2U(SCH_1):PAGE108
   J28  181 DQ22_A SCONN288_ADR50017P087CC-SCONN2A    I47 @S9S_MB_2U_LIB.S9S_MB_2U(SCH_1):PAGE109

M_F_CPU1_SA_DQ<23> @S9S_MB_2U_LIB.S9S_MB_2U(SCH_1):M_F_CPU1_SA_DQ(23)
    U1 EG62 DDR5_SA_DQ23 SOCKET4677_AZIF0045P001C01CS-SA   I168 @S9S_MB_2U_LIB.S9S_MB_2U(SCH_1):PAGE56
   J27  183 DQ23_A SCONN288_ADR50017P130CC-SCONN2A   I179 @S9S_MB_2U_LIB.S9S_MB_2U(SCH_1):PAGE108
   J28  183 DQ23_A SCONN288_ADR50017P087CC-SCONN2A    I47 @S9S_MB_2U_LIB.S9S_MB_2U(SCH_1):PAGE109

M_F_CPU1_SA_DQ<24> @S9S_MB_2U_LIB.S9S_MB_2U(SCH_1):M_F_CPU1_SA_DQ(24)
    U1 DV57 DDR5_SA_DQ24 SOCKET4677_AZIF0045P001C01CS-SA   I168 @S9S_MB_2U_LIB.S9S_MB_2U(SCH_1):PAGE56
   J27   40 DQ24_A SCONN288_ADR50017P130CC-SCONN2A   I179 @S9S_MB_2U_LIB.S9S_MB_2U(SCH_1):PAGE108
   J28   40 DQ24_A SCONN288_ADR50017P087CC-SCONN2A    I47 @S9S_MB_2U_LIB.S9S_MB_2U(SCH_1):PAGE109

M_F_CPU1_SA_DQ<25> @S9S_MB_2U_LIB.S9S_MB_2U(SCH_1):M_F_CPU1_SA_DQ(25)
    U1 DU56 DDR5_SA_DQ25 SOCKET4677_AZIF0045P001C01CS-SA   I168 @S9S_MB_2U_LIB.S9S_MB_2U(SCH_1):PAGE56
   J27   42 DQ25_A SCONN288_ADR50017P130CC-SCONN2A   I179 @S9S_MB_2U_LIB.S9S_MB_2U(SCH_1):PAGE108
   J28   42 DQ25_A SCONN288_ADR50017P087CC-SCONN2A    I47 @S9S_MB_2U_LIB.S9S_MB_2U(SCH_1):PAGE109

M_F_CPU1_SA_DQ<26> @S9S_MB_2U_LIB.S9S_MB_2U(SCH_1):M_F_CPU1_SA_DQ(26)
    U1 DY57 DDR5_SA_DQ26 SOCKET4677_AZIF0045P001C01CS-SA   I168 @S9S_MB_2U_LIB.S9S_MB_2U(SCH_1):PAGE56
   J27  185 DQ26_A SCONN288_ADR50017P130CC-SCONN2A   I179 @S9S_MB_2U_LIB.S9S_MB_2U(SCH_1):PAGE108
   J28  185 DQ26_A SCONN288_ADR50017P087CC-SCONN2A    I47 @S9S_MB_2U_LIB.S9S_MB_2U(SCH_1):PAGE109

M_F_CPU1_SA_DQ<27> @S9S_MB_2U_LIB.S9S_MB_2U(SCH_1):M_F_CPU1_SA_DQ(27)
    U1 EA56 DDR5_SA_DQ27 SOCKET4677_AZIF0045P001C01CS-SA   I168 @S9S_MB_2U_LIB.S9S_MB_2U(SCH_1):PAGE56
   J27  187 DQ27_A SCONN288_ADR50017P130CC-SCONN2A   I179 @S9S_MB_2U_LIB.S9S_MB_2U(SCH_1):PAGE108
   J28  187 DQ27_A SCONN288_ADR50017P087CC-SCONN2A    I47 @S9S_MB_2U_LIB.S9S_MB_2U(SCH_1):PAGE109

M_F_CPU1_SA_DQ<28> @S9S_MB_2U_LIB.S9S_MB_2U(SCH_1):M_F_CPU1_SA_DQ(28)
    U1 DU54 DDR5_SA_DQ28 SOCKET4677_AZIF0045P001C01CS-SA   I168 @S9S_MB_2U_LIB.S9S_MB_2U(SCH_1):PAGE56
   J27   47 DQ28_A SCONN288_ADR50017P130CC-SCONN2A   I179 @S9S_MB_2U_LIB.S9S_MB_2U(SCH_1):PAGE108
   J28   47 DQ28_A SCONN288_ADR50017P087CC-SCONN2A    I47 @S9S_MB_2U_LIB.S9S_MB_2U(SCH_1):PAGE109

M_F_CPU1_SA_DQ<29> @S9S_MB_2U_LIB.S9S_MB_2U(SCH_1):M_F_CPU1_SA_DQ(29)
    U1 DV53 DDR5_SA_DQ29 SOCKET4677_AZIF0045P001C01CS-SA   I168 @S9S_MB_2U_LIB.S9S_MB_2U(SCH_1):PAGE56
   J27   49 DQ29_A SCONN288_ADR50017P130CC-SCONN2A   I179 @S9S_MB_2U_LIB.S9S_MB_2U(SCH_1):PAGE108
   J28   49 DQ29_A SCONN288_ADR50017P087CC-SCONN2A    I47 @S9S_MB_2U_LIB.S9S_MB_2U(SCH_1):PAGE109

M_F_CPU1_SA_DQ<2> @S9S_MB_2U_LIB.S9S_MB_2U(SCH_1):M_F_CPU1_SA_DQ(2)
    U1 ED77 DDR5_SA_DQ2 SOCKET4677_AZIF0045P001C01CS-SA   I168 @S9S_MB_2U_LIB.S9S_MB_2U(SCH_1):PAGE56
   J27  152  DQ2_A SCONN288_ADR50017P130CC-SCONN2A   I179 @S9S_MB_2U_LIB.S9S_MB_2U(SCH_1):PAGE108
   J28  152  DQ2_A SCONN288_ADR50017P087CC-SCONN2A    I47 @S9S_MB_2U_LIB.S9S_MB_2U(SCH_1):PAGE109

M_F_CPU1_SA_DQ<30> @S9S_MB_2U_LIB.S9S_MB_2U(SCH_1):M_F_CPU1_SA_DQ(30)
    U1 EA54 DDR5_SA_DQ30 SOCKET4677_AZIF0045P001C01CS-SA   I168 @S9S_MB_2U_LIB.S9S_MB_2U(SCH_1):PAGE56
   J27  192 DQ30_A SCONN288_ADR50017P130CC-SCONN2A   I179 @S9S_MB_2U_LIB.S9S_MB_2U(SCH_1):PAGE108
   J28  192 DQ30_A SCONN288_ADR50017P087CC-SCONN2A    I47 @S9S_MB_2U_LIB.S9S_MB_2U(SCH_1):PAGE109

M_F_CPU1_SA_DQ<31> @S9S_MB_2U_LIB.S9S_MB_2U(SCH_1):M_F_CPU1_SA_DQ(31)
    U1 DY53 DDR5_SA_DQ31 SOCKET4677_AZIF0045P001C01CS-SA   I168 @S9S_MB_2U_LIB.S9S_MB_2U(SCH_1):PAGE56
   J27  194 DQ31_A SCONN288_ADR50017P130CC-SCONN2A   I179 @S9S_MB_2U_LIB.S9S_MB_2U(SCH_1):PAGE108
   J28  194 DQ31_A SCONN288_ADR50017P087CC-SCONN2A    I47 @S9S_MB_2U_LIB.S9S_MB_2U(SCH_1):PAGE109

M_F_CPU1_SA_DQ<3> @S9S_MB_2U_LIB.S9S_MB_2U(SCH_1):M_F_CPU1_SA_DQ(3)
    U1 EG78 DDR5_SA_DQ3 SOCKET4677_AZIF0045P001C01CS-SA   I168 @S9S_MB_2U_LIB.S9S_MB_2U(SCH_1):PAGE56
   J27  154  DQ3_A SCONN288_ADR50017P130CC-SCONN2A   I179 @S9S_MB_2U_LIB.S9S_MB_2U(SCH_1):PAGE108
   J28  154  DQ3_A SCONN288_ADR50017P087CC-SCONN2A    I47 @S9S_MB_2U_LIB.S9S_MB_2U(SCH_1):PAGE109

M_F_CPU1_SA_DQ<4> @S9S_MB_2U_LIB.S9S_MB_2U(SCH_1):M_F_CPU1_SA_DQ(4)
    U1 ED75 DDR5_SA_DQ4 SOCKET4677_AZIF0045P001C01CS-SA   I168 @S9S_MB_2U_LIB.S9S_MB_2U(SCH_1):PAGE56
   J27   14  DQ4_A SCONN288_ADR50017P130CC-SCONN2A   I179 @S9S_MB_2U_LIB.S9S_MB_2U(SCH_1):PAGE108
   J28   14  DQ4_A SCONN288_ADR50017P087CC-SCONN2A    I47 @S9S_MB_2U_LIB.S9S_MB_2U(SCH_1):PAGE109

M_F_CPU1_SA_DQ<5> @S9S_MB_2U_LIB.S9S_MB_2U(SCH_1):M_F_CPU1_SA_DQ(5)
    U1 EE74 DDR5_SA_DQ5 SOCKET4677_AZIF0045P001C01CS-SA   I168 @S9S_MB_2U_LIB.S9S_MB_2U(SCH_1):PAGE56
   J27   16  DQ5_A SCONN288_ADR50017P130CC-SCONN2A   I179 @S9S_MB_2U_LIB.S9S_MB_2U(SCH_1):PAGE108
   J28   16  DQ5_A SCONN288_ADR50017P087CC-SCONN2A    I47 @S9S_MB_2U_LIB.S9S_MB_2U(SCH_1):PAGE109

M_F_CPU1_SA_DQ<6> @S9S_MB_2U_LIB.S9S_MB_2U(SCH_1):M_F_CPU1_SA_DQ(6)
    U1 EH75 DDR5_SA_DQ6 SOCKET4677_AZIF0045P001C01CS-SA   I168 @S9S_MB_2U_LIB.S9S_MB_2U(SCH_1):PAGE56
   J27  159  DQ6_A SCONN288_ADR50017P130CC-SCONN2A   I179 @S9S_MB_2U_LIB.S9S_MB_2U(SCH_1):PAGE108
   J28  159  DQ6_A SCONN288_ADR50017P087CC-SCONN2A    I47 @S9S_MB_2U_LIB.S9S_MB_2U(SCH_1):PAGE109

M_F_CPU1_SA_DQ<7> @S9S_MB_2U_LIB.S9S_MB_2U(SCH_1):M_F_CPU1_SA_DQ(7)
    U1 EG74 DDR5_SA_DQ7 SOCKET4677_AZIF0045P001C01CS-SA   I168 @S9S_MB_2U_LIB.S9S_MB_2U(SCH_1):PAGE56
   J27  161  DQ7_A SCONN288_ADR50017P130CC-SCONN2A   I179 @S9S_MB_2U_LIB.S9S_MB_2U(SCH_1):PAGE108
   J28  161  DQ7_A SCONN288_ADR50017P087CC-SCONN2A    I47 @S9S_MB_2U_LIB.S9S_MB_2U(SCH_1):PAGE109

M_F_CPU1_SA_DQ<8> @S9S_MB_2U_LIB.S9S_MB_2U(SCH_1):M_F_CPU1_SA_DQ(8)
    U1 DV69 DDR5_SA_DQ8 SOCKET4677_AZIF0045P001C01CS-SA   I168 @S9S_MB_2U_LIB.S9S_MB_2U(SCH_1):PAGE56
   J27   18  DQ8_A SCONN288_ADR50017P130CC-SCONN2A   I179 @S9S_MB_2U_LIB.S9S_MB_2U(SCH_1):PAGE108
   J28   18  DQ8_A SCONN288_ADR50017P087CC-SCONN2A    I47 @S9S_MB_2U_LIB.S9S_MB_2U(SCH_1):PAGE109

M_F_CPU1_SA_DQ<9> @S9S_MB_2U_LIB.S9S_MB_2U(SCH_1):M_F_CPU1_SA_DQ(9)
    U1 DU68 DDR5_SA_DQ9 SOCKET4677_AZIF0045P001C01CS-SA   I168 @S9S_MB_2U_LIB.S9S_MB_2U(SCH_1):PAGE56
   J27   20  DQ9_A SCONN288_ADR50017P130CC-SCONN2A   I179 @S9S_MB_2U_LIB.S9S_MB_2U(SCH_1):PAGE108
   J28   20  DQ9_A SCONN288_ADR50017P087CC-SCONN2A    I47 @S9S_MB_2U_LIB.S9S_MB_2U(SCH_1):PAGE109

M_F_CPU1_SA_DQS_DN<0> @S9S_MB_2U_LIB.S9S_MB_2U(SCH_1):M_F_CPU1_SA_DQS_DN(0)
    U1 EE76 DDR5_SA_DQS_DN0 SOCKET4677_AZIF0045P001C01CS-SA   I168 @S9S_MB_2U_LIB.S9S_MB_2U(SCH_1):PAGE56
   J27   12 DQS0_A_C SCONN288_ADR50017P130CC-SCONN2A   I180 @S9S_MB_2U_LIB.S9S_MB_2U(SCH_1):PAGE108
   J28   12 DQS0_A_C SCONN288_ADR50017P087CC-SCONN2A   I178 @S9S_MB_2U_LIB.S9S_MB_2U(SCH_1):PAGE109

M_F_CPU1_SA_DQS_DN<1> @S9S_MB_2U_LIB.S9S_MB_2U(SCH_1):M_F_CPU1_SA_DQS_DN(1)
    U1 DT67 DDR5_SA_DQS_DN1 SOCKET4677_AZIF0045P001C01CS-SA   I168 @S9S_MB_2U_LIB.S9S_MB_2U(SCH_1):PAGE56
   J27   23 DQS1_A_C SCONN288_ADR50017P130CC-SCONN2A   I180 @S9S_MB_2U_LIB.S9S_MB_2U(SCH_1):PAGE108
   J28   23 DQS1_A_C SCONN288_ADR50017P087CC-SCONN2A   I178 @S9S_MB_2U_LIB.S9S_MB_2U(SCH_1):PAGE109

M_F_CPU1_SA_DQS_DN<2> @S9S_MB_2U_LIB.S9S_MB_2U(SCH_1):M_F_CPU1_SA_DQS_DN(2)
    U1 EC64 DDR5_SA_DQS_DN2 SOCKET4677_AZIF0045P001C01CS-SA   I168 @S9S_MB_2U_LIB.S9S_MB_2U(SCH_1):PAGE56
   J27   34 DQS2_A_C SCONN288_ADR50017P130CC-SCONN2A   I180 @S9S_MB_2U_LIB.S9S_MB_2U(SCH_1):PAGE108
   J28   34 DQS2_A_C SCONN288_ADR50017P087CC-SCONN2A   I178 @S9S_MB_2U_LIB.S9S_MB_2U(SCH_1):PAGE109

M_F_CPU1_SA_DQS_DN<3> @S9S_MB_2U_LIB.S9S_MB_2U(SCH_1):M_F_CPU1_SA_DQS_DN(3)
    U1 DV55 DDR5_SA_DQS_DN3 SOCKET4677_AZIF0045P001C01CS-SA   I168 @S9S_MB_2U_LIB.S9S_MB_2U(SCH_1):PAGE56
   J27   45 DQS3_A_C SCONN288_ADR50017P130CC-SCONN2A   I180 @S9S_MB_2U_LIB.S9S_MB_2U(SCH_1):PAGE108
   J28   45 DQS3_A_C SCONN288_ADR50017P087CC-SCONN2A   I178 @S9S_MB_2U_LIB.S9S_MB_2U(SCH_1):PAGE109

M_F_CPU1_SA_DQS_DN<4> @S9S_MB_2U_LIB.S9S_MB_2U(SCH_1):M_F_CPU1_SA_DQS_DN(4)
    U1 EE58 DDR5_SA_DQS_DN4 SOCKET4677_AZIF0045P001C01CS-SA   I168 @S9S_MB_2U_LIB.S9S_MB_2U(SCH_1):PAGE56
   J27   56 DQS4_A_C SCONN288_ADR50017P130CC-SCONN2A   I180 @S9S_MB_2U_LIB.S9S_MB_2U(SCH_1):PAGE108
   J28   56 DQS4_A_C SCONN288_ADR50017P087CC-SCONN2A   I178 @S9S_MB_2U_LIB.S9S_MB_2U(SCH_1):PAGE109

M_F_CPU1_SA_DQS_DN<5> @S9S_MB_2U_LIB.S9S_MB_2U(SCH_1):M_F_CPU1_SA_DQS_DN(5)
    U1 EJ76 DDR5_SA_DQS_DN5 SOCKET4677_AZIF0045P001C01CS-SA   I168 @S9S_MB_2U_LIB.S9S_MB_2U(SCH_1):PAGE56
   J27  156 DQS5_A_C||TDQS5_A_C||DQS5_A_T||TDQS5_A_T SCONN288_ADR50017P130CC-SCONN2A   I180 @S9S_MB_2U_LIB.S9S_MB_2U(SCH_1):PAGE108
   J28  156 DQS5_A_C||TDQS5_A_C||DQS5_A_T||TDQS5_A_T SCONN288_ADR50017P087CC-SCONN2A   I178 @S9S_MB_2U_LIB.S9S_MB_2U(SCH_1):PAGE109

M_F_CPU1_SA_DQS_DN<6> @S9S_MB_2U_LIB.S9S_MB_2U(SCH_1):M_F_CPU1_SA_DQS_DN(6)
    U1 EB67 DDR5_SA_DQS_DN6 SOCKET4677_AZIF0045P001C01CS-SA   I168 @S9S_MB_2U_LIB.S9S_MB_2U(SCH_1):PAGE56
   J27  167 DQS6_A_C||TDQS6_A_C||DQS6_A_T||TDQS6_A_T SCONN288_ADR50017P130CC-SCONN2A   I180 @S9S_MB_2U_LIB.S9S_MB_2U(SCH_1):PAGE108
   J28  167 DQS6_A_C||TDQS6_A_C||DQS6_A_T||TDQS6_A_T SCONN288_ADR50017P087CC-SCONN2A   I178 @S9S_MB_2U_LIB.S9S_MB_2U(SCH_1):PAGE109

M_F_CPU1_SA_DQS_DN<7> @S9S_MB_2U_LIB.S9S_MB_2U(SCH_1):M_F_CPU1_SA_DQS_DN(7)
    U1 EJ64 DDR5_SA_DQS_DN7 SOCKET4677_AZIF0045P001C01CS-SA   I168 @S9S_MB_2U_LIB.S9S_MB_2U(SCH_1):PAGE56
   J27  178 DQS7_A_C||TDQS7_A_C SCONN288_ADR50017P130CC-SCONN2A   I180 @S9S_MB_2U_LIB.S9S_MB_2U(SCH_1):PAGE108
   J28  178 DQS7_A_C||TDQS7_A_C SCONN288_ADR50017P087CC-SCONN2A   I178 @S9S_MB_2U_LIB.S9S_MB_2U(SCH_1):PAGE109

M_F_CPU1_SA_DQS_DN<8> @S9S_MB_2U_LIB.S9S_MB_2U(SCH_1):M_F_CPU1_SA_DQS_DN(8)
    U1 EB55 DDR5_SA_DQS_DN8 SOCKET4677_AZIF0045P001C01CS-SA   I168 @S9S_MB_2U_LIB.S9S_MB_2U(SCH_1):PAGE56
   J27  189 DQS8_A_C||TDQS8_A_C SCONN288_ADR50017P130CC-SCONN2A   I180 @S9S_MB_2U_LIB.S9S_MB_2U(SCH_1):PAGE108
   J28  189 DQS8_A_C||TDQS8_A_C SCONN288_ADR50017P087CC-SCONN2A   I178 @S9S_MB_2U_LIB.S9S_MB_2U(SCH_1):PAGE109

M_F_CPU1_SA_DQS_DN<9> @S9S_MB_2U_LIB.S9S_MB_2U(SCH_1):M_F_CPU1_SA_DQS_DN(9)
    U1 EJ58 DDR5_SA_DQS_DN9 SOCKET4677_AZIF0045P001C01CS-SA   I168 @S9S_MB_2U_LIB.S9S_MB_2U(SCH_1):PAGE56
   J27  200 DQS9_A_C||TDQS9_A_C SCONN288_ADR50017P130CC-SCONN2A   I180 @S9S_MB_2U_LIB.S9S_MB_2U(SCH_1):PAGE108
   J28  200 DQS9_A_C||TDQS9_A_C SCONN288_ADR50017P087CC-SCONN2A   I178 @S9S_MB_2U_LIB.S9S_MB_2U(SCH_1):PAGE109

M_F_CPU1_SA_DQS_DP<0> @S9S_MB_2U_LIB.S9S_MB_2U(SCH_1):M_F_CPU1_SA_DQS_DP(0)
    U1 EC76 DDR5_SA_DQS_DP0 SOCKET4677_AZIF0045P001C01CS-SA   I168 @S9S_MB_2U_LIB.S9S_MB_2U(SCH_1):PAGE56
   J27   11 DQS0_A_T SCONN288_ADR50017P130CC-SCONN2A   I180 @S9S_MB_2U_LIB.S9S_MB_2U(SCH_1):PAGE108
   J28   11 DQS0_A_T SCONN288_ADR50017P087CC-SCONN2A   I178 @S9S_MB_2U_LIB.S9S_MB_2U(SCH_1):PAGE109

M_F_CPU1_SA_DQS_DP<1> @S9S_MB_2U_LIB.S9S_MB_2U(SCH_1):M_F_CPU1_SA_DQS_DP(1)
    U1 DV67 DDR5_SA_DQS_DP1 SOCKET4677_AZIF0045P001C01CS-SA   I168 @S9S_MB_2U_LIB.S9S_MB_2U(SCH_1):PAGE56
   J27   22 DQS1_A_T SCONN288_ADR50017P130CC-SCONN2A   I180 @S9S_MB_2U_LIB.S9S_MB_2U(SCH_1):PAGE108
   J28   22 DQS1_A_T SCONN288_ADR50017P087CC-SCONN2A   I178 @S9S_MB_2U_LIB.S9S_MB_2U(SCH_1):PAGE109

M_F_CPU1_SA_DQS_DP<2> @S9S_MB_2U_LIB.S9S_MB_2U(SCH_1):M_F_CPU1_SA_DQS_DP(2)
    U1 EE64 DDR5_SA_DQS_DP2 SOCKET4677_AZIF0045P001C01CS-SA   I168 @S9S_MB_2U_LIB.S9S_MB_2U(SCH_1):PAGE56
   J27   33 DQS2_A_T SCONN288_ADR50017P130CC-SCONN2A   I180 @S9S_MB_2U_LIB.S9S_MB_2U(SCH_1):PAGE108
   J28   33 DQS2_A_T SCONN288_ADR50017P087CC-SCONN2A   I178 @S9S_MB_2U_LIB.S9S_MB_2U(SCH_1):PAGE109

M_F_CPU1_SA_DQS_DP<3> @S9S_MB_2U_LIB.S9S_MB_2U(SCH_1):M_F_CPU1_SA_DQS_DP(3)
    U1 DT55 DDR5_SA_DQS_DP3 SOCKET4677_AZIF0045P001C01CS-SA   I168 @S9S_MB_2U_LIB.S9S_MB_2U(SCH_1):PAGE56
   J27   44 DQS3_A_T SCONN288_ADR50017P130CC-SCONN2A   I180 @S9S_MB_2U_LIB.S9S_MB_2U(SCH_1):PAGE108
   J28   44 DQS3_A_T SCONN288_ADR50017P087CC-SCONN2A   I178 @S9S_MB_2U_LIB.S9S_MB_2U(SCH_1):PAGE109

M_F_CPU1_SA_DQS_DP<4> @S9S_MB_2U_LIB.S9S_MB_2U(SCH_1):M_F_CPU1_SA_DQS_DP(4)
    U1 EC58 DDR5_SA_DQS_DP4 SOCKET4677_AZIF0045P001C01CS-SA   I168 @S9S_MB_2U_LIB.S9S_MB_2U(SCH_1):PAGE56
   J27   55 DQS4_A_T SCONN288_ADR50017P130CC-SCONN2A   I180 @S9S_MB_2U_LIB.S9S_MB_2U(SCH_1):PAGE108
   J28   55 DQS4_A_T SCONN288_ADR50017P087CC-SCONN2A   I178 @S9S_MB_2U_LIB.S9S_MB_2U(SCH_1):PAGE109

M_F_CPU1_SA_DQS_DP<5> @S9S_MB_2U_LIB.S9S_MB_2U(SCH_1):M_F_CPU1_SA_DQS_DP(5)
    U1 EG76 DDR5_SA_DQS_DP5 SOCKET4677_AZIF0045P001C01CS-SA   I168 @S9S_MB_2U_LIB.S9S_MB_2U(SCH_1):PAGE56
   J27  157 DQS5_A_T||TDQS5_A_T SCONN288_ADR50017P130CC-SCONN2A   I180 @S9S_MB_2U_LIB.S9S_MB_2U(SCH_1):PAGE108
   J28  157 DQS5_A_T||TDQS5_A_T SCONN288_ADR50017P087CC-SCONN2A   I178 @S9S_MB_2U_LIB.S9S_MB_2U(SCH_1):PAGE109

M_F_CPU1_SA_DQS_DP<6> @S9S_MB_2U_LIB.S9S_MB_2U(SCH_1):M_F_CPU1_SA_DQS_DP(6)
    U1 DY67 DDR5_SA_DQS_DP6 SOCKET4677_AZIF0045P001C01CS-SA   I168 @S9S_MB_2U_LIB.S9S_MB_2U(SCH_1):PAGE56
   J27  168 DQS6_A_T||TDQS6_A_T SCONN288_ADR50017P130CC-SCONN2A   I180 @S9S_MB_2U_LIB.S9S_MB_2U(SCH_1):PAGE108
   J28  168 DQS6_A_T||TDQS6_A_T SCONN288_ADR50017P087CC-SCONN2A   I178 @S9S_MB_2U_LIB.S9S_MB_2U(SCH_1):PAGE109

M_F_CPU1_SA_DQS_DP<7> @S9S_MB_2U_LIB.S9S_MB_2U(SCH_1):M_F_CPU1_SA_DQS_DP(7)
    U1 EG64 DDR5_SA_DQS_DP7 SOCKET4677_AZIF0045P001C01CS-SA   I168 @S9S_MB_2U_LIB.S9S_MB_2U(SCH_1):PAGE56
   J27  179 DQS7_A_T||TDQS7_A_T SCONN288_ADR50017P130CC-SCONN2A   I180 @S9S_MB_2U_LIB.S9S_MB_2U(SCH_1):PAGE108
   J28  179 DQS7_A_T||TDQS7_A_T SCONN288_ADR50017P087CC-SCONN2A   I178 @S9S_MB_2U_LIB.S9S_MB_2U(SCH_1):PAGE109

M_F_CPU1_SA_DQS_DP<8> @S9S_MB_2U_LIB.S9S_MB_2U(SCH_1):M_F_CPU1_SA_DQS_DP(8)
    U1 DY55 DDR5_SA_DQS_DP8 SOCKET4677_AZIF0045P001C01CS-SA   I168 @S9S_MB_2U_LIB.S9S_MB_2U(SCH_1):PAGE56
   J27  190 DQS8_A_T||TDQS8_A_T SCONN288_ADR50017P130CC-SCONN2A   I180 @S9S_MB_2U_LIB.S9S_MB_2U(SCH_1):PAGE108
   J28  190 DQS8_A_T||TDQS8_A_T SCONN288_ADR50017P087CC-SCONN2A   I178 @S9S_MB_2U_LIB.S9S_MB_2U(SCH_1):PAGE109

M_F_CPU1_SA_DQS_DP<9> @S9S_MB_2U_LIB.S9S_MB_2U(SCH_1):M_F_CPU1_SA_DQS_DP(9)
    U1 EG58 DDR5_SA_DQS_DP9 SOCKET4677_AZIF0045P001C01CS-SA   I168 @S9S_MB_2U_LIB.S9S_MB_2U(SCH_1):PAGE56
   J27  201 DQS9_A_T||TDQS9_A_T SCONN288_ADR50017P130CC-SCONN2A   I180 @S9S_MB_2U_LIB.S9S_MB_2U(SCH_1):PAGE108
   J28  201 DQS9_A_T||TDQS9_A_T SCONN288_ADR50017P087CC-SCONN2A   I178 @S9S_MB_2U_LIB.S9S_MB_2U(SCH_1):PAGE109

M_F_CPU1_SA_PAR @S9S_MB_2U_LIB.S9S_MB_2U(SCH_1):M_F_CPU1_SA_PAR
    U1 EA50 DDR5_SA_PAR SOCKET4677_AZIF0045P001C01CS-SA   I168 @S9S_MB_2U_LIB.S9S_MB_2U(SCH_1):PAGE56
   J27   74  PAR_A SCONN288_ADR50017P130CC-SCONN2A   I179 @S9S_MB_2U_LIB.S9S_MB_2U(SCH_1):PAGE108
   J28   74  PAR_A SCONN288_ADR50017P087CC-SCONN2A    I47 @S9S_MB_2U_LIB.S9S_MB_2U(SCH_1):PAGE109

M_F_CPU1_SA_RSP<0> @S9S_MB_2U_LIB.S9S_MB_2U(SCH_1):M_F_CPU1_SA_RSP(0)
    U1 DN48 DDR5_A_RSP0 SOCKET4677_AZIF0045P001C01CS-SA   I168 @S9S_MB_2U_LIB.S9S_MB_2U(SCH_1):PAGE56
   J27   86 LBD||RSP_A_N SCONN288_ADR50017P130CC-SCONN2A   I179 @S9S_MB_2U_LIB.S9S_MB_2U(SCH_1):PAGE108

M_F_CPU1_SA_RSP<1> @S9S_MB_2U_LIB.S9S_MB_2U(SCH_1):M_F_CPU1_SA_RSP(1)
    U1 DP47 DDR5_A_RSP1 SOCKET4677_AZIF0045P001C01CS-SA   I168 @S9S_MB_2U_LIB.S9S_MB_2U(SCH_1):PAGE56
   J28   86 LBD||RSP_A_N SCONN288_ADR50017P087CC-SCONN2A    I47 @S9S_MB_2U_LIB.S9S_MB_2U(SCH_1):PAGE109

M_F_CPU1_SB_CA<0> @S9S_MB_2U_LIB.S9S_MB_2U(SCH_1):M_F_CPU1_SB_CA(0)
    U1 DV51 DDR5_SB_CA0 SOCKET4677_AZIF0045P001C01CS-SA   I168 @S9S_MB_2U_LIB.S9S_MB_2U(SCH_1):PAGE56
   J27   76  CA0_B SCONN288_ADR50017P130CC-SCONN2A   I179 @S9S_MB_2U_LIB.S9S_MB_2U(SCH_1):PAGE108
   J28   76  CA0_B SCONN288_ADR50017P087CC-SCONN2A    I47 @S9S_MB_2U_LIB.S9S_MB_2U(SCH_1):PAGE109

M_F_CPU1_SB_CA<1> @S9S_MB_2U_LIB.S9S_MB_2U(SCH_1):M_F_CPU1_SB_CA(1)
    U1 DU50 DDR5_SB_CA1 SOCKET4677_AZIF0045P001C01CS-SA   I168 @S9S_MB_2U_LIB.S9S_MB_2U(SCH_1):PAGE56
   J27  221  CA1_B SCONN288_ADR50017P130CC-SCONN2A   I179 @S9S_MB_2U_LIB.S9S_MB_2U(SCH_1):PAGE108
   J28  221  CA1_B SCONN288_ADR50017P087CC-SCONN2A    I47 @S9S_MB_2U_LIB.S9S_MB_2U(SCH_1):PAGE109

M_F_CPU1_SB_CA<2> @S9S_MB_2U_LIB.S9S_MB_2U(SCH_1):M_F_CPU1_SB_CA(2)
    U1 EE41 DDR5_SB_CA2 SOCKET4677_AZIF0045P001C01CS-SA   I168 @S9S_MB_2U_LIB.S9S_MB_2U(SCH_1):PAGE56
   J27   78  CA2_B SCONN288_ADR50017P130CC-SCONN2A   I179 @S9S_MB_2U_LIB.S9S_MB_2U(SCH_1):PAGE108
   J28   78  CA2_B SCONN288_ADR50017P087CC-SCONN2A    I47 @S9S_MB_2U_LIB.S9S_MB_2U(SCH_1):PAGE109

M_F_CPU1_SB_CA<3> @S9S_MB_2U_LIB.S9S_MB_2U(SCH_1):M_F_CPU1_SB_CA(3)
    U1 EG41 DDR5_SB_CA3 SOCKET4677_AZIF0045P001C01CS-SA   I168 @S9S_MB_2U_LIB.S9S_MB_2U(SCH_1):PAGE56
   J27  223  CA3_B SCONN288_ADR50017P130CC-SCONN2A   I179 @S9S_MB_2U_LIB.S9S_MB_2U(SCH_1):PAGE108
   J28  223  CA3_B SCONN288_ADR50017P087CC-SCONN2A    I47 @S9S_MB_2U_LIB.S9S_MB_2U(SCH_1):PAGE109

M_F_CPU1_SB_CA<4> @S9S_MB_2U_LIB.S9S_MB_2U(SCH_1):M_F_CPU1_SB_CA(4)
    U1 ED40 DDR5_SB_CA4 SOCKET4677_AZIF0045P001C01CS-SA   I168 @S9S_MB_2U_LIB.S9S_MB_2U(SCH_1):PAGE56
   J27   80  CA4_B SCONN288_ADR50017P130CC-SCONN2A   I179 @S9S_MB_2U_LIB.S9S_MB_2U(SCH_1):PAGE108
   J28   80  CA4_B SCONN288_ADR50017P087CC-SCONN2A    I47 @S9S_MB_2U_LIB.S9S_MB_2U(SCH_1):PAGE109

M_F_CPU1_SB_CA<5> @S9S_MB_2U_LIB.S9S_MB_2U(SCH_1):M_F_CPU1_SB_CA(5)
    U1 EH40 DDR5_SB_CA5 SOCKET4677_AZIF0045P001C01CS-SA   I168 @S9S_MB_2U_LIB.S9S_MB_2U(SCH_1):PAGE56
   J27  225  CA5_B SCONN288_ADR50017P130CC-SCONN2A   I179 @S9S_MB_2U_LIB.S9S_MB_2U(SCH_1):PAGE108
   J28  225  CA5_B SCONN288_ADR50017P087CC-SCONN2A    I47 @S9S_MB_2U_LIB.S9S_MB_2U(SCH_1):PAGE109

M_F_CPU1_SB_CA<6> @S9S_MB_2U_LIB.S9S_MB_2U(SCH_1):M_F_CPU1_SB_CA(6)
    U1 EC39 DDR5_SB_CA6 SOCKET4677_AZIF0045P001C01CS-SA   I168 @S9S_MB_2U_LIB.S9S_MB_2U(SCH_1):PAGE56
   J27   82  CA6_B SCONN288_ADR50017P130CC-SCONN2A   I179 @S9S_MB_2U_LIB.S9S_MB_2U(SCH_1):PAGE108
   J28   82  CA6_B SCONN288_ADR50017P087CC-SCONN2A    I47 @S9S_MB_2U_LIB.S9S_MB_2U(SCH_1):PAGE109

M_F_CPU1_SB_CB<0> @S9S_MB_2U_LIB.S9S_MB_2U(SCH_1):M_F_CPU1_SB_CB(0)
    U1 ED32 DDR5_SB_ECC0 SOCKET4677_AZIF0045P001C01CS-SA   I168 @S9S_MB_2U_LIB.S9S_MB_2U(SCH_1):PAGE56
   J27   96  CB0_B SCONN288_ADR50017P130CC-SCONN2A   I179 @S9S_MB_2U_LIB.S9S_MB_2U(SCH_1):PAGE108
   J28   96  CB0_B SCONN288_ADR50017P087CC-SCONN2A    I47 @S9S_MB_2U_LIB.S9S_MB_2U(SCH_1):PAGE109

M_F_CPU1_SB_CB<1> @S9S_MB_2U_LIB.S9S_MB_2U(SCH_1):M_F_CPU1_SB_CB(1)
    U1 EE31 DDR5_SB_ECC1 SOCKET4677_AZIF0045P001C01CS-SA   I168 @S9S_MB_2U_LIB.S9S_MB_2U(SCH_1):PAGE56
   J27   98  CB1_B SCONN288_ADR50017P130CC-SCONN2A   I179 @S9S_MB_2U_LIB.S9S_MB_2U(SCH_1):PAGE108
   J28   98  CB1_B SCONN288_ADR50017P087CC-SCONN2A    I47 @S9S_MB_2U_LIB.S9S_MB_2U(SCH_1):PAGE109

M_F_CPU1_SB_CB<2> @S9S_MB_2U_LIB.S9S_MB_2U(SCH_1):M_F_CPU1_SB_CB(2)
    U1 EH32 DDR5_SB_ECC2 SOCKET4677_AZIF0045P001C01CS-SA   I168 @S9S_MB_2U_LIB.S9S_MB_2U(SCH_1):PAGE56
   J27  241  CB2_B SCONN288_ADR50017P130CC-SCONN2A   I179 @S9S_MB_2U_LIB.S9S_MB_2U(SCH_1):PAGE108
   J28  241  CB2_B SCONN288_ADR50017P087CC-SCONN2A    I47 @S9S_MB_2U_LIB.S9S_MB_2U(SCH_1):PAGE109

M_F_CPU1_SB_CB<3> @S9S_MB_2U_LIB.S9S_MB_2U(SCH_1):M_F_CPU1_SB_CB(3)
    U1 EG31 DDR5_SB_ECC3 SOCKET4677_AZIF0045P001C01CS-SA   I168 @S9S_MB_2U_LIB.S9S_MB_2U(SCH_1):PAGE56
   J27  243  CB3_B SCONN288_ADR50017P130CC-SCONN2A   I179 @S9S_MB_2U_LIB.S9S_MB_2U(SCH_1):PAGE108
   J28  243  CB3_B SCONN288_ADR50017P087CC-SCONN2A    I47 @S9S_MB_2U_LIB.S9S_MB_2U(SCH_1):PAGE109

M_F_CPU1_SB_CB<4> @S9S_MB_2U_LIB.S9S_MB_2U(SCH_1):M_F_CPU1_SB_CB(4)
    U1 EE35 DDR5_SB_ECC4 SOCKET4677_AZIF0045P001C01CS-SA   I168 @S9S_MB_2U_LIB.S9S_MB_2U(SCH_1):PAGE56
   J27   89  CB4_B SCONN288_ADR50017P130CC-SCONN2A   I179 @S9S_MB_2U_LIB.S9S_MB_2U(SCH_1):PAGE108
   J28   89  CB4_B SCONN288_ADR50017P087CC-SCONN2A    I47 @S9S_MB_2U_LIB.S9S_MB_2U(SCH_1):PAGE109

M_F_CPU1_SB_CB<5> @S9S_MB_2U_LIB.S9S_MB_2U(SCH_1):M_F_CPU1_SB_CB(5)
    U1 ED34 DDR5_SB_ECC5 SOCKET4677_AZIF0045P001C01CS-SA   I168 @S9S_MB_2U_LIB.S9S_MB_2U(SCH_1):PAGE56
   J27   91  CB5_B SCONN288_ADR50017P130CC-SCONN2A   I179 @S9S_MB_2U_LIB.S9S_MB_2U(SCH_1):PAGE108
   J28   91  CB5_B SCONN288_ADR50017P087CC-SCONN2A    I47 @S9S_MB_2U_LIB.S9S_MB_2U(SCH_1):PAGE109

M_F_CPU1_SB_CB<6> @S9S_MB_2U_LIB.S9S_MB_2U(SCH_1):M_F_CPU1_SB_CB(6)
    U1 EG35 DDR5_SB_ECC6 SOCKET4677_AZIF0045P001C01CS-SA   I168 @S9S_MB_2U_LIB.S9S_MB_2U(SCH_1):PAGE56
   J27  234  CB6_B SCONN288_ADR50017P130CC-SCONN2A   I179 @S9S_MB_2U_LIB.S9S_MB_2U(SCH_1):PAGE108
   J28  234  CB6_B SCONN288_ADR50017P087CC-SCONN2A    I47 @S9S_MB_2U_LIB.S9S_MB_2U(SCH_1):PAGE109

M_F_CPU1_SB_CB<7> @S9S_MB_2U_LIB.S9S_MB_2U(SCH_1):M_F_CPU1_SB_CB(7)
    U1 EH34 DDR5_SB_ECC7 SOCKET4677_AZIF0045P001C01CS-SA   I168 @S9S_MB_2U_LIB.S9S_MB_2U(SCH_1):PAGE56
   J27  236  CB7_B SCONN288_ADR50017P130CC-SCONN2A   I179 @S9S_MB_2U_LIB.S9S_MB_2U(SCH_1):PAGE108
   J28  236  CB7_B SCONN288_ADR50017P087CC-SCONN2A    I47 @S9S_MB_2U_LIB.S9S_MB_2U(SCH_1):PAGE109

M_F_CPU1_SB_CS_N<0> @S9S_MB_2U_LIB.S9S_MB_2U(SCH_1):M_F_CPU1_SB_CS_N(0)
    U1 EH38 DDR5_SB_CS_N0 SOCKET4677_AZIF0045P001C01CS-SA   I168 @S9S_MB_2U_LIB.S9S_MB_2U(SCH_1):PAGE56
   J27   84 CS0_B_N SCONN288_ADR50017P130CC-SCONN2A   I179 @S9S_MB_2U_LIB.S9S_MB_2U(SCH_1):PAGE108

M_F_CPU1_SB_CS_N<1> @S9S_MB_2U_LIB.S9S_MB_2U(SCH_1):M_F_CPU1_SB_CS_N(1)
    U1 EG37 DDR5_SB_CS_N1 SOCKET4677_AZIF0045P001C01CS-SA   I168 @S9S_MB_2U_LIB.S9S_MB_2U(SCH_1):PAGE56
   J27  229 CS1_B_N SCONN288_ADR50017P130CC-SCONN2A   I179 @S9S_MB_2U_LIB.S9S_MB_2U(SCH_1):PAGE108

M_F_CPU1_SB_CS_N<2> @S9S_MB_2U_LIB.S9S_MB_2U(SCH_1):M_F_CPU1_SB_CS_N(2)
    U1 ED38 DDR5_SB_CS_N2 SOCKET4677_AZIF0045P001C01CS-SA   I168 @S9S_MB_2U_LIB.S9S_MB_2U(SCH_1):PAGE56
   J28   84 CS0_B_N SCONN288_ADR50017P087CC-SCONN2A    I47 @S9S_MB_2U_LIB.S9S_MB_2U(SCH_1):PAGE109

M_F_CPU1_SB_CS_N<3> @S9S_MB_2U_LIB.S9S_MB_2U(SCH_1):M_F_CPU1_SB_CS_N(3)
    U1 EE37 DDR5_SB_CS_N3 SOCKET4677_AZIF0045P001C01CS-SA   I168 @S9S_MB_2U_LIB.S9S_MB_2U(SCH_1):PAGE56
   J28  229 CS1_B_N SCONN288_ADR50017P087CC-SCONN2A    I47 @S9S_MB_2U_LIB.S9S_MB_2U(SCH_1):PAGE109

M_F_CPU1_SB_DQ<0> @S9S_MB_2U_LIB.S9S_MB_2U(SCH_1):M_F_CPU1_SB_DQ(0)
    U1 DV32 DDR5_SB_DQ0 SOCKET4677_AZIF0045P001C01CS-SA   I168 @S9S_MB_2U_LIB.S9S_MB_2U(SCH_1):PAGE56
   J27  100  DQ0_B SCONN288_ADR50017P130CC-SCONN2A   I179 @S9S_MB_2U_LIB.S9S_MB_2U(SCH_1):PAGE108
   J28  100  DQ0_B SCONN288_ADR50017P087CC-SCONN2A    I47 @S9S_MB_2U_LIB.S9S_MB_2U(SCH_1):PAGE109

M_F_CPU1_SB_DQ<10> @S9S_MB_2U_LIB.S9S_MB_2U(SCH_1):M_F_CPU1_SB_DQ(10)
    U1 EG23 DDR5_SB_DQ10 SOCKET4677_AZIF0045P001C01CS-SA   I168 @S9S_MB_2U_LIB.S9S_MB_2U(SCH_1):PAGE56
   J27  256 DQ10_B SCONN288_ADR50017P130CC-SCONN2A   I179 @S9S_MB_2U_LIB.S9S_MB_2U(SCH_1):PAGE108
   J28  256 DQ10_B SCONN288_ADR50017P087CC-SCONN2A    I47 @S9S_MB_2U_LIB.S9S_MB_2U(SCH_1):PAGE109

M_F_CPU1_SB_DQ<11> @S9S_MB_2U_LIB.S9S_MB_2U(SCH_1):M_F_CPU1_SB_DQ(11)
    U1 EH22 DDR5_SB_DQ11 SOCKET4677_AZIF0045P001C01CS-SA   I168 @S9S_MB_2U_LIB.S9S_MB_2U(SCH_1):PAGE56
   J27  258 DQ11_B SCONN288_ADR50017P130CC-SCONN2A   I179 @S9S_MB_2U_LIB.S9S_MB_2U(SCH_1):PAGE108
   J28  258 DQ11_B SCONN288_ADR50017P087CC-SCONN2A    I47 @S9S_MB_2U_LIB.S9S_MB_2U(SCH_1):PAGE109

M_F_CPU1_SB_DQ<12> @S9S_MB_2U_LIB.S9S_MB_2U(SCH_1):M_F_CPU1_SB_DQ(12)
    U1 ED20 DDR5_SB_DQ12 SOCKET4677_AZIF0045P001C01CS-SA   I168 @S9S_MB_2U_LIB.S9S_MB_2U(SCH_1):PAGE56
   J27  118 DQ12_B SCONN288_ADR50017P130CC-SCONN2A   I179 @S9S_MB_2U_LIB.S9S_MB_2U(SCH_1):PAGE108
   J28  118 DQ12_B SCONN288_ADR50017P087CC-SCONN2A    I47 @S9S_MB_2U_LIB.S9S_MB_2U(SCH_1):PAGE109

M_F_CPU1_SB_DQ<13> @S9S_MB_2U_LIB.S9S_MB_2U(SCH_1):M_F_CPU1_SB_DQ(13)
    U1 EE19 DDR5_SB_DQ13 SOCKET4677_AZIF0045P001C01CS-SA   I168 @S9S_MB_2U_LIB.S9S_MB_2U(SCH_1):PAGE56
   J27  120 DQ13_B SCONN288_ADR50017P130CC-SCONN2A   I179 @S9S_MB_2U_LIB.S9S_MB_2U(SCH_1):PAGE108
   J28  120 DQ13_B SCONN288_ADR50017P087CC-SCONN2A    I47 @S9S_MB_2U_LIB.S9S_MB_2U(SCH_1):PAGE109

M_F_CPU1_SB_DQ<14> @S9S_MB_2U_LIB.S9S_MB_2U(SCH_1):M_F_CPU1_SB_DQ(14)
    U1 EH20 DDR5_SB_DQ14 SOCKET4677_AZIF0045P001C01CS-SA   I168 @S9S_MB_2U_LIB.S9S_MB_2U(SCH_1):PAGE56
   J27  263 DQ14_B SCONN288_ADR50017P130CC-SCONN2A   I179 @S9S_MB_2U_LIB.S9S_MB_2U(SCH_1):PAGE108
   J28  263 DQ14_B SCONN288_ADR50017P087CC-SCONN2A    I47 @S9S_MB_2U_LIB.S9S_MB_2U(SCH_1):PAGE109

M_F_CPU1_SB_DQ<15> @S9S_MB_2U_LIB.S9S_MB_2U(SCH_1):M_F_CPU1_SB_DQ(15)
    U1 EG19 DDR5_SB_DQ15 SOCKET4677_AZIF0045P001C01CS-SA   I168 @S9S_MB_2U_LIB.S9S_MB_2U(SCH_1):PAGE56
   J27  265 DQ15_B SCONN288_ADR50017P130CC-SCONN2A   I179 @S9S_MB_2U_LIB.S9S_MB_2U(SCH_1):PAGE108
   J28  265 DQ15_B SCONN288_ADR50017P087CC-SCONN2A    I47 @S9S_MB_2U_LIB.S9S_MB_2U(SCH_1):PAGE109

M_F_CPU1_SB_DQ<16> @S9S_MB_2U_LIB.S9S_MB_2U(SCH_1):M_F_CPU1_SB_DQ(16)
    U1 EM14 DDR5_SB_DQ16 SOCKET4677_AZIF0045P001C01CS-SA   I168 @S9S_MB_2U_LIB.S9S_MB_2U(SCH_1):PAGE56
   J27  122 DQ16_B SCONN288_ADR50017P130CC-SCONN2A   I179 @S9S_MB_2U_LIB.S9S_MB_2U(SCH_1):PAGE108
   J28  122 DQ16_B SCONN288_ADR50017P087CC-SCONN2A    I47 @S9S_MB_2U_LIB.S9S_MB_2U(SCH_1):PAGE109

M_F_CPU1_SB_DQ<17> @S9S_MB_2U_LIB.S9S_MB_2U(SCH_1):M_F_CPU1_SB_DQ(17)
    U1 EL13 DDR5_SB_DQ17 SOCKET4677_AZIF0045P001C01CS-SA   I168 @S9S_MB_2U_LIB.S9S_MB_2U(SCH_1):PAGE56
   J27  124 DQ17_B SCONN288_ADR50017P130CC-SCONN2A   I179 @S9S_MB_2U_LIB.S9S_MB_2U(SCH_1):PAGE108
   J28  124 DQ17_B SCONN288_ADR50017P087CC-SCONN2A    I47 @S9S_MB_2U_LIB.S9S_MB_2U(SCH_1):PAGE109

M_F_CPU1_SB_DQ<18> @S9S_MB_2U_LIB.S9S_MB_2U(SCH_1):M_F_CPU1_SB_DQ(18)
    U1 EP14 DDR5_SB_DQ18 SOCKET4677_AZIF0045P001C01CS-SA   I168 @S9S_MB_2U_LIB.S9S_MB_2U(SCH_1):PAGE56
   J27  267 DQ18_B SCONN288_ADR50017P130CC-SCONN2A   I179 @S9S_MB_2U_LIB.S9S_MB_2U(SCH_1):PAGE108
   J28  267 DQ18_B SCONN288_ADR50017P087CC-SCONN2A    I47 @S9S_MB_2U_LIB.S9S_MB_2U(SCH_1):PAGE109

M_F_CPU1_SB_DQ<19> @S9S_MB_2U_LIB.S9S_MB_2U(SCH_1):M_F_CPU1_SB_DQ(19)
    U1 ER13 DDR5_SB_DQ19 SOCKET4677_AZIF0045P001C01CS-SA   I168 @S9S_MB_2U_LIB.S9S_MB_2U(SCH_1):PAGE56
   J27  269 DQ19_B SCONN288_ADR50017P130CC-SCONN2A   I179 @S9S_MB_2U_LIB.S9S_MB_2U(SCH_1):PAGE108
   J28  269 DQ19_B SCONN288_ADR50017P087CC-SCONN2A    I47 @S9S_MB_2U_LIB.S9S_MB_2U(SCH_1):PAGE109

M_F_CPU1_SB_DQ<1> @S9S_MB_2U_LIB.S9S_MB_2U(SCH_1):M_F_CPU1_SB_DQ(1)
    U1 DU31 DDR5_SB_DQ1 SOCKET4677_AZIF0045P001C01CS-SA   I168 @S9S_MB_2U_LIB.S9S_MB_2U(SCH_1):PAGE56
   J27  102  DQ1_B SCONN288_ADR50017P130CC-SCONN2A   I179 @S9S_MB_2U_LIB.S9S_MB_2U(SCH_1):PAGE108
   J28  102  DQ1_B SCONN288_ADR50017P087CC-SCONN2A    I47 @S9S_MB_2U_LIB.S9S_MB_2U(SCH_1):PAGE109

M_F_CPU1_SB_DQ<20> @S9S_MB_2U_LIB.S9S_MB_2U(SCH_1):M_F_CPU1_SB_DQ(20)
    U1 EL11 DDR5_SB_DQ20 SOCKET4677_AZIF0045P001C01CS-SA   I168 @S9S_MB_2U_LIB.S9S_MB_2U(SCH_1):PAGE56
   J27  129 DQ20_B SCONN288_ADR50017P130CC-SCONN2A   I179 @S9S_MB_2U_LIB.S9S_MB_2U(SCH_1):PAGE108
   J28  129 DQ20_B SCONN288_ADR50017P087CC-SCONN2A    I47 @S9S_MB_2U_LIB.S9S_MB_2U(SCH_1):PAGE109

M_F_CPU1_SB_DQ<21> @S9S_MB_2U_LIB.S9S_MB_2U(SCH_1):M_F_CPU1_SB_DQ(21)
    U1 EM10 DDR5_SB_DQ21 SOCKET4677_AZIF0045P001C01CS-SA   I168 @S9S_MB_2U_LIB.S9S_MB_2U(SCH_1):PAGE56
   J27  131 DQ21_B SCONN288_ADR50017P130CC-SCONN2A   I179 @S9S_MB_2U_LIB.S9S_MB_2U(SCH_1):PAGE108
   J28  131 DQ21_B SCONN288_ADR50017P087CC-SCONN2A    I47 @S9S_MB_2U_LIB.S9S_MB_2U(SCH_1):PAGE109

M_F_CPU1_SB_DQ<22> @S9S_MB_2U_LIB.S9S_MB_2U(SCH_1):M_F_CPU1_SB_DQ(22)
    U1 ER11 DDR5_SB_DQ22 SOCKET4677_AZIF0045P001C01CS-SA   I168 @S9S_MB_2U_LIB.S9S_MB_2U(SCH_1):PAGE56
   J27  274 DQ22_B SCONN288_ADR50017P130CC-SCONN2A   I179 @S9S_MB_2U_LIB.S9S_MB_2U(SCH_1):PAGE108
   J28  274 DQ22_B SCONN288_ADR50017P087CC-SCONN2A    I47 @S9S_MB_2U_LIB.S9S_MB_2U(SCH_1):PAGE109

M_F_CPU1_SB_DQ<23> @S9S_MB_2U_LIB.S9S_MB_2U(SCH_1):M_F_CPU1_SB_DQ(23)
    U1 EP10 DDR5_SB_DQ23 SOCKET4677_AZIF0045P001C01CS-SA   I168 @S9S_MB_2U_LIB.S9S_MB_2U(SCH_1):PAGE56
   J27  276 DQ23_B SCONN288_ADR50017P130CC-SCONN2A   I179 @S9S_MB_2U_LIB.S9S_MB_2U(SCH_1):PAGE108
   J28  276 DQ23_B SCONN288_ADR50017P087CC-SCONN2A    I47 @S9S_MB_2U_LIB.S9S_MB_2U(SCH_1):PAGE109

M_F_CPU1_SB_DQ<24> @S9S_MB_2U_LIB.S9S_MB_2U(SCH_1):M_F_CPU1_SB_DQ(24)
    U1 DV20 DDR5_SB_DQ24 SOCKET4677_AZIF0045P001C01CS-SA   I168 @S9S_MB_2U_LIB.S9S_MB_2U(SCH_1):PAGE56
   J27  133 DQ24_B SCONN288_ADR50017P130CC-SCONN2A   I179 @S9S_MB_2U_LIB.S9S_MB_2U(SCH_1):PAGE108
   J28  133 DQ24_B SCONN288_ADR50017P087CC-SCONN2A    I47 @S9S_MB_2U_LIB.S9S_MB_2U(SCH_1):PAGE109

M_F_CPU1_SB_DQ<25> @S9S_MB_2U_LIB.S9S_MB_2U(SCH_1):M_F_CPU1_SB_DQ(25)
    U1 DU19 DDR5_SB_DQ25 SOCKET4677_AZIF0045P001C01CS-SA   I168 @S9S_MB_2U_LIB.S9S_MB_2U(SCH_1):PAGE56
   J27  135 DQ25_B SCONN288_ADR50017P130CC-SCONN2A   I179 @S9S_MB_2U_LIB.S9S_MB_2U(SCH_1):PAGE108
   J28  135 DQ25_B SCONN288_ADR50017P087CC-SCONN2A    I47 @S9S_MB_2U_LIB.S9S_MB_2U(SCH_1):PAGE109

M_F_CPU1_SB_DQ<26> @S9S_MB_2U_LIB.S9S_MB_2U(SCH_1):M_F_CPU1_SB_DQ(26)
    U1 DY20 DDR5_SB_DQ26 SOCKET4677_AZIF0045P001C01CS-SA   I168 @S9S_MB_2U_LIB.S9S_MB_2U(SCH_1):PAGE56
   J27  278 DQ26_B SCONN288_ADR50017P130CC-SCONN2A   I179 @S9S_MB_2U_LIB.S9S_MB_2U(SCH_1):PAGE108
   J28  278 DQ26_B SCONN288_ADR50017P087CC-SCONN2A    I47 @S9S_MB_2U_LIB.S9S_MB_2U(SCH_1):PAGE109

M_F_CPU1_SB_DQ<27> @S9S_MB_2U_LIB.S9S_MB_2U(SCH_1):M_F_CPU1_SB_DQ(27)
    U1 EA19 DDR5_SB_DQ27 SOCKET4677_AZIF0045P001C01CS-SA   I168 @S9S_MB_2U_LIB.S9S_MB_2U(SCH_1):PAGE56
   J27  280 DQ27_B SCONN288_ADR50017P130CC-SCONN2A   I179 @S9S_MB_2U_LIB.S9S_MB_2U(SCH_1):PAGE108
   J28  280 DQ27_B SCONN288_ADR50017P087CC-SCONN2A    I47 @S9S_MB_2U_LIB.S9S_MB_2U(SCH_1):PAGE109

M_F_CPU1_SB_DQ<28> @S9S_MB_2U_LIB.S9S_MB_2U(SCH_1):M_F_CPU1_SB_DQ(28)
    U1 EA17 DDR5_SB_DQ28 SOCKET4677_AZIF0045P001C01CS-SA   I168 @S9S_MB_2U_LIB.S9S_MB_2U(SCH_1):PAGE56
   J27  140 DQ28_B SCONN288_ADR50017P130CC-SCONN2A   I179 @S9S_MB_2U_LIB.S9S_MB_2U(SCH_1):PAGE108
   J28  140 DQ28_B SCONN288_ADR50017P087CC-SCONN2A    I47 @S9S_MB_2U_LIB.S9S_MB_2U(SCH_1):PAGE109

M_F_CPU1_SB_DQ<29> @S9S_MB_2U_LIB.S9S_MB_2U(SCH_1):M_F_CPU1_SB_DQ(29)
    U1 DU17 DDR5_SB_DQ29 SOCKET4677_AZIF0045P001C01CS-SA   I168 @S9S_MB_2U_LIB.S9S_MB_2U(SCH_1):PAGE56
   J27  142 DQ29_B SCONN288_ADR50017P130CC-SCONN2A   I179 @S9S_MB_2U_LIB.S9S_MB_2U(SCH_1):PAGE108
   J28  142 DQ29_B SCONN288_ADR50017P087CC-SCONN2A    I47 @S9S_MB_2U_LIB.S9S_MB_2U(SCH_1):PAGE109

M_F_CPU1_SB_DQ<2> @S9S_MB_2U_LIB.S9S_MB_2U(SCH_1):M_F_CPU1_SB_DQ(2)
    U1 DY32 DDR5_SB_DQ2 SOCKET4677_AZIF0045P001C01CS-SA   I168 @S9S_MB_2U_LIB.S9S_MB_2U(SCH_1):PAGE56
   J27  245  DQ2_B SCONN288_ADR50017P130CC-SCONN2A   I179 @S9S_MB_2U_LIB.S9S_MB_2U(SCH_1):PAGE108
   J28  245  DQ2_B SCONN288_ADR50017P087CC-SCONN2A    I47 @S9S_MB_2U_LIB.S9S_MB_2U(SCH_1):PAGE109

M_F_CPU1_SB_DQ<30> @S9S_MB_2U_LIB.S9S_MB_2U(SCH_1):M_F_CPU1_SB_DQ(30)
    U1 EC17 DDR5_SB_DQ30 SOCKET4677_AZIF0045P001C01CS-SA   I168 @S9S_MB_2U_LIB.S9S_MB_2U(SCH_1):PAGE56
   J27  285 DQ30_B SCONN288_ADR50017P130CC-SCONN2A   I179 @S9S_MB_2U_LIB.S9S_MB_2U(SCH_1):PAGE108
   J28  285 DQ30_B SCONN288_ADR50017P087CC-SCONN2A    I47 @S9S_MB_2U_LIB.S9S_MB_2U(SCH_1):PAGE109

M_F_CPU1_SB_DQ<31> @S9S_MB_2U_LIB.S9S_MB_2U(SCH_1):M_F_CPU1_SB_DQ(31)
    U1 DR17 DDR5_SB_DQ31 SOCKET4677_AZIF0045P001C01CS-SA   I168 @S9S_MB_2U_LIB.S9S_MB_2U(SCH_1):PAGE56
   J27  287 DQ31_B SCONN288_ADR50017P130CC-SCONN2A   I179 @S9S_MB_2U_LIB.S9S_MB_2U(SCH_1):PAGE108
   J28  287 DQ31_B SCONN288_ADR50017P087CC-SCONN2A    I47 @S9S_MB_2U_LIB.S9S_MB_2U(SCH_1):PAGE109

M_F_CPU1_SB_DQ<3> @S9S_MB_2U_LIB.S9S_MB_2U(SCH_1):M_F_CPU1_SB_DQ(3)
    U1 EA31 DDR5_SB_DQ3 SOCKET4677_AZIF0045P001C01CS-SA   I168 @S9S_MB_2U_LIB.S9S_MB_2U(SCH_1):PAGE56
   J27  247  DQ3_B SCONN288_ADR50017P130CC-SCONN2A   I179 @S9S_MB_2U_LIB.S9S_MB_2U(SCH_1):PAGE108
   J28  247  DQ3_B SCONN288_ADR50017P087CC-SCONN2A    I47 @S9S_MB_2U_LIB.S9S_MB_2U(SCH_1):PAGE109

M_F_CPU1_SB_DQ<4> @S9S_MB_2U_LIB.S9S_MB_2U(SCH_1):M_F_CPU1_SB_DQ(4)
    U1 DU29 DDR5_SB_DQ4 SOCKET4677_AZIF0045P001C01CS-SA   I168 @S9S_MB_2U_LIB.S9S_MB_2U(SCH_1):PAGE56
   J27  107  DQ4_B SCONN288_ADR50017P130CC-SCONN2A   I179 @S9S_MB_2U_LIB.S9S_MB_2U(SCH_1):PAGE108
   J28  107  DQ4_B SCONN288_ADR50017P087CC-SCONN2A    I47 @S9S_MB_2U_LIB.S9S_MB_2U(SCH_1):PAGE109

M_F_CPU1_SB_DQ<5> @S9S_MB_2U_LIB.S9S_MB_2U(SCH_1):M_F_CPU1_SB_DQ(5)
    U1 DV28 DDR5_SB_DQ5 SOCKET4677_AZIF0045P001C01CS-SA   I168 @S9S_MB_2U_LIB.S9S_MB_2U(SCH_1):PAGE56
   J27  109  DQ5_B SCONN288_ADR50017P130CC-SCONN2A   I179 @S9S_MB_2U_LIB.S9S_MB_2U(SCH_1):PAGE108
   J28  109  DQ5_B SCONN288_ADR50017P087CC-SCONN2A    I47 @S9S_MB_2U_LIB.S9S_MB_2U(SCH_1):PAGE109

M_F_CPU1_SB_DQ<6> @S9S_MB_2U_LIB.S9S_MB_2U(SCH_1):M_F_CPU1_SB_DQ(6)
    U1 EA29 DDR5_SB_DQ6 SOCKET4677_AZIF0045P001C01CS-SA   I168 @S9S_MB_2U_LIB.S9S_MB_2U(SCH_1):PAGE56
   J27  252  DQ6_B SCONN288_ADR50017P130CC-SCONN2A   I179 @S9S_MB_2U_LIB.S9S_MB_2U(SCH_1):PAGE108
   J28  252  DQ6_B SCONN288_ADR50017P087CC-SCONN2A    I47 @S9S_MB_2U_LIB.S9S_MB_2U(SCH_1):PAGE109

M_F_CPU1_SB_DQ<7> @S9S_MB_2U_LIB.S9S_MB_2U(SCH_1):M_F_CPU1_SB_DQ(7)
    U1 DY28 DDR5_SB_DQ7 SOCKET4677_AZIF0045P001C01CS-SA   I168 @S9S_MB_2U_LIB.S9S_MB_2U(SCH_1):PAGE56
   J27  254  DQ7_B SCONN288_ADR50017P130CC-SCONN2A   I179 @S9S_MB_2U_LIB.S9S_MB_2U(SCH_1):PAGE108
   J28  254  DQ7_B SCONN288_ADR50017P087CC-SCONN2A    I47 @S9S_MB_2U_LIB.S9S_MB_2U(SCH_1):PAGE109

M_F_CPU1_SB_DQ<8> @S9S_MB_2U_LIB.S9S_MB_2U(SCH_1):M_F_CPU1_SB_DQ(8)
    U1 EE23 DDR5_SB_DQ8 SOCKET4677_AZIF0045P001C01CS-SA   I168 @S9S_MB_2U_LIB.S9S_MB_2U(SCH_1):PAGE56
   J27  111  DQ8_B SCONN288_ADR50017P130CC-SCONN2A   I179 @S9S_MB_2U_LIB.S9S_MB_2U(SCH_1):PAGE108
   J28  111  DQ8_B SCONN288_ADR50017P087CC-SCONN2A    I47 @S9S_MB_2U_LIB.S9S_MB_2U(SCH_1):PAGE109

M_F_CPU1_SB_DQ<9> @S9S_MB_2U_LIB.S9S_MB_2U(SCH_1):M_F_CPU1_SB_DQ(9)
    U1 ED22 DDR5_SB_DQ9 SOCKET4677_AZIF0045P001C01CS-SA   I168 @S9S_MB_2U_LIB.S9S_MB_2U(SCH_1):PAGE56
   J27  113  DQ9_B SCONN288_ADR50017P130CC-SCONN2A   I179 @S9S_MB_2U_LIB.S9S_MB_2U(SCH_1):PAGE108
   J28  113  DQ9_B SCONN288_ADR50017P087CC-SCONN2A    I47 @S9S_MB_2U_LIB.S9S_MB_2U(SCH_1):PAGE109

M_F_CPU1_SB_DQS_DN<0> @S9S_MB_2U_LIB.S9S_MB_2U(SCH_1):M_F_CPU1_SB_DQS_DN(0)
    U1 DV30 DDR5_SB_DQS_DN0 SOCKET4677_AZIF0045P001C01CS-SA   I168 @S9S_MB_2U_LIB.S9S_MB_2U(SCH_1):PAGE56
   J27  105 DQS0_B_C SCONN288_ADR50017P130CC-SCONN2A   I180 @S9S_MB_2U_LIB.S9S_MB_2U(SCH_1):PAGE108
   J28  105 DQS0_B_C SCONN288_ADR50017P087CC-SCONN2A   I178 @S9S_MB_2U_LIB.S9S_MB_2U(SCH_1):PAGE109

M_F_CPU1_SB_DQS_DN<1> @S9S_MB_2U_LIB.S9S_MB_2U(SCH_1):M_F_CPU1_SB_DQS_DN(1)
    U1 EE21 DDR5_SB_DQS_DN1 SOCKET4677_AZIF0045P001C01CS-SA   I168 @S9S_MB_2U_LIB.S9S_MB_2U(SCH_1):PAGE56
   J27  116 DQS1_B_C SCONN288_ADR50017P130CC-SCONN2A   I180 @S9S_MB_2U_LIB.S9S_MB_2U(SCH_1):PAGE108
   J28  116 DQS1_B_C SCONN288_ADR50017P087CC-SCONN2A   I178 @S9S_MB_2U_LIB.S9S_MB_2U(SCH_1):PAGE109

M_F_CPU1_SB_DQS_DN<2> @S9S_MB_2U_LIB.S9S_MB_2U(SCH_1):M_F_CPU1_SB_DQS_DN(2)
    U1 EM12 DDR5_SB_DQS_DN2 SOCKET4677_AZIF0045P001C01CS-SA   I168 @S9S_MB_2U_LIB.S9S_MB_2U(SCH_1):PAGE56
   J27  127 DQS2_B_C SCONN288_ADR50017P130CC-SCONN2A   I180 @S9S_MB_2U_LIB.S9S_MB_2U(SCH_1):PAGE108
   J28  127 DQS2_B_C SCONN288_ADR50017P087CC-SCONN2A   I178 @S9S_MB_2U_LIB.S9S_MB_2U(SCH_1):PAGE109

M_F_CPU1_SB_DQS_DN<3> @S9S_MB_2U_LIB.S9S_MB_2U(SCH_1):M_F_CPU1_SB_DQS_DN(3)
    U1 DT18 DDR5_SB_DQS_DN3 SOCKET4677_AZIF0045P001C01CS-SA   I168 @S9S_MB_2U_LIB.S9S_MB_2U(SCH_1):PAGE56
   J27  138 DQS3_B_C SCONN288_ADR50017P130CC-SCONN2A   I180 @S9S_MB_2U_LIB.S9S_MB_2U(SCH_1):PAGE108
   J28  138 DQS3_B_C SCONN288_ADR50017P087CC-SCONN2A   I178 @S9S_MB_2U_LIB.S9S_MB_2U(SCH_1):PAGE109

M_F_CPU1_SB_DQS_DN<4> @S9S_MB_2U_LIB.S9S_MB_2U(SCH_1):M_F_CPU1_SB_DQS_DN(4)
    U1 EJ33 DDR5_SB_DQS_DN4 SOCKET4677_AZIF0045P001C01CS-SA   I168 @S9S_MB_2U_LIB.S9S_MB_2U(SCH_1):PAGE56
   J27  238 DQS4_B_C SCONN288_ADR50017P130CC-SCONN2A   I180 @S9S_MB_2U_LIB.S9S_MB_2U(SCH_1):PAGE108
   J28  238 DQS4_B_C SCONN288_ADR50017P087CC-SCONN2A   I178 @S9S_MB_2U_LIB.S9S_MB_2U(SCH_1):PAGE109

M_F_CPU1_SB_DQS_DN<5> @S9S_MB_2U_LIB.S9S_MB_2U(SCH_1):M_F_CPU1_SB_DQS_DN(5)
    U1 EB30 DDR5_SB_DQS_DN5 SOCKET4677_AZIF0045P001C01CS-SA   I168 @S9S_MB_2U_LIB.S9S_MB_2U(SCH_1):PAGE56
   J27  249 DQS5_B_C||TDQS5_B_C SCONN288_ADR50017P130CC-SCONN2A   I180 @S9S_MB_2U_LIB.S9S_MB_2U(SCH_1):PAGE108
   J28  249 DQS5_B_C||TDQS5_B_C SCONN288_ADR50017P087CC-SCONN2A   I178 @S9S_MB_2U_LIB.S9S_MB_2U(SCH_1):PAGE109

M_F_CPU1_SB_DQS_DN<6> @S9S_MB_2U_LIB.S9S_MB_2U(SCH_1):M_F_CPU1_SB_DQS_DN(6)
    U1 EJ21 DDR5_SB_DQS_DN6 SOCKET4677_AZIF0045P001C01CS-SA   I168 @S9S_MB_2U_LIB.S9S_MB_2U(SCH_1):PAGE56
   J27  260 DQS6_B_C||TDQS6_B_C SCONN288_ADR50017P130CC-SCONN2A   I180 @S9S_MB_2U_LIB.S9S_MB_2U(SCH_1):PAGE108
   J28  260 DQS6_B_C||TDQS6_B_C SCONN288_ADR50017P087CC-SCONN2A   I178 @S9S_MB_2U_LIB.S9S_MB_2U(SCH_1):PAGE109

M_F_CPU1_SB_DQS_DN<7> @S9S_MB_2U_LIB.S9S_MB_2U(SCH_1):M_F_CPU1_SB_DQS_DN(7)
    U1 ET12 DDR5_SB_DQS_DN7 SOCKET4677_AZIF0045P001C01CS-SA   I168 @S9S_MB_2U_LIB.S9S_MB_2U(SCH_1):PAGE56
   J27  271 DQS7_B_C||TDQS7_B_C SCONN288_ADR50017P130CC-SCONN2A   I180 @S9S_MB_2U_LIB.S9S_MB_2U(SCH_1):PAGE108
   J28  271 DQS7_B_C||TDQS7_B_C SCONN288_ADR50017P087CC-SCONN2A   I178 @S9S_MB_2U_LIB.S9S_MB_2U(SCH_1):PAGE109

M_F_CPU1_SB_DQS_DN<8> @S9S_MB_2U_LIB.S9S_MB_2U(SCH_1):M_F_CPU1_SB_DQS_DN(8)
    U1 DY18 DDR5_SB_DQS_DN8 SOCKET4677_AZIF0045P001C01CS-SA   I168 @S9S_MB_2U_LIB.S9S_MB_2U(SCH_1):PAGE56
   J27  282 DQS8_B_C||TDQS8_B_C SCONN288_ADR50017P130CC-SCONN2A   I180 @S9S_MB_2U_LIB.S9S_MB_2U(SCH_1):PAGE108
   J28  282 DQS8_B_C||TDQS8_B_C SCONN288_ADR50017P087CC-SCONN2A   I178 @S9S_MB_2U_LIB.S9S_MB_2U(SCH_1):PAGE109

M_F_CPU1_SB_DQS_DN<9> @S9S_MB_2U_LIB.S9S_MB_2U(SCH_1):M_F_CPU1_SB_DQS_DN(9)
    U1 EE33 DDR5_SB_DQS_DN9 SOCKET4677_AZIF0045P001C01CS-SA   I168 @S9S_MB_2U_LIB.S9S_MB_2U(SCH_1):PAGE56
   J27   94 DQS9_B_C||TDQS9_B_C SCONN288_ADR50017P130CC-SCONN2A   I180 @S9S_MB_2U_LIB.S9S_MB_2U(SCH_1):PAGE108
   J28   94 DQS9_B_C||TDQS9_B_C SCONN288_ADR50017P087CC-SCONN2A   I178 @S9S_MB_2U_LIB.S9S_MB_2U(SCH_1):PAGE109

M_F_CPU1_SB_DQS_DP<0> @S9S_MB_2U_LIB.S9S_MB_2U(SCH_1):M_F_CPU1_SB_DQS_DP(0)
    U1 DT30 DDR5_SB_DQS_DP0 SOCKET4677_AZIF0045P001C01CS-SA   I168 @S9S_MB_2U_LIB.S9S_MB_2U(SCH_1):PAGE56
   J27  104 DQS0_B_T SCONN288_ADR50017P130CC-SCONN2A   I180 @S9S_MB_2U_LIB.S9S_MB_2U(SCH_1):PAGE108
   J28  104 DQS0_B_T SCONN288_ADR50017P087CC-SCONN2A   I178 @S9S_MB_2U_LIB.S9S_MB_2U(SCH_1):PAGE109

M_F_CPU1_SB_DQS_DP<1> @S9S_MB_2U_LIB.S9S_MB_2U(SCH_1):M_F_CPU1_SB_DQS_DP(1)
    U1 EC21 DDR5_SB_DQS_DP1 SOCKET4677_AZIF0045P001C01CS-SA   I168 @S9S_MB_2U_LIB.S9S_MB_2U(SCH_1):PAGE56
   J27  115 DQS1_B_T SCONN288_ADR50017P130CC-SCONN2A   I180 @S9S_MB_2U_LIB.S9S_MB_2U(SCH_1):PAGE108
   J28  115 DQS1_B_T SCONN288_ADR50017P087CC-SCONN2A   I178 @S9S_MB_2U_LIB.S9S_MB_2U(SCH_1):PAGE109

M_F_CPU1_SB_DQS_DP<2> @S9S_MB_2U_LIB.S9S_MB_2U(SCH_1):M_F_CPU1_SB_DQS_DP(2)
    U1 EK12 DDR5_SB_DQS_DP2 SOCKET4677_AZIF0045P001C01CS-SA   I168 @S9S_MB_2U_LIB.S9S_MB_2U(SCH_1):PAGE56
   J27  126 DQS2_B_T SCONN288_ADR50017P130CC-SCONN2A   I180 @S9S_MB_2U_LIB.S9S_MB_2U(SCH_1):PAGE108
   J28  126 DQS2_B_T SCONN288_ADR50017P087CC-SCONN2A   I178 @S9S_MB_2U_LIB.S9S_MB_2U(SCH_1):PAGE109

M_F_CPU1_SB_DQS_DP<3> @S9S_MB_2U_LIB.S9S_MB_2U(SCH_1):M_F_CPU1_SB_DQS_DP(3)
    U1 DV18 DDR5_SB_DQS_DP3 SOCKET4677_AZIF0045P001C01CS-SA   I168 @S9S_MB_2U_LIB.S9S_MB_2U(SCH_1):PAGE56
   J27  137 DQS3_B_T SCONN288_ADR50017P130CC-SCONN2A   I180 @S9S_MB_2U_LIB.S9S_MB_2U(SCH_1):PAGE108
   J28  137 DQS3_B_T SCONN288_ADR50017P087CC-SCONN2A   I178 @S9S_MB_2U_LIB.S9S_MB_2U(SCH_1):PAGE109

M_F_CPU1_SB_DQS_DP<4> @S9S_MB_2U_LIB.S9S_MB_2U(SCH_1):M_F_CPU1_SB_DQS_DP(4)
    U1 EG33 DDR5_SB_DQS_DP4 SOCKET4677_AZIF0045P001C01CS-SA   I168 @S9S_MB_2U_LIB.S9S_MB_2U(SCH_1):PAGE56
   J27  239 DQS4_B_T SCONN288_ADR50017P130CC-SCONN2A   I180 @S9S_MB_2U_LIB.S9S_MB_2U(SCH_1):PAGE108
   J28  239 DQS4_B_T SCONN288_ADR50017P087CC-SCONN2A   I178 @S9S_MB_2U_LIB.S9S_MB_2U(SCH_1):PAGE109

M_F_CPU1_SB_DQS_DP<5> @S9S_MB_2U_LIB.S9S_MB_2U(SCH_1):M_F_CPU1_SB_DQS_DP(5)
    U1 DY30 DDR5_SB_DQS_DP5 SOCKET4677_AZIF0045P001C01CS-SA   I168 @S9S_MB_2U_LIB.S9S_MB_2U(SCH_1):PAGE56
   J27  250 DQS5_B_T||TDQS5_B_T SCONN288_ADR50017P130CC-SCONN2A   I180 @S9S_MB_2U_LIB.S9S_MB_2U(SCH_1):PAGE108
   J28  250 DQS5_B_T||TDQS5_B_T SCONN288_ADR50017P087CC-SCONN2A   I178 @S9S_MB_2U_LIB.S9S_MB_2U(SCH_1):PAGE109

M_F_CPU1_SB_DQS_DP<6> @S9S_MB_2U_LIB.S9S_MB_2U(SCH_1):M_F_CPU1_SB_DQS_DP(6)
    U1 EG21 DDR5_SB_DQS_DP6 SOCKET4677_AZIF0045P001C01CS-SA   I168 @S9S_MB_2U_LIB.S9S_MB_2U(SCH_1):PAGE56
   J27  261 DQS6_B_T||TDQS6_B_T SCONN288_ADR50017P130CC-SCONN2A   I180 @S9S_MB_2U_LIB.S9S_MB_2U(SCH_1):PAGE108
   J28  261 DQS6_B_T||TDQS6_B_T SCONN288_ADR50017P087CC-SCONN2A   I178 @S9S_MB_2U_LIB.S9S_MB_2U(SCH_1):PAGE109

M_F_CPU1_SB_DQS_DP<7> @S9S_MB_2U_LIB.S9S_MB_2U(SCH_1):M_F_CPU1_SB_DQS_DP(7)
    U1 EP12 DDR5_SB_DQS_DP7 SOCKET4677_AZIF0045P001C01CS-SA   I168 @S9S_MB_2U_LIB.S9S_MB_2U(SCH_1):PAGE56
   J27  272 DQS7_B_T||TDQS7_B_T SCONN288_ADR50017P130CC-SCONN2A   I180 @S9S_MB_2U_LIB.S9S_MB_2U(SCH_1):PAGE108
   J28  272 DQS7_B_T||TDQS7_B_T SCONN288_ADR50017P087CC-SCONN2A   I178 @S9S_MB_2U_LIB.S9S_MB_2U(SCH_1):PAGE109

M_F_CPU1_SB_DQS_DP<8> @S9S_MB_2U_LIB.S9S_MB_2U(SCH_1):M_F_CPU1_SB_DQS_DP(8)
    U1 EB18 DDR5_SB_DQS_DP8 SOCKET4677_AZIF0045P001C01CS-SA   I168 @S9S_MB_2U_LIB.S9S_MB_2U(SCH_1):PAGE56
   J27  283 DQS8_B_T||TDQS8_B_T SCONN288_ADR50017P130CC-SCONN2A   I180 @S9S_MB_2U_LIB.S9S_MB_2U(SCH_1):PAGE108
   J28  283 DQS8_B_T||TDQS8_B_T SCONN288_ADR50017P087CC-SCONN2A   I178 @S9S_MB_2U_LIB.S9S_MB_2U(SCH_1):PAGE109

M_F_CPU1_SB_DQS_DP<9> @S9S_MB_2U_LIB.S9S_MB_2U(SCH_1):M_F_CPU1_SB_DQS_DP(9)
    U1 EC33 DDR5_SB_DQS_DP9 SOCKET4677_AZIF0045P001C01CS-SA   I168 @S9S_MB_2U_LIB.S9S_MB_2U(SCH_1):PAGE56
   J27   93 DQS9_B_T||TDQS9_B_T||DBI4_B_N SCONN288_ADR50017P130CC-SCONN2A   I180 @S9S_MB_2U_LIB.S9S_MB_2U(SCH_1):PAGE108
   J28   93 DQS9_B_T||TDQS9_B_T||DBI4_B_N SCONN288_ADR50017P087CC-SCONN2A   I178 @S9S_MB_2U_LIB.S9S_MB_2U(SCH_1):PAGE109

M_F_CPU1_SB_PAR @S9S_MB_2U_LIB.S9S_MB_2U(SCH_1):M_F_CPU1_SB_PAR
    U1 EJ39 DDR5_SB_PAR SOCKET4677_AZIF0045P001C01CS-SA   I168 @S9S_MB_2U_LIB.S9S_MB_2U(SCH_1):PAGE56
   J27  227  PAR_B SCONN288_ADR50017P130CC-SCONN2A   I179 @S9S_MB_2U_LIB.S9S_MB_2U(SCH_1):PAGE108
   J28  227  PAR_B SCONN288_ADR50017P087CC-SCONN2A    I47 @S9S_MB_2U_LIB.S9S_MB_2U(SCH_1):PAGE109

M_F_CPU1_SB_RSP<0> @S9S_MB_2U_LIB.S9S_MB_2U(SCH_1):M_F_CPU1_SB_RSP(0)
    U1 DL48 DDR5_B_RSP0 SOCKET4677_AZIF0045P001C01CS-SA   I168 @S9S_MB_2U_LIB.S9S_MB_2U(SCH_1):PAGE56
   J27   87 LBS||RSP_B_N SCONN288_ADR50017P130CC-SCONN2A   I179 @S9S_MB_2U_LIB.S9S_MB_2U(SCH_1):PAGE108

M_F_CPU1_SB_RSP<1> @S9S_MB_2U_LIB.S9S_MB_2U(SCH_1):M_F_CPU1_SB_RSP(1)
    U1 DK47 DDR5_B_RSP1 SOCKET4677_AZIF0045P001C01CS-SA   I168 @S9S_MB_2U_LIB.S9S_MB_2U(SCH_1):PAGE56
   J28   87 LBS||RSP_B_N SCONN288_ADR50017P087CC-SCONN2A    I47 @S9S_MB_2U_LIB.S9S_MB_2U(SCH_1):PAGE109

M_G_CPU0_ALERT_N @S9S_MB_2U_LIB.S9S_MB_2U(SCH_1):M_G_CPU0_ALERT_N
    U2 CW50 DDR6_ALERT_N SOCKET4677_AZIF0045P001C01CS-SA   I169 @S9S_MB_2U_LIB.S9S_MB_2U(SCH_1):PAGE26
   J13   62 ALERT_N SCONN288_ADR50017P130CC-SCONN2A    I11 @S9S_MB_2U_LIB.S9S_MB_2U(SCH_1):PAGE94
   J14   62 ALERT_N SCONN288_ADR50017P087CC-SCONN2A    I47 @S9S_MB_2U_LIB.S9S_MB_2U(SCH_1):PAGE95

M_G_CPU0_CLK_DN<0> @S9S_MB_2U_LIB.S9S_MB_2U(SCH_1):M_G_CPU0_CLK_DN(0)
    U2 DR45 DDR6_CLK_DN0 SOCKET4677_AZIF0045P001C01CS-SA   I169 @S9S_MB_2U_LIB.S9S_MB_2U(SCH_1):PAGE26
   J13  218   CK_C SCONN288_ADR50017P130CC-SCONN2A    I11 @S9S_MB_2U_LIB.S9S_MB_2U(SCH_1):PAGE94

M_G_CPU0_CLK_DN<1> @S9S_MB_2U_LIB.S9S_MB_2U(SCH_1):M_G_CPU0_CLK_DN(1)
    U2 DL45 DDR6_CLK_DN1 SOCKET4677_AZIF0045P001C01CS-SA   I169 @S9S_MB_2U_LIB.S9S_MB_2U(SCH_1):PAGE26
   J14  218   CK_C SCONN288_ADR50017P087CC-SCONN2A    I47 @S9S_MB_2U_LIB.S9S_MB_2U(SCH_1):PAGE95

M_G_CPU0_CLK_DP<0> @S9S_MB_2U_LIB.S9S_MB_2U(SCH_1):M_G_CPU0_CLK_DP(0)
    U2 DN45 DDR6_CLK_DP0 SOCKET4677_AZIF0045P001C01CS-SA   I169 @S9S_MB_2U_LIB.S9S_MB_2U(SCH_1):PAGE26
   J13  217   CK_T SCONN288_ADR50017P130CC-SCONN2A    I11 @S9S_MB_2U_LIB.S9S_MB_2U(SCH_1):PAGE94

M_G_CPU0_CLK_DP<1> @S9S_MB_2U_LIB.S9S_MB_2U(SCH_1):M_G_CPU0_CLK_DP(1)
    U2 DJ45 DDR6_CLK_DP1 SOCKET4677_AZIF0045P001C01CS-SA   I169 @S9S_MB_2U_LIB.S9S_MB_2U(SCH_1):PAGE26
   J14  217   CK_T SCONN288_ADR50017P087CC-SCONN2A    I47 @S9S_MB_2U_LIB.S9S_MB_2U(SCH_1):PAGE95

M_G_CPU0_SA_CA<0> @S9S_MB_2U_LIB.S9S_MB_2U(SCH_1):M_G_CPU0_SA_CA(0)
    U2 DJ52 DDR6_SA_CA0 SOCKET4677_AZIF0045P001C01CS-SA   I169 @S9S_MB_2U_LIB.S9S_MB_2U(SCH_1):PAGE26
   J13   66  CA0_A SCONN288_ADR50017P130CC-SCONN2A    I11 @S9S_MB_2U_LIB.S9S_MB_2U(SCH_1):PAGE94
   J14   66  CA0_A SCONN288_ADR50017P087CC-SCONN2A    I47 @S9S_MB_2U_LIB.S9S_MB_2U(SCH_1):PAGE95

M_G_CPU0_SA_CA<1> @S9S_MB_2U_LIB.S9S_MB_2U(SCH_1):M_G_CPU0_SA_CA(1)
    U2 DR52 DDR6_SA_CA1 SOCKET4677_AZIF0045P001C01CS-SA   I169 @S9S_MB_2U_LIB.S9S_MB_2U(SCH_1):PAGE26
   J13  211  CA1_A SCONN288_ADR50017P130CC-SCONN2A    I11 @S9S_MB_2U_LIB.S9S_MB_2U(SCH_1):PAGE94
   J14  211  CA1_A SCONN288_ADR50017P087CC-SCONN2A    I47 @S9S_MB_2U_LIB.S9S_MB_2U(SCH_1):PAGE95

M_G_CPU0_SA_CA<2> @S9S_MB_2U_LIB.S9S_MB_2U(SCH_1):M_G_CPU0_SA_CA(2)
    U2 DK51 DDR6_SA_CA2 SOCKET4677_AZIF0045P001C01CS-SA   I169 @S9S_MB_2U_LIB.S9S_MB_2U(SCH_1):PAGE26
   J13   68  CA2_A SCONN288_ADR50017P130CC-SCONN2A    I11 @S9S_MB_2U_LIB.S9S_MB_2U(SCH_1):PAGE94
   J14   68  CA2_A SCONN288_ADR50017P087CC-SCONN2A    I47 @S9S_MB_2U_LIB.S9S_MB_2U(SCH_1):PAGE95

M_G_CPU0_SA_CA<3> @S9S_MB_2U_LIB.S9S_MB_2U(SCH_1):M_G_CPU0_SA_CA(3)
    U2 DP51 DDR6_SA_CA3 SOCKET4677_AZIF0045P001C01CS-SA   I169 @S9S_MB_2U_LIB.S9S_MB_2U(SCH_1):PAGE26
   J13  213  CA3_A SCONN288_ADR50017P130CC-SCONN2A    I11 @S9S_MB_2U_LIB.S9S_MB_2U(SCH_1):PAGE94
   J14  213  CA3_A SCONN288_ADR50017P087CC-SCONN2A    I47 @S9S_MB_2U_LIB.S9S_MB_2U(SCH_1):PAGE95

M_G_CPU0_SA_CA<4> @S9S_MB_2U_LIB.S9S_MB_2U(SCH_1):M_G_CPU0_SA_CA(4)
    U2 DL50 DDR6_SA_CA4 SOCKET4677_AZIF0045P001C01CS-SA   I169 @S9S_MB_2U_LIB.S9S_MB_2U(SCH_1):PAGE26
   J13   70  CA4_A SCONN288_ADR50017P130CC-SCONN2A    I11 @S9S_MB_2U_LIB.S9S_MB_2U(SCH_1):PAGE94
   J14   70  CA4_A SCONN288_ADR50017P087CC-SCONN2A    I47 @S9S_MB_2U_LIB.S9S_MB_2U(SCH_1):PAGE95

M_G_CPU0_SA_CA<5> @S9S_MB_2U_LIB.S9S_MB_2U(SCH_1):M_G_CPU0_SA_CA(5)
    U2 DN50 DDR6_SA_CA5 SOCKET4677_AZIF0045P001C01CS-SA   I169 @S9S_MB_2U_LIB.S9S_MB_2U(SCH_1):PAGE26
   J13  215  CA5_A SCONN288_ADR50017P130CC-SCONN2A    I11 @S9S_MB_2U_LIB.S9S_MB_2U(SCH_1):PAGE94
   J14  215  CA5_A SCONN288_ADR50017P087CC-SCONN2A    I47 @S9S_MB_2U_LIB.S9S_MB_2U(SCH_1):PAGE95

M_G_CPU0_SA_CA<6> @S9S_MB_2U_LIB.S9S_MB_2U(SCH_1):M_G_CPU0_SA_CA(6)
    U2 DK44 DDR6_SA_CA6 SOCKET4677_AZIF0045P001C01CS-SA   I169 @S9S_MB_2U_LIB.S9S_MB_2U(SCH_1):PAGE26
   J13   72  CA6_A SCONN288_ADR50017P130CC-SCONN2A    I11 @S9S_MB_2U_LIB.S9S_MB_2U(SCH_1):PAGE94
   J14   72  CA6_A SCONN288_ADR50017P087CC-SCONN2A    I47 @S9S_MB_2U_LIB.S9S_MB_2U(SCH_1):PAGE95

M_G_CPU0_SA_CB<0> @S9S_MB_2U_LIB.S9S_MB_2U(SCH_1):M_G_CPU0_SA_CB(0)
    U2 DL60 DDR6_SA_ECC0 SOCKET4677_AZIF0045P001C01CS-SA   I169 @S9S_MB_2U_LIB.S9S_MB_2U(SCH_1):PAGE26
   J13   51  CB0_A SCONN288_ADR50017P130CC-SCONN2A    I11 @S9S_MB_2U_LIB.S9S_MB_2U(SCH_1):PAGE94
   J14   51  CB0_A SCONN288_ADR50017P087CC-SCONN2A    I47 @S9S_MB_2U_LIB.S9S_MB_2U(SCH_1):PAGE95

M_G_CPU0_SA_CB<1> @S9S_MB_2U_LIB.S9S_MB_2U(SCH_1):M_G_CPU0_SA_CB(1)
    U2 DK59 DDR6_SA_ECC1 SOCKET4677_AZIF0045P001C01CS-SA   I169 @S9S_MB_2U_LIB.S9S_MB_2U(SCH_1):PAGE26
   J13   53  CB1_A SCONN288_ADR50017P130CC-SCONN2A    I11 @S9S_MB_2U_LIB.S9S_MB_2U(SCH_1):PAGE94
   J14   53  CB1_A SCONN288_ADR50017P087CC-SCONN2A    I47 @S9S_MB_2U_LIB.S9S_MB_2U(SCH_1):PAGE95

M_G_CPU0_SA_CB<2> @S9S_MB_2U_LIB.S9S_MB_2U(SCH_1):M_G_CPU0_SA_CB(2)
    U2 DN60 DDR6_SA_ECC2 SOCKET4677_AZIF0045P001C01CS-SA   I169 @S9S_MB_2U_LIB.S9S_MB_2U(SCH_1):PAGE26
   J13  196  CB2_A SCONN288_ADR50017P130CC-SCONN2A    I11 @S9S_MB_2U_LIB.S9S_MB_2U(SCH_1):PAGE94
   J14  196  CB2_A SCONN288_ADR50017P087CC-SCONN2A    I47 @S9S_MB_2U_LIB.S9S_MB_2U(SCH_1):PAGE95

M_G_CPU0_SA_CB<3> @S9S_MB_2U_LIB.S9S_MB_2U(SCH_1):M_G_CPU0_SA_CB(3)
    U2 DP59 DDR6_SA_ECC3 SOCKET4677_AZIF0045P001C01CS-SA   I169 @S9S_MB_2U_LIB.S9S_MB_2U(SCH_1):PAGE26
   J13  198  CB3_A SCONN288_ADR50017P130CC-SCONN2A    I11 @S9S_MB_2U_LIB.S9S_MB_2U(SCH_1):PAGE94
   J14  198  CB3_A SCONN288_ADR50017P087CC-SCONN2A    I47 @S9S_MB_2U_LIB.S9S_MB_2U(SCH_1):PAGE95

M_G_CPU0_SA_CB<4> @S9S_MB_2U_LIB.S9S_MB_2U(SCH_1):M_G_CPU0_SA_CB(4)
    U2 DK57 DDR6_SA_ECC4 SOCKET4677_AZIF0045P001C01CS-SA   I169 @S9S_MB_2U_LIB.S9S_MB_2U(SCH_1):PAGE26
   J13   58  CB4_A SCONN288_ADR50017P130CC-SCONN2A    I11 @S9S_MB_2U_LIB.S9S_MB_2U(SCH_1):PAGE94
   J14   58  CB4_A SCONN288_ADR50017P087CC-SCONN2A    I47 @S9S_MB_2U_LIB.S9S_MB_2U(SCH_1):PAGE95

M_G_CPU0_SA_CB<5> @S9S_MB_2U_LIB.S9S_MB_2U(SCH_1):M_G_CPU0_SA_CB(5)
    U2 DL56 DDR6_SA_ECC5 SOCKET4677_AZIF0045P001C01CS-SA   I169 @S9S_MB_2U_LIB.S9S_MB_2U(SCH_1):PAGE26
   J13   60  CB5_A SCONN288_ADR50017P130CC-SCONN2A    I11 @S9S_MB_2U_LIB.S9S_MB_2U(SCH_1):PAGE94
   J14   60  CB5_A SCONN288_ADR50017P087CC-SCONN2A    I47 @S9S_MB_2U_LIB.S9S_MB_2U(SCH_1):PAGE95

M_G_CPU0_SA_CB<6> @S9S_MB_2U_LIB.S9S_MB_2U(SCH_1):M_G_CPU0_SA_CB(6)
    U2 DP57 DDR6_SA_ECC6 SOCKET4677_AZIF0045P001C01CS-SA   I169 @S9S_MB_2U_LIB.S9S_MB_2U(SCH_1):PAGE26
   J13  203  CB6_A SCONN288_ADR50017P130CC-SCONN2A    I11 @S9S_MB_2U_LIB.S9S_MB_2U(SCH_1):PAGE94
   J14  203  CB6_A SCONN288_ADR50017P087CC-SCONN2A    I47 @S9S_MB_2U_LIB.S9S_MB_2U(SCH_1):PAGE95

M_G_CPU0_SA_CB<7> @S9S_MB_2U_LIB.S9S_MB_2U(SCH_1):M_G_CPU0_SA_CB(7)
    U2 DN56 DDR6_SA_ECC7 SOCKET4677_AZIF0045P001C01CS-SA   I169 @S9S_MB_2U_LIB.S9S_MB_2U(SCH_1):PAGE26
   J13  205  CB7_A SCONN288_ADR50017P130CC-SCONN2A    I11 @S9S_MB_2U_LIB.S9S_MB_2U(SCH_1):PAGE94
   J14  205  CB7_A SCONN288_ADR50017P087CC-SCONN2A    I47 @S9S_MB_2U_LIB.S9S_MB_2U(SCH_1):PAGE95

M_G_CPU0_SA_CS_N<0> @S9S_MB_2U_LIB.S9S_MB_2U(SCH_1):M_G_CPU0_SA_CS_N(0)
    U2 DN54 DDR6_SA_CS_N0 SOCKET4677_AZIF0045P001C01CS-SA   I169 @S9S_MB_2U_LIB.S9S_MB_2U(SCH_1):PAGE26
   J13   64 CS0_A_N SCONN288_ADR50017P130CC-SCONN2A    I11 @S9S_MB_2U_LIB.S9S_MB_2U(SCH_1):PAGE94

M_G_CPU0_SA_CS_N<1> @S9S_MB_2U_LIB.S9S_MB_2U(SCH_1):M_G_CPU0_SA_CS_N(1)
    U2 DP53 DDR6_SA_CS_N1 SOCKET4677_AZIF0045P001C01CS-SA   I169 @S9S_MB_2U_LIB.S9S_MB_2U(SCH_1):PAGE26
   J13  209 CS1_A_N SCONN288_ADR50017P130CC-SCONN2A    I11 @S9S_MB_2U_LIB.S9S_MB_2U(SCH_1):PAGE94

M_G_CPU0_SA_CS_N<2> @S9S_MB_2U_LIB.S9S_MB_2U(SCH_1):M_G_CPU0_SA_CS_N(2)
    U2 DL54 DDR6_SA_CS_N2 SOCKET4677_AZIF0045P001C01CS-SA   I169 @S9S_MB_2U_LIB.S9S_MB_2U(SCH_1):PAGE26
   J14   64 CS0_A_N SCONN288_ADR50017P087CC-SCONN2A    I47 @S9S_MB_2U_LIB.S9S_MB_2U(SCH_1):PAGE95

M_G_CPU0_SA_CS_N<3> @S9S_MB_2U_LIB.S9S_MB_2U(SCH_1):M_G_CPU0_SA_CS_N(3)
    U2 DK53 DDR6_SA_CS_N3 SOCKET4677_AZIF0045P001C01CS-SA   I169 @S9S_MB_2U_LIB.S9S_MB_2U(SCH_1):PAGE26
   J14  209 CS1_A_N SCONN288_ADR50017P087CC-SCONN2A    I47 @S9S_MB_2U_LIB.S9S_MB_2U(SCH_1):PAGE95

M_G_CPU0_SA_DQ<0> @S9S_MB_2U_LIB.S9S_MB_2U(SCH_1):M_G_CPU0_SA_DQ(0)
    U2 DV75 DDR6_SA_DQ0 SOCKET4677_AZIF0045P001C01CS-SA   I169 @S9S_MB_2U_LIB.S9S_MB_2U(SCH_1):PAGE26
   J13    7  DQ0_A SCONN288_ADR50017P130CC-SCONN2A    I11 @S9S_MB_2U_LIB.S9S_MB_2U(SCH_1):PAGE94
   J14    7  DQ0_A SCONN288_ADR50017P087CC-SCONN2A    I47 @S9S_MB_2U_LIB.S9S_MB_2U(SCH_1):PAGE95

M_G_CPU0_SA_DQ<10> @S9S_MB_2U_LIB.S9S_MB_2U(SCH_1):M_G_CPU0_SA_DQ(10)
    U2 DN72 DDR6_SA_DQ10 SOCKET4677_AZIF0045P001C01CS-SA   I169 @S9S_MB_2U_LIB.S9S_MB_2U(SCH_1):PAGE26
   J13  163 DQ10_A SCONN288_ADR50017P130CC-SCONN2A    I11 @S9S_MB_2U_LIB.S9S_MB_2U(SCH_1):PAGE94
   J14  163 DQ10_A SCONN288_ADR50017P087CC-SCONN2A    I47 @S9S_MB_2U_LIB.S9S_MB_2U(SCH_1):PAGE95

M_G_CPU0_SA_DQ<11> @S9S_MB_2U_LIB.S9S_MB_2U(SCH_1):M_G_CPU0_SA_DQ(11)
    U2 DP71 DDR6_SA_DQ11 SOCKET4677_AZIF0045P001C01CS-SA   I169 @S9S_MB_2U_LIB.S9S_MB_2U(SCH_1):PAGE26
   J13  165 DQ11_A SCONN288_ADR50017P130CC-SCONN2A    I11 @S9S_MB_2U_LIB.S9S_MB_2U(SCH_1):PAGE94
   J14  165 DQ11_A SCONN288_ADR50017P087CC-SCONN2A    I47 @S9S_MB_2U_LIB.S9S_MB_2U(SCH_1):PAGE95

M_G_CPU0_SA_DQ<12> @S9S_MB_2U_LIB.S9S_MB_2U(SCH_1):M_G_CPU0_SA_DQ(12)
    U2 DK69 DDR6_SA_DQ12 SOCKET4677_AZIF0045P001C01CS-SA   I169 @S9S_MB_2U_LIB.S9S_MB_2U(SCH_1):PAGE26
   J13   25 DQ12_A SCONN288_ADR50017P130CC-SCONN2A    I11 @S9S_MB_2U_LIB.S9S_MB_2U(SCH_1):PAGE94
   J14   25 DQ12_A SCONN288_ADR50017P087CC-SCONN2A    I47 @S9S_MB_2U_LIB.S9S_MB_2U(SCH_1):PAGE95

M_G_CPU0_SA_DQ<13> @S9S_MB_2U_LIB.S9S_MB_2U(SCH_1):M_G_CPU0_SA_DQ(13)
    U2 DL68 DDR6_SA_DQ13 SOCKET4677_AZIF0045P001C01CS-SA   I169 @S9S_MB_2U_LIB.S9S_MB_2U(SCH_1):PAGE26
   J13   27 DQ13_A SCONN288_ADR50017P130CC-SCONN2A    I11 @S9S_MB_2U_LIB.S9S_MB_2U(SCH_1):PAGE94
   J14   27 DQ13_A SCONN288_ADR50017P087CC-SCONN2A    I47 @S9S_MB_2U_LIB.S9S_MB_2U(SCH_1):PAGE95

M_G_CPU0_SA_DQ<14> @S9S_MB_2U_LIB.S9S_MB_2U(SCH_1):M_G_CPU0_SA_DQ(14)
    U2 DP69 DDR6_SA_DQ14 SOCKET4677_AZIF0045P001C01CS-SA   I169 @S9S_MB_2U_LIB.S9S_MB_2U(SCH_1):PAGE26
   J13  170 DQ14_A SCONN288_ADR50017P130CC-SCONN2A    I11 @S9S_MB_2U_LIB.S9S_MB_2U(SCH_1):PAGE94
   J14  170 DQ14_A SCONN288_ADR50017P087CC-SCONN2A    I47 @S9S_MB_2U_LIB.S9S_MB_2U(SCH_1):PAGE95

M_G_CPU0_SA_DQ<15> @S9S_MB_2U_LIB.S9S_MB_2U(SCH_1):M_G_CPU0_SA_DQ(15)
    U2 DN68 DDR6_SA_DQ15 SOCKET4677_AZIF0045P001C01CS-SA   I169 @S9S_MB_2U_LIB.S9S_MB_2U(SCH_1):PAGE26
   J13  172 DQ15_A SCONN288_ADR50017P130CC-SCONN2A    I11 @S9S_MB_2U_LIB.S9S_MB_2U(SCH_1):PAGE94
   J14  172 DQ15_A SCONN288_ADR50017P087CC-SCONN2A    I47 @S9S_MB_2U_LIB.S9S_MB_2U(SCH_1):PAGE95

M_G_CPU0_SA_DQ<16> @S9S_MB_2U_LIB.S9S_MB_2U(SCH_1):M_G_CPU0_SA_DQ(16)
    U2 DV63 DDR6_SA_DQ16 SOCKET4677_AZIF0045P001C01CS-SA   I169 @S9S_MB_2U_LIB.S9S_MB_2U(SCH_1):PAGE26
   J13   29 DQ16_A SCONN288_ADR50017P130CC-SCONN2A    I11 @S9S_MB_2U_LIB.S9S_MB_2U(SCH_1):PAGE94
   J14   29 DQ16_A SCONN288_ADR50017P087CC-SCONN2A    I47 @S9S_MB_2U_LIB.S9S_MB_2U(SCH_1):PAGE95

M_G_CPU0_SA_DQ<17> @S9S_MB_2U_LIB.S9S_MB_2U(SCH_1):M_G_CPU0_SA_DQ(17)
    U2 DU62 DDR6_SA_DQ17 SOCKET4677_AZIF0045P001C01CS-SA   I169 @S9S_MB_2U_LIB.S9S_MB_2U(SCH_1):PAGE26
   J13   31 DQ17_A SCONN288_ADR50017P130CC-SCONN2A    I11 @S9S_MB_2U_LIB.S9S_MB_2U(SCH_1):PAGE94
   J14   31 DQ17_A SCONN288_ADR50017P087CC-SCONN2A    I47 @S9S_MB_2U_LIB.S9S_MB_2U(SCH_1):PAGE95

M_G_CPU0_SA_DQ<18> @S9S_MB_2U_LIB.S9S_MB_2U(SCH_1):M_G_CPU0_SA_DQ(18)
    U2 DY63 DDR6_SA_DQ18 SOCKET4677_AZIF0045P001C01CS-SA   I169 @S9S_MB_2U_LIB.S9S_MB_2U(SCH_1):PAGE26
   J13  174 DQ18_A SCONN288_ADR50017P130CC-SCONN2A    I11 @S9S_MB_2U_LIB.S9S_MB_2U(SCH_1):PAGE94
   J14  174 DQ18_A SCONN288_ADR50017P087CC-SCONN2A    I47 @S9S_MB_2U_LIB.S9S_MB_2U(SCH_1):PAGE95

M_G_CPU0_SA_DQ<19> @S9S_MB_2U_LIB.S9S_MB_2U(SCH_1):M_G_CPU0_SA_DQ(19)
    U2 EA62 DDR6_SA_DQ19 SOCKET4677_AZIF0045P001C01CS-SA   I169 @S9S_MB_2U_LIB.S9S_MB_2U(SCH_1):PAGE26
   J13  176 DQ19_A SCONN288_ADR50017P130CC-SCONN2A    I11 @S9S_MB_2U_LIB.S9S_MB_2U(SCH_1):PAGE94
   J14  176 DQ19_A SCONN288_ADR50017P087CC-SCONN2A    I47 @S9S_MB_2U_LIB.S9S_MB_2U(SCH_1):PAGE95

M_G_CPU0_SA_DQ<1> @S9S_MB_2U_LIB.S9S_MB_2U(SCH_1):M_G_CPU0_SA_DQ(1)
    U2 DU74 DDR6_SA_DQ1 SOCKET4677_AZIF0045P001C01CS-SA   I169 @S9S_MB_2U_LIB.S9S_MB_2U(SCH_1):PAGE26
   J13    9  DQ1_A SCONN288_ADR50017P130CC-SCONN2A    I11 @S9S_MB_2U_LIB.S9S_MB_2U(SCH_1):PAGE94
   J14    9  DQ1_A SCONN288_ADR50017P087CC-SCONN2A    I47 @S9S_MB_2U_LIB.S9S_MB_2U(SCH_1):PAGE95

M_G_CPU0_SA_DQ<20> @S9S_MB_2U_LIB.S9S_MB_2U(SCH_1):M_G_CPU0_SA_DQ(20)
    U2 DU60 DDR6_SA_DQ20 SOCKET4677_AZIF0045P001C01CS-SA   I169 @S9S_MB_2U_LIB.S9S_MB_2U(SCH_1):PAGE26
   J13   36 DQ20_A SCONN288_ADR50017P130CC-SCONN2A    I11 @S9S_MB_2U_LIB.S9S_MB_2U(SCH_1):PAGE94
   J14   36 DQ20_A SCONN288_ADR50017P087CC-SCONN2A    I47 @S9S_MB_2U_LIB.S9S_MB_2U(SCH_1):PAGE95

M_G_CPU0_SA_DQ<21> @S9S_MB_2U_LIB.S9S_MB_2U(SCH_1):M_G_CPU0_SA_DQ(21)
    U2 DV59 DDR6_SA_DQ21 SOCKET4677_AZIF0045P001C01CS-SA   I169 @S9S_MB_2U_LIB.S9S_MB_2U(SCH_1):PAGE26
   J13   38 DQ21_A SCONN288_ADR50017P130CC-SCONN2A    I11 @S9S_MB_2U_LIB.S9S_MB_2U(SCH_1):PAGE94
   J14   38 DQ21_A SCONN288_ADR50017P087CC-SCONN2A    I47 @S9S_MB_2U_LIB.S9S_MB_2U(SCH_1):PAGE95

M_G_CPU0_SA_DQ<22> @S9S_MB_2U_LIB.S9S_MB_2U(SCH_1):M_G_CPU0_SA_DQ(22)
    U2 EA60 DDR6_SA_DQ22 SOCKET4677_AZIF0045P001C01CS-SA   I169 @S9S_MB_2U_LIB.S9S_MB_2U(SCH_1):PAGE26
   J13  181 DQ22_A SCONN288_ADR50017P130CC-SCONN2A    I11 @S9S_MB_2U_LIB.S9S_MB_2U(SCH_1):PAGE94
   J14  181 DQ22_A SCONN288_ADR50017P087CC-SCONN2A    I47 @S9S_MB_2U_LIB.S9S_MB_2U(SCH_1):PAGE95

M_G_CPU0_SA_DQ<23> @S9S_MB_2U_LIB.S9S_MB_2U(SCH_1):M_G_CPU0_SA_DQ(23)
    U2 DY59 DDR6_SA_DQ23 SOCKET4677_AZIF0045P001C01CS-SA   I169 @S9S_MB_2U_LIB.S9S_MB_2U(SCH_1):PAGE26
   J13  183 DQ23_A SCONN288_ADR50017P130CC-SCONN2A    I11 @S9S_MB_2U_LIB.S9S_MB_2U(SCH_1):PAGE94
   J14  183 DQ23_A SCONN288_ADR50017P087CC-SCONN2A    I47 @S9S_MB_2U_LIB.S9S_MB_2U(SCH_1):PAGE95

M_G_CPU0_SA_DQ<24> @S9S_MB_2U_LIB.S9S_MB_2U(SCH_1):M_G_CPU0_SA_DQ(24)
    U2 DL66 DDR6_SA_DQ24 SOCKET4677_AZIF0045P001C01CS-SA   I169 @S9S_MB_2U_LIB.S9S_MB_2U(SCH_1):PAGE26
   J13   40 DQ24_A SCONN288_ADR50017P130CC-SCONN2A    I11 @S9S_MB_2U_LIB.S9S_MB_2U(SCH_1):PAGE94
   J14   40 DQ24_A SCONN288_ADR50017P087CC-SCONN2A    I47 @S9S_MB_2U_LIB.S9S_MB_2U(SCH_1):PAGE95

M_G_CPU0_SA_DQ<25> @S9S_MB_2U_LIB.S9S_MB_2U(SCH_1):M_G_CPU0_SA_DQ(25)
    U2 DK65 DDR6_SA_DQ25 SOCKET4677_AZIF0045P001C01CS-SA   I169 @S9S_MB_2U_LIB.S9S_MB_2U(SCH_1):PAGE26
   J13   42 DQ25_A SCONN288_ADR50017P130CC-SCONN2A    I11 @S9S_MB_2U_LIB.S9S_MB_2U(SCH_1):PAGE94
   J14   42 DQ25_A SCONN288_ADR50017P087CC-SCONN2A    I47 @S9S_MB_2U_LIB.S9S_MB_2U(SCH_1):PAGE95

M_G_CPU0_SA_DQ<26> @S9S_MB_2U_LIB.S9S_MB_2U(SCH_1):M_G_CPU0_SA_DQ(26)
    U2 DN66 DDR6_SA_DQ26 SOCKET4677_AZIF0045P001C01CS-SA   I169 @S9S_MB_2U_LIB.S9S_MB_2U(SCH_1):PAGE26
   J13  185 DQ26_A SCONN288_ADR50017P130CC-SCONN2A    I11 @S9S_MB_2U_LIB.S9S_MB_2U(SCH_1):PAGE94
   J14  185 DQ26_A SCONN288_ADR50017P087CC-SCONN2A    I47 @S9S_MB_2U_LIB.S9S_MB_2U(SCH_1):PAGE95

M_G_CPU0_SA_DQ<27> @S9S_MB_2U_LIB.S9S_MB_2U(SCH_1):M_G_CPU0_SA_DQ(27)
    U2 DP65 DDR6_SA_DQ27 SOCKET4677_AZIF0045P001C01CS-SA   I169 @S9S_MB_2U_LIB.S9S_MB_2U(SCH_1):PAGE26
   J13  187 DQ27_A SCONN288_ADR50017P130CC-SCONN2A    I11 @S9S_MB_2U_LIB.S9S_MB_2U(SCH_1):PAGE94
   J14  187 DQ27_A SCONN288_ADR50017P087CC-SCONN2A    I47 @S9S_MB_2U_LIB.S9S_MB_2U(SCH_1):PAGE95

M_G_CPU0_SA_DQ<28> @S9S_MB_2U_LIB.S9S_MB_2U(SCH_1):M_G_CPU0_SA_DQ(28)
    U2 DK63 DDR6_SA_DQ28 SOCKET4677_AZIF0045P001C01CS-SA   I169 @S9S_MB_2U_LIB.S9S_MB_2U(SCH_1):PAGE26
   J13   47 DQ28_A SCONN288_ADR50017P130CC-SCONN2A    I11 @S9S_MB_2U_LIB.S9S_MB_2U(SCH_1):PAGE94
   J14   47 DQ28_A SCONN288_ADR50017P087CC-SCONN2A    I47 @S9S_MB_2U_LIB.S9S_MB_2U(SCH_1):PAGE95

M_G_CPU0_SA_DQ<29> @S9S_MB_2U_LIB.S9S_MB_2U(SCH_1):M_G_CPU0_SA_DQ(29)
    U2 DL62 DDR6_SA_DQ29 SOCKET4677_AZIF0045P001C01CS-SA   I169 @S9S_MB_2U_LIB.S9S_MB_2U(SCH_1):PAGE26
   J13   49 DQ29_A SCONN288_ADR50017P130CC-SCONN2A    I11 @S9S_MB_2U_LIB.S9S_MB_2U(SCH_1):PAGE94
   J14   49 DQ29_A SCONN288_ADR50017P087CC-SCONN2A    I47 @S9S_MB_2U_LIB.S9S_MB_2U(SCH_1):PAGE95

M_G_CPU0_SA_DQ<2> @S9S_MB_2U_LIB.S9S_MB_2U(SCH_1):M_G_CPU0_SA_DQ(2)
    U2 DY75 DDR6_SA_DQ2 SOCKET4677_AZIF0045P001C01CS-SA   I169 @S9S_MB_2U_LIB.S9S_MB_2U(SCH_1):PAGE26
   J13  152  DQ2_A SCONN288_ADR50017P130CC-SCONN2A    I11 @S9S_MB_2U_LIB.S9S_MB_2U(SCH_1):PAGE94
   J14  152  DQ2_A SCONN288_ADR50017P087CC-SCONN2A    I47 @S9S_MB_2U_LIB.S9S_MB_2U(SCH_1):PAGE95

M_G_CPU0_SA_DQ<30> @S9S_MB_2U_LIB.S9S_MB_2U(SCH_1):M_G_CPU0_SA_DQ(30)
    U2 DP63 DDR6_SA_DQ30 SOCKET4677_AZIF0045P001C01CS-SA   I169 @S9S_MB_2U_LIB.S9S_MB_2U(SCH_1):PAGE26
   J13  192 DQ30_A SCONN288_ADR50017P130CC-SCONN2A    I11 @S9S_MB_2U_LIB.S9S_MB_2U(SCH_1):PAGE94
   J14  192 DQ30_A SCONN288_ADR50017P087CC-SCONN2A    I47 @S9S_MB_2U_LIB.S9S_MB_2U(SCH_1):PAGE95

M_G_CPU0_SA_DQ<31> @S9S_MB_2U_LIB.S9S_MB_2U(SCH_1):M_G_CPU0_SA_DQ(31)
    U2 DN62 DDR6_SA_DQ31 SOCKET4677_AZIF0045P001C01CS-SA   I169 @S9S_MB_2U_LIB.S9S_MB_2U(SCH_1):PAGE26
   J13  194 DQ31_A SCONN288_ADR50017P130CC-SCONN2A    I11 @S9S_MB_2U_LIB.S9S_MB_2U(SCH_1):PAGE94
   J14  194 DQ31_A SCONN288_ADR50017P087CC-SCONN2A    I47 @S9S_MB_2U_LIB.S9S_MB_2U(SCH_1):PAGE95

M_G_CPU0_SA_DQ<3> @S9S_MB_2U_LIB.S9S_MB_2U(SCH_1):M_G_CPU0_SA_DQ(3)
    U2 EA74 DDR6_SA_DQ3 SOCKET4677_AZIF0045P001C01CS-SA   I169 @S9S_MB_2U_LIB.S9S_MB_2U(SCH_1):PAGE26
   J13  154  DQ3_A SCONN288_ADR50017P130CC-SCONN2A    I11 @S9S_MB_2U_LIB.S9S_MB_2U(SCH_1):PAGE94
   J14  154  DQ3_A SCONN288_ADR50017P087CC-SCONN2A    I47 @S9S_MB_2U_LIB.S9S_MB_2U(SCH_1):PAGE95

M_G_CPU0_SA_DQ<4> @S9S_MB_2U_LIB.S9S_MB_2U(SCH_1):M_G_CPU0_SA_DQ(4)
    U2 DU72 DDR6_SA_DQ4 SOCKET4677_AZIF0045P001C01CS-SA   I169 @S9S_MB_2U_LIB.S9S_MB_2U(SCH_1):PAGE26
   J13   14  DQ4_A SCONN288_ADR50017P130CC-SCONN2A    I11 @S9S_MB_2U_LIB.S9S_MB_2U(SCH_1):PAGE94
   J14   14  DQ4_A SCONN288_ADR50017P087CC-SCONN2A    I47 @S9S_MB_2U_LIB.S9S_MB_2U(SCH_1):PAGE95

M_G_CPU0_SA_DQ<5> @S9S_MB_2U_LIB.S9S_MB_2U(SCH_1):M_G_CPU0_SA_DQ(5)
    U2 DV71 DDR6_SA_DQ5 SOCKET4677_AZIF0045P001C01CS-SA   I169 @S9S_MB_2U_LIB.S9S_MB_2U(SCH_1):PAGE26
   J13   16  DQ5_A SCONN288_ADR50017P130CC-SCONN2A    I11 @S9S_MB_2U_LIB.S9S_MB_2U(SCH_1):PAGE94
   J14   16  DQ5_A SCONN288_ADR50017P087CC-SCONN2A    I47 @S9S_MB_2U_LIB.S9S_MB_2U(SCH_1):PAGE95

M_G_CPU0_SA_DQ<6> @S9S_MB_2U_LIB.S9S_MB_2U(SCH_1):M_G_CPU0_SA_DQ(6)
    U2 EA72 DDR6_SA_DQ6 SOCKET4677_AZIF0045P001C01CS-SA   I169 @S9S_MB_2U_LIB.S9S_MB_2U(SCH_1):PAGE26
   J13  159  DQ6_A SCONN288_ADR50017P130CC-SCONN2A    I11 @S9S_MB_2U_LIB.S9S_MB_2U(SCH_1):PAGE94
   J14  159  DQ6_A SCONN288_ADR50017P087CC-SCONN2A    I47 @S9S_MB_2U_LIB.S9S_MB_2U(SCH_1):PAGE95

M_G_CPU0_SA_DQ<7> @S9S_MB_2U_LIB.S9S_MB_2U(SCH_1):M_G_CPU0_SA_DQ(7)
    U2 DY71 DDR6_SA_DQ7 SOCKET4677_AZIF0045P001C01CS-SA   I169 @S9S_MB_2U_LIB.S9S_MB_2U(SCH_1):PAGE26
   J13  161  DQ7_A SCONN288_ADR50017P130CC-SCONN2A    I11 @S9S_MB_2U_LIB.S9S_MB_2U(SCH_1):PAGE94
   J14  161  DQ7_A SCONN288_ADR50017P087CC-SCONN2A    I47 @S9S_MB_2U_LIB.S9S_MB_2U(SCH_1):PAGE95

M_G_CPU0_SA_DQ<8> @S9S_MB_2U_LIB.S9S_MB_2U(SCH_1):M_G_CPU0_SA_DQ(8)
    U2 DL72 DDR6_SA_DQ8 SOCKET4677_AZIF0045P001C01CS-SA   I169 @S9S_MB_2U_LIB.S9S_MB_2U(SCH_1):PAGE26
   J13   18  DQ8_A SCONN288_ADR50017P130CC-SCONN2A    I11 @S9S_MB_2U_LIB.S9S_MB_2U(SCH_1):PAGE94
   J14   18  DQ8_A SCONN288_ADR50017P087CC-SCONN2A    I47 @S9S_MB_2U_LIB.S9S_MB_2U(SCH_1):PAGE95

M_G_CPU0_SA_DQ<9> @S9S_MB_2U_LIB.S9S_MB_2U(SCH_1):M_G_CPU0_SA_DQ(9)
    U2 DK71 DDR6_SA_DQ9 SOCKET4677_AZIF0045P001C01CS-SA   I169 @S9S_MB_2U_LIB.S9S_MB_2U(SCH_1):PAGE26
   J13   20  DQ9_A SCONN288_ADR50017P130CC-SCONN2A    I11 @S9S_MB_2U_LIB.S9S_MB_2U(SCH_1):PAGE94
   J14   20  DQ9_A SCONN288_ADR50017P087CC-SCONN2A    I47 @S9S_MB_2U_LIB.S9S_MB_2U(SCH_1):PAGE95

M_G_CPU0_SA_DQS_DN<0> @S9S_MB_2U_LIB.S9S_MB_2U(SCH_1):M_G_CPU0_SA_DQS_DN(0)
    U2 DV73 DDR6_SA_DQS_DN0 SOCKET4677_AZIF0045P001C01CS-SA   I169 @S9S_MB_2U_LIB.S9S_MB_2U(SCH_1):PAGE26
   J13   12 DQS0_A_C SCONN288_ADR50017P130CC-SCONN2A   I178 @S9S_MB_2U_LIB.S9S_MB_2U(SCH_1):PAGE94
   J14   12 DQS0_A_C SCONN288_ADR50017P087CC-SCONN2A   I178 @S9S_MB_2U_LIB.S9S_MB_2U(SCH_1):PAGE95

M_G_CPU0_SA_DQS_DN<1> @S9S_MB_2U_LIB.S9S_MB_2U(SCH_1):M_G_CPU0_SA_DQS_DN(1)
    U2 DJ70 DDR6_SA_DQS_DN1 SOCKET4677_AZIF0045P001C01CS-SA   I169 @S9S_MB_2U_LIB.S9S_MB_2U(SCH_1):PAGE26
   J13   23 DQS1_A_C SCONN288_ADR50017P130CC-SCONN2A   I178 @S9S_MB_2U_LIB.S9S_MB_2U(SCH_1):PAGE94
   J14   23 DQS1_A_C SCONN288_ADR50017P087CC-SCONN2A   I178 @S9S_MB_2U_LIB.S9S_MB_2U(SCH_1):PAGE95

M_G_CPU0_SA_DQS_DN<2> @S9S_MB_2U_LIB.S9S_MB_2U(SCH_1):M_G_CPU0_SA_DQS_DN(2)
    U2 DT61 DDR6_SA_DQS_DN2 SOCKET4677_AZIF0045P001C01CS-SA   I169 @S9S_MB_2U_LIB.S9S_MB_2U(SCH_1):PAGE26
   J13   34 DQS2_A_C SCONN288_ADR50017P130CC-SCONN2A   I178 @S9S_MB_2U_LIB.S9S_MB_2U(SCH_1):PAGE94
   J14   34 DQS2_A_C SCONN288_ADR50017P087CC-SCONN2A   I178 @S9S_MB_2U_LIB.S9S_MB_2U(SCH_1):PAGE95

M_G_CPU0_SA_DQS_DN<3> @S9S_MB_2U_LIB.S9S_MB_2U(SCH_1):M_G_CPU0_SA_DQS_DN(3)
    U2 DL64 DDR6_SA_DQS_DN3 SOCKET4677_AZIF0045P001C01CS-SA   I169 @S9S_MB_2U_LIB.S9S_MB_2U(SCH_1):PAGE26
   J13   45 DQS3_A_C SCONN288_ADR50017P130CC-SCONN2A   I178 @S9S_MB_2U_LIB.S9S_MB_2U(SCH_1):PAGE94
   J14   45 DQS3_A_C SCONN288_ADR50017P087CC-SCONN2A   I178 @S9S_MB_2U_LIB.S9S_MB_2U(SCH_1):PAGE95

M_G_CPU0_SA_DQS_DN<4> @S9S_MB_2U_LIB.S9S_MB_2U(SCH_1):M_G_CPU0_SA_DQS_DN(4)
    U2 DL58 DDR6_SA_DQS_DN4 SOCKET4677_AZIF0045P001C01CS-SA   I169 @S9S_MB_2U_LIB.S9S_MB_2U(SCH_1):PAGE26
   J13   56 DQS4_A_C SCONN288_ADR50017P130CC-SCONN2A   I178 @S9S_MB_2U_LIB.S9S_MB_2U(SCH_1):PAGE94
   J14   56 DQS4_A_C SCONN288_ADR50017P087CC-SCONN2A   I178 @S9S_MB_2U_LIB.S9S_MB_2U(SCH_1):PAGE95

M_G_CPU0_SA_DQS_DN<5> @S9S_MB_2U_LIB.S9S_MB_2U(SCH_1):M_G_CPU0_SA_DQS_DN(5)
    U2 EB73 DDR6_SA_DQS_DN5 SOCKET4677_AZIF0045P001C01CS-SA   I169 @S9S_MB_2U_LIB.S9S_MB_2U(SCH_1):PAGE26
   J13  156 DQS5_A_C||TDQS5_A_C||DQS5_A_T||TDQS5_A_T SCONN288_ADR50017P130CC-SCONN2A   I178 @S9S_MB_2U_LIB.S9S_MB_2U(SCH_1):PAGE94
   J14  156 DQS5_A_C||TDQS5_A_C||DQS5_A_T||TDQS5_A_T SCONN288_ADR50017P087CC-SCONN2A   I178 @S9S_MB_2U_LIB.S9S_MB_2U(SCH_1):PAGE95

M_G_CPU0_SA_DQS_DN<6> @S9S_MB_2U_LIB.S9S_MB_2U(SCH_1):M_G_CPU0_SA_DQS_DN(6)
    U2 DR70 DDR6_SA_DQS_DN6 SOCKET4677_AZIF0045P001C01CS-SA   I169 @S9S_MB_2U_LIB.S9S_MB_2U(SCH_1):PAGE26
   J13  167 DQS6_A_C||TDQS6_A_C||DQS6_A_T||TDQS6_A_T SCONN288_ADR50017P130CC-SCONN2A   I178 @S9S_MB_2U_LIB.S9S_MB_2U(SCH_1):PAGE94
   J14  167 DQS6_A_C||TDQS6_A_C||DQS6_A_T||TDQS6_A_T SCONN288_ADR50017P087CC-SCONN2A   I178 @S9S_MB_2U_LIB.S9S_MB_2U(SCH_1):PAGE95

M_G_CPU0_SA_DQS_DN<7> @S9S_MB_2U_LIB.S9S_MB_2U(SCH_1):M_G_CPU0_SA_DQS_DN(7)
    U2 EB61 DDR6_SA_DQS_DN7 SOCKET4677_AZIF0045P001C01CS-SA   I169 @S9S_MB_2U_LIB.S9S_MB_2U(SCH_1):PAGE26
   J13  178 DQS7_A_C||TDQS7_A_C SCONN288_ADR50017P130CC-SCONN2A   I178 @S9S_MB_2U_LIB.S9S_MB_2U(SCH_1):PAGE94
   J14  178 DQS7_A_C||TDQS7_A_C SCONN288_ADR50017P087CC-SCONN2A   I178 @S9S_MB_2U_LIB.S9S_MB_2U(SCH_1):PAGE95

M_G_CPU0_SA_DQS_DN<8> @S9S_MB_2U_LIB.S9S_MB_2U(SCH_1):M_G_CPU0_SA_DQS_DN(8)
    U2 DR64 DDR6_SA_DQS_DN8 SOCKET4677_AZIF0045P001C01CS-SA   I169 @S9S_MB_2U_LIB.S9S_MB_2U(SCH_1):PAGE26
   J13  189 DQS8_A_C||TDQS8_A_C SCONN288_ADR50017P130CC-SCONN2A   I178 @S9S_MB_2U_LIB.S9S_MB_2U(SCH_1):PAGE94
   J14  189 DQS8_A_C||TDQS8_A_C SCONN288_ADR50017P087CC-SCONN2A   I178 @S9S_MB_2U_LIB.S9S_MB_2U(SCH_1):PAGE95

M_G_CPU0_SA_DQS_DN<9> @S9S_MB_2U_LIB.S9S_MB_2U(SCH_1):M_G_CPU0_SA_DQS_DN(9)
    U2 DR58 DDR6_SA_DQS_DN9 SOCKET4677_AZIF0045P001C01CS-SA   I169 @S9S_MB_2U_LIB.S9S_MB_2U(SCH_1):PAGE26
   J13  200 DQS9_A_C||TDQS9_A_C SCONN288_ADR50017P130CC-SCONN2A   I178 @S9S_MB_2U_LIB.S9S_MB_2U(SCH_1):PAGE94
   J14  200 DQS9_A_C||TDQS9_A_C SCONN288_ADR50017P087CC-SCONN2A   I178 @S9S_MB_2U_LIB.S9S_MB_2U(SCH_1):PAGE95

M_G_CPU0_SA_DQS_DP<0> @S9S_MB_2U_LIB.S9S_MB_2U(SCH_1):M_G_CPU0_SA_DQS_DP(0)
    U2 DT73 DDR6_SA_DQS_DP0 SOCKET4677_AZIF0045P001C01CS-SA   I169 @S9S_MB_2U_LIB.S9S_MB_2U(SCH_1):PAGE26
   J13   11 DQS0_A_T SCONN288_ADR50017P130CC-SCONN2A   I178 @S9S_MB_2U_LIB.S9S_MB_2U(SCH_1):PAGE94
   J14   11 DQS0_A_T SCONN288_ADR50017P087CC-SCONN2A   I178 @S9S_MB_2U_LIB.S9S_MB_2U(SCH_1):PAGE95

M_G_CPU0_SA_DQS_DP<1> @S9S_MB_2U_LIB.S9S_MB_2U(SCH_1):M_G_CPU0_SA_DQS_DP(1)
    U2 DL70 DDR6_SA_DQS_DP1 SOCKET4677_AZIF0045P001C01CS-SA   I169 @S9S_MB_2U_LIB.S9S_MB_2U(SCH_1):PAGE26
   J13   22 DQS1_A_T SCONN288_ADR50017P130CC-SCONN2A   I178 @S9S_MB_2U_LIB.S9S_MB_2U(SCH_1):PAGE94
   J14   22 DQS1_A_T SCONN288_ADR50017P087CC-SCONN2A   I178 @S9S_MB_2U_LIB.S9S_MB_2U(SCH_1):PAGE95

M_G_CPU0_SA_DQS_DP<2> @S9S_MB_2U_LIB.S9S_MB_2U(SCH_1):M_G_CPU0_SA_DQS_DP(2)
    U2 DV61 DDR6_SA_DQS_DP2 SOCKET4677_AZIF0045P001C01CS-SA   I169 @S9S_MB_2U_LIB.S9S_MB_2U(SCH_1):PAGE26
   J13   33 DQS2_A_T SCONN288_ADR50017P130CC-SCONN2A   I178 @S9S_MB_2U_LIB.S9S_MB_2U(SCH_1):PAGE94
   J14   33 DQS2_A_T SCONN288_ADR50017P087CC-SCONN2A   I178 @S9S_MB_2U_LIB.S9S_MB_2U(SCH_1):PAGE95

M_G_CPU0_SA_DQS_DP<3> @S9S_MB_2U_LIB.S9S_MB_2U(SCH_1):M_G_CPU0_SA_DQS_DP(3)
    U2 DJ64 DDR6_SA_DQS_DP3 SOCKET4677_AZIF0045P001C01CS-SA   I169 @S9S_MB_2U_LIB.S9S_MB_2U(SCH_1):PAGE26
   J13   44 DQS3_A_T SCONN288_ADR50017P130CC-SCONN2A   I178 @S9S_MB_2U_LIB.S9S_MB_2U(SCH_1):PAGE94
   J14   44 DQS3_A_T SCONN288_ADR50017P087CC-SCONN2A   I178 @S9S_MB_2U_LIB.S9S_MB_2U(SCH_1):PAGE95

M_G_CPU0_SA_DQS_DP<4> @S9S_MB_2U_LIB.S9S_MB_2U(SCH_1):M_G_CPU0_SA_DQS_DP(4)
    U2 DJ58 DDR6_SA_DQS_DP4 SOCKET4677_AZIF0045P001C01CS-SA   I169 @S9S_MB_2U_LIB.S9S_MB_2U(SCH_1):PAGE26
   J13   55 DQS4_A_T SCONN288_ADR50017P130CC-SCONN2A   I178 @S9S_MB_2U_LIB.S9S_MB_2U(SCH_1):PAGE94
   J14   55 DQS4_A_T SCONN288_ADR50017P087CC-SCONN2A   I178 @S9S_MB_2U_LIB.S9S_MB_2U(SCH_1):PAGE95

M_G_CPU0_SA_DQS_DP<5> @S9S_MB_2U_LIB.S9S_MB_2U(SCH_1):M_G_CPU0_SA_DQS_DP(5)
    U2 DY73 DDR6_SA_DQS_DP5 SOCKET4677_AZIF0045P001C01CS-SA   I169 @S9S_MB_2U_LIB.S9S_MB_2U(SCH_1):PAGE26
   J13  157 DQS5_A_T||TDQS5_A_T SCONN288_ADR50017P130CC-SCONN2A   I178 @S9S_MB_2U_LIB.S9S_MB_2U(SCH_1):PAGE94
   J14  157 DQS5_A_T||TDQS5_A_T SCONN288_ADR50017P087CC-SCONN2A   I178 @S9S_MB_2U_LIB.S9S_MB_2U(SCH_1):PAGE95

M_G_CPU0_SA_DQS_DP<6> @S9S_MB_2U_LIB.S9S_MB_2U(SCH_1):M_G_CPU0_SA_DQS_DP(6)
    U2 DN70 DDR6_SA_DQS_DP6 SOCKET4677_AZIF0045P001C01CS-SA   I169 @S9S_MB_2U_LIB.S9S_MB_2U(SCH_1):PAGE26
   J13  168 DQS6_A_T||TDQS6_A_T SCONN288_ADR50017P130CC-SCONN2A   I178 @S9S_MB_2U_LIB.S9S_MB_2U(SCH_1):PAGE94
   J14  168 DQS6_A_T||TDQS6_A_T SCONN288_ADR50017P087CC-SCONN2A   I178 @S9S_MB_2U_LIB.S9S_MB_2U(SCH_1):PAGE95

M_G_CPU0_SA_DQS_DP<7> @S9S_MB_2U_LIB.S9S_MB_2U(SCH_1):M_G_CPU0_SA_DQS_DP(7)
    U2 DY61 DDR6_SA_DQS_DP7 SOCKET4677_AZIF0045P001C01CS-SA   I169 @S9S_MB_2U_LIB.S9S_MB_2U(SCH_1):PAGE26
   J13  179 DQS7_A_T||TDQS7_A_T SCONN288_ADR50017P130CC-SCONN2A   I178 @S9S_MB_2U_LIB.S9S_MB_2U(SCH_1):PAGE94
   J14  179 DQS7_A_T||TDQS7_A_T SCONN288_ADR50017P087CC-SCONN2A   I178 @S9S_MB_2U_LIB.S9S_MB_2U(SCH_1):PAGE95

M_G_CPU0_SA_DQS_DP<8> @S9S_MB_2U_LIB.S9S_MB_2U(SCH_1):M_G_CPU0_SA_DQS_DP(8)
    U2 DN64 DDR6_SA_DQS_DP8 SOCKET4677_AZIF0045P001C01CS-SA   I169 @S9S_MB_2U_LIB.S9S_MB_2U(SCH_1):PAGE26
   J13  190 DQS8_A_T||TDQS8_A_T SCONN288_ADR50017P130CC-SCONN2A   I178 @S9S_MB_2U_LIB.S9S_MB_2U(SCH_1):PAGE94
   J14  190 DQS8_A_T||TDQS8_A_T SCONN288_ADR50017P087CC-SCONN2A   I178 @S9S_MB_2U_LIB.S9S_MB_2U(SCH_1):PAGE95

M_G_CPU0_SA_DQS_DP<9> @S9S_MB_2U_LIB.S9S_MB_2U(SCH_1):M_G_CPU0_SA_DQS_DP(9)
    U2 DN58 DDR6_SA_DQS_DP9 SOCKET4677_AZIF0045P001C01CS-SA   I169 @S9S_MB_2U_LIB.S9S_MB_2U(SCH_1):PAGE26
   J13  201 DQS9_A_T||TDQS9_A_T SCONN288_ADR50017P130CC-SCONN2A   I178 @S9S_MB_2U_LIB.S9S_MB_2U(SCH_1):PAGE94
   J14  201 DQS9_A_T||TDQS9_A_T SCONN288_ADR50017P087CC-SCONN2A   I178 @S9S_MB_2U_LIB.S9S_MB_2U(SCH_1):PAGE95

M_G_CPU0_SA_PAR @S9S_MB_2U_LIB.S9S_MB_2U(SCH_1):M_G_CPU0_SA_PAR
    U2 DL43 DDR6_SA_PAR SOCKET4677_AZIF0045P001C01CS-SA   I169 @S9S_MB_2U_LIB.S9S_MB_2U(SCH_1):PAGE26
   J13   74  PAR_A SCONN288_ADR50017P130CC-SCONN2A    I11 @S9S_MB_2U_LIB.S9S_MB_2U(SCH_1):PAGE94
   J14   74  PAR_A SCONN288_ADR50017P087CC-SCONN2A    I47 @S9S_MB_2U_LIB.S9S_MB_2U(SCH_1):PAGE95

M_G_CPU0_SA_RSP<0> @S9S_MB_2U_LIB.S9S_MB_2U(SCH_1):M_G_CPU0_SA_RSP(0)
    U2 EA48 DDR6_A_RSP0 SOCKET4677_AZIF0045P001C01CS-SA   I169 @S9S_MB_2U_LIB.S9S_MB_2U(SCH_1):PAGE26
   J13   86 LBD||RSP_A_N SCONN288_ADR50017P130CC-SCONN2A    I11 @S9S_MB_2U_LIB.S9S_MB_2U(SCH_1):PAGE94

M_G_CPU0_SA_RSP<1> @S9S_MB_2U_LIB.S9S_MB_2U(SCH_1):M_G_CPU0_SA_RSP(1)
    U2 DY47 DDR6_A_RSP1 SOCKET4677_AZIF0045P001C01CS-SA   I169 @S9S_MB_2U_LIB.S9S_MB_2U(SCH_1):PAGE26
   J14   86 LBD||RSP_A_N SCONN288_ADR50017P087CC-SCONN2A    I47 @S9S_MB_2U_LIB.S9S_MB_2U(SCH_1):PAGE95

M_G_CPU0_SB_CA<0> @S9S_MB_2U_LIB.S9S_MB_2U(SCH_1):M_G_CPU0_SB_CA(0)
    U2 DN43 DDR6_SB_CA0 SOCKET4677_AZIF0045P001C01CS-SA   I169 @S9S_MB_2U_LIB.S9S_MB_2U(SCH_1):PAGE26
   J13   76  CA0_B SCONN288_ADR50017P130CC-SCONN2A    I11 @S9S_MB_2U_LIB.S9S_MB_2U(SCH_1):PAGE94
   J14   76  CA0_B SCONN288_ADR50017P087CC-SCONN2A    I47 @S9S_MB_2U_LIB.S9S_MB_2U(SCH_1):PAGE95

M_G_CPU0_SB_CA<1> @S9S_MB_2U_LIB.S9S_MB_2U(SCH_1):M_G_CPU0_SB_CA(1)
    U2 DP44 DDR6_SB_CA1 SOCKET4677_AZIF0045P001C01CS-SA   I169 @S9S_MB_2U_LIB.S9S_MB_2U(SCH_1):PAGE26
   J13  221  CA1_B SCONN288_ADR50017P130CC-SCONN2A    I11 @S9S_MB_2U_LIB.S9S_MB_2U(SCH_1):PAGE94
   J14  221  CA1_B SCONN288_ADR50017P087CC-SCONN2A    I47 @S9S_MB_2U_LIB.S9S_MB_2U(SCH_1):PAGE95

M_G_CPU0_SB_CA<2> @S9S_MB_2U_LIB.S9S_MB_2U(SCH_1):M_G_CPU0_SB_CA(2)
    U2 DV44 DDR6_SB_CA2 SOCKET4677_AZIF0045P001C01CS-SA   I169 @S9S_MB_2U_LIB.S9S_MB_2U(SCH_1):PAGE26
   J13   78  CA2_B SCONN288_ADR50017P130CC-SCONN2A    I11 @S9S_MB_2U_LIB.S9S_MB_2U(SCH_1):PAGE94
   J14   78  CA2_B SCONN288_ADR50017P087CC-SCONN2A    I47 @S9S_MB_2U_LIB.S9S_MB_2U(SCH_1):PAGE95

M_G_CPU0_SB_CA<3> @S9S_MB_2U_LIB.S9S_MB_2U(SCH_1):M_G_CPU0_SB_CA(3)
    U2 DY44 DDR6_SB_CA3 SOCKET4677_AZIF0045P001C01CS-SA   I169 @S9S_MB_2U_LIB.S9S_MB_2U(SCH_1):PAGE26
   J13  223  CA3_B SCONN288_ADR50017P130CC-SCONN2A    I11 @S9S_MB_2U_LIB.S9S_MB_2U(SCH_1):PAGE94
   J14  223  CA3_B SCONN288_ADR50017P087CC-SCONN2A    I47 @S9S_MB_2U_LIB.S9S_MB_2U(SCH_1):PAGE95

M_G_CPU0_SB_CA<4> @S9S_MB_2U_LIB.S9S_MB_2U(SCH_1):M_G_CPU0_SB_CA(4)
    U2 DU43 DDR6_SB_CA4 SOCKET4677_AZIF0045P001C01CS-SA   I169 @S9S_MB_2U_LIB.S9S_MB_2U(SCH_1):PAGE26
   J13   80  CA4_B SCONN288_ADR50017P130CC-SCONN2A    I11 @S9S_MB_2U_LIB.S9S_MB_2U(SCH_1):PAGE94
   J14   80  CA4_B SCONN288_ADR50017P087CC-SCONN2A    I47 @S9S_MB_2U_LIB.S9S_MB_2U(SCH_1):PAGE95

M_G_CPU0_SB_CA<5> @S9S_MB_2U_LIB.S9S_MB_2U(SCH_1):M_G_CPU0_SB_CA(5)
    U2 EA43 DDR6_SB_CA5 SOCKET4677_AZIF0045P001C01CS-SA   I169 @S9S_MB_2U_LIB.S9S_MB_2U(SCH_1):PAGE26
   J13  225  CA5_B SCONN288_ADR50017P130CC-SCONN2A    I11 @S9S_MB_2U_LIB.S9S_MB_2U(SCH_1):PAGE94
   J14  225  CA5_B SCONN288_ADR50017P087CC-SCONN2A    I47 @S9S_MB_2U_LIB.S9S_MB_2U(SCH_1):PAGE95

M_G_CPU0_SB_CA<6> @S9S_MB_2U_LIB.S9S_MB_2U(SCH_1):M_G_CPU0_SB_CA(6)
    U2 DT42 DDR6_SB_CA6 SOCKET4677_AZIF0045P001C01CS-SA   I169 @S9S_MB_2U_LIB.S9S_MB_2U(SCH_1):PAGE26
   J13   82  CA6_B SCONN288_ADR50017P130CC-SCONN2A    I11 @S9S_MB_2U_LIB.S9S_MB_2U(SCH_1):PAGE94
   J14   82  CA6_B SCONN288_ADR50017P087CC-SCONN2A    I47 @S9S_MB_2U_LIB.S9S_MB_2U(SCH_1):PAGE95

M_G_CPU0_SB_CB<0> @S9S_MB_2U_LIB.S9S_MB_2U(SCH_1):M_G_CPU0_SB_CB(0)
    U2 DU35 DDR6_SB_ECC0 SOCKET4677_AZIF0045P001C01CS-SA   I169 @S9S_MB_2U_LIB.S9S_MB_2U(SCH_1):PAGE26
   J13   96  CB0_B SCONN288_ADR50017P130CC-SCONN2A    I11 @S9S_MB_2U_LIB.S9S_MB_2U(SCH_1):PAGE94
   J14   96  CB0_B SCONN288_ADR50017P087CC-SCONN2A    I47 @S9S_MB_2U_LIB.S9S_MB_2U(SCH_1):PAGE95

M_G_CPU0_SB_CB<1> @S9S_MB_2U_LIB.S9S_MB_2U(SCH_1):M_G_CPU0_SB_CB(1)
    U2 DV34 DDR6_SB_ECC1 SOCKET4677_AZIF0045P001C01CS-SA   I169 @S9S_MB_2U_LIB.S9S_MB_2U(SCH_1):PAGE26
   J13   98  CB1_B SCONN288_ADR50017P130CC-SCONN2A    I11 @S9S_MB_2U_LIB.S9S_MB_2U(SCH_1):PAGE94
   J14   98  CB1_B SCONN288_ADR50017P087CC-SCONN2A    I47 @S9S_MB_2U_LIB.S9S_MB_2U(SCH_1):PAGE95

M_G_CPU0_SB_CB<2> @S9S_MB_2U_LIB.S9S_MB_2U(SCH_1):M_G_CPU0_SB_CB(2)
    U2 EA35 DDR6_SB_ECC2 SOCKET4677_AZIF0045P001C01CS-SA   I169 @S9S_MB_2U_LIB.S9S_MB_2U(SCH_1):PAGE26
   J13  241  CB2_B SCONN288_ADR50017P130CC-SCONN2A    I11 @S9S_MB_2U_LIB.S9S_MB_2U(SCH_1):PAGE94
   J14  241  CB2_B SCONN288_ADR50017P087CC-SCONN2A    I47 @S9S_MB_2U_LIB.S9S_MB_2U(SCH_1):PAGE95

M_G_CPU0_SB_CB<3> @S9S_MB_2U_LIB.S9S_MB_2U(SCH_1):M_G_CPU0_SB_CB(3)
    U2 DY34 DDR6_SB_ECC3 SOCKET4677_AZIF0045P001C01CS-SA   I169 @S9S_MB_2U_LIB.S9S_MB_2U(SCH_1):PAGE26
   J13  243  CB3_B SCONN288_ADR50017P130CC-SCONN2A    I11 @S9S_MB_2U_LIB.S9S_MB_2U(SCH_1):PAGE94
   J14  243  CB3_B SCONN288_ADR50017P087CC-SCONN2A    I47 @S9S_MB_2U_LIB.S9S_MB_2U(SCH_1):PAGE95

M_G_CPU0_SB_CB<4> @S9S_MB_2U_LIB.S9S_MB_2U(SCH_1):M_G_CPU0_SB_CB(4)
    U2 DV38 DDR6_SB_ECC4 SOCKET4677_AZIF0045P001C01CS-SA   I169 @S9S_MB_2U_LIB.S9S_MB_2U(SCH_1):PAGE26
   J13   89  CB4_B SCONN288_ADR50017P130CC-SCONN2A    I11 @S9S_MB_2U_LIB.S9S_MB_2U(SCH_1):PAGE94
   J14   89  CB4_B SCONN288_ADR50017P087CC-SCONN2A    I47 @S9S_MB_2U_LIB.S9S_MB_2U(SCH_1):PAGE95

M_G_CPU0_SB_CB<5> @S9S_MB_2U_LIB.S9S_MB_2U(SCH_1):M_G_CPU0_SB_CB(5)
    U2 DU37 DDR6_SB_ECC5 SOCKET4677_AZIF0045P001C01CS-SA   I169 @S9S_MB_2U_LIB.S9S_MB_2U(SCH_1):PAGE26
   J13   91  CB5_B SCONN288_ADR50017P130CC-SCONN2A    I11 @S9S_MB_2U_LIB.S9S_MB_2U(SCH_1):PAGE94
   J14   91  CB5_B SCONN288_ADR50017P087CC-SCONN2A    I47 @S9S_MB_2U_LIB.S9S_MB_2U(SCH_1):PAGE95

M_G_CPU0_SB_CB<6> @S9S_MB_2U_LIB.S9S_MB_2U(SCH_1):M_G_CPU0_SB_CB(6)
    U2 DY38 DDR6_SB_ECC6 SOCKET4677_AZIF0045P001C01CS-SA   I169 @S9S_MB_2U_LIB.S9S_MB_2U(SCH_1):PAGE26
   J13  234  CB6_B SCONN288_ADR50017P130CC-SCONN2A    I11 @S9S_MB_2U_LIB.S9S_MB_2U(SCH_1):PAGE94
   J14  234  CB6_B SCONN288_ADR50017P087CC-SCONN2A    I47 @S9S_MB_2U_LIB.S9S_MB_2U(SCH_1):PAGE95

M_G_CPU0_SB_CB<7> @S9S_MB_2U_LIB.S9S_MB_2U(SCH_1):M_G_CPU0_SB_CB(7)
    U2 EA37 DDR6_SB_ECC7 SOCKET4677_AZIF0045P001C01CS-SA   I169 @S9S_MB_2U_LIB.S9S_MB_2U(SCH_1):PAGE26
   J13  236  CB7_B SCONN288_ADR50017P130CC-SCONN2A    I11 @S9S_MB_2U_LIB.S9S_MB_2U(SCH_1):PAGE94
   J14  236  CB7_B SCONN288_ADR50017P087CC-SCONN2A    I47 @S9S_MB_2U_LIB.S9S_MB_2U(SCH_1):PAGE95

M_G_CPU0_SB_CS_N<0> @S9S_MB_2U_LIB.S9S_MB_2U(SCH_1):M_G_CPU0_SB_CS_N(0)
    U2 EA41 DDR6_SB_CS_N0 SOCKET4677_AZIF0045P001C01CS-SA   I169 @S9S_MB_2U_LIB.S9S_MB_2U(SCH_1):PAGE26
   J13   84 CS0_B_N SCONN288_ADR50017P130CC-SCONN2A    I11 @S9S_MB_2U_LIB.S9S_MB_2U(SCH_1):PAGE94

M_G_CPU0_SB_CS_N<1> @S9S_MB_2U_LIB.S9S_MB_2U(SCH_1):M_G_CPU0_SB_CS_N(1)
    U2 DY40 DDR6_SB_CS_N1 SOCKET4677_AZIF0045P001C01CS-SA   I169 @S9S_MB_2U_LIB.S9S_MB_2U(SCH_1):PAGE26
   J13  229 CS1_B_N SCONN288_ADR50017P130CC-SCONN2A    I11 @S9S_MB_2U_LIB.S9S_MB_2U(SCH_1):PAGE94

M_G_CPU0_SB_CS_N<2> @S9S_MB_2U_LIB.S9S_MB_2U(SCH_1):M_G_CPU0_SB_CS_N(2)
    U2 DU41 DDR6_SB_CS_N2 SOCKET4677_AZIF0045P001C01CS-SA   I169 @S9S_MB_2U_LIB.S9S_MB_2U(SCH_1):PAGE26
   J14   84 CS0_B_N SCONN288_ADR50017P087CC-SCONN2A    I47 @S9S_MB_2U_LIB.S9S_MB_2U(SCH_1):PAGE95

M_G_CPU0_SB_CS_N<3> @S9S_MB_2U_LIB.S9S_MB_2U(SCH_1):M_G_CPU0_SB_CS_N(3)
    U2 DV40 DDR6_SB_CS_N3 SOCKET4677_AZIF0045P001C01CS-SA   I169 @S9S_MB_2U_LIB.S9S_MB_2U(SCH_1):PAGE26
   J14  229 CS1_B_N SCONN288_ADR50017P087CC-SCONN2A    I47 @S9S_MB_2U_LIB.S9S_MB_2U(SCH_1):PAGE95

M_G_CPU0_SB_DQ<0> @S9S_MB_2U_LIB.S9S_MB_2U(SCH_1):M_G_CPU0_SB_DQ(0)
    U2 DL35 DDR6_SB_DQ0 SOCKET4677_AZIF0045P001C01CS-SA   I169 @S9S_MB_2U_LIB.S9S_MB_2U(SCH_1):PAGE26
   J13  100  DQ0_B SCONN288_ADR50017P130CC-SCONN2A    I11 @S9S_MB_2U_LIB.S9S_MB_2U(SCH_1):PAGE94
   J14  100  DQ0_B SCONN288_ADR50017P087CC-SCONN2A    I47 @S9S_MB_2U_LIB.S9S_MB_2U(SCH_1):PAGE95

M_G_CPU0_SB_DQ<10> @S9S_MB_2U_LIB.S9S_MB_2U(SCH_1):M_G_CPU0_SB_DQ(10)
    U2 DL29 DDR6_SB_DQ10 SOCKET4677_AZIF0045P001C01CS-SA   I169 @S9S_MB_2U_LIB.S9S_MB_2U(SCH_1):PAGE26
   J13  256 DQ10_B SCONN288_ADR50017P130CC-SCONN2A    I11 @S9S_MB_2U_LIB.S9S_MB_2U(SCH_1):PAGE94
   J14  256 DQ10_B SCONN288_ADR50017P087CC-SCONN2A    I47 @S9S_MB_2U_LIB.S9S_MB_2U(SCH_1):PAGE95

M_G_CPU0_SB_DQ<11> @S9S_MB_2U_LIB.S9S_MB_2U(SCH_1):M_G_CPU0_SB_DQ(11)
    U2 DP28 DDR6_SB_DQ11 SOCKET4677_AZIF0045P001C01CS-SA   I169 @S9S_MB_2U_LIB.S9S_MB_2U(SCH_1):PAGE26
   J13  258 DQ11_B SCONN288_ADR50017P130CC-SCONN2A    I11 @S9S_MB_2U_LIB.S9S_MB_2U(SCH_1):PAGE94
   J14  258 DQ11_B SCONN288_ADR50017P087CC-SCONN2A    I47 @S9S_MB_2U_LIB.S9S_MB_2U(SCH_1):PAGE95

M_G_CPU0_SB_DQ<12> @S9S_MB_2U_LIB.S9S_MB_2U(SCH_1):M_G_CPU0_SB_DQ(12)
    U2 DK26 DDR6_SB_DQ12 SOCKET4677_AZIF0045P001C01CS-SA   I169 @S9S_MB_2U_LIB.S9S_MB_2U(SCH_1):PAGE26
   J13  118 DQ12_B SCONN288_ADR50017P130CC-SCONN2A    I11 @S9S_MB_2U_LIB.S9S_MB_2U(SCH_1):PAGE94
   J14  118 DQ12_B SCONN288_ADR50017P087CC-SCONN2A    I47 @S9S_MB_2U_LIB.S9S_MB_2U(SCH_1):PAGE95

M_G_CPU0_SB_DQ<13> @S9S_MB_2U_LIB.S9S_MB_2U(SCH_1):M_G_CPU0_SB_DQ(13)
    U2 DL25 DDR6_SB_DQ13 SOCKET4677_AZIF0045P001C01CS-SA   I169 @S9S_MB_2U_LIB.S9S_MB_2U(SCH_1):PAGE26
   J13  120 DQ13_B SCONN288_ADR50017P130CC-SCONN2A    I11 @S9S_MB_2U_LIB.S9S_MB_2U(SCH_1):PAGE94
   J14  120 DQ13_B SCONN288_ADR50017P087CC-SCONN2A    I47 @S9S_MB_2U_LIB.S9S_MB_2U(SCH_1):PAGE95

M_G_CPU0_SB_DQ<14> @S9S_MB_2U_LIB.S9S_MB_2U(SCH_1):M_G_CPU0_SB_DQ(14)
    U2 DP26 DDR6_SB_DQ14 SOCKET4677_AZIF0045P001C01CS-SA   I169 @S9S_MB_2U_LIB.S9S_MB_2U(SCH_1):PAGE26
   J13  263 DQ14_B SCONN288_ADR50017P130CC-SCONN2A    I11 @S9S_MB_2U_LIB.S9S_MB_2U(SCH_1):PAGE94
   J14  263 DQ14_B SCONN288_ADR50017P087CC-SCONN2A    I47 @S9S_MB_2U_LIB.S9S_MB_2U(SCH_1):PAGE95

M_G_CPU0_SB_DQ<15> @S9S_MB_2U_LIB.S9S_MB_2U(SCH_1):M_G_CPU0_SB_DQ(15)
    U2 DN25 DDR6_SB_DQ15 SOCKET4677_AZIF0045P001C01CS-SA   I169 @S9S_MB_2U_LIB.S9S_MB_2U(SCH_1):PAGE26
   J13  265 DQ15_B SCONN288_ADR50017P130CC-SCONN2A    I11 @S9S_MB_2U_LIB.S9S_MB_2U(SCH_1):PAGE94
   J14  265 DQ15_B SCONN288_ADR50017P087CC-SCONN2A    I47 @S9S_MB_2U_LIB.S9S_MB_2U(SCH_1):PAGE95

M_G_CPU0_SB_DQ<16> @S9S_MB_2U_LIB.S9S_MB_2U(SCH_1):M_G_CPU0_SB_DQ(16)
    U2 DV26 DDR6_SB_DQ16 SOCKET4677_AZIF0045P001C01CS-SA   I169 @S9S_MB_2U_LIB.S9S_MB_2U(SCH_1):PAGE26
   J13  122 DQ16_B SCONN288_ADR50017P130CC-SCONN2A    I11 @S9S_MB_2U_LIB.S9S_MB_2U(SCH_1):PAGE94
   J14  122 DQ16_B SCONN288_ADR50017P087CC-SCONN2A    I47 @S9S_MB_2U_LIB.S9S_MB_2U(SCH_1):PAGE95

M_G_CPU0_SB_DQ<17> @S9S_MB_2U_LIB.S9S_MB_2U(SCH_1):M_G_CPU0_SB_DQ(17)
    U2 DU25 DDR6_SB_DQ17 SOCKET4677_AZIF0045P001C01CS-SA   I169 @S9S_MB_2U_LIB.S9S_MB_2U(SCH_1):PAGE26
   J13  124 DQ17_B SCONN288_ADR50017P130CC-SCONN2A    I11 @S9S_MB_2U_LIB.S9S_MB_2U(SCH_1):PAGE94
   J14  124 DQ17_B SCONN288_ADR50017P087CC-SCONN2A    I47 @S9S_MB_2U_LIB.S9S_MB_2U(SCH_1):PAGE95

M_G_CPU0_SB_DQ<18> @S9S_MB_2U_LIB.S9S_MB_2U(SCH_1):M_G_CPU0_SB_DQ(18)
    U2 DY26 DDR6_SB_DQ18 SOCKET4677_AZIF0045P001C01CS-SA   I169 @S9S_MB_2U_LIB.S9S_MB_2U(SCH_1):PAGE26
   J13  267 DQ18_B SCONN288_ADR50017P130CC-SCONN2A    I11 @S9S_MB_2U_LIB.S9S_MB_2U(SCH_1):PAGE94
   J14  267 DQ18_B SCONN288_ADR50017P087CC-SCONN2A    I47 @S9S_MB_2U_LIB.S9S_MB_2U(SCH_1):PAGE95

M_G_CPU0_SB_DQ<19> @S9S_MB_2U_LIB.S9S_MB_2U(SCH_1):M_G_CPU0_SB_DQ(19)
    U2 EA25 DDR6_SB_DQ19 SOCKET4677_AZIF0045P001C01CS-SA   I169 @S9S_MB_2U_LIB.S9S_MB_2U(SCH_1):PAGE26
   J13  269 DQ19_B SCONN288_ADR50017P130CC-SCONN2A    I11 @S9S_MB_2U_LIB.S9S_MB_2U(SCH_1):PAGE94
   J14  269 DQ19_B SCONN288_ADR50017P087CC-SCONN2A    I47 @S9S_MB_2U_LIB.S9S_MB_2U(SCH_1):PAGE95

M_G_CPU0_SB_DQ<1> @S9S_MB_2U_LIB.S9S_MB_2U(SCH_1):M_G_CPU0_SB_DQ(1)
    U2 DK34 DDR6_SB_DQ1 SOCKET4677_AZIF0045P001C01CS-SA   I169 @S9S_MB_2U_LIB.S9S_MB_2U(SCH_1):PAGE26
   J13  102  DQ1_B SCONN288_ADR50017P130CC-SCONN2A    I11 @S9S_MB_2U_LIB.S9S_MB_2U(SCH_1):PAGE94
   J14  102  DQ1_B SCONN288_ADR50017P087CC-SCONN2A    I47 @S9S_MB_2U_LIB.S9S_MB_2U(SCH_1):PAGE95

M_G_CPU0_SB_DQ<20> @S9S_MB_2U_LIB.S9S_MB_2U(SCH_1):M_G_CPU0_SB_DQ(20)
    U2 DU23 DDR6_SB_DQ20 SOCKET4677_AZIF0045P001C01CS-SA   I169 @S9S_MB_2U_LIB.S9S_MB_2U(SCH_1):PAGE26
   J13  129 DQ20_B SCONN288_ADR50017P130CC-SCONN2A    I11 @S9S_MB_2U_LIB.S9S_MB_2U(SCH_1):PAGE94
   J14  129 DQ20_B SCONN288_ADR50017P087CC-SCONN2A    I47 @S9S_MB_2U_LIB.S9S_MB_2U(SCH_1):PAGE95

M_G_CPU0_SB_DQ<21> @S9S_MB_2U_LIB.S9S_MB_2U(SCH_1):M_G_CPU0_SB_DQ(21)
    U2 DV22 DDR6_SB_DQ21 SOCKET4677_AZIF0045P001C01CS-SA   I169 @S9S_MB_2U_LIB.S9S_MB_2U(SCH_1):PAGE26
   J13  131 DQ21_B SCONN288_ADR50017P130CC-SCONN2A    I11 @S9S_MB_2U_LIB.S9S_MB_2U(SCH_1):PAGE94
   J14  131 DQ21_B SCONN288_ADR50017P087CC-SCONN2A    I47 @S9S_MB_2U_LIB.S9S_MB_2U(SCH_1):PAGE95

M_G_CPU0_SB_DQ<22> @S9S_MB_2U_LIB.S9S_MB_2U(SCH_1):M_G_CPU0_SB_DQ(22)
    U2 EA23 DDR6_SB_DQ22 SOCKET4677_AZIF0045P001C01CS-SA   I169 @S9S_MB_2U_LIB.S9S_MB_2U(SCH_1):PAGE26
   J13  274 DQ22_B SCONN288_ADR50017P130CC-SCONN2A    I11 @S9S_MB_2U_LIB.S9S_MB_2U(SCH_1):PAGE94
   J14  274 DQ22_B SCONN288_ADR50017P087CC-SCONN2A    I47 @S9S_MB_2U_LIB.S9S_MB_2U(SCH_1):PAGE95

M_G_CPU0_SB_DQ<23> @S9S_MB_2U_LIB.S9S_MB_2U(SCH_1):M_G_CPU0_SB_DQ(23)
    U2 DY22 DDR6_SB_DQ23 SOCKET4677_AZIF0045P001C01CS-SA   I169 @S9S_MB_2U_LIB.S9S_MB_2U(SCH_1):PAGE26
   J13  276 DQ23_B SCONN288_ADR50017P130CC-SCONN2A    I11 @S9S_MB_2U_LIB.S9S_MB_2U(SCH_1):PAGE94
   J14  276 DQ23_B SCONN288_ADR50017P087CC-SCONN2A    I47 @S9S_MB_2U_LIB.S9S_MB_2U(SCH_1):PAGE95

M_G_CPU0_SB_DQ<24> @S9S_MB_2U_LIB.S9S_MB_2U(SCH_1):M_G_CPU0_SB_DQ(24)
    U2  EK8 DDR6_SB_DQ24 SOCKET4677_AZIF0045P001C01CS-SA   I169 @S9S_MB_2U_LIB.S9S_MB_2U(SCH_1):PAGE26
   J13  133 DQ24_B SCONN288_ADR50017P130CC-SCONN2A    I11 @S9S_MB_2U_LIB.S9S_MB_2U(SCH_1):PAGE94
   J14  133 DQ24_B SCONN288_ADR50017P087CC-SCONN2A    I47 @S9S_MB_2U_LIB.S9S_MB_2U(SCH_1):PAGE95

M_G_CPU0_SB_DQ<25> @S9S_MB_2U_LIB.S9S_MB_2U(SCH_1):M_G_CPU0_SB_DQ(25)
    U2  EH8 DDR6_SB_DQ25 SOCKET4677_AZIF0045P001C01CS-SA   I169 @S9S_MB_2U_LIB.S9S_MB_2U(SCH_1):PAGE26
   J13  135 DQ25_B SCONN288_ADR50017P130CC-SCONN2A    I11 @S9S_MB_2U_LIB.S9S_MB_2U(SCH_1):PAGE94
   J14  135 DQ25_B SCONN288_ADR50017P087CC-SCONN2A    I47 @S9S_MB_2U_LIB.S9S_MB_2U(SCH_1):PAGE95

M_G_CPU0_SB_DQ<26> @S9S_MB_2U_LIB.S9S_MB_2U(SCH_1):M_G_CPU0_SB_DQ(26)
    U2  EP8 DDR6_SB_DQ26 SOCKET4677_AZIF0045P001C01CS-SA   I169 @S9S_MB_2U_LIB.S9S_MB_2U(SCH_1):PAGE26
   J13  278 DQ26_B SCONN288_ADR50017P130CC-SCONN2A    I11 @S9S_MB_2U_LIB.S9S_MB_2U(SCH_1):PAGE94
   J14  278 DQ26_B SCONN288_ADR50017P087CC-SCONN2A    I47 @S9S_MB_2U_LIB.S9S_MB_2U(SCH_1):PAGE95

M_G_CPU0_SB_DQ<27> @S9S_MB_2U_LIB.S9S_MB_2U(SCH_1):M_G_CPU0_SB_DQ(27)
    U2  ET8 DDR6_SB_DQ27 SOCKET4677_AZIF0045P001C01CS-SA   I169 @S9S_MB_2U_LIB.S9S_MB_2U(SCH_1):PAGE26
   J13  280 DQ27_B SCONN288_ADR50017P130CC-SCONN2A    I11 @S9S_MB_2U_LIB.S9S_MB_2U(SCH_1):PAGE94
   J14  280 DQ27_B SCONN288_ADR50017P087CC-SCONN2A    I47 @S9S_MB_2U_LIB.S9S_MB_2U(SCH_1):PAGE95

M_G_CPU0_SB_DQ<28> @S9S_MB_2U_LIB.S9S_MB_2U(SCH_1):M_G_CPU0_SB_DQ(28)
    U2  EK6 DDR6_SB_DQ28 SOCKET4677_AZIF0045P001C01CS-SA   I169 @S9S_MB_2U_LIB.S9S_MB_2U(SCH_1):PAGE26
   J13  140 DQ28_B SCONN288_ADR50017P130CC-SCONN2A    I11 @S9S_MB_2U_LIB.S9S_MB_2U(SCH_1):PAGE94
   J14  140 DQ28_B SCONN288_ADR50017P087CC-SCONN2A    I47 @S9S_MB_2U_LIB.S9S_MB_2U(SCH_1):PAGE95

M_G_CPU0_SB_DQ<29> @S9S_MB_2U_LIB.S9S_MB_2U(SCH_1):M_G_CPU0_SB_DQ(29)
    U2  EJ5 DDR6_SB_DQ29 SOCKET4677_AZIF0045P001C01CS-SA   I169 @S9S_MB_2U_LIB.S9S_MB_2U(SCH_1):PAGE26
   J13  142 DQ29_B SCONN288_ADR50017P130CC-SCONN2A    I11 @S9S_MB_2U_LIB.S9S_MB_2U(SCH_1):PAGE94
   J14  142 DQ29_B SCONN288_ADR50017P087CC-SCONN2A    I47 @S9S_MB_2U_LIB.S9S_MB_2U(SCH_1):PAGE95

M_G_CPU0_SB_DQ<2> @S9S_MB_2U_LIB.S9S_MB_2U(SCH_1):M_G_CPU0_SB_DQ(2)
    U2 DN35 DDR6_SB_DQ2 SOCKET4677_AZIF0045P001C01CS-SA   I169 @S9S_MB_2U_LIB.S9S_MB_2U(SCH_1):PAGE26
   J13  245  DQ2_B SCONN288_ADR50017P130CC-SCONN2A    I11 @S9S_MB_2U_LIB.S9S_MB_2U(SCH_1):PAGE94
   J14  245  DQ2_B SCONN288_ADR50017P087CC-SCONN2A    I47 @S9S_MB_2U_LIB.S9S_MB_2U(SCH_1):PAGE95

M_G_CPU0_SB_DQ<30> @S9S_MB_2U_LIB.S9S_MB_2U(SCH_1):M_G_CPU0_SB_DQ(30)
    U2  EP4 DDR6_SB_DQ30 SOCKET4677_AZIF0045P001C01CS-SA   I169 @S9S_MB_2U_LIB.S9S_MB_2U(SCH_1):PAGE26
   J13  285 DQ30_B SCONN288_ADR50017P130CC-SCONN2A    I11 @S9S_MB_2U_LIB.S9S_MB_2U(SCH_1):PAGE94
   J14  285 DQ30_B SCONN288_ADR50017P087CC-SCONN2A    I47 @S9S_MB_2U_LIB.S9S_MB_2U(SCH_1):PAGE95

M_G_CPU0_SB_DQ<31> @S9S_MB_2U_LIB.S9S_MB_2U(SCH_1):M_G_CPU0_SB_DQ(31)
    U2  EM4 DDR6_SB_DQ31 SOCKET4677_AZIF0045P001C01CS-SA   I169 @S9S_MB_2U_LIB.S9S_MB_2U(SCH_1):PAGE26
   J13  287 DQ31_B SCONN288_ADR50017P130CC-SCONN2A    I11 @S9S_MB_2U_LIB.S9S_MB_2U(SCH_1):PAGE94
   J14  287 DQ31_B SCONN288_ADR50017P087CC-SCONN2A    I47 @S9S_MB_2U_LIB.S9S_MB_2U(SCH_1):PAGE95

M_G_CPU0_SB_DQ<3> @S9S_MB_2U_LIB.S9S_MB_2U(SCH_1):M_G_CPU0_SB_DQ(3)
    U2 DP34 DDR6_SB_DQ3 SOCKET4677_AZIF0045P001C01CS-SA   I169 @S9S_MB_2U_LIB.S9S_MB_2U(SCH_1):PAGE26
   J13  247  DQ3_B SCONN288_ADR50017P130CC-SCONN2A    I11 @S9S_MB_2U_LIB.S9S_MB_2U(SCH_1):PAGE94
   J14  247  DQ3_B SCONN288_ADR50017P087CC-SCONN2A    I47 @S9S_MB_2U_LIB.S9S_MB_2U(SCH_1):PAGE95

M_G_CPU0_SB_DQ<4> @S9S_MB_2U_LIB.S9S_MB_2U(SCH_1):M_G_CPU0_SB_DQ(4)
    U2 DK32 DDR6_SB_DQ4 SOCKET4677_AZIF0045P001C01CS-SA   I169 @S9S_MB_2U_LIB.S9S_MB_2U(SCH_1):PAGE26
   J13  107  DQ4_B SCONN288_ADR50017P130CC-SCONN2A    I11 @S9S_MB_2U_LIB.S9S_MB_2U(SCH_1):PAGE94
   J14  107  DQ4_B SCONN288_ADR50017P087CC-SCONN2A    I47 @S9S_MB_2U_LIB.S9S_MB_2U(SCH_1):PAGE95

M_G_CPU0_SB_DQ<5> @S9S_MB_2U_LIB.S9S_MB_2U(SCH_1):M_G_CPU0_SB_DQ(5)
    U2 DL31 DDR6_SB_DQ5 SOCKET4677_AZIF0045P001C01CS-SA   I169 @S9S_MB_2U_LIB.S9S_MB_2U(SCH_1):PAGE26
   J13  109  DQ5_B SCONN288_ADR50017P130CC-SCONN2A    I11 @S9S_MB_2U_LIB.S9S_MB_2U(SCH_1):PAGE94
   J14  109  DQ5_B SCONN288_ADR50017P087CC-SCONN2A    I47 @S9S_MB_2U_LIB.S9S_MB_2U(SCH_1):PAGE95

M_G_CPU0_SB_DQ<6> @S9S_MB_2U_LIB.S9S_MB_2U(SCH_1):M_G_CPU0_SB_DQ(6)
    U2 DP32 DDR6_SB_DQ6 SOCKET4677_AZIF0045P001C01CS-SA   I169 @S9S_MB_2U_LIB.S9S_MB_2U(SCH_1):PAGE26
   J13  252  DQ6_B SCONN288_ADR50017P130CC-SCONN2A    I11 @S9S_MB_2U_LIB.S9S_MB_2U(SCH_1):PAGE94
   J14  252  DQ6_B SCONN288_ADR50017P087CC-SCONN2A    I47 @S9S_MB_2U_LIB.S9S_MB_2U(SCH_1):PAGE95

M_G_CPU0_SB_DQ<7> @S9S_MB_2U_LIB.S9S_MB_2U(SCH_1):M_G_CPU0_SB_DQ(7)
    U2 DN31 DDR6_SB_DQ7 SOCKET4677_AZIF0045P001C01CS-SA   I169 @S9S_MB_2U_LIB.S9S_MB_2U(SCH_1):PAGE26
   J13  254  DQ7_B SCONN288_ADR50017P130CC-SCONN2A    I11 @S9S_MB_2U_LIB.S9S_MB_2U(SCH_1):PAGE94
   J14  254  DQ7_B SCONN288_ADR50017P087CC-SCONN2A    I47 @S9S_MB_2U_LIB.S9S_MB_2U(SCH_1):PAGE95

M_G_CPU0_SB_DQ<8> @S9S_MB_2U_LIB.S9S_MB_2U(SCH_1):M_G_CPU0_SB_DQ(8)
    U2 DN29 DDR6_SB_DQ8 SOCKET4677_AZIF0045P001C01CS-SA   I169 @S9S_MB_2U_LIB.S9S_MB_2U(SCH_1):PAGE26
   J13  111  DQ8_B SCONN288_ADR50017P130CC-SCONN2A    I11 @S9S_MB_2U_LIB.S9S_MB_2U(SCH_1):PAGE94
   J14  111  DQ8_B SCONN288_ADR50017P087CC-SCONN2A    I47 @S9S_MB_2U_LIB.S9S_MB_2U(SCH_1):PAGE95

M_G_CPU0_SB_DQ<9> @S9S_MB_2U_LIB.S9S_MB_2U(SCH_1):M_G_CPU0_SB_DQ(9)
    U2 DK28 DDR6_SB_DQ9 SOCKET4677_AZIF0045P001C01CS-SA   I169 @S9S_MB_2U_LIB.S9S_MB_2U(SCH_1):PAGE26
   J13  113  DQ9_B SCONN288_ADR50017P130CC-SCONN2A    I11 @S9S_MB_2U_LIB.S9S_MB_2U(SCH_1):PAGE94
   J14  113  DQ9_B SCONN288_ADR50017P087CC-SCONN2A    I47 @S9S_MB_2U_LIB.S9S_MB_2U(SCH_1):PAGE95

M_G_CPU0_SB_DQS_DN<0> @S9S_MB_2U_LIB.S9S_MB_2U(SCH_1):M_G_CPU0_SB_DQS_DN(0)
    U2 DJ33 DDR6_SB_DQS_DN0 SOCKET4677_AZIF0045P001C01CS-SA   I169 @S9S_MB_2U_LIB.S9S_MB_2U(SCH_1):PAGE26
   J13  105 DQS0_B_C SCONN288_ADR50017P130CC-SCONN2A   I178 @S9S_MB_2U_LIB.S9S_MB_2U(SCH_1):PAGE94
   J14  105 DQS0_B_C SCONN288_ADR50017P087CC-SCONN2A   I178 @S9S_MB_2U_LIB.S9S_MB_2U(SCH_1):PAGE95

M_G_CPU0_SB_DQS_DN<1> @S9S_MB_2U_LIB.S9S_MB_2U(SCH_1):M_G_CPU0_SB_DQS_DN(1)
    U2 DJ27 DDR6_SB_DQS_DN1 SOCKET4677_AZIF0045P001C01CS-SA   I169 @S9S_MB_2U_LIB.S9S_MB_2U(SCH_1):PAGE26
   J13  116 DQS1_B_C SCONN288_ADR50017P130CC-SCONN2A   I178 @S9S_MB_2U_LIB.S9S_MB_2U(SCH_1):PAGE94
   J14  116 DQS1_B_C SCONN288_ADR50017P087CC-SCONN2A   I178 @S9S_MB_2U_LIB.S9S_MB_2U(SCH_1):PAGE95

M_G_CPU0_SB_DQS_DN<2> @S9S_MB_2U_LIB.S9S_MB_2U(SCH_1):M_G_CPU0_SB_DQS_DN(2)
    U2 DV24 DDR6_SB_DQS_DN2 SOCKET4677_AZIF0045P001C01CS-SA   I169 @S9S_MB_2U_LIB.S9S_MB_2U(SCH_1):PAGE26
   J13  127 DQS2_B_C SCONN288_ADR50017P130CC-SCONN2A   I178 @S9S_MB_2U_LIB.S9S_MB_2U(SCH_1):PAGE94
   J14  127 DQS2_B_C SCONN288_ADR50017P087CC-SCONN2A   I178 @S9S_MB_2U_LIB.S9S_MB_2U(SCH_1):PAGE95

M_G_CPU0_SB_DQS_DN<3> @S9S_MB_2U_LIB.S9S_MB_2U(SCH_1):M_G_CPU0_SB_DQS_DN(3)
    U2  EP6 DDR6_SB_DQS_DN3 SOCKET4677_AZIF0045P001C01CS-SA   I169 @S9S_MB_2U_LIB.S9S_MB_2U(SCH_1):PAGE26
   J13  138 DQS3_B_C SCONN288_ADR50017P130CC-SCONN2A   I178 @S9S_MB_2U_LIB.S9S_MB_2U(SCH_1):PAGE94
   J14  138 DQS3_B_C SCONN288_ADR50017P087CC-SCONN2A   I178 @S9S_MB_2U_LIB.S9S_MB_2U(SCH_1):PAGE95

M_G_CPU0_SB_DQS_DN<4> @S9S_MB_2U_LIB.S9S_MB_2U(SCH_1):M_G_CPU0_SB_DQS_DN(4)
    U2 EB36 DDR6_SB_DQS_DN4 SOCKET4677_AZIF0045P001C01CS-SA   I169 @S9S_MB_2U_LIB.S9S_MB_2U(SCH_1):PAGE26
   J13  238 DQS4_B_C SCONN288_ADR50017P130CC-SCONN2A   I178 @S9S_MB_2U_LIB.S9S_MB_2U(SCH_1):PAGE94
   J14  238 DQS4_B_C SCONN288_ADR50017P087CC-SCONN2A   I178 @S9S_MB_2U_LIB.S9S_MB_2U(SCH_1):PAGE95

M_G_CPU0_SB_DQS_DN<5> @S9S_MB_2U_LIB.S9S_MB_2U(SCH_1):M_G_CPU0_SB_DQS_DN(5)
    U2 DR33 DDR6_SB_DQS_DN5 SOCKET4677_AZIF0045P001C01CS-SA   I169 @S9S_MB_2U_LIB.S9S_MB_2U(SCH_1):PAGE26
   J13  249 DQS5_B_C||TDQS5_B_C SCONN288_ADR50017P130CC-SCONN2A   I178 @S9S_MB_2U_LIB.S9S_MB_2U(SCH_1):PAGE94
   J14  249 DQS5_B_C||TDQS5_B_C SCONN288_ADR50017P087CC-SCONN2A   I178 @S9S_MB_2U_LIB.S9S_MB_2U(SCH_1):PAGE95

M_G_CPU0_SB_DQS_DN<6> @S9S_MB_2U_LIB.S9S_MB_2U(SCH_1):M_G_CPU0_SB_DQS_DN(6)
    U2 DN27 DDR6_SB_DQS_DN6 SOCKET4677_AZIF0045P001C01CS-SA   I169 @S9S_MB_2U_LIB.S9S_MB_2U(SCH_1):PAGE26
   J13  260 DQS6_B_C||TDQS6_B_C SCONN288_ADR50017P130CC-SCONN2A   I178 @S9S_MB_2U_LIB.S9S_MB_2U(SCH_1):PAGE94
   J14  260 DQS6_B_C||TDQS6_B_C SCONN288_ADR50017P087CC-SCONN2A   I178 @S9S_MB_2U_LIB.S9S_MB_2U(SCH_1):PAGE95

M_G_CPU0_SB_DQS_DN<7> @S9S_MB_2U_LIB.S9S_MB_2U(SCH_1):M_G_CPU0_SB_DQS_DN(7)
    U2 EB24 DDR6_SB_DQS_DN7 SOCKET4677_AZIF0045P001C01CS-SA   I169 @S9S_MB_2U_LIB.S9S_MB_2U(SCH_1):PAGE26
   J13  271 DQS7_B_C||TDQS7_B_C SCONN288_ADR50017P130CC-SCONN2A   I178 @S9S_MB_2U_LIB.S9S_MB_2U(SCH_1):PAGE94
   J14  271 DQS7_B_C||TDQS7_B_C SCONN288_ADR50017P087CC-SCONN2A   I178 @S9S_MB_2U_LIB.S9S_MB_2U(SCH_1):PAGE95

M_G_CPU0_SB_DQS_DN<8> @S9S_MB_2U_LIB.S9S_MB_2U(SCH_1):M_G_CPU0_SB_DQS_DN(8)
    U2  EM6 DDR6_SB_DQS_DN8 SOCKET4677_AZIF0045P001C01CS-SA   I169 @S9S_MB_2U_LIB.S9S_MB_2U(SCH_1):PAGE26
   J13  282 DQS8_B_C||TDQS8_B_C SCONN288_ADR50017P130CC-SCONN2A   I178 @S9S_MB_2U_LIB.S9S_MB_2U(SCH_1):PAGE94
   J14  282 DQS8_B_C||TDQS8_B_C SCONN288_ADR50017P087CC-SCONN2A   I178 @S9S_MB_2U_LIB.S9S_MB_2U(SCH_1):PAGE95

M_G_CPU0_SB_DQS_DN<9> @S9S_MB_2U_LIB.S9S_MB_2U(SCH_1):M_G_CPU0_SB_DQS_DN(9)
    U2 DV36 DDR6_SB_DQS_DN9 SOCKET4677_AZIF0045P001C01CS-SA   I169 @S9S_MB_2U_LIB.S9S_MB_2U(SCH_1):PAGE26
   J13   94 DQS9_B_C||TDQS9_B_C SCONN288_ADR50017P130CC-SCONN2A   I178 @S9S_MB_2U_LIB.S9S_MB_2U(SCH_1):PAGE94
   J14   94 DQS9_B_C||TDQS9_B_C SCONN288_ADR50017P087CC-SCONN2A   I178 @S9S_MB_2U_LIB.S9S_MB_2U(SCH_1):PAGE95

M_G_CPU0_SB_DQS_DP<0> @S9S_MB_2U_LIB.S9S_MB_2U(SCH_1):M_G_CPU0_SB_DQS_DP(0)
    U2 DL33 DDR6_SB_DQS_DP0 SOCKET4677_AZIF0045P001C01CS-SA   I169 @S9S_MB_2U_LIB.S9S_MB_2U(SCH_1):PAGE26
   J13  104 DQS0_B_T SCONN288_ADR50017P130CC-SCONN2A   I178 @S9S_MB_2U_LIB.S9S_MB_2U(SCH_1):PAGE94
   J14  104 DQS0_B_T SCONN288_ADR50017P087CC-SCONN2A   I178 @S9S_MB_2U_LIB.S9S_MB_2U(SCH_1):PAGE95

M_G_CPU0_SB_DQS_DP<1> @S9S_MB_2U_LIB.S9S_MB_2U(SCH_1):M_G_CPU0_SB_DQS_DP(1)
    U2 DL27 DDR6_SB_DQS_DP1 SOCKET4677_AZIF0045P001C01CS-SA   I169 @S9S_MB_2U_LIB.S9S_MB_2U(SCH_1):PAGE26
   J13  115 DQS1_B_T SCONN288_ADR50017P130CC-SCONN2A   I178 @S9S_MB_2U_LIB.S9S_MB_2U(SCH_1):PAGE94
   J14  115 DQS1_B_T SCONN288_ADR50017P087CC-SCONN2A   I178 @S9S_MB_2U_LIB.S9S_MB_2U(SCH_1):PAGE95

M_G_CPU0_SB_DQS_DP<2> @S9S_MB_2U_LIB.S9S_MB_2U(SCH_1):M_G_CPU0_SB_DQS_DP(2)
    U2 DT24 DDR6_SB_DQS_DP2 SOCKET4677_AZIF0045P001C01CS-SA   I169 @S9S_MB_2U_LIB.S9S_MB_2U(SCH_1):PAGE26
   J13  126 DQS2_B_T SCONN288_ADR50017P130CC-SCONN2A   I178 @S9S_MB_2U_LIB.S9S_MB_2U(SCH_1):PAGE94
   J14  126 DQS2_B_T SCONN288_ADR50017P087CC-SCONN2A   I178 @S9S_MB_2U_LIB.S9S_MB_2U(SCH_1):PAGE95

M_G_CPU0_SB_DQS_DP<3> @S9S_MB_2U_LIB.S9S_MB_2U(SCH_1):M_G_CPU0_SB_DQS_DP(3)
    U2  EN7 DDR6_SB_DQS_DP3 SOCKET4677_AZIF0045P001C01CS-SA   I169 @S9S_MB_2U_LIB.S9S_MB_2U(SCH_1):PAGE26
   J13  137 DQS3_B_T SCONN288_ADR50017P130CC-SCONN2A   I178 @S9S_MB_2U_LIB.S9S_MB_2U(SCH_1):PAGE94
   J14  137 DQS3_B_T SCONN288_ADR50017P087CC-SCONN2A   I178 @S9S_MB_2U_LIB.S9S_MB_2U(SCH_1):PAGE95

M_G_CPU0_SB_DQS_DP<4> @S9S_MB_2U_LIB.S9S_MB_2U(SCH_1):M_G_CPU0_SB_DQS_DP(4)
    U2 DY36 DDR6_SB_DQS_DP4 SOCKET4677_AZIF0045P001C01CS-SA   I169 @S9S_MB_2U_LIB.S9S_MB_2U(SCH_1):PAGE26
   J13  239 DQS4_B_T SCONN288_ADR50017P130CC-SCONN2A   I178 @S9S_MB_2U_LIB.S9S_MB_2U(SCH_1):PAGE94
   J14  239 DQS4_B_T SCONN288_ADR50017P087CC-SCONN2A   I178 @S9S_MB_2U_LIB.S9S_MB_2U(SCH_1):PAGE95

M_G_CPU0_SB_DQS_DP<5> @S9S_MB_2U_LIB.S9S_MB_2U(SCH_1):M_G_CPU0_SB_DQS_DP(5)
    U2 DN33 DDR6_SB_DQS_DP5 SOCKET4677_AZIF0045P001C01CS-SA   I169 @S9S_MB_2U_LIB.S9S_MB_2U(SCH_1):PAGE26
   J13  250 DQS5_B_T||TDQS5_B_T SCONN288_ADR50017P130CC-SCONN2A   I178 @S9S_MB_2U_LIB.S9S_MB_2U(SCH_1):PAGE94
   J14  250 DQS5_B_T||TDQS5_B_T SCONN288_ADR50017P087CC-SCONN2A   I178 @S9S_MB_2U_LIB.S9S_MB_2U(SCH_1):PAGE95

M_G_CPU0_SB_DQS_DP<6> @S9S_MB_2U_LIB.S9S_MB_2U(SCH_1):M_G_CPU0_SB_DQS_DP(6)
    U2 DR27 DDR6_SB_DQS_DP6 SOCKET4677_AZIF0045P001C01CS-SA   I169 @S9S_MB_2U_LIB.S9S_MB_2U(SCH_1):PAGE26
   J13  261 DQS6_B_T||TDQS6_B_T SCONN288_ADR50017P130CC-SCONN2A   I178 @S9S_MB_2U_LIB.S9S_MB_2U(SCH_1):PAGE94
   J14  261 DQS6_B_T||TDQS6_B_T SCONN288_ADR50017P087CC-SCONN2A   I178 @S9S_MB_2U_LIB.S9S_MB_2U(SCH_1):PAGE95

M_G_CPU0_SB_DQS_DP<7> @S9S_MB_2U_LIB.S9S_MB_2U(SCH_1):M_G_CPU0_SB_DQS_DP(7)
    U2 DY24 DDR6_SB_DQS_DP7 SOCKET4677_AZIF0045P001C01CS-SA   I169 @S9S_MB_2U_LIB.S9S_MB_2U(SCH_1):PAGE26
   J13  272 DQS7_B_T||TDQS7_B_T SCONN288_ADR50017P130CC-SCONN2A   I178 @S9S_MB_2U_LIB.S9S_MB_2U(SCH_1):PAGE94
   J14  272 DQS7_B_T||TDQS7_B_T SCONN288_ADR50017P087CC-SCONN2A   I178 @S9S_MB_2U_LIB.S9S_MB_2U(SCH_1):PAGE95

M_G_CPU0_SB_DQS_DP<8> @S9S_MB_2U_LIB.S9S_MB_2U(SCH_1):M_G_CPU0_SB_DQS_DP(8)
    U2  EN5 DDR6_SB_DQS_DP8 SOCKET4677_AZIF0045P001C01CS-SA   I169 @S9S_MB_2U_LIB.S9S_MB_2U(SCH_1):PAGE26
   J13  283 DQS8_B_T||TDQS8_B_T SCONN288_ADR50017P130CC-SCONN2A   I178 @S9S_MB_2U_LIB.S9S_MB_2U(SCH_1):PAGE94
   J14  283 DQS8_B_T||TDQS8_B_T SCONN288_ADR50017P087CC-SCONN2A   I178 @S9S_MB_2U_LIB.S9S_MB_2U(SCH_1):PAGE95

M_G_CPU0_SB_DQS_DP<9> @S9S_MB_2U_LIB.S9S_MB_2U(SCH_1):M_G_CPU0_SB_DQS_DP(9)
    U2 DT36 DDR6_SB_DQS_DP9 SOCKET4677_AZIF0045P001C01CS-SA   I169 @S9S_MB_2U_LIB.S9S_MB_2U(SCH_1):PAGE26
   J13   93 DQS9_B_T||TDQS9_B_T||DBI4_B_N SCONN288_ADR50017P130CC-SCONN2A   I178 @S9S_MB_2U_LIB.S9S_MB_2U(SCH_1):PAGE94
   J14   93 DQS9_B_T||TDQS9_B_T||DBI4_B_N SCONN288_ADR50017P087CC-SCONN2A   I178 @S9S_MB_2U_LIB.S9S_MB_2U(SCH_1):PAGE95

M_G_CPU0_SB_PAR @S9S_MB_2U_LIB.S9S_MB_2U(SCH_1):M_G_CPU0_SB_PAR
    U2 EB42 DDR6_SB_PAR SOCKET4677_AZIF0045P001C01CS-SA   I169 @S9S_MB_2U_LIB.S9S_MB_2U(SCH_1):PAGE26
   J13  227  PAR_B SCONN288_ADR50017P130CC-SCONN2A    I11 @S9S_MB_2U_LIB.S9S_MB_2U(SCH_1):PAGE94
   J14  227  PAR_B SCONN288_ADR50017P087CC-SCONN2A    I47 @S9S_MB_2U_LIB.S9S_MB_2U(SCH_1):PAGE95

M_G_CPU0_SB_RSP<0> @S9S_MB_2U_LIB.S9S_MB_2U(SCH_1):M_G_CPU0_SB_RSP(0)
    U2 DU48 DDR6_B_RSP0 SOCKET4677_AZIF0045P001C01CS-SA   I169 @S9S_MB_2U_LIB.S9S_MB_2U(SCH_1):PAGE26
   J13   87 LBS||RSP_B_N SCONN288_ADR50017P130CC-SCONN2A    I11 @S9S_MB_2U_LIB.S9S_MB_2U(SCH_1):PAGE94

M_G_CPU0_SB_RSP<1> @S9S_MB_2U_LIB.S9S_MB_2U(SCH_1):M_G_CPU0_SB_RSP(1)
    U2 DV47 DDR6_B_RSP1 SOCKET4677_AZIF0045P001C01CS-SA   I169 @S9S_MB_2U_LIB.S9S_MB_2U(SCH_1):PAGE26
   J14   87 LBS||RSP_B_N SCONN288_ADR50017P087CC-SCONN2A    I47 @S9S_MB_2U_LIB.S9S_MB_2U(SCH_1):PAGE95

M_G_CPU1_ALERT_N @S9S_MB_2U_LIB.S9S_MB_2U(SCH_1):M_G_CPU1_ALERT_N
    U1 CW50 DDR6_ALERT_N SOCKET4677_AZIF0045P001C01CS-SA   I168 @S9S_MB_2U_LIB.S9S_MB_2U(SCH_1):PAGE57
   J29   62 ALERT_N SCONN288_ADR50017P130CC-SCONN2A   I179 @S9S_MB_2U_LIB.S9S_MB_2U(SCH_1):PAGE110
   J30   62 ALERT_N SCONN288_ADR50017P087CC-SCONN2A   I179 @S9S_MB_2U_LIB.S9S_MB_2U(SCH_1):PAGE111

M_G_CPU1_CLK_DN<0> @S9S_MB_2U_LIB.S9S_MB_2U(SCH_1):M_G_CPU1_CLK_DN(0)
    U1 DR45 DDR6_CLK_DN0 SOCKET4677_AZIF0045P001C01CS-SA   I168 @S9S_MB_2U_LIB.S9S_MB_2U(SCH_1):PAGE57
   J29  218   CK_C SCONN288_ADR50017P130CC-SCONN2A   I179 @S9S_MB_2U_LIB.S9S_MB_2U(SCH_1):PAGE110

M_G_CPU1_CLK_DN<1> @S9S_MB_2U_LIB.S9S_MB_2U(SCH_1):M_G_CPU1_CLK_DN(1)
    U1 DL45 DDR6_CLK_DN1 SOCKET4677_AZIF0045P001C01CS-SA   I168 @S9S_MB_2U_LIB.S9S_MB_2U(SCH_1):PAGE57
   J30  218   CK_C SCONN288_ADR50017P087CC-SCONN2A   I179 @S9S_MB_2U_LIB.S9S_MB_2U(SCH_1):PAGE111

M_G_CPU1_CLK_DP<0> @S9S_MB_2U_LIB.S9S_MB_2U(SCH_1):M_G_CPU1_CLK_DP(0)
    U1 DN45 DDR6_CLK_DP0 SOCKET4677_AZIF0045P001C01CS-SA   I168 @S9S_MB_2U_LIB.S9S_MB_2U(SCH_1):PAGE57
   J29  217   CK_T SCONN288_ADR50017P130CC-SCONN2A   I179 @S9S_MB_2U_LIB.S9S_MB_2U(SCH_1):PAGE110

M_G_CPU1_CLK_DP<1> @S9S_MB_2U_LIB.S9S_MB_2U(SCH_1):M_G_CPU1_CLK_DP(1)
    U1 DJ45 DDR6_CLK_DP1 SOCKET4677_AZIF0045P001C01CS-SA   I168 @S9S_MB_2U_LIB.S9S_MB_2U(SCH_1):PAGE57
   J30  217   CK_T SCONN288_ADR50017P087CC-SCONN2A   I179 @S9S_MB_2U_LIB.S9S_MB_2U(SCH_1):PAGE111

M_G_CPU1_SA_CA<0> @S9S_MB_2U_LIB.S9S_MB_2U(SCH_1):M_G_CPU1_SA_CA(0)
    U1 DJ52 DDR6_SA_CA0 SOCKET4677_AZIF0045P001C01CS-SA   I168 @S9S_MB_2U_LIB.S9S_MB_2U(SCH_1):PAGE57
   J29   66  CA0_A SCONN288_ADR50017P130CC-SCONN2A   I179 @S9S_MB_2U_LIB.S9S_MB_2U(SCH_1):PAGE110
   J30   66  CA0_A SCONN288_ADR50017P087CC-SCONN2A   I179 @S9S_MB_2U_LIB.S9S_MB_2U(SCH_1):PAGE111

M_G_CPU1_SA_CA<1> @S9S_MB_2U_LIB.S9S_MB_2U(SCH_1):M_G_CPU1_SA_CA(1)
    U1 DR52 DDR6_SA_CA1 SOCKET4677_AZIF0045P001C01CS-SA   I168 @S9S_MB_2U_LIB.S9S_MB_2U(SCH_1):PAGE57
   J29  211  CA1_A SCONN288_ADR50017P130CC-SCONN2A   I179 @S9S_MB_2U_LIB.S9S_MB_2U(SCH_1):PAGE110
   J30  211  CA1_A SCONN288_ADR50017P087CC-SCONN2A   I179 @S9S_MB_2U_LIB.S9S_MB_2U(SCH_1):PAGE111

M_G_CPU1_SA_CA<2> @S9S_MB_2U_LIB.S9S_MB_2U(SCH_1):M_G_CPU1_SA_CA(2)
    U1 DK51 DDR6_SA_CA2 SOCKET4677_AZIF0045P001C01CS-SA   I168 @S9S_MB_2U_LIB.S9S_MB_2U(SCH_1):PAGE57
   J29   68  CA2_A SCONN288_ADR50017P130CC-SCONN2A   I179 @S9S_MB_2U_LIB.S9S_MB_2U(SCH_1):PAGE110
   J30   68  CA2_A SCONN288_ADR50017P087CC-SCONN2A   I179 @S9S_MB_2U_LIB.S9S_MB_2U(SCH_1):PAGE111

M_G_CPU1_SA_CA<3> @S9S_MB_2U_LIB.S9S_MB_2U(SCH_1):M_G_CPU1_SA_CA(3)
    U1 DP51 DDR6_SA_CA3 SOCKET4677_AZIF0045P001C01CS-SA   I168 @S9S_MB_2U_LIB.S9S_MB_2U(SCH_1):PAGE57
   J29  213  CA3_A SCONN288_ADR50017P130CC-SCONN2A   I179 @S9S_MB_2U_LIB.S9S_MB_2U(SCH_1):PAGE110
   J30  213  CA3_A SCONN288_ADR50017P087CC-SCONN2A   I179 @S9S_MB_2U_LIB.S9S_MB_2U(SCH_1):PAGE111

M_G_CPU1_SA_CA<4> @S9S_MB_2U_LIB.S9S_MB_2U(SCH_1):M_G_CPU1_SA_CA(4)
    U1 DL50 DDR6_SA_CA4 SOCKET4677_AZIF0045P001C01CS-SA   I168 @S9S_MB_2U_LIB.S9S_MB_2U(SCH_1):PAGE57
   J29   70  CA4_A SCONN288_ADR50017P130CC-SCONN2A   I179 @S9S_MB_2U_LIB.S9S_MB_2U(SCH_1):PAGE110
   J30   70  CA4_A SCONN288_ADR50017P087CC-SCONN2A   I179 @S9S_MB_2U_LIB.S9S_MB_2U(SCH_1):PAGE111

M_G_CPU1_SA_CA<5> @S9S_MB_2U_LIB.S9S_MB_2U(SCH_1):M_G_CPU1_SA_CA(5)
    U1 DN50 DDR6_SA_CA5 SOCKET4677_AZIF0045P001C01CS-SA   I168 @S9S_MB_2U_LIB.S9S_MB_2U(SCH_1):PAGE57
   J29  215  CA5_A SCONN288_ADR50017P130CC-SCONN2A   I179 @S9S_MB_2U_LIB.S9S_MB_2U(SCH_1):PAGE110
   J30  215  CA5_A SCONN288_ADR50017P087CC-SCONN2A   I179 @S9S_MB_2U_LIB.S9S_MB_2U(SCH_1):PAGE111

M_G_CPU1_SA_CA<6> @S9S_MB_2U_LIB.S9S_MB_2U(SCH_1):M_G_CPU1_SA_CA(6)
    U1 DK44 DDR6_SA_CA6 SOCKET4677_AZIF0045P001C01CS-SA   I168 @S9S_MB_2U_LIB.S9S_MB_2U(SCH_1):PAGE57
   J29   72  CA6_A SCONN288_ADR50017P130CC-SCONN2A   I179 @S9S_MB_2U_LIB.S9S_MB_2U(SCH_1):PAGE110
   J30   72  CA6_A SCONN288_ADR50017P087CC-SCONN2A   I179 @S9S_MB_2U_LIB.S9S_MB_2U(SCH_1):PAGE111

M_G_CPU1_SA_CB<0> @S9S_MB_2U_LIB.S9S_MB_2U(SCH_1):M_G_CPU1_SA_CB(0)
    U1 DL60 DDR6_SA_ECC0 SOCKET4677_AZIF0045P001C01CS-SA   I168 @S9S_MB_2U_LIB.S9S_MB_2U(SCH_1):PAGE57
   J29   51  CB0_A SCONN288_ADR50017P130CC-SCONN2A   I179 @S9S_MB_2U_LIB.S9S_MB_2U(SCH_1):PAGE110
   J30   51  CB0_A SCONN288_ADR50017P087CC-SCONN2A   I179 @S9S_MB_2U_LIB.S9S_MB_2U(SCH_1):PAGE111

M_G_CPU1_SA_CB<1> @S9S_MB_2U_LIB.S9S_MB_2U(SCH_1):M_G_CPU1_SA_CB(1)
    U1 DK59 DDR6_SA_ECC1 SOCKET4677_AZIF0045P001C01CS-SA   I168 @S9S_MB_2U_LIB.S9S_MB_2U(SCH_1):PAGE57
   J29   53  CB1_A SCONN288_ADR50017P130CC-SCONN2A   I179 @S9S_MB_2U_LIB.S9S_MB_2U(SCH_1):PAGE110
   J30   53  CB1_A SCONN288_ADR50017P087CC-SCONN2A   I179 @S9S_MB_2U_LIB.S9S_MB_2U(SCH_1):PAGE111

M_G_CPU1_SA_CB<2> @S9S_MB_2U_LIB.S9S_MB_2U(SCH_1):M_G_CPU1_SA_CB(2)
    U1 DN60 DDR6_SA_ECC2 SOCKET4677_AZIF0045P001C01CS-SA   I168 @S9S_MB_2U_LIB.S9S_MB_2U(SCH_1):PAGE57
   J29  196  CB2_A SCONN288_ADR50017P130CC-SCONN2A   I179 @S9S_MB_2U_LIB.S9S_MB_2U(SCH_1):PAGE110
   J30  196  CB2_A SCONN288_ADR50017P087CC-SCONN2A   I179 @S9S_MB_2U_LIB.S9S_MB_2U(SCH_1):PAGE111

M_G_CPU1_SA_CB<3> @S9S_MB_2U_LIB.S9S_MB_2U(SCH_1):M_G_CPU1_SA_CB(3)
    U1 DP59 DDR6_SA_ECC3 SOCKET4677_AZIF0045P001C01CS-SA   I168 @S9S_MB_2U_LIB.S9S_MB_2U(SCH_1):PAGE57
   J29  198  CB3_A SCONN288_ADR50017P130CC-SCONN2A   I179 @S9S_MB_2U_LIB.S9S_MB_2U(SCH_1):PAGE110
   J30  198  CB3_A SCONN288_ADR50017P087CC-SCONN2A   I179 @S9S_MB_2U_LIB.S9S_MB_2U(SCH_1):PAGE111

M_G_CPU1_SA_CB<4> @S9S_MB_2U_LIB.S9S_MB_2U(SCH_1):M_G_CPU1_SA_CB(4)
    U1 DK57 DDR6_SA_ECC4 SOCKET4677_AZIF0045P001C01CS-SA   I168 @S9S_MB_2U_LIB.S9S_MB_2U(SCH_1):PAGE57
   J29   58  CB4_A SCONN288_ADR50017P130CC-SCONN2A   I179 @S9S_MB_2U_LIB.S9S_MB_2U(SCH_1):PAGE110
   J30   58  CB4_A SCONN288_ADR50017P087CC-SCONN2A   I179 @S9S_MB_2U_LIB.S9S_MB_2U(SCH_1):PAGE111

M_G_CPU1_SA_CB<5> @S9S_MB_2U_LIB.S9S_MB_2U(SCH_1):M_G_CPU1_SA_CB(5)
    U1 DL56 DDR6_SA_ECC5 SOCKET4677_AZIF0045P001C01CS-SA   I168 @S9S_MB_2U_LIB.S9S_MB_2U(SCH_1):PAGE57
   J29   60  CB5_A SCONN288_ADR50017P130CC-SCONN2A   I179 @S9S_MB_2U_LIB.S9S_MB_2U(SCH_1):PAGE110
   J30   60  CB5_A SCONN288_ADR50017P087CC-SCONN2A   I179 @S9S_MB_2U_LIB.S9S_MB_2U(SCH_1):PAGE111

M_G_CPU1_SA_CB<6> @S9S_MB_2U_LIB.S9S_MB_2U(SCH_1):M_G_CPU1_SA_CB(6)
    U1 DP57 DDR6_SA_ECC6 SOCKET4677_AZIF0045P001C01CS-SA   I168 @S9S_MB_2U_LIB.S9S_MB_2U(SCH_1):PAGE57
   J29  203  CB6_A SCONN288_ADR50017P130CC-SCONN2A   I179 @S9S_MB_2U_LIB.S9S_MB_2U(SCH_1):PAGE110
   J30  203  CB6_A SCONN288_ADR50017P087CC-SCONN2A   I179 @S9S_MB_2U_LIB.S9S_MB_2U(SCH_1):PAGE111

M_G_CPU1_SA_CB<7> @S9S_MB_2U_LIB.S9S_MB_2U(SCH_1):M_G_CPU1_SA_CB(7)
    U1 DN56 DDR6_SA_ECC7 SOCKET4677_AZIF0045P001C01CS-SA   I168 @S9S_MB_2U_LIB.S9S_MB_2U(SCH_1):PAGE57
   J29  205  CB7_A SCONN288_ADR50017P130CC-SCONN2A   I179 @S9S_MB_2U_LIB.S9S_MB_2U(SCH_1):PAGE110
   J30  205  CB7_A SCONN288_ADR50017P087CC-SCONN2A   I179 @S9S_MB_2U_LIB.S9S_MB_2U(SCH_1):PAGE111

M_G_CPU1_SA_CS_N<0> @S9S_MB_2U_LIB.S9S_MB_2U(SCH_1):M_G_CPU1_SA_CS_N(0)
    U1 DN54 DDR6_SA_CS_N0 SOCKET4677_AZIF0045P001C01CS-SA   I168 @S9S_MB_2U_LIB.S9S_MB_2U(SCH_1):PAGE57
   J29   64 CS0_A_N SCONN288_ADR50017P130CC-SCONN2A   I179 @S9S_MB_2U_LIB.S9S_MB_2U(SCH_1):PAGE110

M_G_CPU1_SA_CS_N<1> @S9S_MB_2U_LIB.S9S_MB_2U(SCH_1):M_G_CPU1_SA_CS_N(1)
    U1 DP53 DDR6_SA_CS_N1 SOCKET4677_AZIF0045P001C01CS-SA   I168 @S9S_MB_2U_LIB.S9S_MB_2U(SCH_1):PAGE57
   J29  209 CS1_A_N SCONN288_ADR50017P130CC-SCONN2A   I179 @S9S_MB_2U_LIB.S9S_MB_2U(SCH_1):PAGE110

M_G_CPU1_SA_CS_N<2> @S9S_MB_2U_LIB.S9S_MB_2U(SCH_1):M_G_CPU1_SA_CS_N(2)
    U1 DL54 DDR6_SA_CS_N2 SOCKET4677_AZIF0045P001C01CS-SA   I168 @S9S_MB_2U_LIB.S9S_MB_2U(SCH_1):PAGE57
   J30   64 CS0_A_N SCONN288_ADR50017P087CC-SCONN2A   I179 @S9S_MB_2U_LIB.S9S_MB_2U(SCH_1):PAGE111

M_G_CPU1_SA_CS_N<3> @S9S_MB_2U_LIB.S9S_MB_2U(SCH_1):M_G_CPU1_SA_CS_N(3)
    U1 DK53 DDR6_SA_CS_N3 SOCKET4677_AZIF0045P001C01CS-SA   I168 @S9S_MB_2U_LIB.S9S_MB_2U(SCH_1):PAGE57
   J30  209 CS1_A_N SCONN288_ADR50017P087CC-SCONN2A   I179 @S9S_MB_2U_LIB.S9S_MB_2U(SCH_1):PAGE111

M_G_CPU1_SA_DQ<0> @S9S_MB_2U_LIB.S9S_MB_2U(SCH_1):M_G_CPU1_SA_DQ(0)
    U1 DV75 DDR6_SA_DQ0 SOCKET4677_AZIF0045P001C01CS-SA   I168 @S9S_MB_2U_LIB.S9S_MB_2U(SCH_1):PAGE57
   J29    7  DQ0_A SCONN288_ADR50017P130CC-SCONN2A   I179 @S9S_MB_2U_LIB.S9S_MB_2U(SCH_1):PAGE110
   J30    7  DQ0_A SCONN288_ADR50017P087CC-SCONN2A   I179 @S9S_MB_2U_LIB.S9S_MB_2U(SCH_1):PAGE111

M_G_CPU1_SA_DQ<10> @S9S_MB_2U_LIB.S9S_MB_2U(SCH_1):M_G_CPU1_SA_DQ(10)
    U1 DN72 DDR6_SA_DQ10 SOCKET4677_AZIF0045P001C01CS-SA   I168 @S9S_MB_2U_LIB.S9S_MB_2U(SCH_1):PAGE57
   J29  163 DQ10_A SCONN288_ADR50017P130CC-SCONN2A   I179 @S9S_MB_2U_LIB.S9S_MB_2U(SCH_1):PAGE110
   J30  163 DQ10_A SCONN288_ADR50017P087CC-SCONN2A   I179 @S9S_MB_2U_LIB.S9S_MB_2U(SCH_1):PAGE111

M_G_CPU1_SA_DQ<11> @S9S_MB_2U_LIB.S9S_MB_2U(SCH_1):M_G_CPU1_SA_DQ(11)
    U1 DP71 DDR6_SA_DQ11 SOCKET4677_AZIF0045P001C01CS-SA   I168 @S9S_MB_2U_LIB.S9S_MB_2U(SCH_1):PAGE57
   J29  165 DQ11_A SCONN288_ADR50017P130CC-SCONN2A   I179 @S9S_MB_2U_LIB.S9S_MB_2U(SCH_1):PAGE110
   J30  165 DQ11_A SCONN288_ADR50017P087CC-SCONN2A   I179 @S9S_MB_2U_LIB.S9S_MB_2U(SCH_1):PAGE111

M_G_CPU1_SA_DQ<12> @S9S_MB_2U_LIB.S9S_MB_2U(SCH_1):M_G_CPU1_SA_DQ(12)
    U1 DK69 DDR6_SA_DQ12 SOCKET4677_AZIF0045P001C01CS-SA   I168 @S9S_MB_2U_LIB.S9S_MB_2U(SCH_1):PAGE57
   J29   25 DQ12_A SCONN288_ADR50017P130CC-SCONN2A   I179 @S9S_MB_2U_LIB.S9S_MB_2U(SCH_1):PAGE110
   J30   25 DQ12_A SCONN288_ADR50017P087CC-SCONN2A   I179 @S9S_MB_2U_LIB.S9S_MB_2U(SCH_1):PAGE111

M_G_CPU1_SA_DQ<13> @S9S_MB_2U_LIB.S9S_MB_2U(SCH_1):M_G_CPU1_SA_DQ(13)
    U1 DL68 DDR6_SA_DQ13 SOCKET4677_AZIF0045P001C01CS-SA   I168 @S9S_MB_2U_LIB.S9S_MB_2U(SCH_1):PAGE57
   J29   27 DQ13_A SCONN288_ADR50017P130CC-SCONN2A   I179 @S9S_MB_2U_LIB.S9S_MB_2U(SCH_1):PAGE110
   J30   27 DQ13_A SCONN288_ADR50017P087CC-SCONN2A   I179 @S9S_MB_2U_LIB.S9S_MB_2U(SCH_1):PAGE111

M_G_CPU1_SA_DQ<14> @S9S_MB_2U_LIB.S9S_MB_2U(SCH_1):M_G_CPU1_SA_DQ(14)
    U1 DP69 DDR6_SA_DQ14 SOCKET4677_AZIF0045P001C01CS-SA   I168 @S9S_MB_2U_LIB.S9S_MB_2U(SCH_1):PAGE57
   J29  170 DQ14_A SCONN288_ADR50017P130CC-SCONN2A   I179 @S9S_MB_2U_LIB.S9S_MB_2U(SCH_1):PAGE110
   J30  170 DQ14_A SCONN288_ADR50017P087CC-SCONN2A   I179 @S9S_MB_2U_LIB.S9S_MB_2U(SCH_1):PAGE111

M_G_CPU1_SA_DQ<15> @S9S_MB_2U_LIB.S9S_MB_2U(SCH_1):M_G_CPU1_SA_DQ(15)
    U1 DN68 DDR6_SA_DQ15 SOCKET4677_AZIF0045P001C01CS-SA   I168 @S9S_MB_2U_LIB.S9S_MB_2U(SCH_1):PAGE57
   J29  172 DQ15_A SCONN288_ADR50017P130CC-SCONN2A   I179 @S9S_MB_2U_LIB.S9S_MB_2U(SCH_1):PAGE110
   J30  172 DQ15_A SCONN288_ADR50017P087CC-SCONN2A   I179 @S9S_MB_2U_LIB.S9S_MB_2U(SCH_1):PAGE111

M_G_CPU1_SA_DQ<16> @S9S_MB_2U_LIB.S9S_MB_2U(SCH_1):M_G_CPU1_SA_DQ(16)
    U1 DV63 DDR6_SA_DQ16 SOCKET4677_AZIF0045P001C01CS-SA   I168 @S9S_MB_2U_LIB.S9S_MB_2U(SCH_1):PAGE57
   J29   29 DQ16_A SCONN288_ADR50017P130CC-SCONN2A   I179 @S9S_MB_2U_LIB.S9S_MB_2U(SCH_1):PAGE110
   J30   29 DQ16_A SCONN288_ADR50017P087CC-SCONN2A   I179 @S9S_MB_2U_LIB.S9S_MB_2U(SCH_1):PAGE111

M_G_CPU1_SA_DQ<17> @S9S_MB_2U_LIB.S9S_MB_2U(SCH_1):M_G_CPU1_SA_DQ(17)
    U1 DU62 DDR6_SA_DQ17 SOCKET4677_AZIF0045P001C01CS-SA   I168 @S9S_MB_2U_LIB.S9S_MB_2U(SCH_1):PAGE57
   J29   31 DQ17_A SCONN288_ADR50017P130CC-SCONN2A   I179 @S9S_MB_2U_LIB.S9S_MB_2U(SCH_1):PAGE110
   J30   31 DQ17_A SCONN288_ADR50017P087CC-SCONN2A   I179 @S9S_MB_2U_LIB.S9S_MB_2U(SCH_1):PAGE111

M_G_CPU1_SA_DQ<18> @S9S_MB_2U_LIB.S9S_MB_2U(SCH_1):M_G_CPU1_SA_DQ(18)
    U1 DY63 DDR6_SA_DQ18 SOCKET4677_AZIF0045P001C01CS-SA   I168 @S9S_MB_2U_LIB.S9S_MB_2U(SCH_1):PAGE57
   J29  174 DQ18_A SCONN288_ADR50017P130CC-SCONN2A   I179 @S9S_MB_2U_LIB.S9S_MB_2U(SCH_1):PAGE110
   J30  174 DQ18_A SCONN288_ADR50017P087CC-SCONN2A   I179 @S9S_MB_2U_LIB.S9S_MB_2U(SCH_1):PAGE111

M_G_CPU1_SA_DQ<19> @S9S_MB_2U_LIB.S9S_MB_2U(SCH_1):M_G_CPU1_SA_DQ(19)
    U1 EA62 DDR6_SA_DQ19 SOCKET4677_AZIF0045P001C01CS-SA   I168 @S9S_MB_2U_LIB.S9S_MB_2U(SCH_1):PAGE57
   J29  176 DQ19_A SCONN288_ADR50017P130CC-SCONN2A   I179 @S9S_MB_2U_LIB.S9S_MB_2U(SCH_1):PAGE110
   J30  176 DQ19_A SCONN288_ADR50017P087CC-SCONN2A   I179 @S9S_MB_2U_LIB.S9S_MB_2U(SCH_1):PAGE111

M_G_CPU1_SA_DQ<1> @S9S_MB_2U_LIB.S9S_MB_2U(SCH_1):M_G_CPU1_SA_DQ(1)
    U1 DU74 DDR6_SA_DQ1 SOCKET4677_AZIF0045P001C01CS-SA   I168 @S9S_MB_2U_LIB.S9S_MB_2U(SCH_1):PAGE57
   J29    9  DQ1_A SCONN288_ADR50017P130CC-SCONN2A   I179 @S9S_MB_2U_LIB.S9S_MB_2U(SCH_1):PAGE110
   J30    9  DQ1_A SCONN288_ADR50017P087CC-SCONN2A   I179 @S9S_MB_2U_LIB.S9S_MB_2U(SCH_1):PAGE111

M_G_CPU1_SA_DQ<20> @S9S_MB_2U_LIB.S9S_MB_2U(SCH_1):M_G_CPU1_SA_DQ(20)
    U1 DU60 DDR6_SA_DQ20 SOCKET4677_AZIF0045P001C01CS-SA   I168 @S9S_MB_2U_LIB.S9S_MB_2U(SCH_1):PAGE57
   J29   36 DQ20_A SCONN288_ADR50017P130CC-SCONN2A   I179 @S9S_MB_2U_LIB.S9S_MB_2U(SCH_1):PAGE110
   J30   36 DQ20_A SCONN288_ADR50017P087CC-SCONN2A   I179 @S9S_MB_2U_LIB.S9S_MB_2U(SCH_1):PAGE111

M_G_CPU1_SA_DQ<21> @S9S_MB_2U_LIB.S9S_MB_2U(SCH_1):M_G_CPU1_SA_DQ(21)
    U1 DV59 DDR6_SA_DQ21 SOCKET4677_AZIF0045P001C01CS-SA   I168 @S9S_MB_2U_LIB.S9S_MB_2U(SCH_1):PAGE57
   J29   38 DQ21_A SCONN288_ADR50017P130CC-SCONN2A   I179 @S9S_MB_2U_LIB.S9S_MB_2U(SCH_1):PAGE110
   J30   38 DQ21_A SCONN288_ADR50017P087CC-SCONN2A   I179 @S9S_MB_2U_LIB.S9S_MB_2U(SCH_1):PAGE111

M_G_CPU1_SA_DQ<22> @S9S_MB_2U_LIB.S9S_MB_2U(SCH_1):M_G_CPU1_SA_DQ(22)
    U1 EA60 DDR6_SA_DQ22 SOCKET4677_AZIF0045P001C01CS-SA   I168 @S9S_MB_2U_LIB.S9S_MB_2U(SCH_1):PAGE57
   J29  181 DQ22_A SCONN288_ADR50017P130CC-SCONN2A   I179 @S9S_MB_2U_LIB.S9S_MB_2U(SCH_1):PAGE110
   J30  181 DQ22_A SCONN288_ADR50017P087CC-SCONN2A   I179 @S9S_MB_2U_LIB.S9S_MB_2U(SCH_1):PAGE111

M_G_CPU1_SA_DQ<23> @S9S_MB_2U_LIB.S9S_MB_2U(SCH_1):M_G_CPU1_SA_DQ(23)
    U1 DY59 DDR6_SA_DQ23 SOCKET4677_AZIF0045P001C01CS-SA   I168 @S9S_MB_2U_LIB.S9S_MB_2U(SCH_1):PAGE57
   J29  183 DQ23_A SCONN288_ADR50017P130CC-SCONN2A   I179 @S9S_MB_2U_LIB.S9S_MB_2U(SCH_1):PAGE110
   J30  183 DQ23_A SCONN288_ADR50017P087CC-SCONN2A   I179 @S9S_MB_2U_LIB.S9S_MB_2U(SCH_1):PAGE111

M_G_CPU1_SA_DQ<24> @S9S_MB_2U_LIB.S9S_MB_2U(SCH_1):M_G_CPU1_SA_DQ(24)
    U1 DL66 DDR6_SA_DQ24 SOCKET4677_AZIF0045P001C01CS-SA   I168 @S9S_MB_2U_LIB.S9S_MB_2U(SCH_1):PAGE57
   J29   40 DQ24_A SCONN288_ADR50017P130CC-SCONN2A   I179 @S9S_MB_2U_LIB.S9S_MB_2U(SCH_1):PAGE110
   J30   40 DQ24_A SCONN288_ADR50017P087CC-SCONN2A   I179 @S9S_MB_2U_LIB.S9S_MB_2U(SCH_1):PAGE111

M_G_CPU1_SA_DQ<25> @S9S_MB_2U_LIB.S9S_MB_2U(SCH_1):M_G_CPU1_SA_DQ(25)
    U1 DK65 DDR6_SA_DQ25 SOCKET4677_AZIF0045P001C01CS-SA   I168 @S9S_MB_2U_LIB.S9S_MB_2U(SCH_1):PAGE57
   J29   42 DQ25_A SCONN288_ADR50017P130CC-SCONN2A   I179 @S9S_MB_2U_LIB.S9S_MB_2U(SCH_1):PAGE110
   J30   42 DQ25_A SCONN288_ADR50017P087CC-SCONN2A   I179 @S9S_MB_2U_LIB.S9S_MB_2U(SCH_1):PAGE111

M_G_CPU1_SA_DQ<26> @S9S_MB_2U_LIB.S9S_MB_2U(SCH_1):M_G_CPU1_SA_DQ(26)
    U1 DN66 DDR6_SA_DQ26 SOCKET4677_AZIF0045P001C01CS-SA   I168 @S9S_MB_2U_LIB.S9S_MB_2U(SCH_1):PAGE57
   J29  185 DQ26_A SCONN288_ADR50017P130CC-SCONN2A   I179 @S9S_MB_2U_LIB.S9S_MB_2U(SCH_1):PAGE110
   J30  185 DQ26_A SCONN288_ADR50017P087CC-SCONN2A   I179 @S9S_MB_2U_LIB.S9S_MB_2U(SCH_1):PAGE111

M_G_CPU1_SA_DQ<27> @S9S_MB_2U_LIB.S9S_MB_2U(SCH_1):M_G_CPU1_SA_DQ(27)
    U1 DP65 DDR6_SA_DQ27 SOCKET4677_AZIF0045P001C01CS-SA   I168 @S9S_MB_2U_LIB.S9S_MB_2U(SCH_1):PAGE57
   J29  187 DQ27_A SCONN288_ADR50017P130CC-SCONN2A   I179 @S9S_MB_2U_LIB.S9S_MB_2U(SCH_1):PAGE110
   J30  187 DQ27_A SCONN288_ADR50017P087CC-SCONN2A   I179 @S9S_MB_2U_LIB.S9S_MB_2U(SCH_1):PAGE111

M_G_CPU1_SA_DQ<28> @S9S_MB_2U_LIB.S9S_MB_2U(SCH_1):M_G_CPU1_SA_DQ(28)
    U1 DK63 DDR6_SA_DQ28 SOCKET4677_AZIF0045P001C01CS-SA   I168 @S9S_MB_2U_LIB.S9S_MB_2U(SCH_1):PAGE57
   J29   47 DQ28_A SCONN288_ADR50017P130CC-SCONN2A   I179 @S9S_MB_2U_LIB.S9S_MB_2U(SCH_1):PAGE110
   J30   47 DQ28_A SCONN288_ADR50017P087CC-SCONN2A   I179 @S9S_MB_2U_LIB.S9S_MB_2U(SCH_1):PAGE111

M_G_CPU1_SA_DQ<29> @S9S_MB_2U_LIB.S9S_MB_2U(SCH_1):M_G_CPU1_SA_DQ(29)
    U1 DL62 DDR6_SA_DQ29 SOCKET4677_AZIF0045P001C01CS-SA   I168 @S9S_MB_2U_LIB.S9S_MB_2U(SCH_1):PAGE57
   J29   49 DQ29_A SCONN288_ADR50017P130CC-SCONN2A   I179 @S9S_MB_2U_LIB.S9S_MB_2U(SCH_1):PAGE110
   J30   49 DQ29_A SCONN288_ADR50017P087CC-SCONN2A   I179 @S9S_MB_2U_LIB.S9S_MB_2U(SCH_1):PAGE111

M_G_CPU1_SA_DQ<2> @S9S_MB_2U_LIB.S9S_MB_2U(SCH_1):M_G_CPU1_SA_DQ(2)
    U1 DY75 DDR6_SA_DQ2 SOCKET4677_AZIF0045P001C01CS-SA   I168 @S9S_MB_2U_LIB.S9S_MB_2U(SCH_1):PAGE57
   J29  152  DQ2_A SCONN288_ADR50017P130CC-SCONN2A   I179 @S9S_MB_2U_LIB.S9S_MB_2U(SCH_1):PAGE110
   J30  152  DQ2_A SCONN288_ADR50017P087CC-SCONN2A   I179 @S9S_MB_2U_LIB.S9S_MB_2U(SCH_1):PAGE111

M_G_CPU1_SA_DQ<30> @S9S_MB_2U_LIB.S9S_MB_2U(SCH_1):M_G_CPU1_SA_DQ(30)
    U1 DP63 DDR6_SA_DQ30 SOCKET4677_AZIF0045P001C01CS-SA   I168 @S9S_MB_2U_LIB.S9S_MB_2U(SCH_1):PAGE57
   J29  192 DQ30_A SCONN288_ADR50017P130CC-SCONN2A   I179 @S9S_MB_2U_LIB.S9S_MB_2U(SCH_1):PAGE110
   J30  192 DQ30_A SCONN288_ADR50017P087CC-SCONN2A   I179 @S9S_MB_2U_LIB.S9S_MB_2U(SCH_1):PAGE111

M_G_CPU1_SA_DQ<31> @S9S_MB_2U_LIB.S9S_MB_2U(SCH_1):M_G_CPU1_SA_DQ(31)
    U1 DN62 DDR6_SA_DQ31 SOCKET4677_AZIF0045P001C01CS-SA   I168 @S9S_MB_2U_LIB.S9S_MB_2U(SCH_1):PAGE57
   J29  194 DQ31_A SCONN288_ADR50017P130CC-SCONN2A   I179 @S9S_MB_2U_LIB.S9S_MB_2U(SCH_1):PAGE110
   J30  194 DQ31_A SCONN288_ADR50017P087CC-SCONN2A   I179 @S9S_MB_2U_LIB.S9S_MB_2U(SCH_1):PAGE111

M_G_CPU1_SA_DQ<3> @S9S_MB_2U_LIB.S9S_MB_2U(SCH_1):M_G_CPU1_SA_DQ(3)
    U1 EA74 DDR6_SA_DQ3 SOCKET4677_AZIF0045P001C01CS-SA   I168 @S9S_MB_2U_LIB.S9S_MB_2U(SCH_1):PAGE57
   J29  154  DQ3_A SCONN288_ADR50017P130CC-SCONN2A   I179 @S9S_MB_2U_LIB.S9S_MB_2U(SCH_1):PAGE110
   J30  154  DQ3_A SCONN288_ADR50017P087CC-SCONN2A   I179 @S9S_MB_2U_LIB.S9S_MB_2U(SCH_1):PAGE111

M_G_CPU1_SA_DQ<4> @S9S_MB_2U_LIB.S9S_MB_2U(SCH_1):M_G_CPU1_SA_DQ(4)
    U1 DU72 DDR6_SA_DQ4 SOCKET4677_AZIF0045P001C01CS-SA   I168 @S9S_MB_2U_LIB.S9S_MB_2U(SCH_1):PAGE57
   J29   14  DQ4_A SCONN288_ADR50017P130CC-SCONN2A   I179 @S9S_MB_2U_LIB.S9S_MB_2U(SCH_1):PAGE110
   J30   14  DQ4_A SCONN288_ADR50017P087CC-SCONN2A   I179 @S9S_MB_2U_LIB.S9S_MB_2U(SCH_1):PAGE111

M_G_CPU1_SA_DQ<5> @S9S_MB_2U_LIB.S9S_MB_2U(SCH_1):M_G_CPU1_SA_DQ(5)
    U1 DV71 DDR6_SA_DQ5 SOCKET4677_AZIF0045P001C01CS-SA   I168 @S9S_MB_2U_LIB.S9S_MB_2U(SCH_1):PAGE57
   J29   16  DQ5_A SCONN288_ADR50017P130CC-SCONN2A   I179 @S9S_MB_2U_LIB.S9S_MB_2U(SCH_1):PAGE110
   J30   16  DQ5_A SCONN288_ADR50017P087CC-SCONN2A   I179 @S9S_MB_2U_LIB.S9S_MB_2U(SCH_1):PAGE111

M_G_CPU1_SA_DQ<6> @S9S_MB_2U_LIB.S9S_MB_2U(SCH_1):M_G_CPU1_SA_DQ(6)
    U1 EA72 DDR6_SA_DQ6 SOCKET4677_AZIF0045P001C01CS-SA   I168 @S9S_MB_2U_LIB.S9S_MB_2U(SCH_1):PAGE57
   J29  159  DQ6_A SCONN288_ADR50017P130CC-SCONN2A   I179 @S9S_MB_2U_LIB.S9S_MB_2U(SCH_1):PAGE110
   J30  159  DQ6_A SCONN288_ADR50017P087CC-SCONN2A   I179 @S9S_MB_2U_LIB.S9S_MB_2U(SCH_1):PAGE111

M_G_CPU1_SA_DQ<7> @S9S_MB_2U_LIB.S9S_MB_2U(SCH_1):M_G_CPU1_SA_DQ(7)
    U1 DY71 DDR6_SA_DQ7 SOCKET4677_AZIF0045P001C01CS-SA   I168 @S9S_MB_2U_LIB.S9S_MB_2U(SCH_1):PAGE57
   J29  161  DQ7_A SCONN288_ADR50017P130CC-SCONN2A   I179 @S9S_MB_2U_LIB.S9S_MB_2U(SCH_1):PAGE110
   J30  161  DQ7_A SCONN288_ADR50017P087CC-SCONN2A   I179 @S9S_MB_2U_LIB.S9S_MB_2U(SCH_1):PAGE111

M_G_CPU1_SA_DQ<8> @S9S_MB_2U_LIB.S9S_MB_2U(SCH_1):M_G_CPU1_SA_DQ(8)
    U1 DL72 DDR6_SA_DQ8 SOCKET4677_AZIF0045P001C01CS-SA   I168 @S9S_MB_2U_LIB.S9S_MB_2U(SCH_1):PAGE57
   J29   18  DQ8_A SCONN288_ADR50017P130CC-SCONN2A   I179 @S9S_MB_2U_LIB.S9S_MB_2U(SCH_1):PAGE110
   J30   18  DQ8_A SCONN288_ADR50017P087CC-SCONN2A   I179 @S9S_MB_2U_LIB.S9S_MB_2U(SCH_1):PAGE111

M_G_CPU1_SA_DQ<9> @S9S_MB_2U_LIB.S9S_MB_2U(SCH_1):M_G_CPU1_SA_DQ(9)
    U1 DK71 DDR6_SA_DQ9 SOCKET4677_AZIF0045P001C01CS-SA   I168 @S9S_MB_2U_LIB.S9S_MB_2U(SCH_1):PAGE57
   J29   20  DQ9_A SCONN288_ADR50017P130CC-SCONN2A   I179 @S9S_MB_2U_LIB.S9S_MB_2U(SCH_1):PAGE110
   J30   20  DQ9_A SCONN288_ADR50017P087CC-SCONN2A   I179 @S9S_MB_2U_LIB.S9S_MB_2U(SCH_1):PAGE111

M_G_CPU1_SA_DQS_DN<0> @S9S_MB_2U_LIB.S9S_MB_2U(SCH_1):M_G_CPU1_SA_DQS_DN(0)
    U1 DV73 DDR6_SA_DQS_DN0 SOCKET4677_AZIF0045P001C01CS-SA   I168 @S9S_MB_2U_LIB.S9S_MB_2U(SCH_1):PAGE57
   J29   12 DQS0_A_C SCONN288_ADR50017P130CC-SCONN2A   I180 @S9S_MB_2U_LIB.S9S_MB_2U(SCH_1):PAGE110
   J30   12 DQS0_A_C SCONN288_ADR50017P087CC-SCONN2A   I180 @S9S_MB_2U_LIB.S9S_MB_2U(SCH_1):PAGE111

M_G_CPU1_SA_DQS_DN<1> @S9S_MB_2U_LIB.S9S_MB_2U(SCH_1):M_G_CPU1_SA_DQS_DN(1)
    U1 DJ70 DDR6_SA_DQS_DN1 SOCKET4677_AZIF0045P001C01CS-SA   I168 @S9S_MB_2U_LIB.S9S_MB_2U(SCH_1):PAGE57
   J29   23 DQS1_A_C SCONN288_ADR50017P130CC-SCONN2A   I180 @S9S_MB_2U_LIB.S9S_MB_2U(SCH_1):PAGE110
   J30   23 DQS1_A_C SCONN288_ADR50017P087CC-SCONN2A   I180 @S9S_MB_2U_LIB.S9S_MB_2U(SCH_1):PAGE111

M_G_CPU1_SA_DQS_DN<2> @S9S_MB_2U_LIB.S9S_MB_2U(SCH_1):M_G_CPU1_SA_DQS_DN(2)
    U1 DT61 DDR6_SA_DQS_DN2 SOCKET4677_AZIF0045P001C01CS-SA   I168 @S9S_MB_2U_LIB.S9S_MB_2U(SCH_1):PAGE57
   J29   34 DQS2_A_C SCONN288_ADR50017P130CC-SCONN2A   I180 @S9S_MB_2U_LIB.S9S_MB_2U(SCH_1):PAGE110
   J30   34 DQS2_A_C SCONN288_ADR50017P087CC-SCONN2A   I180 @S9S_MB_2U_LIB.S9S_MB_2U(SCH_1):PAGE111

M_G_CPU1_SA_DQS_DN<3> @S9S_MB_2U_LIB.S9S_MB_2U(SCH_1):M_G_CPU1_SA_DQS_DN(3)
    U1 DL64 DDR6_SA_DQS_DN3 SOCKET4677_AZIF0045P001C01CS-SA   I168 @S9S_MB_2U_LIB.S9S_MB_2U(SCH_1):PAGE57
   J29   45 DQS3_A_C SCONN288_ADR50017P130CC-SCONN2A   I180 @S9S_MB_2U_LIB.S9S_MB_2U(SCH_1):PAGE110
   J30   45 DQS3_A_C SCONN288_ADR50017P087CC-SCONN2A   I180 @S9S_MB_2U_LIB.S9S_MB_2U(SCH_1):PAGE111

M_G_CPU1_SA_DQS_DN<4> @S9S_MB_2U_LIB.S9S_MB_2U(SCH_1):M_G_CPU1_SA_DQS_DN(4)
    U1 DL58 DDR6_SA_DQS_DN4 SOCKET4677_AZIF0045P001C01CS-SA   I168 @S9S_MB_2U_LIB.S9S_MB_2U(SCH_1):PAGE57
   J29   56 DQS4_A_C SCONN288_ADR50017P130CC-SCONN2A   I180 @S9S_MB_2U_LIB.S9S_MB_2U(SCH_1):PAGE110
   J30   56 DQS4_A_C SCONN288_ADR50017P087CC-SCONN2A   I180 @S9S_MB_2U_LIB.S9S_MB_2U(SCH_1):PAGE111

M_G_CPU1_SA_DQS_DN<5> @S9S_MB_2U_LIB.S9S_MB_2U(SCH_1):M_G_CPU1_SA_DQS_DN(5)
    U1 EB73 DDR6_SA_DQS_DN5 SOCKET4677_AZIF0045P001C01CS-SA   I168 @S9S_MB_2U_LIB.S9S_MB_2U(SCH_1):PAGE57
   J29  156 DQS5_A_C||TDQS5_A_C||DQS5_A_T||TDQS5_A_T SCONN288_ADR50017P130CC-SCONN2A   I180 @S9S_MB_2U_LIB.S9S_MB_2U(SCH_1):PAGE110
   J30  156 DQS5_A_C||TDQS5_A_C||DQS5_A_T||TDQS5_A_T SCONN288_ADR50017P087CC-SCONN2A   I180 @S9S_MB_2U_LIB.S9S_MB_2U(SCH_1):PAGE111

M_G_CPU1_SA_DQS_DN<6> @S9S_MB_2U_LIB.S9S_MB_2U(SCH_1):M_G_CPU1_SA_DQS_DN(6)
    U1 DR70 DDR6_SA_DQS_DN6 SOCKET4677_AZIF0045P001C01CS-SA   I168 @S9S_MB_2U_LIB.S9S_MB_2U(SCH_1):PAGE57
   J29  167 DQS6_A_C||TDQS6_A_C||DQS6_A_T||TDQS6_A_T SCONN288_ADR50017P130CC-SCONN2A   I180 @S9S_MB_2U_LIB.S9S_MB_2U(SCH_1):PAGE110
   J30  167 DQS6_A_C||TDQS6_A_C||DQS6_A_T||TDQS6_A_T SCONN288_ADR50017P087CC-SCONN2A   I180 @S9S_MB_2U_LIB.S9S_MB_2U(SCH_1):PAGE111

M_G_CPU1_SA_DQS_DN<7> @S9S_MB_2U_LIB.S9S_MB_2U(SCH_1):M_G_CPU1_SA_DQS_DN(7)
    U1 EB61 DDR6_SA_DQS_DN7 SOCKET4677_AZIF0045P001C01CS-SA   I168 @S9S_MB_2U_LIB.S9S_MB_2U(SCH_1):PAGE57
   J29  178 DQS7_A_C||TDQS7_A_C SCONN288_ADR50017P130CC-SCONN2A   I180 @S9S_MB_2U_LIB.S9S_MB_2U(SCH_1):PAGE110
   J30  178 DQS7_A_C||TDQS7_A_C SCONN288_ADR50017P087CC-SCONN2A   I180 @S9S_MB_2U_LIB.S9S_MB_2U(SCH_1):PAGE111

M_G_CPU1_SA_DQS_DN<8> @S9S_MB_2U_LIB.S9S_MB_2U(SCH_1):M_G_CPU1_SA_DQS_DN(8)
    U1 DR64 DDR6_SA_DQS_DN8 SOCKET4677_AZIF0045P001C01CS-SA   I168 @S9S_MB_2U_LIB.S9S_MB_2U(SCH_1):PAGE57
   J29  189 DQS8_A_C||TDQS8_A_C SCONN288_ADR50017P130CC-SCONN2A   I180 @S9S_MB_2U_LIB.S9S_MB_2U(SCH_1):PAGE110
   J30  189 DQS8_A_C||TDQS8_A_C SCONN288_ADR50017P087CC-SCONN2A   I180 @S9S_MB_2U_LIB.S9S_MB_2U(SCH_1):PAGE111

M_G_CPU1_SA_DQS_DN<9> @S9S_MB_2U_LIB.S9S_MB_2U(SCH_1):M_G_CPU1_SA_DQS_DN(9)
    U1 DR58 DDR6_SA_DQS_DN9 SOCKET4677_AZIF0045P001C01CS-SA   I168 @S9S_MB_2U_LIB.S9S_MB_2U(SCH_1):PAGE57
   J29  200 DQS9_A_C||TDQS9_A_C SCONN288_ADR50017P130CC-SCONN2A   I180 @S9S_MB_2U_LIB.S9S_MB_2U(SCH_1):PAGE110
   J30  200 DQS9_A_C||TDQS9_A_C SCONN288_ADR50017P087CC-SCONN2A   I180 @S9S_MB_2U_LIB.S9S_MB_2U(SCH_1):PAGE111

M_G_CPU1_SA_DQS_DP<0> @S9S_MB_2U_LIB.S9S_MB_2U(SCH_1):M_G_CPU1_SA_DQS_DP(0)
    U1 DT73 DDR6_SA_DQS_DP0 SOCKET4677_AZIF0045P001C01CS-SA   I168 @S9S_MB_2U_LIB.S9S_MB_2U(SCH_1):PAGE57
   J29   11 DQS0_A_T SCONN288_ADR50017P130CC-SCONN2A   I180 @S9S_MB_2U_LIB.S9S_MB_2U(SCH_1):PAGE110
   J30   11 DQS0_A_T SCONN288_ADR50017P087CC-SCONN2A   I180 @S9S_MB_2U_LIB.S9S_MB_2U(SCH_1):PAGE111

M_G_CPU1_SA_DQS_DP<1> @S9S_MB_2U_LIB.S9S_MB_2U(SCH_1):M_G_CPU1_SA_DQS_DP(1)
    U1 DL70 DDR6_SA_DQS_DP1 SOCKET4677_AZIF0045P001C01CS-SA   I168 @S9S_MB_2U_LIB.S9S_MB_2U(SCH_1):PAGE57
   J29   22 DQS1_A_T SCONN288_ADR50017P130CC-SCONN2A   I180 @S9S_MB_2U_LIB.S9S_MB_2U(SCH_1):PAGE110
   J30   22 DQS1_A_T SCONN288_ADR50017P087CC-SCONN2A   I180 @S9S_MB_2U_LIB.S9S_MB_2U(SCH_1):PAGE111

M_G_CPU1_SA_DQS_DP<2> @S9S_MB_2U_LIB.S9S_MB_2U(SCH_1):M_G_CPU1_SA_DQS_DP(2)
    U1 DV61 DDR6_SA_DQS_DP2 SOCKET4677_AZIF0045P001C01CS-SA   I168 @S9S_MB_2U_LIB.S9S_MB_2U(SCH_1):PAGE57
   J29   33 DQS2_A_T SCONN288_ADR50017P130CC-SCONN2A   I180 @S9S_MB_2U_LIB.S9S_MB_2U(SCH_1):PAGE110
   J30   33 DQS2_A_T SCONN288_ADR50017P087CC-SCONN2A   I180 @S9S_MB_2U_LIB.S9S_MB_2U(SCH_1):PAGE111

M_G_CPU1_SA_DQS_DP<3> @S9S_MB_2U_LIB.S9S_MB_2U(SCH_1):M_G_CPU1_SA_DQS_DP(3)
    U1 DJ64 DDR6_SA_DQS_DP3 SOCKET4677_AZIF0045P001C01CS-SA   I168 @S9S_MB_2U_LIB.S9S_MB_2U(SCH_1):PAGE57
   J29   44 DQS3_A_T SCONN288_ADR50017P130CC-SCONN2A   I180 @S9S_MB_2U_LIB.S9S_MB_2U(SCH_1):PAGE110
   J30   44 DQS3_A_T SCONN288_ADR50017P087CC-SCONN2A   I180 @S9S_MB_2U_LIB.S9S_MB_2U(SCH_1):PAGE111

M_G_CPU1_SA_DQS_DP<4> @S9S_MB_2U_LIB.S9S_MB_2U(SCH_1):M_G_CPU1_SA_DQS_DP(4)
    U1 DJ58 DDR6_SA_DQS_DP4 SOCKET4677_AZIF0045P001C01CS-SA   I168 @S9S_MB_2U_LIB.S9S_MB_2U(SCH_1):PAGE57
   J29   55 DQS4_A_T SCONN288_ADR50017P130CC-SCONN2A   I180 @S9S_MB_2U_LIB.S9S_MB_2U(SCH_1):PAGE110
   J30   55 DQS4_A_T SCONN288_ADR50017P087CC-SCONN2A   I180 @S9S_MB_2U_LIB.S9S_MB_2U(SCH_1):PAGE111

M_G_CPU1_SA_DQS_DP<5> @S9S_MB_2U_LIB.S9S_MB_2U(SCH_1):M_G_CPU1_SA_DQS_DP(5)
    U1 DY73 DDR6_SA_DQS_DP5 SOCKET4677_AZIF0045P001C01CS-SA   I168 @S9S_MB_2U_LIB.S9S_MB_2U(SCH_1):PAGE57
   J29  157 DQS5_A_T||TDQS5_A_T SCONN288_ADR50017P130CC-SCONN2A   I180 @S9S_MB_2U_LIB.S9S_MB_2U(SCH_1):PAGE110
   J30  157 DQS5_A_T||TDQS5_A_T SCONN288_ADR50017P087CC-SCONN2A   I180 @S9S_MB_2U_LIB.S9S_MB_2U(SCH_1):PAGE111

M_G_CPU1_SA_DQS_DP<6> @S9S_MB_2U_LIB.S9S_MB_2U(SCH_1):M_G_CPU1_SA_DQS_DP(6)
    U1 DN70 DDR6_SA_DQS_DP6 SOCKET4677_AZIF0045P001C01CS-SA   I168 @S9S_MB_2U_LIB.S9S_MB_2U(SCH_1):PAGE57
   J29  168 DQS6_A_T||TDQS6_A_T SCONN288_ADR50017P130CC-SCONN2A   I180 @S9S_MB_2U_LIB.S9S_MB_2U(SCH_1):PAGE110
   J30  168 DQS6_A_T||TDQS6_A_T SCONN288_ADR50017P087CC-SCONN2A   I180 @S9S_MB_2U_LIB.S9S_MB_2U(SCH_1):PAGE111

M_G_CPU1_SA_DQS_DP<7> @S9S_MB_2U_LIB.S9S_MB_2U(SCH_1):M_G_CPU1_SA_DQS_DP(7)
    U1 DY61 DDR6_SA_DQS_DP7 SOCKET4677_AZIF0045P001C01CS-SA   I168 @S9S_MB_2U_LIB.S9S_MB_2U(SCH_1):PAGE57
   J29  179 DQS7_A_T||TDQS7_A_T SCONN288_ADR50017P130CC-SCONN2A   I180 @S9S_MB_2U_LIB.S9S_MB_2U(SCH_1):PAGE110
   J30  179 DQS7_A_T||TDQS7_A_T SCONN288_ADR50017P087CC-SCONN2A   I180 @S9S_MB_2U_LIB.S9S_MB_2U(SCH_1):PAGE111

M_G_CPU1_SA_DQS_DP<8> @S9S_MB_2U_LIB.S9S_MB_2U(SCH_1):M_G_CPU1_SA_DQS_DP(8)
    U1 DN64 DDR6_SA_DQS_DP8 SOCKET4677_AZIF0045P001C01CS-SA   I168 @S9S_MB_2U_LIB.S9S_MB_2U(SCH_1):PAGE57
   J29  190 DQS8_A_T||TDQS8_A_T SCONN288_ADR50017P130CC-SCONN2A   I180 @S9S_MB_2U_LIB.S9S_MB_2U(SCH_1):PAGE110
   J30  190 DQS8_A_T||TDQS8_A_T SCONN288_ADR50017P087CC-SCONN2A   I180 @S9S_MB_2U_LIB.S9S_MB_2U(SCH_1):PAGE111

M_G_CPU1_SA_DQS_DP<9> @S9S_MB_2U_LIB.S9S_MB_2U(SCH_1):M_G_CPU1_SA_DQS_DP(9)
    U1 DN58 DDR6_SA_DQS_DP9 SOCKET4677_AZIF0045P001C01CS-SA   I168 @S9S_MB_2U_LIB.S9S_MB_2U(SCH_1):PAGE57
   J29  201 DQS9_A_T||TDQS9_A_T SCONN288_ADR50017P130CC-SCONN2A   I180 @S9S_MB_2U_LIB.S9S_MB_2U(SCH_1):PAGE110
   J30  201 DQS9_A_T||TDQS9_A_T SCONN288_ADR50017P087CC-SCONN2A   I180 @S9S_MB_2U_LIB.S9S_MB_2U(SCH_1):PAGE111

M_G_CPU1_SA_PAR @S9S_MB_2U_LIB.S9S_MB_2U(SCH_1):M_G_CPU1_SA_PAR
    U1 DL43 DDR6_SA_PAR SOCKET4677_AZIF0045P001C01CS-SA   I168 @S9S_MB_2U_LIB.S9S_MB_2U(SCH_1):PAGE57
   J29   74  PAR_A SCONN288_ADR50017P130CC-SCONN2A   I179 @S9S_MB_2U_LIB.S9S_MB_2U(SCH_1):PAGE110
   J30   74  PAR_A SCONN288_ADR50017P087CC-SCONN2A   I179 @S9S_MB_2U_LIB.S9S_MB_2U(SCH_1):PAGE111

M_G_CPU1_SA_RSP<0> @S9S_MB_2U_LIB.S9S_MB_2U(SCH_1):M_G_CPU1_SA_RSP(0)
    U1 EA48 DDR6_A_RSP0 SOCKET4677_AZIF0045P001C01CS-SA   I168 @S9S_MB_2U_LIB.S9S_MB_2U(SCH_1):PAGE57
   J29   86 LBD||RSP_A_N SCONN288_ADR50017P130CC-SCONN2A   I179 @S9S_MB_2U_LIB.S9S_MB_2U(SCH_1):PAGE110

M_G_CPU1_SA_RSP<1> @S9S_MB_2U_LIB.S9S_MB_2U(SCH_1):M_G_CPU1_SA_RSP(1)
    U1 DY47 DDR6_A_RSP1 SOCKET4677_AZIF0045P001C01CS-SA   I168 @S9S_MB_2U_LIB.S9S_MB_2U(SCH_1):PAGE57
   J30   86 LBD||RSP_A_N SCONN288_ADR50017P087CC-SCONN2A   I179 @S9S_MB_2U_LIB.S9S_MB_2U(SCH_1):PAGE111

M_G_CPU1_SB_CA<0> @S9S_MB_2U_LIB.S9S_MB_2U(SCH_1):M_G_CPU1_SB_CA(0)
    U1 DN43 DDR6_SB_CA0 SOCKET4677_AZIF0045P001C01CS-SA   I168 @S9S_MB_2U_LIB.S9S_MB_2U(SCH_1):PAGE57
   J29   76  CA0_B SCONN288_ADR50017P130CC-SCONN2A   I179 @S9S_MB_2U_LIB.S9S_MB_2U(SCH_1):PAGE110
   J30   76  CA0_B SCONN288_ADR50017P087CC-SCONN2A   I179 @S9S_MB_2U_LIB.S9S_MB_2U(SCH_1):PAGE111

M_G_CPU1_SB_CA<1> @S9S_MB_2U_LIB.S9S_MB_2U(SCH_1):M_G_CPU1_SB_CA(1)
    U1 DP44 DDR6_SB_CA1 SOCKET4677_AZIF0045P001C01CS-SA   I168 @S9S_MB_2U_LIB.S9S_MB_2U(SCH_1):PAGE57
   J29  221  CA1_B SCONN288_ADR50017P130CC-SCONN2A   I179 @S9S_MB_2U_LIB.S9S_MB_2U(SCH_1):PAGE110
   J30  221  CA1_B SCONN288_ADR50017P087CC-SCONN2A   I179 @S9S_MB_2U_LIB.S9S_MB_2U(SCH_1):PAGE111

M_G_CPU1_SB_CA<2> @S9S_MB_2U_LIB.S9S_MB_2U(SCH_1):M_G_CPU1_SB_CA(2)
    U1 DV44 DDR6_SB_CA2 SOCKET4677_AZIF0045P001C01CS-SA   I168 @S9S_MB_2U_LIB.S9S_MB_2U(SCH_1):PAGE57
   J29   78  CA2_B SCONN288_ADR50017P130CC-SCONN2A   I179 @S9S_MB_2U_LIB.S9S_MB_2U(SCH_1):PAGE110
   J30   78  CA2_B SCONN288_ADR50017P087CC-SCONN2A   I179 @S9S_MB_2U_LIB.S9S_MB_2U(SCH_1):PAGE111

M_G_CPU1_SB_CA<3> @S9S_MB_2U_LIB.S9S_MB_2U(SCH_1):M_G_CPU1_SB_CA(3)
    U1 DY44 DDR6_SB_CA3 SOCKET4677_AZIF0045P001C01CS-SA   I168 @S9S_MB_2U_LIB.S9S_MB_2U(SCH_1):PAGE57
   J29  223  CA3_B SCONN288_ADR50017P130CC-SCONN2A   I179 @S9S_MB_2U_LIB.S9S_MB_2U(SCH_1):PAGE110
   J30  223  CA3_B SCONN288_ADR50017P087CC-SCONN2A   I179 @S9S_MB_2U_LIB.S9S_MB_2U(SCH_1):PAGE111

M_G_CPU1_SB_CA<4> @S9S_MB_2U_LIB.S9S_MB_2U(SCH_1):M_G_CPU1_SB_CA(4)
    U1 DU43 DDR6_SB_CA4 SOCKET4677_AZIF0045P001C01CS-SA   I168 @S9S_MB_2U_LIB.S9S_MB_2U(SCH_1):PAGE57
   J29   80  CA4_B SCONN288_ADR50017P130CC-SCONN2A   I179 @S9S_MB_2U_LIB.S9S_MB_2U(SCH_1):PAGE110
   J30   80  CA4_B SCONN288_ADR50017P087CC-SCONN2A   I179 @S9S_MB_2U_LIB.S9S_MB_2U(SCH_1):PAGE111

M_G_CPU1_SB_CA<5> @S9S_MB_2U_LIB.S9S_MB_2U(SCH_1):M_G_CPU1_SB_CA(5)
    U1 EA43 DDR6_SB_CA5 SOCKET4677_AZIF0045P001C01CS-SA   I168 @S9S_MB_2U_LIB.S9S_MB_2U(SCH_1):PAGE57
   J29  225  CA5_B SCONN288_ADR50017P130CC-SCONN2A   I179 @S9S_MB_2U_LIB.S9S_MB_2U(SCH_1):PAGE110
   J30  225  CA5_B SCONN288_ADR50017P087CC-SCONN2A   I179 @S9S_MB_2U_LIB.S9S_MB_2U(SCH_1):PAGE111

M_G_CPU1_SB_CA<6> @S9S_MB_2U_LIB.S9S_MB_2U(SCH_1):M_G_CPU1_SB_CA(6)
    U1 DT42 DDR6_SB_CA6 SOCKET4677_AZIF0045P001C01CS-SA   I168 @S9S_MB_2U_LIB.S9S_MB_2U(SCH_1):PAGE57
   J29   82  CA6_B SCONN288_ADR50017P130CC-SCONN2A   I179 @S9S_MB_2U_LIB.S9S_MB_2U(SCH_1):PAGE110
   J30   82  CA6_B SCONN288_ADR50017P087CC-SCONN2A   I179 @S9S_MB_2U_LIB.S9S_MB_2U(SCH_1):PAGE111

M_G_CPU1_SB_CB<0> @S9S_MB_2U_LIB.S9S_MB_2U(SCH_1):M_G_CPU1_SB_CB(0)
    U1 DU35 DDR6_SB_ECC0 SOCKET4677_AZIF0045P001C01CS-SA   I168 @S9S_MB_2U_LIB.S9S_MB_2U(SCH_1):PAGE57
   J29   96  CB0_B SCONN288_ADR50017P130CC-SCONN2A   I179 @S9S_MB_2U_LIB.S9S_MB_2U(SCH_1):PAGE110
   J30   96  CB0_B SCONN288_ADR50017P087CC-SCONN2A   I179 @S9S_MB_2U_LIB.S9S_MB_2U(SCH_1):PAGE111

M_G_CPU1_SB_CB<1> @S9S_MB_2U_LIB.S9S_MB_2U(SCH_1):M_G_CPU1_SB_CB(1)
    U1 DV34 DDR6_SB_ECC1 SOCKET4677_AZIF0045P001C01CS-SA   I168 @S9S_MB_2U_LIB.S9S_MB_2U(SCH_1):PAGE57
   J29   98  CB1_B SCONN288_ADR50017P130CC-SCONN2A   I179 @S9S_MB_2U_LIB.S9S_MB_2U(SCH_1):PAGE110
   J30   98  CB1_B SCONN288_ADR50017P087CC-SCONN2A   I179 @S9S_MB_2U_LIB.S9S_MB_2U(SCH_1):PAGE111

M_G_CPU1_SB_CB<2> @S9S_MB_2U_LIB.S9S_MB_2U(SCH_1):M_G_CPU1_SB_CB(2)
    U1 EA35 DDR6_SB_ECC2 SOCKET4677_AZIF0045P001C01CS-SA   I168 @S9S_MB_2U_LIB.S9S_MB_2U(SCH_1):PAGE57
   J29  241  CB2_B SCONN288_ADR50017P130CC-SCONN2A   I179 @S9S_MB_2U_LIB.S9S_MB_2U(SCH_1):PAGE110
   J30  241  CB2_B SCONN288_ADR50017P087CC-SCONN2A   I179 @S9S_MB_2U_LIB.S9S_MB_2U(SCH_1):PAGE111

M_G_CPU1_SB_CB<3> @S9S_MB_2U_LIB.S9S_MB_2U(SCH_1):M_G_CPU1_SB_CB(3)
    U1 DY34 DDR6_SB_ECC3 SOCKET4677_AZIF0045P001C01CS-SA   I168 @S9S_MB_2U_LIB.S9S_MB_2U(SCH_1):PAGE57
   J29  243  CB3_B SCONN288_ADR50017P130CC-SCONN2A   I179 @S9S_MB_2U_LIB.S9S_MB_2U(SCH_1):PAGE110
   J30  243  CB3_B SCONN288_ADR50017P087CC-SCONN2A   I179 @S9S_MB_2U_LIB.S9S_MB_2U(SCH_1):PAGE111

M_G_CPU1_SB_CB<4> @S9S_MB_2U_LIB.S9S_MB_2U(SCH_1):M_G_CPU1_SB_CB(4)
    U1 DV38 DDR6_SB_ECC4 SOCKET4677_AZIF0045P001C01CS-SA   I168 @S9S_MB_2U_LIB.S9S_MB_2U(SCH_1):PAGE57
   J29   89  CB4_B SCONN288_ADR50017P130CC-SCONN2A   I179 @S9S_MB_2U_LIB.S9S_MB_2U(SCH_1):PAGE110
   J30   89  CB4_B SCONN288_ADR50017P087CC-SCONN2A   I179 @S9S_MB_2U_LIB.S9S_MB_2U(SCH_1):PAGE111

M_G_CPU1_SB_CB<5> @S9S_MB_2U_LIB.S9S_MB_2U(SCH_1):M_G_CPU1_SB_CB(5)
    U1 DU37 DDR6_SB_ECC5 SOCKET4677_AZIF0045P001C01CS-SA   I168 @S9S_MB_2U_LIB.S9S_MB_2U(SCH_1):PAGE57
   J29   91  CB5_B SCONN288_ADR50017P130CC-SCONN2A   I179 @S9S_MB_2U_LIB.S9S_MB_2U(SCH_1):PAGE110
   J30   91  CB5_B SCONN288_ADR50017P087CC-SCONN2A   I179 @S9S_MB_2U_LIB.S9S_MB_2U(SCH_1):PAGE111

M_G_CPU1_SB_CB<6> @S9S_MB_2U_LIB.S9S_MB_2U(SCH_1):M_G_CPU1_SB_CB(6)
    U1 DY38 DDR6_SB_ECC6 SOCKET4677_AZIF0045P001C01CS-SA   I168 @S9S_MB_2U_LIB.S9S_MB_2U(SCH_1):PAGE57
   J29  234  CB6_B SCONN288_ADR50017P130CC-SCONN2A   I179 @S9S_MB_2U_LIB.S9S_MB_2U(SCH_1):PAGE110
   J30  234  CB6_B SCONN288_ADR50017P087CC-SCONN2A   I179 @S9S_MB_2U_LIB.S9S_MB_2U(SCH_1):PAGE111

M_G_CPU1_SB_CB<7> @S9S_MB_2U_LIB.S9S_MB_2U(SCH_1):M_G_CPU1_SB_CB(7)
    U1 EA37 DDR6_SB_ECC7 SOCKET4677_AZIF0045P001C01CS-SA   I168 @S9S_MB_2U_LIB.S9S_MB_2U(SCH_1):PAGE57
   J29  236  CB7_B SCONN288_ADR50017P130CC-SCONN2A   I179 @S9S_MB_2U_LIB.S9S_MB_2U(SCH_1):PAGE110
   J30  236  CB7_B SCONN288_ADR50017P087CC-SCONN2A   I179 @S9S_MB_2U_LIB.S9S_MB_2U(SCH_1):PAGE111

M_G_CPU1_SB_CS_N<0> @S9S_MB_2U_LIB.S9S_MB_2U(SCH_1):M_G_CPU1_SB_CS_N(0)
    U1 EA41 DDR6_SB_CS_N0 SOCKET4677_AZIF0045P001C01CS-SA   I168 @S9S_MB_2U_LIB.S9S_MB_2U(SCH_1):PAGE57
   J29   84 CS0_B_N SCONN288_ADR50017P130CC-SCONN2A   I179 @S9S_MB_2U_LIB.S9S_MB_2U(SCH_1):PAGE110

M_G_CPU1_SB_CS_N<1> @S9S_MB_2U_LIB.S9S_MB_2U(SCH_1):M_G_CPU1_SB_CS_N(1)
    U1 DY40 DDR6_SB_CS_N1 SOCKET4677_AZIF0045P001C01CS-SA   I168 @S9S_MB_2U_LIB.S9S_MB_2U(SCH_1):PAGE57
   J29  229 CS1_B_N SCONN288_ADR50017P130CC-SCONN2A   I179 @S9S_MB_2U_LIB.S9S_MB_2U(SCH_1):PAGE110

M_G_CPU1_SB_CS_N<2> @S9S_MB_2U_LIB.S9S_MB_2U(SCH_1):M_G_CPU1_SB_CS_N(2)
    U1 DU41 DDR6_SB_CS_N2 SOCKET4677_AZIF0045P001C01CS-SA   I168 @S9S_MB_2U_LIB.S9S_MB_2U(SCH_1):PAGE57
   J30   84 CS0_B_N SCONN288_ADR50017P087CC-SCONN2A   I179 @S9S_MB_2U_LIB.S9S_MB_2U(SCH_1):PAGE111

M_G_CPU1_SB_CS_N<3> @S9S_MB_2U_LIB.S9S_MB_2U(SCH_1):M_G_CPU1_SB_CS_N(3)
    U1 DV40 DDR6_SB_CS_N3 SOCKET4677_AZIF0045P001C01CS-SA   I168 @S9S_MB_2U_LIB.S9S_MB_2U(SCH_1):PAGE57
   J30  229 CS1_B_N SCONN288_ADR50017P087CC-SCONN2A   I179 @S9S_MB_2U_LIB.S9S_MB_2U(SCH_1):PAGE111

M_G_CPU1_SB_DQ<0> @S9S_MB_2U_LIB.S9S_MB_2U(SCH_1):M_G_CPU1_SB_DQ(0)
    U1 DL35 DDR6_SB_DQ0 SOCKET4677_AZIF0045P001C01CS-SA   I168 @S9S_MB_2U_LIB.S9S_MB_2U(SCH_1):PAGE57
   J29  100  DQ0_B SCONN288_ADR50017P130CC-SCONN2A   I179 @S9S_MB_2U_LIB.S9S_MB_2U(SCH_1):PAGE110
   J30  100  DQ0_B SCONN288_ADR50017P087CC-SCONN2A   I179 @S9S_MB_2U_LIB.S9S_MB_2U(SCH_1):PAGE111

M_G_CPU1_SB_DQ<10> @S9S_MB_2U_LIB.S9S_MB_2U(SCH_1):M_G_CPU1_SB_DQ(10)
    U1 DL29 DDR6_SB_DQ10 SOCKET4677_AZIF0045P001C01CS-SA   I168 @S9S_MB_2U_LIB.S9S_MB_2U(SCH_1):PAGE57
   J29  256 DQ10_B SCONN288_ADR50017P130CC-SCONN2A   I179 @S9S_MB_2U_LIB.S9S_MB_2U(SCH_1):PAGE110
   J30  256 DQ10_B SCONN288_ADR50017P087CC-SCONN2A   I179 @S9S_MB_2U_LIB.S9S_MB_2U(SCH_1):PAGE111

M_G_CPU1_SB_DQ<11> @S9S_MB_2U_LIB.S9S_MB_2U(SCH_1):M_G_CPU1_SB_DQ(11)
    U1 DP28 DDR6_SB_DQ11 SOCKET4677_AZIF0045P001C01CS-SA   I168 @S9S_MB_2U_LIB.S9S_MB_2U(SCH_1):PAGE57
   J29  258 DQ11_B SCONN288_ADR50017P130CC-SCONN2A   I179 @S9S_MB_2U_LIB.S9S_MB_2U(SCH_1):PAGE110
   J30  258 DQ11_B SCONN288_ADR50017P087CC-SCONN2A   I179 @S9S_MB_2U_LIB.S9S_MB_2U(SCH_1):PAGE111

M_G_CPU1_SB_DQ<12> @S9S_MB_2U_LIB.S9S_MB_2U(SCH_1):M_G_CPU1_SB_DQ(12)
    U1 DK26 DDR6_SB_DQ12 SOCKET4677_AZIF0045P001C01CS-SA   I168 @S9S_MB_2U_LIB.S9S_MB_2U(SCH_1):PAGE57
   J29  118 DQ12_B SCONN288_ADR50017P130CC-SCONN2A   I179 @S9S_MB_2U_LIB.S9S_MB_2U(SCH_1):PAGE110
   J30  118 DQ12_B SCONN288_ADR50017P087CC-SCONN2A   I179 @S9S_MB_2U_LIB.S9S_MB_2U(SCH_1):PAGE111

M_G_CPU1_SB_DQ<13> @S9S_MB_2U_LIB.S9S_MB_2U(SCH_1):M_G_CPU1_SB_DQ(13)
    U1 DL25 DDR6_SB_DQ13 SOCKET4677_AZIF0045P001C01CS-SA   I168 @S9S_MB_2U_LIB.S9S_MB_2U(SCH_1):PAGE57
   J29  120 DQ13_B SCONN288_ADR50017P130CC-SCONN2A   I179 @S9S_MB_2U_LIB.S9S_MB_2U(SCH_1):PAGE110
   J30  120 DQ13_B SCONN288_ADR50017P087CC-SCONN2A   I179 @S9S_MB_2U_LIB.S9S_MB_2U(SCH_1):PAGE111

M_G_CPU1_SB_DQ<14> @S9S_MB_2U_LIB.S9S_MB_2U(SCH_1):M_G_CPU1_SB_DQ(14)
    U1 DP26 DDR6_SB_DQ14 SOCKET4677_AZIF0045P001C01CS-SA   I168 @S9S_MB_2U_LIB.S9S_MB_2U(SCH_1):PAGE57
   J29  263 DQ14_B SCONN288_ADR50017P130CC-SCONN2A   I179 @S9S_MB_2U_LIB.S9S_MB_2U(SCH_1):PAGE110
   J30  263 DQ14_B SCONN288_ADR50017P087CC-SCONN2A   I179 @S9S_MB_2U_LIB.S9S_MB_2U(SCH_1):PAGE111

M_G_CPU1_SB_DQ<15> @S9S_MB_2U_LIB.S9S_MB_2U(SCH_1):M_G_CPU1_SB_DQ(15)
    U1 DN25 DDR6_SB_DQ15 SOCKET4677_AZIF0045P001C01CS-SA   I168 @S9S_MB_2U_LIB.S9S_MB_2U(SCH_1):PAGE57
   J29  265 DQ15_B SCONN288_ADR50017P130CC-SCONN2A   I179 @S9S_MB_2U_LIB.S9S_MB_2U(SCH_1):PAGE110
   J30  265 DQ15_B SCONN288_ADR50017P087CC-SCONN2A   I179 @S9S_MB_2U_LIB.S9S_MB_2U(SCH_1):PAGE111

M_G_CPU1_SB_DQ<16> @S9S_MB_2U_LIB.S9S_MB_2U(SCH_1):M_G_CPU1_SB_DQ(16)
    U1 DV26 DDR6_SB_DQ16 SOCKET4677_AZIF0045P001C01CS-SA   I168 @S9S_MB_2U_LIB.S9S_MB_2U(SCH_1):PAGE57
   J29  122 DQ16_B SCONN288_ADR50017P130CC-SCONN2A   I179 @S9S_MB_2U_LIB.S9S_MB_2U(SCH_1):PAGE110
   J30  122 DQ16_B SCONN288_ADR50017P087CC-SCONN2A   I179 @S9S_MB_2U_LIB.S9S_MB_2U(SCH_1):PAGE111

M_G_CPU1_SB_DQ<17> @S9S_MB_2U_LIB.S9S_MB_2U(SCH_1):M_G_CPU1_SB_DQ(17)
    U1 DU25 DDR6_SB_DQ17 SOCKET4677_AZIF0045P001C01CS-SA   I168 @S9S_MB_2U_LIB.S9S_MB_2U(SCH_1):PAGE57
   J29  124 DQ17_B SCONN288_ADR50017P130CC-SCONN2A   I179 @S9S_MB_2U_LIB.S9S_MB_2U(SCH_1):PAGE110
   J30  124 DQ17_B SCONN288_ADR50017P087CC-SCONN2A   I179 @S9S_MB_2U_LIB.S9S_MB_2U(SCH_1):PAGE111

M_G_CPU1_SB_DQ<18> @S9S_MB_2U_LIB.S9S_MB_2U(SCH_1):M_G_CPU1_SB_DQ(18)
    U1 DY26 DDR6_SB_DQ18 SOCKET4677_AZIF0045P001C01CS-SA   I168 @S9S_MB_2U_LIB.S9S_MB_2U(SCH_1):PAGE57
   J29  267 DQ18_B SCONN288_ADR50017P130CC-SCONN2A   I179 @S9S_MB_2U_LIB.S9S_MB_2U(SCH_1):PAGE110
   J30  267 DQ18_B SCONN288_ADR50017P087CC-SCONN2A   I179 @S9S_MB_2U_LIB.S9S_MB_2U(SCH_1):PAGE111

M_G_CPU1_SB_DQ<19> @S9S_MB_2U_LIB.S9S_MB_2U(SCH_1):M_G_CPU1_SB_DQ(19)
    U1 EA25 DDR6_SB_DQ19 SOCKET4677_AZIF0045P001C01CS-SA   I168 @S9S_MB_2U_LIB.S9S_MB_2U(SCH_1):PAGE57
   J29  269 DQ19_B SCONN288_ADR50017P130CC-SCONN2A   I179 @S9S_MB_2U_LIB.S9S_MB_2U(SCH_1):PAGE110
   J30  269 DQ19_B SCONN288_ADR50017P087CC-SCONN2A   I179 @S9S_MB_2U_LIB.S9S_MB_2U(SCH_1):PAGE111

M_G_CPU1_SB_DQ<1> @S9S_MB_2U_LIB.S9S_MB_2U(SCH_1):M_G_CPU1_SB_DQ(1)
    U1 DK34 DDR6_SB_DQ1 SOCKET4677_AZIF0045P001C01CS-SA   I168 @S9S_MB_2U_LIB.S9S_MB_2U(SCH_1):PAGE57
   J29  102  DQ1_B SCONN288_ADR50017P130CC-SCONN2A   I179 @S9S_MB_2U_LIB.S9S_MB_2U(SCH_1):PAGE110
   J30  102  DQ1_B SCONN288_ADR50017P087CC-SCONN2A   I179 @S9S_MB_2U_LIB.S9S_MB_2U(SCH_1):PAGE111

M_G_CPU1_SB_DQ<20> @S9S_MB_2U_LIB.S9S_MB_2U(SCH_1):M_G_CPU1_SB_DQ(20)
    U1 DU23 DDR6_SB_DQ20 SOCKET4677_AZIF0045P001C01CS-SA   I168 @S9S_MB_2U_LIB.S9S_MB_2U(SCH_1):PAGE57
   J29  129 DQ20_B SCONN288_ADR50017P130CC-SCONN2A   I179 @S9S_MB_2U_LIB.S9S_MB_2U(SCH_1):PAGE110
   J30  129 DQ20_B SCONN288_ADR50017P087CC-SCONN2A   I179 @S9S_MB_2U_LIB.S9S_MB_2U(SCH_1):PAGE111

M_G_CPU1_SB_DQ<21> @S9S_MB_2U_LIB.S9S_MB_2U(SCH_1):M_G_CPU1_SB_DQ(21)
    U1 DV22 DDR6_SB_DQ21 SOCKET4677_AZIF0045P001C01CS-SA   I168 @S9S_MB_2U_LIB.S9S_MB_2U(SCH_1):PAGE57
   J29  131 DQ21_B SCONN288_ADR50017P130CC-SCONN2A   I179 @S9S_MB_2U_LIB.S9S_MB_2U(SCH_1):PAGE110
   J30  131 DQ21_B SCONN288_ADR50017P087CC-SCONN2A   I179 @S9S_MB_2U_LIB.S9S_MB_2U(SCH_1):PAGE111

M_G_CPU1_SB_DQ<22> @S9S_MB_2U_LIB.S9S_MB_2U(SCH_1):M_G_CPU1_SB_DQ(22)
    U1 EA23 DDR6_SB_DQ22 SOCKET4677_AZIF0045P001C01CS-SA   I168 @S9S_MB_2U_LIB.S9S_MB_2U(SCH_1):PAGE57
   J29  274 DQ22_B SCONN288_ADR50017P130CC-SCONN2A   I179 @S9S_MB_2U_LIB.S9S_MB_2U(SCH_1):PAGE110
   J30  274 DQ22_B SCONN288_ADR50017P087CC-SCONN2A   I179 @S9S_MB_2U_LIB.S9S_MB_2U(SCH_1):PAGE111

M_G_CPU1_SB_DQ<23> @S9S_MB_2U_LIB.S9S_MB_2U(SCH_1):M_G_CPU1_SB_DQ(23)
    U1 DY22 DDR6_SB_DQ23 SOCKET4677_AZIF0045P001C01CS-SA   I168 @S9S_MB_2U_LIB.S9S_MB_2U(SCH_1):PAGE57
   J29  276 DQ23_B SCONN288_ADR50017P130CC-SCONN2A   I179 @S9S_MB_2U_LIB.S9S_MB_2U(SCH_1):PAGE110
   J30  276 DQ23_B SCONN288_ADR50017P087CC-SCONN2A   I179 @S9S_MB_2U_LIB.S9S_MB_2U(SCH_1):PAGE111

M_G_CPU1_SB_DQ<24> @S9S_MB_2U_LIB.S9S_MB_2U(SCH_1):M_G_CPU1_SB_DQ(24)
    U1  EK8 DDR6_SB_DQ24 SOCKET4677_AZIF0045P001C01CS-SA   I168 @S9S_MB_2U_LIB.S9S_MB_2U(SCH_1):PAGE57
   J29  133 DQ24_B SCONN288_ADR50017P130CC-SCONN2A   I179 @S9S_MB_2U_LIB.S9S_MB_2U(SCH_1):PAGE110
   J30  133 DQ24_B SCONN288_ADR50017P087CC-SCONN2A   I179 @S9S_MB_2U_LIB.S9S_MB_2U(SCH_1):PAGE111

M_G_CPU1_SB_DQ<25> @S9S_MB_2U_LIB.S9S_MB_2U(SCH_1):M_G_CPU1_SB_DQ(25)
    U1  EH8 DDR6_SB_DQ25 SOCKET4677_AZIF0045P001C01CS-SA   I168 @S9S_MB_2U_LIB.S9S_MB_2U(SCH_1):PAGE57
   J29  135 DQ25_B SCONN288_ADR50017P130CC-SCONN2A   I179 @S9S_MB_2U_LIB.S9S_MB_2U(SCH_1):PAGE110
   J30  135 DQ25_B SCONN288_ADR50017P087CC-SCONN2A   I179 @S9S_MB_2U_LIB.S9S_MB_2U(SCH_1):PAGE111

M_G_CPU1_SB_DQ<26> @S9S_MB_2U_LIB.S9S_MB_2U(SCH_1):M_G_CPU1_SB_DQ(26)
    U1  EP8 DDR6_SB_DQ26 SOCKET4677_AZIF0045P001C01CS-SA   I168 @S9S_MB_2U_LIB.S9S_MB_2U(SCH_1):PAGE57
   J29  278 DQ26_B SCONN288_ADR50017P130CC-SCONN2A   I179 @S9S_MB_2U_LIB.S9S_MB_2U(SCH_1):PAGE110
   J30  278 DQ26_B SCONN288_ADR50017P087CC-SCONN2A   I179 @S9S_MB_2U_LIB.S9S_MB_2U(SCH_1):PAGE111

M_G_CPU1_SB_DQ<27> @S9S_MB_2U_LIB.S9S_MB_2U(SCH_1):M_G_CPU1_SB_DQ(27)
    U1  ET8 DDR6_SB_DQ27 SOCKET4677_AZIF0045P001C01CS-SA   I168 @S9S_MB_2U_LIB.S9S_MB_2U(SCH_1):PAGE57
   J29  280 DQ27_B SCONN288_ADR50017P130CC-SCONN2A   I179 @S9S_MB_2U_LIB.S9S_MB_2U(SCH_1):PAGE110
   J30  280 DQ27_B SCONN288_ADR50017P087CC-SCONN2A   I179 @S9S_MB_2U_LIB.S9S_MB_2U(SCH_1):PAGE111

M_G_CPU1_SB_DQ<28> @S9S_MB_2U_LIB.S9S_MB_2U(SCH_1):M_G_CPU1_SB_DQ(28)
    U1  EK6 DDR6_SB_DQ28 SOCKET4677_AZIF0045P001C01CS-SA   I168 @S9S_MB_2U_LIB.S9S_MB_2U(SCH_1):PAGE57
   J29  140 DQ28_B SCONN288_ADR50017P130CC-SCONN2A   I179 @S9S_MB_2U_LIB.S9S_MB_2U(SCH_1):PAGE110
   J30  140 DQ28_B SCONN288_ADR50017P087CC-SCONN2A   I179 @S9S_MB_2U_LIB.S9S_MB_2U(SCH_1):PAGE111

M_G_CPU1_SB_DQ<29> @S9S_MB_2U_LIB.S9S_MB_2U(SCH_1):M_G_CPU1_SB_DQ(29)
    U1  EJ5 DDR6_SB_DQ29 SOCKET4677_AZIF0045P001C01CS-SA   I168 @S9S_MB_2U_LIB.S9S_MB_2U(SCH_1):PAGE57
   J29  142 DQ29_B SCONN288_ADR50017P130CC-SCONN2A   I179 @S9S_MB_2U_LIB.S9S_MB_2U(SCH_1):PAGE110
   J30  142 DQ29_B SCONN288_ADR50017P087CC-SCONN2A   I179 @S9S_MB_2U_LIB.S9S_MB_2U(SCH_1):PAGE111

M_G_CPU1_SB_DQ<2> @S9S_MB_2U_LIB.S9S_MB_2U(SCH_1):M_G_CPU1_SB_DQ(2)
    U1 DN35 DDR6_SB_DQ2 SOCKET4677_AZIF0045P001C01CS-SA   I168 @S9S_MB_2U_LIB.S9S_MB_2U(SCH_1):PAGE57
   J29  245  DQ2_B SCONN288_ADR50017P130CC-SCONN2A   I179 @S9S_MB_2U_LIB.S9S_MB_2U(SCH_1):PAGE110
   J30  245  DQ2_B SCONN288_ADR50017P087CC-SCONN2A   I179 @S9S_MB_2U_LIB.S9S_MB_2U(SCH_1):PAGE111

M_G_CPU1_SB_DQ<30> @S9S_MB_2U_LIB.S9S_MB_2U(SCH_1):M_G_CPU1_SB_DQ(30)
    U1  EP4 DDR6_SB_DQ30 SOCKET4677_AZIF0045P001C01CS-SA   I168 @S9S_MB_2U_LIB.S9S_MB_2U(SCH_1):PAGE57
   J29  285 DQ30_B SCONN288_ADR50017P130CC-SCONN2A   I179 @S9S_MB_2U_LIB.S9S_MB_2U(SCH_1):PAGE110
   J30  285 DQ30_B SCONN288_ADR50017P087CC-SCONN2A   I179 @S9S_MB_2U_LIB.S9S_MB_2U(SCH_1):PAGE111

M_G_CPU1_SB_DQ<31> @S9S_MB_2U_LIB.S9S_MB_2U(SCH_1):M_G_CPU1_SB_DQ(31)
    U1  EM4 DDR6_SB_DQ31 SOCKET4677_AZIF0045P001C01CS-SA   I168 @S9S_MB_2U_LIB.S9S_MB_2U(SCH_1):PAGE57
   J29  287 DQ31_B SCONN288_ADR50017P130CC-SCONN2A   I179 @S9S_MB_2U_LIB.S9S_MB_2U(SCH_1):PAGE110
   J30  287 DQ31_B SCONN288_ADR50017P087CC-SCONN2A   I179 @S9S_MB_2U_LIB.S9S_MB_2U(SCH_1):PAGE111

M_G_CPU1_SB_DQ<3> @S9S_MB_2U_LIB.S9S_MB_2U(SCH_1):M_G_CPU1_SB_DQ(3)
    U1 DP34 DDR6_SB_DQ3 SOCKET4677_AZIF0045P001C01CS-SA   I168 @S9S_MB_2U_LIB.S9S_MB_2U(SCH_1):PAGE57
   J29  247  DQ3_B SCONN288_ADR50017P130CC-SCONN2A   I179 @S9S_MB_2U_LIB.S9S_MB_2U(SCH_1):PAGE110
   J30  247  DQ3_B SCONN288_ADR50017P087CC-SCONN2A   I179 @S9S_MB_2U_LIB.S9S_MB_2U(SCH_1):PAGE111

M_G_CPU1_SB_DQ<4> @S9S_MB_2U_LIB.S9S_MB_2U(SCH_1):M_G_CPU1_SB_DQ(4)
    U1 DK32 DDR6_SB_DQ4 SOCKET4677_AZIF0045P001C01CS-SA   I168 @S9S_MB_2U_LIB.S9S_MB_2U(SCH_1):PAGE57
   J29  107  DQ4_B SCONN288_ADR50017P130CC-SCONN2A   I179 @S9S_MB_2U_LIB.S9S_MB_2U(SCH_1):PAGE110
   J30  107  DQ4_B SCONN288_ADR50017P087CC-SCONN2A   I179 @S9S_MB_2U_LIB.S9S_MB_2U(SCH_1):PAGE111

M_G_CPU1_SB_DQ<5> @S9S_MB_2U_LIB.S9S_MB_2U(SCH_1):M_G_CPU1_SB_DQ(5)
    U1 DL31 DDR6_SB_DQ5 SOCKET4677_AZIF0045P001C01CS-SA   I168 @S9S_MB_2U_LIB.S9S_MB_2U(SCH_1):PAGE57
   J29  109  DQ5_B SCONN288_ADR50017P130CC-SCONN2A   I179 @S9S_MB_2U_LIB.S9S_MB_2U(SCH_1):PAGE110
   J30  109  DQ5_B SCONN288_ADR50017P087CC-SCONN2A   I179 @S9S_MB_2U_LIB.S9S_MB_2U(SCH_1):PAGE111

M_G_CPU1_SB_DQ<6> @S9S_MB_2U_LIB.S9S_MB_2U(SCH_1):M_G_CPU1_SB_DQ(6)
    U1 DP32 DDR6_SB_DQ6 SOCKET4677_AZIF0045P001C01CS-SA   I168 @S9S_MB_2U_LIB.S9S_MB_2U(SCH_1):PAGE57
   J29  252  DQ6_B SCONN288_ADR50017P130CC-SCONN2A   I179 @S9S_MB_2U_LIB.S9S_MB_2U(SCH_1):PAGE110
   J30  252  DQ6_B SCONN288_ADR50017P087CC-SCONN2A   I179 @S9S_MB_2U_LIB.S9S_MB_2U(SCH_1):PAGE111

M_G_CPU1_SB_DQ<7> @S9S_MB_2U_LIB.S9S_MB_2U(SCH_1):M_G_CPU1_SB_DQ(7)
    U1 DN31 DDR6_SB_DQ7 SOCKET4677_AZIF0045P001C01CS-SA   I168 @S9S_MB_2U_LIB.S9S_MB_2U(SCH_1):PAGE57
   J29  254  DQ7_B SCONN288_ADR50017P130CC-SCONN2A   I179 @S9S_MB_2U_LIB.S9S_MB_2U(SCH_1):PAGE110
   J30  254  DQ7_B SCONN288_ADR50017P087CC-SCONN2A   I179 @S9S_MB_2U_LIB.S9S_MB_2U(SCH_1):PAGE111

M_G_CPU1_SB_DQ<8> @S9S_MB_2U_LIB.S9S_MB_2U(SCH_1):M_G_CPU1_SB_DQ(8)
    U1 DN29 DDR6_SB_DQ8 SOCKET4677_AZIF0045P001C01CS-SA   I168 @S9S_MB_2U_LIB.S9S_MB_2U(SCH_1):PAGE57
   J29  111  DQ8_B SCONN288_ADR50017P130CC-SCONN2A   I179 @S9S_MB_2U_LIB.S9S_MB_2U(SCH_1):PAGE110
   J30  111  DQ8_B SCONN288_ADR50017P087CC-SCONN2A   I179 @S9S_MB_2U_LIB.S9S_MB_2U(SCH_1):PAGE111

M_G_CPU1_SB_DQ<9> @S9S_MB_2U_LIB.S9S_MB_2U(SCH_1):M_G_CPU1_SB_DQ(9)
    U1 DK28 DDR6_SB_DQ9 SOCKET4677_AZIF0045P001C01CS-SA   I168 @S9S_MB_2U_LIB.S9S_MB_2U(SCH_1):PAGE57
   J29  113  DQ9_B SCONN288_ADR50017P130CC-SCONN2A   I179 @S9S_MB_2U_LIB.S9S_MB_2U(SCH_1):PAGE110
   J30  113  DQ9_B SCONN288_ADR50017P087CC-SCONN2A   I179 @S9S_MB_2U_LIB.S9S_MB_2U(SCH_1):PAGE111

M_G_CPU1_SB_DQS_DN<0> @S9S_MB_2U_LIB.S9S_MB_2U(SCH_1):M_G_CPU1_SB_DQS_DN(0)
    U1 DJ33 DDR6_SB_DQS_DN0 SOCKET4677_AZIF0045P001C01CS-SA   I168 @S9S_MB_2U_LIB.S9S_MB_2U(SCH_1):PAGE57
   J29  105 DQS0_B_C SCONN288_ADR50017P130CC-SCONN2A   I180 @S9S_MB_2U_LIB.S9S_MB_2U(SCH_1):PAGE110
   J30  105 DQS0_B_C SCONN288_ADR50017P087CC-SCONN2A   I180 @S9S_MB_2U_LIB.S9S_MB_2U(SCH_1):PAGE111

M_G_CPU1_SB_DQS_DN<1> @S9S_MB_2U_LIB.S9S_MB_2U(SCH_1):M_G_CPU1_SB_DQS_DN(1)
    U1 DJ27 DDR6_SB_DQS_DN1 SOCKET4677_AZIF0045P001C01CS-SA   I168 @S9S_MB_2U_LIB.S9S_MB_2U(SCH_1):PAGE57
   J29  116 DQS1_B_C SCONN288_ADR50017P130CC-SCONN2A   I180 @S9S_MB_2U_LIB.S9S_MB_2U(SCH_1):PAGE110
   J30  116 DQS1_B_C SCONN288_ADR50017P087CC-SCONN2A   I180 @S9S_MB_2U_LIB.S9S_MB_2U(SCH_1):PAGE111

M_G_CPU1_SB_DQS_DN<2> @S9S_MB_2U_LIB.S9S_MB_2U(SCH_1):M_G_CPU1_SB_DQS_DN(2)
    U1 DV24 DDR6_SB_DQS_DN2 SOCKET4677_AZIF0045P001C01CS-SA   I168 @S9S_MB_2U_LIB.S9S_MB_2U(SCH_1):PAGE57
   J29  127 DQS2_B_C SCONN288_ADR50017P130CC-SCONN2A   I180 @S9S_MB_2U_LIB.S9S_MB_2U(SCH_1):PAGE110
   J30  127 DQS2_B_C SCONN288_ADR50017P087CC-SCONN2A   I180 @S9S_MB_2U_LIB.S9S_MB_2U(SCH_1):PAGE111

M_G_CPU1_SB_DQS_DN<3> @S9S_MB_2U_LIB.S9S_MB_2U(SCH_1):M_G_CPU1_SB_DQS_DN(3)
    U1  EP6 DDR6_SB_DQS_DN3 SOCKET4677_AZIF0045P001C01CS-SA   I168 @S9S_MB_2U_LIB.S9S_MB_2U(SCH_1):PAGE57
   J29  138 DQS3_B_C SCONN288_ADR50017P130CC-SCONN2A   I180 @S9S_MB_2U_LIB.S9S_MB_2U(SCH_1):PAGE110
   J30  138 DQS3_B_C SCONN288_ADR50017P087CC-SCONN2A   I180 @S9S_MB_2U_LIB.S9S_MB_2U(SCH_1):PAGE111

M_G_CPU1_SB_DQS_DN<4> @S9S_MB_2U_LIB.S9S_MB_2U(SCH_1):M_G_CPU1_SB_DQS_DN(4)
    U1 EB36 DDR6_SB_DQS_DN4 SOCKET4677_AZIF0045P001C01CS-SA   I168 @S9S_MB_2U_LIB.S9S_MB_2U(SCH_1):PAGE57
   J29  238 DQS4_B_C SCONN288_ADR50017P130CC-SCONN2A   I180 @S9S_MB_2U_LIB.S9S_MB_2U(SCH_1):PAGE110
   J30  238 DQS4_B_C SCONN288_ADR50017P087CC-SCONN2A   I180 @S9S_MB_2U_LIB.S9S_MB_2U(SCH_1):PAGE111

M_G_CPU1_SB_DQS_DN<5> @S9S_MB_2U_LIB.S9S_MB_2U(SCH_1):M_G_CPU1_SB_DQS_DN(5)
    U1 DR33 DDR6_SB_DQS_DN5 SOCKET4677_AZIF0045P001C01CS-SA   I168 @S9S_MB_2U_LIB.S9S_MB_2U(SCH_1):PAGE57
   J29  249 DQS5_B_C||TDQS5_B_C SCONN288_ADR50017P130CC-SCONN2A   I180 @S9S_MB_2U_LIB.S9S_MB_2U(SCH_1):PAGE110
   J30  249 DQS5_B_C||TDQS5_B_C SCONN288_ADR50017P087CC-SCONN2A   I180 @S9S_MB_2U_LIB.S9S_MB_2U(SCH_1):PAGE111

M_G_CPU1_SB_DQS_DN<6> @S9S_MB_2U_LIB.S9S_MB_2U(SCH_1):M_G_CPU1_SB_DQS_DN(6)
    U1 DN27 DDR6_SB_DQS_DN6 SOCKET4677_AZIF0045P001C01CS-SA   I168 @S9S_MB_2U_LIB.S9S_MB_2U(SCH_1):PAGE57
   J29  260 DQS6_B_C||TDQS6_B_C SCONN288_ADR50017P130CC-SCONN2A   I180 @S9S_MB_2U_LIB.S9S_MB_2U(SCH_1):PAGE110
   J30  260 DQS6_B_C||TDQS6_B_C SCONN288_ADR50017P087CC-SCONN2A   I180 @S9S_MB_2U_LIB.S9S_MB_2U(SCH_1):PAGE111

M_G_CPU1_SB_DQS_DN<7> @S9S_MB_2U_LIB.S9S_MB_2U(SCH_1):M_G_CPU1_SB_DQS_DN(7)
    U1 EB24 DDR6_SB_DQS_DN7 SOCKET4677_AZIF0045P001C01CS-SA   I168 @S9S_MB_2U_LIB.S9S_MB_2U(SCH_1):PAGE57
   J29  271 DQS7_B_C||TDQS7_B_C SCONN288_ADR50017P130CC-SCONN2A   I180 @S9S_MB_2U_LIB.S9S_MB_2U(SCH_1):PAGE110
   J30  271 DQS7_B_C||TDQS7_B_C SCONN288_ADR50017P087CC-SCONN2A   I180 @S9S_MB_2U_LIB.S9S_MB_2U(SCH_1):PAGE111

M_G_CPU1_SB_DQS_DN<8> @S9S_MB_2U_LIB.S9S_MB_2U(SCH_1):M_G_CPU1_SB_DQS_DN(8)
    U1  EM6 DDR6_SB_DQS_DN8 SOCKET4677_AZIF0045P001C01CS-SA   I168 @S9S_MB_2U_LIB.S9S_MB_2U(SCH_1):PAGE57
   J29  282 DQS8_B_C||TDQS8_B_C SCONN288_ADR50017P130CC-SCONN2A   I180 @S9S_MB_2U_LIB.S9S_MB_2U(SCH_1):PAGE110
   J30  282 DQS8_B_C||TDQS8_B_C SCONN288_ADR50017P087CC-SCONN2A   I180 @S9S_MB_2U_LIB.S9S_MB_2U(SCH_1):PAGE111

M_G_CPU1_SB_DQS_DN<9> @S9S_MB_2U_LIB.S9S_MB_2U(SCH_1):M_G_CPU1_SB_DQS_DN(9)
    U1 DV36 DDR6_SB_DQS_DN9 SOCKET4677_AZIF0045P001C01CS-SA   I168 @S9S_MB_2U_LIB.S9S_MB_2U(SCH_1):PAGE57
   J29   94 DQS9_B_C||TDQS9_B_C SCONN288_ADR50017P130CC-SCONN2A   I180 @S9S_MB_2U_LIB.S9S_MB_2U(SCH_1):PAGE110
   J30   94 DQS9_B_C||TDQS9_B_C SCONN288_ADR50017P087CC-SCONN2A   I180 @S9S_MB_2U_LIB.S9S_MB_2U(SCH_1):PAGE111

M_G_CPU1_SB_DQS_DP<0> @S9S_MB_2U_LIB.S9S_MB_2U(SCH_1):M_G_CPU1_SB_DQS_DP(0)
    U1 DL33 DDR6_SB_DQS_DP0 SOCKET4677_AZIF0045P001C01CS-SA   I168 @S9S_MB_2U_LIB.S9S_MB_2U(SCH_1):PAGE57
   J29  104 DQS0_B_T SCONN288_ADR50017P130CC-SCONN2A   I180 @S9S_MB_2U_LIB.S9S_MB_2U(SCH_1):PAGE110
   J30  104 DQS0_B_T SCONN288_ADR50017P087CC-SCONN2A   I180 @S9S_MB_2U_LIB.S9S_MB_2U(SCH_1):PAGE111

M_G_CPU1_SB_DQS_DP<1> @S9S_MB_2U_LIB.S9S_MB_2U(SCH_1):M_G_CPU1_SB_DQS_DP(1)
    U1 DL27 DDR6_SB_DQS_DP1 SOCKET4677_AZIF0045P001C01CS-SA   I168 @S9S_MB_2U_LIB.S9S_MB_2U(SCH_1):PAGE57
   J29  115 DQS1_B_T SCONN288_ADR50017P130CC-SCONN2A   I180 @S9S_MB_2U_LIB.S9S_MB_2U(SCH_1):PAGE110
   J30  115 DQS1_B_T SCONN288_ADR50017P087CC-SCONN2A   I180 @S9S_MB_2U_LIB.S9S_MB_2U(SCH_1):PAGE111

M_G_CPU1_SB_DQS_DP<2> @S9S_MB_2U_LIB.S9S_MB_2U(SCH_1):M_G_CPU1_SB_DQS_DP(2)
    U1 DT24 DDR6_SB_DQS_DP2 SOCKET4677_AZIF0045P001C01CS-SA   I168 @S9S_MB_2U_LIB.S9S_MB_2U(SCH_1):PAGE57
   J29  126 DQS2_B_T SCONN288_ADR50017P130CC-SCONN2A   I180 @S9S_MB_2U_LIB.S9S_MB_2U(SCH_1):PAGE110
   J30  126 DQS2_B_T SCONN288_ADR50017P087CC-SCONN2A   I180 @S9S_MB_2U_LIB.S9S_MB_2U(SCH_1):PAGE111

M_G_CPU1_SB_DQS_DP<3> @S9S_MB_2U_LIB.S9S_MB_2U(SCH_1):M_G_CPU1_SB_DQS_DP(3)
    U1  EN7 DDR6_SB_DQS_DP3 SOCKET4677_AZIF0045P001C01CS-SA   I168 @S9S_MB_2U_LIB.S9S_MB_2U(SCH_1):PAGE57
   J29  137 DQS3_B_T SCONN288_ADR50017P130CC-SCONN2A   I180 @S9S_MB_2U_LIB.S9S_MB_2U(SCH_1):PAGE110
   J30  137 DQS3_B_T SCONN288_ADR50017P087CC-SCONN2A   I180 @S9S_MB_2U_LIB.S9S_MB_2U(SCH_1):PAGE111

M_G_CPU1_SB_DQS_DP<4> @S9S_MB_2U_LIB.S9S_MB_2U(SCH_1):M_G_CPU1_SB_DQS_DP(4)
    U1 DY36 DDR6_SB_DQS_DP4 SOCKET4677_AZIF0045P001C01CS-SA   I168 @S9S_MB_2U_LIB.S9S_MB_2U(SCH_1):PAGE57
   J29  239 DQS4_B_T SCONN288_ADR50017P130CC-SCONN2A   I180 @S9S_MB_2U_LIB.S9S_MB_2U(SCH_1):PAGE110
   J30  239 DQS4_B_T SCONN288_ADR50017P087CC-SCONN2A   I180 @S9S_MB_2U_LIB.S9S_MB_2U(SCH_1):PAGE111

M_G_CPU1_SB_DQS_DP<5> @S9S_MB_2U_LIB.S9S_MB_2U(SCH_1):M_G_CPU1_SB_DQS_DP(5)
    U1 DN33 DDR6_SB_DQS_DP5 SOCKET4677_AZIF0045P001C01CS-SA   I168 @S9S_MB_2U_LIB.S9S_MB_2U(SCH_1):PAGE57
   J29  250 DQS5_B_T||TDQS5_B_T SCONN288_ADR50017P130CC-SCONN2A   I180 @S9S_MB_2U_LIB.S9S_MB_2U(SCH_1):PAGE110
   J30  250 DQS5_B_T||TDQS5_B_T SCONN288_ADR50017P087CC-SCONN2A   I180 @S9S_MB_2U_LIB.S9S_MB_2U(SCH_1):PAGE111

M_G_CPU1_SB_DQS_DP<6> @S9S_MB_2U_LIB.S9S_MB_2U(SCH_1):M_G_CPU1_SB_DQS_DP(6)
    U1 DR27 DDR6_SB_DQS_DP6 SOCKET4677_AZIF0045P001C01CS-SA   I168 @S9S_MB_2U_LIB.S9S_MB_2U(SCH_1):PAGE57
   J29  261 DQS6_B_T||TDQS6_B_T SCONN288_ADR50017P130CC-SCONN2A   I180 @S9S_MB_2U_LIB.S9S_MB_2U(SCH_1):PAGE110
   J30  261 DQS6_B_T||TDQS6_B_T SCONN288_ADR50017P087CC-SCONN2A   I180 @S9S_MB_2U_LIB.S9S_MB_2U(SCH_1):PAGE111

M_G_CPU1_SB_DQS_DP<7> @S9S_MB_2U_LIB.S9S_MB_2U(SCH_1):M_G_CPU1_SB_DQS_DP(7)
    U1 DY24 DDR6_SB_DQS_DP7 SOCKET4677_AZIF0045P001C01CS-SA   I168 @S9S_MB_2U_LIB.S9S_MB_2U(SCH_1):PAGE57
   J29  272 DQS7_B_T||TDQS7_B_T SCONN288_ADR50017P130CC-SCONN2A   I180 @S9S_MB_2U_LIB.S9S_MB_2U(SCH_1):PAGE110
   J30  272 DQS7_B_T||TDQS7_B_T SCONN288_ADR50017P087CC-SCONN2A   I180 @S9S_MB_2U_LIB.S9S_MB_2U(SCH_1):PAGE111

M_G_CPU1_SB_DQS_DP<8> @S9S_MB_2U_LIB.S9S_MB_2U(SCH_1):M_G_CPU1_SB_DQS_DP(8)
    U1  EN5 DDR6_SB_DQS_DP8 SOCKET4677_AZIF0045P001C01CS-SA   I168 @S9S_MB_2U_LIB.S9S_MB_2U(SCH_1):PAGE57
   J29  283 DQS8_B_T||TDQS8_B_T SCONN288_ADR50017P130CC-SCONN2A   I180 @S9S_MB_2U_LIB.S9S_MB_2U(SCH_1):PAGE110
   J30  283 DQS8_B_T||TDQS8_B_T SCONN288_ADR50017P087CC-SCONN2A   I180 @S9S_MB_2U_LIB.S9S_MB_2U(SCH_1):PAGE111

M_G_CPU1_SB_DQS_DP<9> @S9S_MB_2U_LIB.S9S_MB_2U(SCH_1):M_G_CPU1_SB_DQS_DP(9)
    U1 DT36 DDR6_SB_DQS_DP9 SOCKET4677_AZIF0045P001C01CS-SA   I168 @S9S_MB_2U_LIB.S9S_MB_2U(SCH_1):PAGE57
   J29   93 DQS9_B_T||TDQS9_B_T||DBI4_B_N SCONN288_ADR50017P130CC-SCONN2A   I180 @S9S_MB_2U_LIB.S9S_MB_2U(SCH_1):PAGE110
   J30   93 DQS9_B_T||TDQS9_B_T||DBI4_B_N SCONN288_ADR50017P087CC-SCONN2A   I180 @S9S_MB_2U_LIB.S9S_MB_2U(SCH_1):PAGE111

M_G_CPU1_SB_PAR @S9S_MB_2U_LIB.S9S_MB_2U(SCH_1):M_G_CPU1_SB_PAR
    U1 EB42 DDR6_SB_PAR SOCKET4677_AZIF0045P001C01CS-SA   I168 @S9S_MB_2U_LIB.S9S_MB_2U(SCH_1):PAGE57
   J29  227  PAR_B SCONN288_ADR50017P130CC-SCONN2A   I179 @S9S_MB_2U_LIB.S9S_MB_2U(SCH_1):PAGE110
   J30  227  PAR_B SCONN288_ADR50017P087CC-SCONN2A   I179 @S9S_MB_2U_LIB.S9S_MB_2U(SCH_1):PAGE111

M_G_CPU1_SB_RSP<0> @S9S_MB_2U_LIB.S9S_MB_2U(SCH_1):M_G_CPU1_SB_RSP(0)
    U1 DU48 DDR6_B_RSP0 SOCKET4677_AZIF0045P001C01CS-SA   I168 @S9S_MB_2U_LIB.S9S_MB_2U(SCH_1):PAGE57
   J29   87 LBS||RSP_B_N SCONN288_ADR50017P130CC-SCONN2A   I179 @S9S_MB_2U_LIB.S9S_MB_2U(SCH_1):PAGE110

M_G_CPU1_SB_RSP<1> @S9S_MB_2U_LIB.S9S_MB_2U(SCH_1):M_G_CPU1_SB_RSP(1)
    U1 DV47 DDR6_B_RSP1 SOCKET4677_AZIF0045P001C01CS-SA   I168 @S9S_MB_2U_LIB.S9S_MB_2U(SCH_1):PAGE57
   J30   87 LBS||RSP_B_N SCONN288_ADR50017P087CC-SCONN2A   I179 @S9S_MB_2U_LIB.S9S_MB_2U(SCH_1):PAGE111

M_H_CPU0_ALERT_N @S9S_MB_2U_LIB.S9S_MB_2U(SCH_1):M_H_CPU0_ALERT_N
    U2 CY51 DDR7_ALERT_N SOCKET4677_AZIF0045P001C01CS-SA   I169 @S9S_MB_2U_LIB.S9S_MB_2U(SCH_1):PAGE27
   J15   62 ALERT_N SCONN288_ADR50017P130CC-SCONN2A    I48 @S9S_MB_2U_LIB.S9S_MB_2U(SCH_1):PAGE96
   J16   62 ALERT_N SCONN288_ADR50017P087CC-SCONN2A     I6 @S9S_MB_2U_LIB.S9S_MB_2U(SCH_1):PAGE97

M_H_CPU0_CLK_DN<0> @S9S_MB_2U_LIB.S9S_MB_2U(SCH_1):M_H_CPU0_CLK_DN(0)
    U2 DH42 DDR7_CLK_DN0 SOCKET4677_AZIF0045P001C01CS-SA   I169 @S9S_MB_2U_LIB.S9S_MB_2U(SCH_1):PAGE27
   J15  218   CK_C SCONN288_ADR50017P130CC-SCONN2A    I48 @S9S_MB_2U_LIB.S9S_MB_2U(SCH_1):PAGE96

M_H_CPU0_CLK_DN<1> @S9S_MB_2U_LIB.S9S_MB_2U(SCH_1):M_H_CPU0_CLK_DN(1)
    U2 DD42 DDR7_CLK_DN1 SOCKET4677_AZIF0045P001C01CS-SA   I169 @S9S_MB_2U_LIB.S9S_MB_2U(SCH_1):PAGE27
   J16  218   CK_C SCONN288_ADR50017P087CC-SCONN2A     I6 @S9S_MB_2U_LIB.S9S_MB_2U(SCH_1):PAGE97

M_H_CPU0_CLK_DP<0> @S9S_MB_2U_LIB.S9S_MB_2U(SCH_1):M_H_CPU0_CLK_DP(0)
    U2 DF42 DDR7_CLK_DP0 SOCKET4677_AZIF0045P001C01CS-SA   I169 @S9S_MB_2U_LIB.S9S_MB_2U(SCH_1):PAGE27
   J15  217   CK_T SCONN288_ADR50017P130CC-SCONN2A    I48 @S9S_MB_2U_LIB.S9S_MB_2U(SCH_1):PAGE96

M_H_CPU0_CLK_DP<1> @S9S_MB_2U_LIB.S9S_MB_2U(SCH_1):M_H_CPU0_CLK_DP(1)
    U2 DB42 DDR7_CLK_DP1 SOCKET4677_AZIF0045P001C01CS-SA   I169 @S9S_MB_2U_LIB.S9S_MB_2U(SCH_1):PAGE27
   J16  217   CK_T SCONN288_ADR50017P087CC-SCONN2A     I6 @S9S_MB_2U_LIB.S9S_MB_2U(SCH_1):PAGE97

M_H_CPU0_SA_CA<0> @S9S_MB_2U_LIB.S9S_MB_2U(SCH_1):M_H_CPU0_SA_CA(0)
    U2 DB49 DDR7_SA_CA0 SOCKET4677_AZIF0045P001C01CS-SA   I169 @S9S_MB_2U_LIB.S9S_MB_2U(SCH_1):PAGE27
   J15   66  CA0_A SCONN288_ADR50017P130CC-SCONN2A    I48 @S9S_MB_2U_LIB.S9S_MB_2U(SCH_1):PAGE96
   J16   66  CA0_A SCONN288_ADR50017P087CC-SCONN2A     I6 @S9S_MB_2U_LIB.S9S_MB_2U(SCH_1):PAGE97

M_H_CPU0_SA_CA<1> @S9S_MB_2U_LIB.S9S_MB_2U(SCH_1):M_H_CPU0_SA_CA(1)
    U2 DH49 DDR7_SA_CA1 SOCKET4677_AZIF0045P001C01CS-SA   I169 @S9S_MB_2U_LIB.S9S_MB_2U(SCH_1):PAGE27
   J15  211  CA1_A SCONN288_ADR50017P130CC-SCONN2A    I48 @S9S_MB_2U_LIB.S9S_MB_2U(SCH_1):PAGE96
   J16  211  CA1_A SCONN288_ADR50017P087CC-SCONN2A     I6 @S9S_MB_2U_LIB.S9S_MB_2U(SCH_1):PAGE97

M_H_CPU0_SA_CA<2> @S9S_MB_2U_LIB.S9S_MB_2U(SCH_1):M_H_CPU0_SA_CA(2)
    U2 DC48 DDR7_SA_CA2 SOCKET4677_AZIF0045P001C01CS-SA   I169 @S9S_MB_2U_LIB.S9S_MB_2U(SCH_1):PAGE27
   J15   68  CA2_A SCONN288_ADR50017P130CC-SCONN2A    I48 @S9S_MB_2U_LIB.S9S_MB_2U(SCH_1):PAGE96
   J16   68  CA2_A SCONN288_ADR50017P087CC-SCONN2A     I6 @S9S_MB_2U_LIB.S9S_MB_2U(SCH_1):PAGE97

M_H_CPU0_SA_CA<3> @S9S_MB_2U_LIB.S9S_MB_2U(SCH_1):M_H_CPU0_SA_CA(3)
    U2 DG48 DDR7_SA_CA3 SOCKET4677_AZIF0045P001C01CS-SA   I169 @S9S_MB_2U_LIB.S9S_MB_2U(SCH_1):PAGE27
   J15  213  CA3_A SCONN288_ADR50017P130CC-SCONN2A    I48 @S9S_MB_2U_LIB.S9S_MB_2U(SCH_1):PAGE96
   J16  213  CA3_A SCONN288_ADR50017P087CC-SCONN2A     I6 @S9S_MB_2U_LIB.S9S_MB_2U(SCH_1):PAGE97

M_H_CPU0_SA_CA<4> @S9S_MB_2U_LIB.S9S_MB_2U(SCH_1):M_H_CPU0_SA_CA(4)
    U2 DD47 DDR7_SA_CA4 SOCKET4677_AZIF0045P001C01CS-SA   I169 @S9S_MB_2U_LIB.S9S_MB_2U(SCH_1):PAGE27
   J15   70  CA4_A SCONN288_ADR50017P130CC-SCONN2A    I48 @S9S_MB_2U_LIB.S9S_MB_2U(SCH_1):PAGE96
   J16   70  CA4_A SCONN288_ADR50017P087CC-SCONN2A     I6 @S9S_MB_2U_LIB.S9S_MB_2U(SCH_1):PAGE97

M_H_CPU0_SA_CA<5> @S9S_MB_2U_LIB.S9S_MB_2U(SCH_1):M_H_CPU0_SA_CA(5)
    U2 DF47 DDR7_SA_CA5 SOCKET4677_AZIF0045P001C01CS-SA   I169 @S9S_MB_2U_LIB.S9S_MB_2U(SCH_1):PAGE27
   J15  215  CA5_A SCONN288_ADR50017P130CC-SCONN2A    I48 @S9S_MB_2U_LIB.S9S_MB_2U(SCH_1):PAGE96
   J16  215  CA5_A SCONN288_ADR50017P087CC-SCONN2A     I6 @S9S_MB_2U_LIB.S9S_MB_2U(SCH_1):PAGE97

M_H_CPU0_SA_CA<6> @S9S_MB_2U_LIB.S9S_MB_2U(SCH_1):M_H_CPU0_SA_CA(6)
    U2 DC41 DDR7_SA_CA6 SOCKET4677_AZIF0045P001C01CS-SA   I169 @S9S_MB_2U_LIB.S9S_MB_2U(SCH_1):PAGE27
   J15   72  CA6_A SCONN288_ADR50017P130CC-SCONN2A    I48 @S9S_MB_2U_LIB.S9S_MB_2U(SCH_1):PAGE96
   J16   72  CA6_A SCONN288_ADR50017P087CC-SCONN2A     I6 @S9S_MB_2U_LIB.S9S_MB_2U(SCH_1):PAGE97

M_H_CPU0_SA_CB<0> @S9S_MB_2U_LIB.S9S_MB_2U(SCH_1):M_H_CPU0_SA_CB(0)
    U2 DD57 DDR7_SA_ECC0 SOCKET4677_AZIF0045P001C01CS-SA   I169 @S9S_MB_2U_LIB.S9S_MB_2U(SCH_1):PAGE27
   J15   51  CB0_A SCONN288_ADR50017P130CC-SCONN2A    I48 @S9S_MB_2U_LIB.S9S_MB_2U(SCH_1):PAGE96
   J16   51  CB0_A SCONN288_ADR50017P087CC-SCONN2A     I6 @S9S_MB_2U_LIB.S9S_MB_2U(SCH_1):PAGE97

M_H_CPU0_SA_CB<1> @S9S_MB_2U_LIB.S9S_MB_2U(SCH_1):M_H_CPU0_SA_CB(1)
    U2 DC56 DDR7_SA_ECC1 SOCKET4677_AZIF0045P001C01CS-SA   I169 @S9S_MB_2U_LIB.S9S_MB_2U(SCH_1):PAGE27
   J15   53  CB1_A SCONN288_ADR50017P130CC-SCONN2A    I48 @S9S_MB_2U_LIB.S9S_MB_2U(SCH_1):PAGE96
   J16   53  CB1_A SCONN288_ADR50017P087CC-SCONN2A     I6 @S9S_MB_2U_LIB.S9S_MB_2U(SCH_1):PAGE97

M_H_CPU0_SA_CB<2> @S9S_MB_2U_LIB.S9S_MB_2U(SCH_1):M_H_CPU0_SA_CB(2)
    U2 DF57 DDR7_SA_ECC2 SOCKET4677_AZIF0045P001C01CS-SA   I169 @S9S_MB_2U_LIB.S9S_MB_2U(SCH_1):PAGE27
   J15  196  CB2_A SCONN288_ADR50017P130CC-SCONN2A    I48 @S9S_MB_2U_LIB.S9S_MB_2U(SCH_1):PAGE96
   J16  196  CB2_A SCONN288_ADR50017P087CC-SCONN2A     I6 @S9S_MB_2U_LIB.S9S_MB_2U(SCH_1):PAGE97

M_H_CPU0_SA_CB<3> @S9S_MB_2U_LIB.S9S_MB_2U(SCH_1):M_H_CPU0_SA_CB(3)
    U2 DG56 DDR7_SA_ECC3 SOCKET4677_AZIF0045P001C01CS-SA   I169 @S9S_MB_2U_LIB.S9S_MB_2U(SCH_1):PAGE27
   J15  198  CB3_A SCONN288_ADR50017P130CC-SCONN2A    I48 @S9S_MB_2U_LIB.S9S_MB_2U(SCH_1):PAGE96
   J16  198  CB3_A SCONN288_ADR50017P087CC-SCONN2A     I6 @S9S_MB_2U_LIB.S9S_MB_2U(SCH_1):PAGE97

M_H_CPU0_SA_CB<4> @S9S_MB_2U_LIB.S9S_MB_2U(SCH_1):M_H_CPU0_SA_CB(4)
    U2 DC54 DDR7_SA_ECC4 SOCKET4677_AZIF0045P001C01CS-SA   I169 @S9S_MB_2U_LIB.S9S_MB_2U(SCH_1):PAGE27
   J15   58  CB4_A SCONN288_ADR50017P130CC-SCONN2A    I48 @S9S_MB_2U_LIB.S9S_MB_2U(SCH_1):PAGE96
   J16   58  CB4_A SCONN288_ADR50017P087CC-SCONN2A     I6 @S9S_MB_2U_LIB.S9S_MB_2U(SCH_1):PAGE97

M_H_CPU0_SA_CB<5> @S9S_MB_2U_LIB.S9S_MB_2U(SCH_1):M_H_CPU0_SA_CB(5)
    U2 DD53 DDR7_SA_ECC5 SOCKET4677_AZIF0045P001C01CS-SA   I169 @S9S_MB_2U_LIB.S9S_MB_2U(SCH_1):PAGE27
   J15   60  CB5_A SCONN288_ADR50017P130CC-SCONN2A    I48 @S9S_MB_2U_LIB.S9S_MB_2U(SCH_1):PAGE96
   J16   60  CB5_A SCONN288_ADR50017P087CC-SCONN2A     I6 @S9S_MB_2U_LIB.S9S_MB_2U(SCH_1):PAGE97

M_H_CPU0_SA_CB<6> @S9S_MB_2U_LIB.S9S_MB_2U(SCH_1):M_H_CPU0_SA_CB(6)
    U2 DG54 DDR7_SA_ECC6 SOCKET4677_AZIF0045P001C01CS-SA   I169 @S9S_MB_2U_LIB.S9S_MB_2U(SCH_1):PAGE27
   J15  203  CB6_A SCONN288_ADR50017P130CC-SCONN2A    I48 @S9S_MB_2U_LIB.S9S_MB_2U(SCH_1):PAGE96
   J16  203  CB6_A SCONN288_ADR50017P087CC-SCONN2A     I6 @S9S_MB_2U_LIB.S9S_MB_2U(SCH_1):PAGE97

M_H_CPU0_SA_CB<7> @S9S_MB_2U_LIB.S9S_MB_2U(SCH_1):M_H_CPU0_SA_CB(7)
    U2 DF53 DDR7_SA_ECC7 SOCKET4677_AZIF0045P001C01CS-SA   I169 @S9S_MB_2U_LIB.S9S_MB_2U(SCH_1):PAGE27
   J15  205  CB7_A SCONN288_ADR50017P130CC-SCONN2A    I48 @S9S_MB_2U_LIB.S9S_MB_2U(SCH_1):PAGE96
   J16  205  CB7_A SCONN288_ADR50017P087CC-SCONN2A     I6 @S9S_MB_2U_LIB.S9S_MB_2U(SCH_1):PAGE97

M_H_CPU0_SA_CS_N<0> @S9S_MB_2U_LIB.S9S_MB_2U(SCH_1):M_H_CPU0_SA_CS_N(0)
    U2 DF51 DDR7_SA_CS_N0 SOCKET4677_AZIF0045P001C01CS-SA   I169 @S9S_MB_2U_LIB.S9S_MB_2U(SCH_1):PAGE27
   J15   64 CS0_A_N SCONN288_ADR50017P130CC-SCONN2A    I48 @S9S_MB_2U_LIB.S9S_MB_2U(SCH_1):PAGE96

M_H_CPU0_SA_CS_N<1> @S9S_MB_2U_LIB.S9S_MB_2U(SCH_1):M_H_CPU0_SA_CS_N(1)
    U2 DG50 DDR7_SA_CS_N1 SOCKET4677_AZIF0045P001C01CS-SA   I169 @S9S_MB_2U_LIB.S9S_MB_2U(SCH_1):PAGE27
   J15  209 CS1_A_N SCONN288_ADR50017P130CC-SCONN2A    I48 @S9S_MB_2U_LIB.S9S_MB_2U(SCH_1):PAGE96

M_H_CPU0_SA_CS_N<2> @S9S_MB_2U_LIB.S9S_MB_2U(SCH_1):M_H_CPU0_SA_CS_N(2)
    U2 DD51 DDR7_SA_CS_N2 SOCKET4677_AZIF0045P001C01CS-SA   I169 @S9S_MB_2U_LIB.S9S_MB_2U(SCH_1):PAGE27
   J16   64 CS0_A_N SCONN288_ADR50017P087CC-SCONN2A     I6 @S9S_MB_2U_LIB.S9S_MB_2U(SCH_1):PAGE97

M_H_CPU0_SA_CS_N<3> @S9S_MB_2U_LIB.S9S_MB_2U(SCH_1):M_H_CPU0_SA_CS_N(3)
    U2 DC50 DDR7_SA_CS_N3 SOCKET4677_AZIF0045P001C01CS-SA   I169 @S9S_MB_2U_LIB.S9S_MB_2U(SCH_1):PAGE27
   J16  209 CS1_A_N SCONN288_ADR50017P087CC-SCONN2A     I6 @S9S_MB_2U_LIB.S9S_MB_2U(SCH_1):PAGE97

M_H_CPU0_SA_DQ<0> @S9S_MB_2U_LIB.S9S_MB_2U(SCH_1):M_H_CPU0_SA_DQ(0)
    U2 DY79 DDR7_SA_DQ0 SOCKET4677_AZIF0045P001C01CS-SA   I169 @S9S_MB_2U_LIB.S9S_MB_2U(SCH_1):PAGE27
   J15    7  DQ0_A SCONN288_ADR50017P130CC-SCONN2A    I48 @S9S_MB_2U_LIB.S9S_MB_2U(SCH_1):PAGE96
   J16    7  DQ0_A SCONN288_ADR50017P087CC-SCONN2A     I6 @S9S_MB_2U_LIB.S9S_MB_2U(SCH_1):PAGE97

M_H_CPU0_SA_DQ<10> @S9S_MB_2U_LIB.S9S_MB_2U(SCH_1):M_H_CPU0_SA_DQ(10)
    U2 DF75 DDR7_SA_DQ10 SOCKET4677_AZIF0045P001C01CS-SA   I169 @S9S_MB_2U_LIB.S9S_MB_2U(SCH_1):PAGE27
   J15  163 DQ10_A SCONN288_ADR50017P130CC-SCONN2A    I48 @S9S_MB_2U_LIB.S9S_MB_2U(SCH_1):PAGE96
   J16  163 DQ10_A SCONN288_ADR50017P087CC-SCONN2A     I6 @S9S_MB_2U_LIB.S9S_MB_2U(SCH_1):PAGE97

M_H_CPU0_SA_DQ<11> @S9S_MB_2U_LIB.S9S_MB_2U(SCH_1):M_H_CPU0_SA_DQ(11)
    U2 DG74 DDR7_SA_DQ11 SOCKET4677_AZIF0045P001C01CS-SA   I169 @S9S_MB_2U_LIB.S9S_MB_2U(SCH_1):PAGE27
   J15  165 DQ11_A SCONN288_ADR50017P130CC-SCONN2A    I48 @S9S_MB_2U_LIB.S9S_MB_2U(SCH_1):PAGE96
   J16  165 DQ11_A SCONN288_ADR50017P087CC-SCONN2A     I6 @S9S_MB_2U_LIB.S9S_MB_2U(SCH_1):PAGE97

M_H_CPU0_SA_DQ<12> @S9S_MB_2U_LIB.S9S_MB_2U(SCH_1):M_H_CPU0_SA_DQ(12)
    U2 DC72 DDR7_SA_DQ12 SOCKET4677_AZIF0045P001C01CS-SA   I169 @S9S_MB_2U_LIB.S9S_MB_2U(SCH_1):PAGE27
   J15   25 DQ12_A SCONN288_ADR50017P130CC-SCONN2A    I48 @S9S_MB_2U_LIB.S9S_MB_2U(SCH_1):PAGE96
   J16   25 DQ12_A SCONN288_ADR50017P087CC-SCONN2A     I6 @S9S_MB_2U_LIB.S9S_MB_2U(SCH_1):PAGE97

M_H_CPU0_SA_DQ<13> @S9S_MB_2U_LIB.S9S_MB_2U(SCH_1):M_H_CPU0_SA_DQ(13)
    U2 DD71 DDR7_SA_DQ13 SOCKET4677_AZIF0045P001C01CS-SA   I169 @S9S_MB_2U_LIB.S9S_MB_2U(SCH_1):PAGE27
   J15   27 DQ13_A SCONN288_ADR50017P130CC-SCONN2A    I48 @S9S_MB_2U_LIB.S9S_MB_2U(SCH_1):PAGE96
   J16   27 DQ13_A SCONN288_ADR50017P087CC-SCONN2A     I6 @S9S_MB_2U_LIB.S9S_MB_2U(SCH_1):PAGE97

M_H_CPU0_SA_DQ<14> @S9S_MB_2U_LIB.S9S_MB_2U(SCH_1):M_H_CPU0_SA_DQ(14)
    U2 DG72 DDR7_SA_DQ14 SOCKET4677_AZIF0045P001C01CS-SA   I169 @S9S_MB_2U_LIB.S9S_MB_2U(SCH_1):PAGE27
   J15  170 DQ14_A SCONN288_ADR50017P130CC-SCONN2A    I48 @S9S_MB_2U_LIB.S9S_MB_2U(SCH_1):PAGE96
   J16  170 DQ14_A SCONN288_ADR50017P087CC-SCONN2A     I6 @S9S_MB_2U_LIB.S9S_MB_2U(SCH_1):PAGE97

M_H_CPU0_SA_DQ<15> @S9S_MB_2U_LIB.S9S_MB_2U(SCH_1):M_H_CPU0_SA_DQ(15)
    U2 DF71 DDR7_SA_DQ15 SOCKET4677_AZIF0045P001C01CS-SA   I169 @S9S_MB_2U_LIB.S9S_MB_2U(SCH_1):PAGE27
   J15  172 DQ15_A SCONN288_ADR50017P130CC-SCONN2A    I48 @S9S_MB_2U_LIB.S9S_MB_2U(SCH_1):PAGE96
   J16  172 DQ15_A SCONN288_ADR50017P087CC-SCONN2A     I6 @S9S_MB_2U_LIB.S9S_MB_2U(SCH_1):PAGE97

M_H_CPU0_SA_DQ<16> @S9S_MB_2U_LIB.S9S_MB_2U(SCH_1):M_H_CPU0_SA_DQ(16)
    U2 DD69 DDR7_SA_DQ16 SOCKET4677_AZIF0045P001C01CS-SA   I169 @S9S_MB_2U_LIB.S9S_MB_2U(SCH_1):PAGE27
   J15   29 DQ16_A SCONN288_ADR50017P130CC-SCONN2A    I48 @S9S_MB_2U_LIB.S9S_MB_2U(SCH_1):PAGE96
   J16   29 DQ16_A SCONN288_ADR50017P087CC-SCONN2A     I6 @S9S_MB_2U_LIB.S9S_MB_2U(SCH_1):PAGE97

M_H_CPU0_SA_DQ<17> @S9S_MB_2U_LIB.S9S_MB_2U(SCH_1):M_H_CPU0_SA_DQ(17)
    U2 DC68 DDR7_SA_DQ17 SOCKET4677_AZIF0045P001C01CS-SA   I169 @S9S_MB_2U_LIB.S9S_MB_2U(SCH_1):PAGE27
   J15   31 DQ17_A SCONN288_ADR50017P130CC-SCONN2A    I48 @S9S_MB_2U_LIB.S9S_MB_2U(SCH_1):PAGE96
   J16   31 DQ17_A SCONN288_ADR50017P087CC-SCONN2A     I6 @S9S_MB_2U_LIB.S9S_MB_2U(SCH_1):PAGE97

M_H_CPU0_SA_DQ<18> @S9S_MB_2U_LIB.S9S_MB_2U(SCH_1):M_H_CPU0_SA_DQ(18)
    U2 DF69 DDR7_SA_DQ18 SOCKET4677_AZIF0045P001C01CS-SA   I169 @S9S_MB_2U_LIB.S9S_MB_2U(SCH_1):PAGE27
   J15  174 DQ18_A SCONN288_ADR50017P130CC-SCONN2A    I48 @S9S_MB_2U_LIB.S9S_MB_2U(SCH_1):PAGE96
   J16  174 DQ18_A SCONN288_ADR50017P087CC-SCONN2A     I6 @S9S_MB_2U_LIB.S9S_MB_2U(SCH_1):PAGE97

M_H_CPU0_SA_DQ<19> @S9S_MB_2U_LIB.S9S_MB_2U(SCH_1):M_H_CPU0_SA_DQ(19)
    U2 DG68 DDR7_SA_DQ19 SOCKET4677_AZIF0045P001C01CS-SA   I169 @S9S_MB_2U_LIB.S9S_MB_2U(SCH_1):PAGE27
   J15  176 DQ19_A SCONN288_ADR50017P130CC-SCONN2A    I48 @S9S_MB_2U_LIB.S9S_MB_2U(SCH_1):PAGE96
   J16  176 DQ19_A SCONN288_ADR50017P087CC-SCONN2A     I6 @S9S_MB_2U_LIB.S9S_MB_2U(SCH_1):PAGE97

M_H_CPU0_SA_DQ<1> @S9S_MB_2U_LIB.S9S_MB_2U(SCH_1):M_H_CPU0_SA_DQ(1)
    U2 DT77 DDR7_SA_DQ1 SOCKET4677_AZIF0045P001C01CS-SA   I169 @S9S_MB_2U_LIB.S9S_MB_2U(SCH_1):PAGE27
   J15    9  DQ1_A SCONN288_ADR50017P130CC-SCONN2A    I48 @S9S_MB_2U_LIB.S9S_MB_2U(SCH_1):PAGE96
   J16    9  DQ1_A SCONN288_ADR50017P087CC-SCONN2A     I6 @S9S_MB_2U_LIB.S9S_MB_2U(SCH_1):PAGE97

M_H_CPU0_SA_DQ<20> @S9S_MB_2U_LIB.S9S_MB_2U(SCH_1):M_H_CPU0_SA_DQ(20)
    U2 DC66 DDR7_SA_DQ20 SOCKET4677_AZIF0045P001C01CS-SA   I169 @S9S_MB_2U_LIB.S9S_MB_2U(SCH_1):PAGE27
   J15   36 DQ20_A SCONN288_ADR50017P130CC-SCONN2A    I48 @S9S_MB_2U_LIB.S9S_MB_2U(SCH_1):PAGE96
   J16   36 DQ20_A SCONN288_ADR50017P087CC-SCONN2A     I6 @S9S_MB_2U_LIB.S9S_MB_2U(SCH_1):PAGE97

M_H_CPU0_SA_DQ<21> @S9S_MB_2U_LIB.S9S_MB_2U(SCH_1):M_H_CPU0_SA_DQ(21)
    U2 DD65 DDR7_SA_DQ21 SOCKET4677_AZIF0045P001C01CS-SA   I169 @S9S_MB_2U_LIB.S9S_MB_2U(SCH_1):PAGE27
   J15   38 DQ21_A SCONN288_ADR50017P130CC-SCONN2A    I48 @S9S_MB_2U_LIB.S9S_MB_2U(SCH_1):PAGE96
   J16   38 DQ21_A SCONN288_ADR50017P087CC-SCONN2A     I6 @S9S_MB_2U_LIB.S9S_MB_2U(SCH_1):PAGE97

M_H_CPU0_SA_DQ<22> @S9S_MB_2U_LIB.S9S_MB_2U(SCH_1):M_H_CPU0_SA_DQ(22)
    U2 DG66 DDR7_SA_DQ22 SOCKET4677_AZIF0045P001C01CS-SA   I169 @S9S_MB_2U_LIB.S9S_MB_2U(SCH_1):PAGE27
   J15  181 DQ22_A SCONN288_ADR50017P130CC-SCONN2A    I48 @S9S_MB_2U_LIB.S9S_MB_2U(SCH_1):PAGE96
   J16  181 DQ22_A SCONN288_ADR50017P087CC-SCONN2A     I6 @S9S_MB_2U_LIB.S9S_MB_2U(SCH_1):PAGE97

M_H_CPU0_SA_DQ<23> @S9S_MB_2U_LIB.S9S_MB_2U(SCH_1):M_H_CPU0_SA_DQ(23)
    U2 DF65 DDR7_SA_DQ23 SOCKET4677_AZIF0045P001C01CS-SA   I169 @S9S_MB_2U_LIB.S9S_MB_2U(SCH_1):PAGE27
   J15  183 DQ23_A SCONN288_ADR50017P130CC-SCONN2A    I48 @S9S_MB_2U_LIB.S9S_MB_2U(SCH_1):PAGE96
   J16  183 DQ23_A SCONN288_ADR50017P087CC-SCONN2A     I6 @S9S_MB_2U_LIB.S9S_MB_2U(SCH_1):PAGE97

M_H_CPU0_SA_DQ<24> @S9S_MB_2U_LIB.S9S_MB_2U(SCH_1):M_H_CPU0_SA_DQ(24)
    U2 DD63 DDR7_SA_DQ24 SOCKET4677_AZIF0045P001C01CS-SA   I169 @S9S_MB_2U_LIB.S9S_MB_2U(SCH_1):PAGE27
   J15   40 DQ24_A SCONN288_ADR50017P130CC-SCONN2A    I48 @S9S_MB_2U_LIB.S9S_MB_2U(SCH_1):PAGE96
   J16   40 DQ24_A SCONN288_ADR50017P087CC-SCONN2A     I6 @S9S_MB_2U_LIB.S9S_MB_2U(SCH_1):PAGE97

M_H_CPU0_SA_DQ<25> @S9S_MB_2U_LIB.S9S_MB_2U(SCH_1):M_H_CPU0_SA_DQ(25)
    U2 DC62 DDR7_SA_DQ25 SOCKET4677_AZIF0045P001C01CS-SA   I169 @S9S_MB_2U_LIB.S9S_MB_2U(SCH_1):PAGE27
   J15   42 DQ25_A SCONN288_ADR50017P130CC-SCONN2A    I48 @S9S_MB_2U_LIB.S9S_MB_2U(SCH_1):PAGE96
   J16   42 DQ25_A SCONN288_ADR50017P087CC-SCONN2A     I6 @S9S_MB_2U_LIB.S9S_MB_2U(SCH_1):PAGE97

M_H_CPU0_SA_DQ<26> @S9S_MB_2U_LIB.S9S_MB_2U(SCH_1):M_H_CPU0_SA_DQ(26)
    U2 DF63 DDR7_SA_DQ26 SOCKET4677_AZIF0045P001C01CS-SA   I169 @S9S_MB_2U_LIB.S9S_MB_2U(SCH_1):PAGE27
   J15  185 DQ26_A SCONN288_ADR50017P130CC-SCONN2A    I48 @S9S_MB_2U_LIB.S9S_MB_2U(SCH_1):PAGE96
   J16  185 DQ26_A SCONN288_ADR50017P087CC-SCONN2A     I6 @S9S_MB_2U_LIB.S9S_MB_2U(SCH_1):PAGE97

M_H_CPU0_SA_DQ<27> @S9S_MB_2U_LIB.S9S_MB_2U(SCH_1):M_H_CPU0_SA_DQ(27)
    U2 DG62 DDR7_SA_DQ27 SOCKET4677_AZIF0045P001C01CS-SA   I169 @S9S_MB_2U_LIB.S9S_MB_2U(SCH_1):PAGE27
   J15  187 DQ27_A SCONN288_ADR50017P130CC-SCONN2A    I48 @S9S_MB_2U_LIB.S9S_MB_2U(SCH_1):PAGE96
   J16  187 DQ27_A SCONN288_ADR50017P087CC-SCONN2A     I6 @S9S_MB_2U_LIB.S9S_MB_2U(SCH_1):PAGE97

M_H_CPU0_SA_DQ<28> @S9S_MB_2U_LIB.S9S_MB_2U(SCH_1):M_H_CPU0_SA_DQ(28)
    U2 DC60 DDR7_SA_DQ28 SOCKET4677_AZIF0045P001C01CS-SA   I169 @S9S_MB_2U_LIB.S9S_MB_2U(SCH_1):PAGE27
   J15   47 DQ28_A SCONN288_ADR50017P130CC-SCONN2A    I48 @S9S_MB_2U_LIB.S9S_MB_2U(SCH_1):PAGE96
   J16   47 DQ28_A SCONN288_ADR50017P087CC-SCONN2A     I6 @S9S_MB_2U_LIB.S9S_MB_2U(SCH_1):PAGE97

M_H_CPU0_SA_DQ<29> @S9S_MB_2U_LIB.S9S_MB_2U(SCH_1):M_H_CPU0_SA_DQ(29)
    U2 DD59 DDR7_SA_DQ29 SOCKET4677_AZIF0045P001C01CS-SA   I169 @S9S_MB_2U_LIB.S9S_MB_2U(SCH_1):PAGE27
   J15   49 DQ29_A SCONN288_ADR50017P130CC-SCONN2A    I48 @S9S_MB_2U_LIB.S9S_MB_2U(SCH_1):PAGE96
   J16   49 DQ29_A SCONN288_ADR50017P087CC-SCONN2A     I6 @S9S_MB_2U_LIB.S9S_MB_2U(SCH_1):PAGE97

M_H_CPU0_SA_DQ<2> @S9S_MB_2U_LIB.S9S_MB_2U(SCH_1):M_H_CPU0_SA_DQ(2)
    U2 DW78 DDR7_SA_DQ2 SOCKET4677_AZIF0045P001C01CS-SA   I169 @S9S_MB_2U_LIB.S9S_MB_2U(SCH_1):PAGE27
   J15  152  DQ2_A SCONN288_ADR50017P130CC-SCONN2A    I48 @S9S_MB_2U_LIB.S9S_MB_2U(SCH_1):PAGE96
   J16  152  DQ2_A SCONN288_ADR50017P087CC-SCONN2A     I6 @S9S_MB_2U_LIB.S9S_MB_2U(SCH_1):PAGE97

M_H_CPU0_SA_DQ<30> @S9S_MB_2U_LIB.S9S_MB_2U(SCH_1):M_H_CPU0_SA_DQ(30)
    U2 DG60 DDR7_SA_DQ30 SOCKET4677_AZIF0045P001C01CS-SA   I169 @S9S_MB_2U_LIB.S9S_MB_2U(SCH_1):PAGE27
   J15  192 DQ30_A SCONN288_ADR50017P130CC-SCONN2A    I48 @S9S_MB_2U_LIB.S9S_MB_2U(SCH_1):PAGE96
   J16  192 DQ30_A SCONN288_ADR50017P087CC-SCONN2A     I6 @S9S_MB_2U_LIB.S9S_MB_2U(SCH_1):PAGE97

M_H_CPU0_SA_DQ<31> @S9S_MB_2U_LIB.S9S_MB_2U(SCH_1):M_H_CPU0_SA_DQ(31)
    U2 DF59 DDR7_SA_DQ31 SOCKET4677_AZIF0045P001C01CS-SA   I169 @S9S_MB_2U_LIB.S9S_MB_2U(SCH_1):PAGE27
   J15  194 DQ31_A SCONN288_ADR50017P130CC-SCONN2A    I48 @S9S_MB_2U_LIB.S9S_MB_2U(SCH_1):PAGE96
   J16  194 DQ31_A SCONN288_ADR50017P087CC-SCONN2A     I6 @S9S_MB_2U_LIB.S9S_MB_2U(SCH_1):PAGE97

M_H_CPU0_SA_DQ<3> @S9S_MB_2U_LIB.S9S_MB_2U(SCH_1):M_H_CPU0_SA_DQ(3)
    U2 DP77 DDR7_SA_DQ3 SOCKET4677_AZIF0045P001C01CS-SA   I169 @S9S_MB_2U_LIB.S9S_MB_2U(SCH_1):PAGE27
   J15  154  DQ3_A SCONN288_ADR50017P130CC-SCONN2A    I48 @S9S_MB_2U_LIB.S9S_MB_2U(SCH_1):PAGE96
   J16  154  DQ3_A SCONN288_ADR50017P087CC-SCONN2A     I6 @S9S_MB_2U_LIB.S9S_MB_2U(SCH_1):PAGE97

M_H_CPU0_SA_DQ<4> @S9S_MB_2U_LIB.S9S_MB_2U(SCH_1):M_H_CPU0_SA_DQ(4)
    U2 DK75 DDR7_SA_DQ4 SOCKET4677_AZIF0045P001C01CS-SA   I169 @S9S_MB_2U_LIB.S9S_MB_2U(SCH_1):PAGE27
   J15   14  DQ4_A SCONN288_ADR50017P130CC-SCONN2A    I48 @S9S_MB_2U_LIB.S9S_MB_2U(SCH_1):PAGE96
   J16   14  DQ4_A SCONN288_ADR50017P087CC-SCONN2A     I6 @S9S_MB_2U_LIB.S9S_MB_2U(SCH_1):PAGE97

M_H_CPU0_SA_DQ<5> @S9S_MB_2U_LIB.S9S_MB_2U(SCH_1):M_H_CPU0_SA_DQ(5)
    U2 DL74 DDR7_SA_DQ5 SOCKET4677_AZIF0045P001C01CS-SA   I169 @S9S_MB_2U_LIB.S9S_MB_2U(SCH_1):PAGE27
   J15   16  DQ5_A SCONN288_ADR50017P130CC-SCONN2A    I48 @S9S_MB_2U_LIB.S9S_MB_2U(SCH_1):PAGE96
   J16   16  DQ5_A SCONN288_ADR50017P087CC-SCONN2A     I6 @S9S_MB_2U_LIB.S9S_MB_2U(SCH_1):PAGE97

M_H_CPU0_SA_DQ<6> @S9S_MB_2U_LIB.S9S_MB_2U(SCH_1):M_H_CPU0_SA_DQ(6)
    U2 DP75 DDR7_SA_DQ6 SOCKET4677_AZIF0045P001C01CS-SA   I169 @S9S_MB_2U_LIB.S9S_MB_2U(SCH_1):PAGE27
   J15  159  DQ6_A SCONN288_ADR50017P130CC-SCONN2A    I48 @S9S_MB_2U_LIB.S9S_MB_2U(SCH_1):PAGE96
   J16  159  DQ6_A SCONN288_ADR50017P087CC-SCONN2A     I6 @S9S_MB_2U_LIB.S9S_MB_2U(SCH_1):PAGE97

M_H_CPU0_SA_DQ<7> @S9S_MB_2U_LIB.S9S_MB_2U(SCH_1):M_H_CPU0_SA_DQ(7)
    U2 DN74 DDR7_SA_DQ7 SOCKET4677_AZIF0045P001C01CS-SA   I169 @S9S_MB_2U_LIB.S9S_MB_2U(SCH_1):PAGE27
   J15  161  DQ7_A SCONN288_ADR50017P130CC-SCONN2A    I48 @S9S_MB_2U_LIB.S9S_MB_2U(SCH_1):PAGE96
   J16  161  DQ7_A SCONN288_ADR50017P087CC-SCONN2A     I6 @S9S_MB_2U_LIB.S9S_MB_2U(SCH_1):PAGE97

M_H_CPU0_SA_DQ<8> @S9S_MB_2U_LIB.S9S_MB_2U(SCH_1):M_H_CPU0_SA_DQ(8)
    U2 DD75 DDR7_SA_DQ8 SOCKET4677_AZIF0045P001C01CS-SA   I169 @S9S_MB_2U_LIB.S9S_MB_2U(SCH_1):PAGE27
   J15   18  DQ8_A SCONN288_ADR50017P130CC-SCONN2A    I48 @S9S_MB_2U_LIB.S9S_MB_2U(SCH_1):PAGE96
   J16   18  DQ8_A SCONN288_ADR50017P087CC-SCONN2A     I6 @S9S_MB_2U_LIB.S9S_MB_2U(SCH_1):PAGE97

M_H_CPU0_SA_DQ<9> @S9S_MB_2U_LIB.S9S_MB_2U(SCH_1):M_H_CPU0_SA_DQ(9)
    U2 DC74 DDR7_SA_DQ9 SOCKET4677_AZIF0045P001C01CS-SA   I169 @S9S_MB_2U_LIB.S9S_MB_2U(SCH_1):PAGE27
   J15   20  DQ9_A SCONN288_ADR50017P130CC-SCONN2A    I48 @S9S_MB_2U_LIB.S9S_MB_2U(SCH_1):PAGE96
   J16   20  DQ9_A SCONN288_ADR50017P087CC-SCONN2A     I6 @S9S_MB_2U_LIB.S9S_MB_2U(SCH_1):PAGE97

M_H_CPU0_SA_DQS_DN<0> @S9S_MB_2U_LIB.S9S_MB_2U(SCH_1):M_H_CPU0_SA_DQS_DN(0)
    U2 DJ76 DDR7_SA_DQS_DN0 SOCKET4677_AZIF0045P001C01CS-SA   I169 @S9S_MB_2U_LIB.S9S_MB_2U(SCH_1):PAGE27
   J15   12 DQS0_A_C SCONN288_ADR50017P130CC-SCONN2A   I178 @S9S_MB_2U_LIB.S9S_MB_2U(SCH_1):PAGE96
   J16   12 DQS0_A_C SCONN288_ADR50017P087CC-SCONN2A   I178 @S9S_MB_2U_LIB.S9S_MB_2U(SCH_1):PAGE97

M_H_CPU0_SA_DQS_DN<1> @S9S_MB_2U_LIB.S9S_MB_2U(SCH_1):M_H_CPU0_SA_DQS_DN(1)
    U2 DB73 DDR7_SA_DQS_DN1 SOCKET4677_AZIF0045P001C01CS-SA   I169 @S9S_MB_2U_LIB.S9S_MB_2U(SCH_1):PAGE27
   J15   23 DQS1_A_C SCONN288_ADR50017P130CC-SCONN2A   I178 @S9S_MB_2U_LIB.S9S_MB_2U(SCH_1):PAGE96
   J16   23 DQS1_A_C SCONN288_ADR50017P087CC-SCONN2A   I178 @S9S_MB_2U_LIB.S9S_MB_2U(SCH_1):PAGE97

M_H_CPU0_SA_DQS_DN<2> @S9S_MB_2U_LIB.S9S_MB_2U(SCH_1):M_H_CPU0_SA_DQS_DN(2)
    U2 DD67 DDR7_SA_DQS_DN2 SOCKET4677_AZIF0045P001C01CS-SA   I169 @S9S_MB_2U_LIB.S9S_MB_2U(SCH_1):PAGE27
   J15   34 DQS2_A_C SCONN288_ADR50017P130CC-SCONN2A   I178 @S9S_MB_2U_LIB.S9S_MB_2U(SCH_1):PAGE96
   J16   34 DQS2_A_C SCONN288_ADR50017P087CC-SCONN2A   I178 @S9S_MB_2U_LIB.S9S_MB_2U(SCH_1):PAGE97

M_H_CPU0_SA_DQS_DN<3> @S9S_MB_2U_LIB.S9S_MB_2U(SCH_1):M_H_CPU0_SA_DQS_DN(3)
    U2 DD61 DDR7_SA_DQS_DN3 SOCKET4677_AZIF0045P001C01CS-SA   I169 @S9S_MB_2U_LIB.S9S_MB_2U(SCH_1):PAGE27
   J15   45 DQS3_A_C SCONN288_ADR50017P130CC-SCONN2A   I178 @S9S_MB_2U_LIB.S9S_MB_2U(SCH_1):PAGE96
   J16   45 DQS3_A_C SCONN288_ADR50017P087CC-SCONN2A   I178 @S9S_MB_2U_LIB.S9S_MB_2U(SCH_1):PAGE97

M_H_CPU0_SA_DQS_DN<4> @S9S_MB_2U_LIB.S9S_MB_2U(SCH_1):M_H_CPU0_SA_DQS_DN(4)
    U2 DD55 DDR7_SA_DQS_DN4 SOCKET4677_AZIF0045P001C01CS-SA   I169 @S9S_MB_2U_LIB.S9S_MB_2U(SCH_1):PAGE27
   J15   56 DQS4_A_C SCONN288_ADR50017P130CC-SCONN2A   I178 @S9S_MB_2U_LIB.S9S_MB_2U(SCH_1):PAGE96
   J16   56 DQS4_A_C SCONN288_ADR50017P087CC-SCONN2A   I178 @S9S_MB_2U_LIB.S9S_MB_2U(SCH_1):PAGE97

M_H_CPU0_SA_DQS_DN<5> @S9S_MB_2U_LIB.S9S_MB_2U(SCH_1):M_H_CPU0_SA_DQS_DN(5)
    U2 DR76 DDR7_SA_DQS_DN5 SOCKET4677_AZIF0045P001C01CS-SA   I169 @S9S_MB_2U_LIB.S9S_MB_2U(SCH_1):PAGE27
   J15  156 DQS5_A_C||TDQS5_A_C||DQS5_A_T||TDQS5_A_T SCONN288_ADR50017P130CC-SCONN2A   I178 @S9S_MB_2U_LIB.S9S_MB_2U(SCH_1):PAGE96
   J16  156 DQS5_A_C||TDQS5_A_C||DQS5_A_T||TDQS5_A_T SCONN288_ADR50017P087CC-SCONN2A   I178 @S9S_MB_2U_LIB.S9S_MB_2U(SCH_1):PAGE97

M_H_CPU0_SA_DQS_DN<6> @S9S_MB_2U_LIB.S9S_MB_2U(SCH_1):M_H_CPU0_SA_DQS_DN(6)
    U2 DH73 DDR7_SA_DQS_DN6 SOCKET4677_AZIF0045P001C01CS-SA   I169 @S9S_MB_2U_LIB.S9S_MB_2U(SCH_1):PAGE27
   J15  167 DQS6_A_C||TDQS6_A_C||DQS6_A_T||TDQS6_A_T SCONN288_ADR50017P130CC-SCONN2A   I178 @S9S_MB_2U_LIB.S9S_MB_2U(SCH_1):PAGE96
   J16  167 DQS6_A_C||TDQS6_A_C||DQS6_A_T||TDQS6_A_T SCONN288_ADR50017P087CC-SCONN2A   I178 @S9S_MB_2U_LIB.S9S_MB_2U(SCH_1):PAGE97

M_H_CPU0_SA_DQS_DN<7> @S9S_MB_2U_LIB.S9S_MB_2U(SCH_1):M_H_CPU0_SA_DQS_DN(7)
    U2 DH67 DDR7_SA_DQS_DN7 SOCKET4677_AZIF0045P001C01CS-SA   I169 @S9S_MB_2U_LIB.S9S_MB_2U(SCH_1):PAGE27
   J15  178 DQS7_A_C||TDQS7_A_C SCONN288_ADR50017P130CC-SCONN2A   I178 @S9S_MB_2U_LIB.S9S_MB_2U(SCH_1):PAGE96
   J16  178 DQS7_A_C||TDQS7_A_C SCONN288_ADR50017P087CC-SCONN2A   I178 @S9S_MB_2U_LIB.S9S_MB_2U(SCH_1):PAGE97

M_H_CPU0_SA_DQS_DN<8> @S9S_MB_2U_LIB.S9S_MB_2U(SCH_1):M_H_CPU0_SA_DQS_DN(8)
    U2 DH61 DDR7_SA_DQS_DN8 SOCKET4677_AZIF0045P001C01CS-SA   I169 @S9S_MB_2U_LIB.S9S_MB_2U(SCH_1):PAGE27
   J15  189 DQS8_A_C||TDQS8_A_C SCONN288_ADR50017P130CC-SCONN2A   I178 @S9S_MB_2U_LIB.S9S_MB_2U(SCH_1):PAGE96
   J16  189 DQS8_A_C||TDQS8_A_C SCONN288_ADR50017P087CC-SCONN2A   I178 @S9S_MB_2U_LIB.S9S_MB_2U(SCH_1):PAGE97

M_H_CPU0_SA_DQS_DN<9> @S9S_MB_2U_LIB.S9S_MB_2U(SCH_1):M_H_CPU0_SA_DQS_DN(9)
    U2 DH55 DDR7_SA_DQS_DN9 SOCKET4677_AZIF0045P001C01CS-SA   I169 @S9S_MB_2U_LIB.S9S_MB_2U(SCH_1):PAGE27
   J15  200 DQS9_A_C||TDQS9_A_C SCONN288_ADR50017P130CC-SCONN2A   I178 @S9S_MB_2U_LIB.S9S_MB_2U(SCH_1):PAGE96
   J16  200 DQS9_A_C||TDQS9_A_C SCONN288_ADR50017P087CC-SCONN2A   I178 @S9S_MB_2U_LIB.S9S_MB_2U(SCH_1):PAGE97

M_H_CPU0_SA_DQS_DP<0> @S9S_MB_2U_LIB.S9S_MB_2U(SCH_1):M_H_CPU0_SA_DQS_DP(0)
    U2 DL76 DDR7_SA_DQS_DP0 SOCKET4677_AZIF0045P001C01CS-SA   I169 @S9S_MB_2U_LIB.S9S_MB_2U(SCH_1):PAGE27
   J15   11 DQS0_A_T SCONN288_ADR50017P130CC-SCONN2A   I178 @S9S_MB_2U_LIB.S9S_MB_2U(SCH_1):PAGE96
   J16   11 DQS0_A_T SCONN288_ADR50017P087CC-SCONN2A   I178 @S9S_MB_2U_LIB.S9S_MB_2U(SCH_1):PAGE97

M_H_CPU0_SA_DQS_DP<1> @S9S_MB_2U_LIB.S9S_MB_2U(SCH_1):M_H_CPU0_SA_DQS_DP(1)
    U2 DD73 DDR7_SA_DQS_DP1 SOCKET4677_AZIF0045P001C01CS-SA   I169 @S9S_MB_2U_LIB.S9S_MB_2U(SCH_1):PAGE27
   J15   22 DQS1_A_T SCONN288_ADR50017P130CC-SCONN2A   I178 @S9S_MB_2U_LIB.S9S_MB_2U(SCH_1):PAGE96
   J16   22 DQS1_A_T SCONN288_ADR50017P087CC-SCONN2A   I178 @S9S_MB_2U_LIB.S9S_MB_2U(SCH_1):PAGE97

M_H_CPU0_SA_DQS_DP<2> @S9S_MB_2U_LIB.S9S_MB_2U(SCH_1):M_H_CPU0_SA_DQS_DP(2)
    U2 DB67 DDR7_SA_DQS_DP2 SOCKET4677_AZIF0045P001C01CS-SA   I169 @S9S_MB_2U_LIB.S9S_MB_2U(SCH_1):PAGE27
   J15   33 DQS2_A_T SCONN288_ADR50017P130CC-SCONN2A   I178 @S9S_MB_2U_LIB.S9S_MB_2U(SCH_1):PAGE96
   J16   33 DQS2_A_T SCONN288_ADR50017P087CC-SCONN2A   I178 @S9S_MB_2U_LIB.S9S_MB_2U(SCH_1):PAGE97

M_H_CPU0_SA_DQS_DP<3> @S9S_MB_2U_LIB.S9S_MB_2U(SCH_1):M_H_CPU0_SA_DQS_DP(3)
    U2 DB61 DDR7_SA_DQS_DP3 SOCKET4677_AZIF0045P001C01CS-SA   I169 @S9S_MB_2U_LIB.S9S_MB_2U(SCH_1):PAGE27
   J15   44 DQS3_A_T SCONN288_ADR50017P130CC-SCONN2A   I178 @S9S_MB_2U_LIB.S9S_MB_2U(SCH_1):PAGE96
   J16   44 DQS3_A_T SCONN288_ADR50017P087CC-SCONN2A   I178 @S9S_MB_2U_LIB.S9S_MB_2U(SCH_1):PAGE97

M_H_CPU0_SA_DQS_DP<4> @S9S_MB_2U_LIB.S9S_MB_2U(SCH_1):M_H_CPU0_SA_DQS_DP(4)
    U2 DB55 DDR7_SA_DQS_DP4 SOCKET4677_AZIF0045P001C01CS-SA   I169 @S9S_MB_2U_LIB.S9S_MB_2U(SCH_1):PAGE27
   J15   55 DQS4_A_T SCONN288_ADR50017P130CC-SCONN2A   I178 @S9S_MB_2U_LIB.S9S_MB_2U(SCH_1):PAGE96
   J16   55 DQS4_A_T SCONN288_ADR50017P087CC-SCONN2A   I178 @S9S_MB_2U_LIB.S9S_MB_2U(SCH_1):PAGE97

M_H_CPU0_SA_DQS_DP<5> @S9S_MB_2U_LIB.S9S_MB_2U(SCH_1):M_H_CPU0_SA_DQS_DP(5)
    U2 DN76 DDR7_SA_DQS_DP5 SOCKET4677_AZIF0045P001C01CS-SA   I169 @S9S_MB_2U_LIB.S9S_MB_2U(SCH_1):PAGE27
   J15  157 DQS5_A_T||TDQS5_A_T SCONN288_ADR50017P130CC-SCONN2A   I178 @S9S_MB_2U_LIB.S9S_MB_2U(SCH_1):PAGE96
   J16  157 DQS5_A_T||TDQS5_A_T SCONN288_ADR50017P087CC-SCONN2A   I178 @S9S_MB_2U_LIB.S9S_MB_2U(SCH_1):PAGE97

M_H_CPU0_SA_DQS_DP<6> @S9S_MB_2U_LIB.S9S_MB_2U(SCH_1):M_H_CPU0_SA_DQS_DP(6)
    U2 DF73 DDR7_SA_DQS_DP6 SOCKET4677_AZIF0045P001C01CS-SA   I169 @S9S_MB_2U_LIB.S9S_MB_2U(SCH_1):PAGE27
   J15  168 DQS6_A_T||TDQS6_A_T SCONN288_ADR50017P130CC-SCONN2A   I178 @S9S_MB_2U_LIB.S9S_MB_2U(SCH_1):PAGE96
   J16  168 DQS6_A_T||TDQS6_A_T SCONN288_ADR50017P087CC-SCONN2A   I178 @S9S_MB_2U_LIB.S9S_MB_2U(SCH_1):PAGE97

M_H_CPU0_SA_DQS_DP<7> @S9S_MB_2U_LIB.S9S_MB_2U(SCH_1):M_H_CPU0_SA_DQS_DP(7)
    U2 DF67 DDR7_SA_DQS_DP7 SOCKET4677_AZIF0045P001C01CS-SA   I169 @S9S_MB_2U_LIB.S9S_MB_2U(SCH_1):PAGE27
   J15  179 DQS7_A_T||TDQS7_A_T SCONN288_ADR50017P130CC-SCONN2A   I178 @S9S_MB_2U_LIB.S9S_MB_2U(SCH_1):PAGE96
   J16  179 DQS7_A_T||TDQS7_A_T SCONN288_ADR50017P087CC-SCONN2A   I178 @S9S_MB_2U_LIB.S9S_MB_2U(SCH_1):PAGE97

M_H_CPU0_SA_DQS_DP<8> @S9S_MB_2U_LIB.S9S_MB_2U(SCH_1):M_H_CPU0_SA_DQS_DP(8)
    U2 DF61 DDR7_SA_DQS_DP8 SOCKET4677_AZIF0045P001C01CS-SA   I169 @S9S_MB_2U_LIB.S9S_MB_2U(SCH_1):PAGE27
   J15  190 DQS8_A_T||TDQS8_A_T SCONN288_ADR50017P130CC-SCONN2A   I178 @S9S_MB_2U_LIB.S9S_MB_2U(SCH_1):PAGE96
   J16  190 DQS8_A_T||TDQS8_A_T SCONN288_ADR50017P087CC-SCONN2A   I178 @S9S_MB_2U_LIB.S9S_MB_2U(SCH_1):PAGE97

M_H_CPU0_SA_DQS_DP<9> @S9S_MB_2U_LIB.S9S_MB_2U(SCH_1):M_H_CPU0_SA_DQS_DP(9)
    U2 DF55 DDR7_SA_DQS_DP9 SOCKET4677_AZIF0045P001C01CS-SA   I169 @S9S_MB_2U_LIB.S9S_MB_2U(SCH_1):PAGE27
   J15  201 DQS9_A_T||TDQS9_A_T SCONN288_ADR50017P130CC-SCONN2A   I178 @S9S_MB_2U_LIB.S9S_MB_2U(SCH_1):PAGE96
   J16  201 DQS9_A_T||TDQS9_A_T SCONN288_ADR50017P087CC-SCONN2A   I178 @S9S_MB_2U_LIB.S9S_MB_2U(SCH_1):PAGE97

M_H_CPU0_SA_PAR @S9S_MB_2U_LIB.S9S_MB_2U(SCH_1):M_H_CPU0_SA_PAR
    U2 DD40 DDR7_SA_PAR SOCKET4677_AZIF0045P001C01CS-SA   I169 @S9S_MB_2U_LIB.S9S_MB_2U(SCH_1):PAGE27
   J15   74  PAR_A SCONN288_ADR50017P130CC-SCONN2A    I48 @S9S_MB_2U_LIB.S9S_MB_2U(SCH_1):PAGE96
   J16   74  PAR_A SCONN288_ADR50017P087CC-SCONN2A     I6 @S9S_MB_2U_LIB.S9S_MB_2U(SCH_1):PAGE97

M_H_CPU0_SA_RSP<0> @S9S_MB_2U_LIB.S9S_MB_2U(SCH_1):M_H_CPU0_SA_RSP(0)
    U2 EG48 DDR7_A_RSP0 SOCKET4677_AZIF0045P001C01CS-SA   I169 @S9S_MB_2U_LIB.S9S_MB_2U(SCH_1):PAGE27
   J15   86 LBD||RSP_A_N SCONN288_ADR50017P130CC-SCONN2A    I48 @S9S_MB_2U_LIB.S9S_MB_2U(SCH_1):PAGE96

M_H_CPU0_SA_RSP<1> @S9S_MB_2U_LIB.S9S_MB_2U(SCH_1):M_H_CPU0_SA_RSP(1)
    U2 EH47 DDR7_A_RSP1 SOCKET4677_AZIF0045P001C01CS-SA   I169 @S9S_MB_2U_LIB.S9S_MB_2U(SCH_1):PAGE27
   J16   86 LBD||RSP_A_N SCONN288_ADR50017P087CC-SCONN2A     I6 @S9S_MB_2U_LIB.S9S_MB_2U(SCH_1):PAGE97

M_H_CPU0_SB_CA<0> @S9S_MB_2U_LIB.S9S_MB_2U(SCH_1):M_H_CPU0_SB_CA(0)
    U2 DF40 DDR7_SB_CA0 SOCKET4677_AZIF0045P001C01CS-SA   I169 @S9S_MB_2U_LIB.S9S_MB_2U(SCH_1):PAGE27
   J15   76  CA0_B SCONN288_ADR50017P130CC-SCONN2A    I48 @S9S_MB_2U_LIB.S9S_MB_2U(SCH_1):PAGE96
   J16   76  CA0_B SCONN288_ADR50017P087CC-SCONN2A     I6 @S9S_MB_2U_LIB.S9S_MB_2U(SCH_1):PAGE97

M_H_CPU0_SB_CA<1> @S9S_MB_2U_LIB.S9S_MB_2U(SCH_1):M_H_CPU0_SB_CA(1)
    U2 DG41 DDR7_SB_CA1 SOCKET4677_AZIF0045P001C01CS-SA   I169 @S9S_MB_2U_LIB.S9S_MB_2U(SCH_1):PAGE27
   J15  221  CA1_B SCONN288_ADR50017P130CC-SCONN2A    I48 @S9S_MB_2U_LIB.S9S_MB_2U(SCH_1):PAGE96
   J16  221  CA1_B SCONN288_ADR50017P087CC-SCONN2A     I6 @S9S_MB_2U_LIB.S9S_MB_2U(SCH_1):PAGE97

M_H_CPU0_SB_CA<2> @S9S_MB_2U_LIB.S9S_MB_2U(SCH_1):M_H_CPU0_SB_CA(2)
    U2 DL41 DDR7_SB_CA2 SOCKET4677_AZIF0045P001C01CS-SA   I169 @S9S_MB_2U_LIB.S9S_MB_2U(SCH_1):PAGE27
   J15   78  CA2_B SCONN288_ADR50017P130CC-SCONN2A    I48 @S9S_MB_2U_LIB.S9S_MB_2U(SCH_1):PAGE96
   J16   78  CA2_B SCONN288_ADR50017P087CC-SCONN2A     I6 @S9S_MB_2U_LIB.S9S_MB_2U(SCH_1):PAGE97

M_H_CPU0_SB_CA<3> @S9S_MB_2U_LIB.S9S_MB_2U(SCH_1):M_H_CPU0_SB_CA(3)
    U2 DN41 DDR7_SB_CA3 SOCKET4677_AZIF0045P001C01CS-SA   I169 @S9S_MB_2U_LIB.S9S_MB_2U(SCH_1):PAGE27
   J15  223  CA3_B SCONN288_ADR50017P130CC-SCONN2A    I48 @S9S_MB_2U_LIB.S9S_MB_2U(SCH_1):PAGE96
   J16  223  CA3_B SCONN288_ADR50017P087CC-SCONN2A     I6 @S9S_MB_2U_LIB.S9S_MB_2U(SCH_1):PAGE97

M_H_CPU0_SB_CA<4> @S9S_MB_2U_LIB.S9S_MB_2U(SCH_1):M_H_CPU0_SB_CA(4)
    U2 DK40 DDR7_SB_CA4 SOCKET4677_AZIF0045P001C01CS-SA   I169 @S9S_MB_2U_LIB.S9S_MB_2U(SCH_1):PAGE27
   J15   80  CA4_B SCONN288_ADR50017P130CC-SCONN2A    I48 @S9S_MB_2U_LIB.S9S_MB_2U(SCH_1):PAGE96
   J16   80  CA4_B SCONN288_ADR50017P087CC-SCONN2A     I6 @S9S_MB_2U_LIB.S9S_MB_2U(SCH_1):PAGE97

M_H_CPU0_SB_CA<5> @S9S_MB_2U_LIB.S9S_MB_2U(SCH_1):M_H_CPU0_SB_CA(5)
    U2 DP40 DDR7_SB_CA5 SOCKET4677_AZIF0045P001C01CS-SA   I169 @S9S_MB_2U_LIB.S9S_MB_2U(SCH_1):PAGE27
   J15  225  CA5_B SCONN288_ADR50017P130CC-SCONN2A    I48 @S9S_MB_2U_LIB.S9S_MB_2U(SCH_1):PAGE96
   J16  225  CA5_B SCONN288_ADR50017P087CC-SCONN2A     I6 @S9S_MB_2U_LIB.S9S_MB_2U(SCH_1):PAGE97

M_H_CPU0_SB_CA<6> @S9S_MB_2U_LIB.S9S_MB_2U(SCH_1):M_H_CPU0_SB_CA(6)
    U2 DJ39 DDR7_SB_CA6 SOCKET4677_AZIF0045P001C01CS-SA   I169 @S9S_MB_2U_LIB.S9S_MB_2U(SCH_1):PAGE27
   J15   82  CA6_B SCONN288_ADR50017P130CC-SCONN2A    I48 @S9S_MB_2U_LIB.S9S_MB_2U(SCH_1):PAGE96
   J16   82  CA6_B SCONN288_ADR50017P087CC-SCONN2A     I6 @S9S_MB_2U_LIB.S9S_MB_2U(SCH_1):PAGE97

M_H_CPU0_SB_CB<0> @S9S_MB_2U_LIB.S9S_MB_2U(SCH_1):M_H_CPU0_SB_CB(0)
    U2 DC35 DDR7_SB_ECC0 SOCKET4677_AZIF0045P001C01CS-SA   I169 @S9S_MB_2U_LIB.S9S_MB_2U(SCH_1):PAGE27
   J15   96  CB0_B SCONN288_ADR50017P130CC-SCONN2A    I48 @S9S_MB_2U_LIB.S9S_MB_2U(SCH_1):PAGE96
   J16   96  CB0_B SCONN288_ADR50017P087CC-SCONN2A     I6 @S9S_MB_2U_LIB.S9S_MB_2U(SCH_1):PAGE97

M_H_CPU0_SB_CB<1> @S9S_MB_2U_LIB.S9S_MB_2U(SCH_1):M_H_CPU0_SB_CB(1)
    U2 DD34 DDR7_SB_ECC1 SOCKET4677_AZIF0045P001C01CS-SA   I169 @S9S_MB_2U_LIB.S9S_MB_2U(SCH_1):PAGE27
   J15   98  CB1_B SCONN288_ADR50017P130CC-SCONN2A    I48 @S9S_MB_2U_LIB.S9S_MB_2U(SCH_1):PAGE96
   J16   98  CB1_B SCONN288_ADR50017P087CC-SCONN2A     I6 @S9S_MB_2U_LIB.S9S_MB_2U(SCH_1):PAGE97

M_H_CPU0_SB_CB<2> @S9S_MB_2U_LIB.S9S_MB_2U(SCH_1):M_H_CPU0_SB_CB(2)
    U2 DG35 DDR7_SB_ECC2 SOCKET4677_AZIF0045P001C01CS-SA   I169 @S9S_MB_2U_LIB.S9S_MB_2U(SCH_1):PAGE27
   J15  241  CB2_B SCONN288_ADR50017P130CC-SCONN2A    I48 @S9S_MB_2U_LIB.S9S_MB_2U(SCH_1):PAGE96
   J16  241  CB2_B SCONN288_ADR50017P087CC-SCONN2A     I6 @S9S_MB_2U_LIB.S9S_MB_2U(SCH_1):PAGE97

M_H_CPU0_SB_CB<3> @S9S_MB_2U_LIB.S9S_MB_2U(SCH_1):M_H_CPU0_SB_CB(3)
    U2 DF34 DDR7_SB_ECC3 SOCKET4677_AZIF0045P001C01CS-SA   I169 @S9S_MB_2U_LIB.S9S_MB_2U(SCH_1):PAGE27
   J15  243  CB3_B SCONN288_ADR50017P130CC-SCONN2A    I48 @S9S_MB_2U_LIB.S9S_MB_2U(SCH_1):PAGE96
   J16  243  CB3_B SCONN288_ADR50017P087CC-SCONN2A     I6 @S9S_MB_2U_LIB.S9S_MB_2U(SCH_1):PAGE97

M_H_CPU0_SB_CB<4> @S9S_MB_2U_LIB.S9S_MB_2U(SCH_1):M_H_CPU0_SB_CB(4)
    U2 DF38 DDR7_SB_ECC4 SOCKET4677_AZIF0045P001C01CS-SA   I169 @S9S_MB_2U_LIB.S9S_MB_2U(SCH_1):PAGE27
   J15   89  CB4_B SCONN288_ADR50017P130CC-SCONN2A    I48 @S9S_MB_2U_LIB.S9S_MB_2U(SCH_1):PAGE96
   J16   89  CB4_B SCONN288_ADR50017P087CC-SCONN2A     I6 @S9S_MB_2U_LIB.S9S_MB_2U(SCH_1):PAGE97

M_H_CPU0_SB_CB<5> @S9S_MB_2U_LIB.S9S_MB_2U(SCH_1):M_H_CPU0_SB_CB(5)
    U2 DG37 DDR7_SB_ECC5 SOCKET4677_AZIF0045P001C01CS-SA   I169 @S9S_MB_2U_LIB.S9S_MB_2U(SCH_1):PAGE27
   J15   91  CB5_B SCONN288_ADR50017P130CC-SCONN2A    I48 @S9S_MB_2U_LIB.S9S_MB_2U(SCH_1):PAGE96
   J16   91  CB5_B SCONN288_ADR50017P087CC-SCONN2A     I6 @S9S_MB_2U_LIB.S9S_MB_2U(SCH_1):PAGE97

M_H_CPU0_SB_CB<6> @S9S_MB_2U_LIB.S9S_MB_2U(SCH_1):M_H_CPU0_SB_CB(6)
    U2 DD38 DDR7_SB_ECC6 SOCKET4677_AZIF0045P001C01CS-SA   I169 @S9S_MB_2U_LIB.S9S_MB_2U(SCH_1):PAGE27
   J15  234  CB6_B SCONN288_ADR50017P130CC-SCONN2A    I48 @S9S_MB_2U_LIB.S9S_MB_2U(SCH_1):PAGE96
   J16  234  CB6_B SCONN288_ADR50017P087CC-SCONN2A     I6 @S9S_MB_2U_LIB.S9S_MB_2U(SCH_1):PAGE97

M_H_CPU0_SB_CB<7> @S9S_MB_2U_LIB.S9S_MB_2U(SCH_1):M_H_CPU0_SB_CB(7)
    U2 DC37 DDR7_SB_ECC7 SOCKET4677_AZIF0045P001C01CS-SA   I169 @S9S_MB_2U_LIB.S9S_MB_2U(SCH_1):PAGE27
   J15  236  CB7_B SCONN288_ADR50017P130CC-SCONN2A    I48 @S9S_MB_2U_LIB.S9S_MB_2U(SCH_1):PAGE96
   J16  236  CB7_B SCONN288_ADR50017P087CC-SCONN2A     I6 @S9S_MB_2U_LIB.S9S_MB_2U(SCH_1):PAGE97

M_H_CPU0_SB_CS_N<0> @S9S_MB_2U_LIB.S9S_MB_2U(SCH_1):M_H_CPU0_SB_CS_N(0)
    U2 DL37 DDR7_SB_CS_N0 SOCKET4677_AZIF0045P001C01CS-SA   I169 @S9S_MB_2U_LIB.S9S_MB_2U(SCH_1):PAGE27
   J15   84 CS0_B_N SCONN288_ADR50017P130CC-SCONN2A    I48 @S9S_MB_2U_LIB.S9S_MB_2U(SCH_1):PAGE96

M_H_CPU0_SB_CS_N<1> @S9S_MB_2U_LIB.S9S_MB_2U(SCH_1):M_H_CPU0_SB_CS_N(1)
    U2 DN37 DDR7_SB_CS_N1 SOCKET4677_AZIF0045P001C01CS-SA   I169 @S9S_MB_2U_LIB.S9S_MB_2U(SCH_1):PAGE27
   J15  229 CS1_B_N SCONN288_ADR50017P130CC-SCONN2A    I48 @S9S_MB_2U_LIB.S9S_MB_2U(SCH_1):PAGE96

M_H_CPU0_SB_CS_N<2> @S9S_MB_2U_LIB.S9S_MB_2U(SCH_1):M_H_CPU0_SB_CS_N(2)
    U2 DK38 DDR7_SB_CS_N2 SOCKET4677_AZIF0045P001C01CS-SA   I169 @S9S_MB_2U_LIB.S9S_MB_2U(SCH_1):PAGE27
   J16   84 CS0_B_N SCONN288_ADR50017P087CC-SCONN2A     I6 @S9S_MB_2U_LIB.S9S_MB_2U(SCH_1):PAGE97

M_H_CPU0_SB_CS_N<3> @S9S_MB_2U_LIB.S9S_MB_2U(SCH_1):M_H_CPU0_SB_CS_N(3)
    U2 DP38 DDR7_SB_CS_N3 SOCKET4677_AZIF0045P001C01CS-SA   I169 @S9S_MB_2U_LIB.S9S_MB_2U(SCH_1):PAGE27
   J16  229 CS1_B_N SCONN288_ADR50017P087CC-SCONN2A     I6 @S9S_MB_2U_LIB.S9S_MB_2U(SCH_1):PAGE97

M_H_CPU0_SB_DQ<0> @S9S_MB_2U_LIB.S9S_MB_2U(SCH_1):M_H_CPU0_SB_DQ(0)
    U2 DD32 DDR7_SB_DQ0 SOCKET4677_AZIF0045P001C01CS-SA   I169 @S9S_MB_2U_LIB.S9S_MB_2U(SCH_1):PAGE27
   J15  100  DQ0_B SCONN288_ADR50017P130CC-SCONN2A    I48 @S9S_MB_2U_LIB.S9S_MB_2U(SCH_1):PAGE96
   J16  100  DQ0_B SCONN288_ADR50017P087CC-SCONN2A     I6 @S9S_MB_2U_LIB.S9S_MB_2U(SCH_1):PAGE97

M_H_CPU0_SB_DQ<10> @S9S_MB_2U_LIB.S9S_MB_2U(SCH_1):M_H_CPU0_SB_DQ(10)
    U2 DF26 DDR7_SB_DQ10 SOCKET4677_AZIF0045P001C01CS-SA   I169 @S9S_MB_2U_LIB.S9S_MB_2U(SCH_1):PAGE27
   J15  256 DQ10_B SCONN288_ADR50017P130CC-SCONN2A    I48 @S9S_MB_2U_LIB.S9S_MB_2U(SCH_1):PAGE96
   J16  256 DQ10_B SCONN288_ADR50017P087CC-SCONN2A     I6 @S9S_MB_2U_LIB.S9S_MB_2U(SCH_1):PAGE97

M_H_CPU0_SB_DQ<11> @S9S_MB_2U_LIB.S9S_MB_2U(SCH_1):M_H_CPU0_SB_DQ(11)
    U2 DG25 DDR7_SB_DQ11 SOCKET4677_AZIF0045P001C01CS-SA   I169 @S9S_MB_2U_LIB.S9S_MB_2U(SCH_1):PAGE27
   J15  258 DQ11_B SCONN288_ADR50017P130CC-SCONN2A    I48 @S9S_MB_2U_LIB.S9S_MB_2U(SCH_1):PAGE96
   J16  258 DQ11_B SCONN288_ADR50017P087CC-SCONN2A     I6 @S9S_MB_2U_LIB.S9S_MB_2U(SCH_1):PAGE97

M_H_CPU0_SB_DQ<12> @S9S_MB_2U_LIB.S9S_MB_2U(SCH_1):M_H_CPU0_SB_DQ(12)
    U2 DC23 DDR7_SB_DQ12 SOCKET4677_AZIF0045P001C01CS-SA   I169 @S9S_MB_2U_LIB.S9S_MB_2U(SCH_1):PAGE27
   J15  118 DQ12_B SCONN288_ADR50017P130CC-SCONN2A    I48 @S9S_MB_2U_LIB.S9S_MB_2U(SCH_1):PAGE96
   J16  118 DQ12_B SCONN288_ADR50017P087CC-SCONN2A     I6 @S9S_MB_2U_LIB.S9S_MB_2U(SCH_1):PAGE97

M_H_CPU0_SB_DQ<13> @S9S_MB_2U_LIB.S9S_MB_2U(SCH_1):M_H_CPU0_SB_DQ(13)
    U2 DD22 DDR7_SB_DQ13 SOCKET4677_AZIF0045P001C01CS-SA   I169 @S9S_MB_2U_LIB.S9S_MB_2U(SCH_1):PAGE27
   J15  120 DQ13_B SCONN288_ADR50017P130CC-SCONN2A    I48 @S9S_MB_2U_LIB.S9S_MB_2U(SCH_1):PAGE96
   J16  120 DQ13_B SCONN288_ADR50017P087CC-SCONN2A     I6 @S9S_MB_2U_LIB.S9S_MB_2U(SCH_1):PAGE97

M_H_CPU0_SB_DQ<14> @S9S_MB_2U_LIB.S9S_MB_2U(SCH_1):M_H_CPU0_SB_DQ(14)
    U2 DG23 DDR7_SB_DQ14 SOCKET4677_AZIF0045P001C01CS-SA   I169 @S9S_MB_2U_LIB.S9S_MB_2U(SCH_1):PAGE27
   J15  263 DQ14_B SCONN288_ADR50017P130CC-SCONN2A    I48 @S9S_MB_2U_LIB.S9S_MB_2U(SCH_1):PAGE96
   J16  263 DQ14_B SCONN288_ADR50017P087CC-SCONN2A     I6 @S9S_MB_2U_LIB.S9S_MB_2U(SCH_1):PAGE97

M_H_CPU0_SB_DQ<15> @S9S_MB_2U_LIB.S9S_MB_2U(SCH_1):M_H_CPU0_SB_DQ(15)
    U2 DF22 DDR7_SB_DQ15 SOCKET4677_AZIF0045P001C01CS-SA   I169 @S9S_MB_2U_LIB.S9S_MB_2U(SCH_1):PAGE27
   J15  265 DQ15_B SCONN288_ADR50017P130CC-SCONN2A    I48 @S9S_MB_2U_LIB.S9S_MB_2U(SCH_1):PAGE96
   J16  265 DQ15_B SCONN288_ADR50017P087CC-SCONN2A     I6 @S9S_MB_2U_LIB.S9S_MB_2U(SCH_1):PAGE97

M_H_CPU0_SB_DQ<16> @S9S_MB_2U_LIB.S9S_MB_2U(SCH_1):M_H_CPU0_SB_DQ(16)
    U2 DL23 DDR7_SB_DQ16 SOCKET4677_AZIF0045P001C01CS-SA   I169 @S9S_MB_2U_LIB.S9S_MB_2U(SCH_1):PAGE27
   J15  122 DQ16_B SCONN288_ADR50017P130CC-SCONN2A    I48 @S9S_MB_2U_LIB.S9S_MB_2U(SCH_1):PAGE96
   J16  122 DQ16_B SCONN288_ADR50017P087CC-SCONN2A     I6 @S9S_MB_2U_LIB.S9S_MB_2U(SCH_1):PAGE97

M_H_CPU0_SB_DQ<17> @S9S_MB_2U_LIB.S9S_MB_2U(SCH_1):M_H_CPU0_SB_DQ(17)
    U2 DK22 DDR7_SB_DQ17 SOCKET4677_AZIF0045P001C01CS-SA   I169 @S9S_MB_2U_LIB.S9S_MB_2U(SCH_1):PAGE27
   J15  124 DQ17_B SCONN288_ADR50017P130CC-SCONN2A    I48 @S9S_MB_2U_LIB.S9S_MB_2U(SCH_1):PAGE96
   J16  124 DQ17_B SCONN288_ADR50017P087CC-SCONN2A     I6 @S9S_MB_2U_LIB.S9S_MB_2U(SCH_1):PAGE97

M_H_CPU0_SB_DQ<18> @S9S_MB_2U_LIB.S9S_MB_2U(SCH_1):M_H_CPU0_SB_DQ(18)
    U2 DN23 DDR7_SB_DQ18 SOCKET4677_AZIF0045P001C01CS-SA   I169 @S9S_MB_2U_LIB.S9S_MB_2U(SCH_1):PAGE27
   J15  267 DQ18_B SCONN288_ADR50017P130CC-SCONN2A    I48 @S9S_MB_2U_LIB.S9S_MB_2U(SCH_1):PAGE96
   J16  267 DQ18_B SCONN288_ADR50017P087CC-SCONN2A     I6 @S9S_MB_2U_LIB.S9S_MB_2U(SCH_1):PAGE97

M_H_CPU0_SB_DQ<19> @S9S_MB_2U_LIB.S9S_MB_2U(SCH_1):M_H_CPU0_SB_DQ(19)
    U2 DP22 DDR7_SB_DQ19 SOCKET4677_AZIF0045P001C01CS-SA   I169 @S9S_MB_2U_LIB.S9S_MB_2U(SCH_1):PAGE27
   J15  269 DQ19_B SCONN288_ADR50017P130CC-SCONN2A    I48 @S9S_MB_2U_LIB.S9S_MB_2U(SCH_1):PAGE96
   J16  269 DQ19_B SCONN288_ADR50017P087CC-SCONN2A     I6 @S9S_MB_2U_LIB.S9S_MB_2U(SCH_1):PAGE97

M_H_CPU0_SB_DQ<1> @S9S_MB_2U_LIB.S9S_MB_2U(SCH_1):M_H_CPU0_SB_DQ(1)
    U2 DC31 DDR7_SB_DQ1 SOCKET4677_AZIF0045P001C01CS-SA   I169 @S9S_MB_2U_LIB.S9S_MB_2U(SCH_1):PAGE27
   J15  102  DQ1_B SCONN288_ADR50017P130CC-SCONN2A    I48 @S9S_MB_2U_LIB.S9S_MB_2U(SCH_1):PAGE96
   J16  102  DQ1_B SCONN288_ADR50017P087CC-SCONN2A     I6 @S9S_MB_2U_LIB.S9S_MB_2U(SCH_1):PAGE97

M_H_CPU0_SB_DQ<20> @S9S_MB_2U_LIB.S9S_MB_2U(SCH_1):M_H_CPU0_SB_DQ(20)
    U2 DK20 DDR7_SB_DQ20 SOCKET4677_AZIF0045P001C01CS-SA   I169 @S9S_MB_2U_LIB.S9S_MB_2U(SCH_1):PAGE27
   J15  129 DQ20_B SCONN288_ADR50017P130CC-SCONN2A    I48 @S9S_MB_2U_LIB.S9S_MB_2U(SCH_1):PAGE96
   J16  129 DQ20_B SCONN288_ADR50017P087CC-SCONN2A     I6 @S9S_MB_2U_LIB.S9S_MB_2U(SCH_1):PAGE97

M_H_CPU0_SB_DQ<21> @S9S_MB_2U_LIB.S9S_MB_2U(SCH_1):M_H_CPU0_SB_DQ(21)
    U2 DL19 DDR7_SB_DQ21 SOCKET4677_AZIF0045P001C01CS-SA   I169 @S9S_MB_2U_LIB.S9S_MB_2U(SCH_1):PAGE27
   J15  131 DQ21_B SCONN288_ADR50017P130CC-SCONN2A    I48 @S9S_MB_2U_LIB.S9S_MB_2U(SCH_1):PAGE96
   J16  131 DQ21_B SCONN288_ADR50017P087CC-SCONN2A     I6 @S9S_MB_2U_LIB.S9S_MB_2U(SCH_1):PAGE97

M_H_CPU0_SB_DQ<22> @S9S_MB_2U_LIB.S9S_MB_2U(SCH_1):M_H_CPU0_SB_DQ(22)
    U2 DP20 DDR7_SB_DQ22 SOCKET4677_AZIF0045P001C01CS-SA   I169 @S9S_MB_2U_LIB.S9S_MB_2U(SCH_1):PAGE27
   J15  274 DQ22_B SCONN288_ADR50017P130CC-SCONN2A    I48 @S9S_MB_2U_LIB.S9S_MB_2U(SCH_1):PAGE96
   J16  274 DQ22_B SCONN288_ADR50017P087CC-SCONN2A     I6 @S9S_MB_2U_LIB.S9S_MB_2U(SCH_1):PAGE97

M_H_CPU0_SB_DQ<23> @S9S_MB_2U_LIB.S9S_MB_2U(SCH_1):M_H_CPU0_SB_DQ(23)
    U2 DN19 DDR7_SB_DQ23 SOCKET4677_AZIF0045P001C01CS-SA   I169 @S9S_MB_2U_LIB.S9S_MB_2U(SCH_1):PAGE27
   J15  276 DQ23_B SCONN288_ADR50017P130CC-SCONN2A    I48 @S9S_MB_2U_LIB.S9S_MB_2U(SCH_1):PAGE96
   J16  276 DQ23_B SCONN288_ADR50017P087CC-SCONN2A     I6 @S9S_MB_2U_LIB.S9S_MB_2U(SCH_1):PAGE97

M_H_CPU0_SB_DQ<24> @S9S_MB_2U_LIB.S9S_MB_2U(SCH_1):M_H_CPU0_SB_DQ(24)
    U2 DD20 DDR7_SB_DQ24 SOCKET4677_AZIF0045P001C01CS-SA   I169 @S9S_MB_2U_LIB.S9S_MB_2U(SCH_1):PAGE27
   J15  133 DQ24_B SCONN288_ADR50017P130CC-SCONN2A    I48 @S9S_MB_2U_LIB.S9S_MB_2U(SCH_1):PAGE96
   J16  133 DQ24_B SCONN288_ADR50017P087CC-SCONN2A     I6 @S9S_MB_2U_LIB.S9S_MB_2U(SCH_1):PAGE97

M_H_CPU0_SB_DQ<25> @S9S_MB_2U_LIB.S9S_MB_2U(SCH_1):M_H_CPU0_SB_DQ(25)
    U2 DC19 DDR7_SB_DQ25 SOCKET4677_AZIF0045P001C01CS-SA   I169 @S9S_MB_2U_LIB.S9S_MB_2U(SCH_1):PAGE27
   J15  135 DQ25_B SCONN288_ADR50017P130CC-SCONN2A    I48 @S9S_MB_2U_LIB.S9S_MB_2U(SCH_1):PAGE96
   J16  135 DQ25_B SCONN288_ADR50017P087CC-SCONN2A     I6 @S9S_MB_2U_LIB.S9S_MB_2U(SCH_1):PAGE97

M_H_CPU0_SB_DQ<26> @S9S_MB_2U_LIB.S9S_MB_2U(SCH_1):M_H_CPU0_SB_DQ(26)
    U2 DF20 DDR7_SB_DQ26 SOCKET4677_AZIF0045P001C01CS-SA   I169 @S9S_MB_2U_LIB.S9S_MB_2U(SCH_1):PAGE27
   J15  278 DQ26_B SCONN288_ADR50017P130CC-SCONN2A    I48 @S9S_MB_2U_LIB.S9S_MB_2U(SCH_1):PAGE96
   J16  278 DQ26_B SCONN288_ADR50017P087CC-SCONN2A     I6 @S9S_MB_2U_LIB.S9S_MB_2U(SCH_1):PAGE97

M_H_CPU0_SB_DQ<27> @S9S_MB_2U_LIB.S9S_MB_2U(SCH_1):M_H_CPU0_SB_DQ(27)
    U2 DG19 DDR7_SB_DQ27 SOCKET4677_AZIF0045P001C01CS-SA   I169 @S9S_MB_2U_LIB.S9S_MB_2U(SCH_1):PAGE27
   J15  280 DQ27_B SCONN288_ADR50017P130CC-SCONN2A    I48 @S9S_MB_2U_LIB.S9S_MB_2U(SCH_1):PAGE96
   J16  280 DQ27_B SCONN288_ADR50017P087CC-SCONN2A     I6 @S9S_MB_2U_LIB.S9S_MB_2U(SCH_1):PAGE97

M_H_CPU0_SB_DQ<28> @S9S_MB_2U_LIB.S9S_MB_2U(SCH_1):M_H_CPU0_SB_DQ(28)
    U2 DG17 DDR7_SB_DQ28 SOCKET4677_AZIF0045P001C01CS-SA   I169 @S9S_MB_2U_LIB.S9S_MB_2U(SCH_1):PAGE27
   J15  140 DQ28_B SCONN288_ADR50017P130CC-SCONN2A    I48 @S9S_MB_2U_LIB.S9S_MB_2U(SCH_1):PAGE96
   J16  140 DQ28_B SCONN288_ADR50017P087CC-SCONN2A     I6 @S9S_MB_2U_LIB.S9S_MB_2U(SCH_1):PAGE97

M_H_CPU0_SB_DQ<29> @S9S_MB_2U_LIB.S9S_MB_2U(SCH_1):M_H_CPU0_SB_DQ(29)
    U2 DA17 DDR7_SB_DQ29 SOCKET4677_AZIF0045P001C01CS-SA   I169 @S9S_MB_2U_LIB.S9S_MB_2U(SCH_1):PAGE27
   J15  142 DQ29_B SCONN288_ADR50017P130CC-SCONN2A    I48 @S9S_MB_2U_LIB.S9S_MB_2U(SCH_1):PAGE96
   J16  142 DQ29_B SCONN288_ADR50017P087CC-SCONN2A     I6 @S9S_MB_2U_LIB.S9S_MB_2U(SCH_1):PAGE97

M_H_CPU0_SB_DQ<2> @S9S_MB_2U_LIB.S9S_MB_2U(SCH_1):M_H_CPU0_SB_DQ(2)
    U2 DF32 DDR7_SB_DQ2 SOCKET4677_AZIF0045P001C01CS-SA   I169 @S9S_MB_2U_LIB.S9S_MB_2U(SCH_1):PAGE27
   J15  245  DQ2_B SCONN288_ADR50017P130CC-SCONN2A    I48 @S9S_MB_2U_LIB.S9S_MB_2U(SCH_1):PAGE96
   J16  245  DQ2_B SCONN288_ADR50017P087CC-SCONN2A     I6 @S9S_MB_2U_LIB.S9S_MB_2U(SCH_1):PAGE97

M_H_CPU0_SB_DQ<30> @S9S_MB_2U_LIB.S9S_MB_2U(SCH_1):M_H_CPU0_SB_DQ(30)
    U2 DJ17 DDR7_SB_DQ30 SOCKET4677_AZIF0045P001C01CS-SA   I169 @S9S_MB_2U_LIB.S9S_MB_2U(SCH_1):PAGE27
   J15  285 DQ30_B SCONN288_ADR50017P130CC-SCONN2A    I48 @S9S_MB_2U_LIB.S9S_MB_2U(SCH_1):PAGE96
   J16  285 DQ30_B SCONN288_ADR50017P087CC-SCONN2A     I6 @S9S_MB_2U_LIB.S9S_MB_2U(SCH_1):PAGE97

M_H_CPU0_SB_DQ<31> @S9S_MB_2U_LIB.S9S_MB_2U(SCH_1):M_H_CPU0_SB_DQ(31)
    U2 DC17 DDR7_SB_DQ31 SOCKET4677_AZIF0045P001C01CS-SA   I169 @S9S_MB_2U_LIB.S9S_MB_2U(SCH_1):PAGE27
   J15  287 DQ31_B SCONN288_ADR50017P130CC-SCONN2A    I48 @S9S_MB_2U_LIB.S9S_MB_2U(SCH_1):PAGE96
   J16  287 DQ31_B SCONN288_ADR50017P087CC-SCONN2A     I6 @S9S_MB_2U_LIB.S9S_MB_2U(SCH_1):PAGE97

M_H_CPU0_SB_DQ<3> @S9S_MB_2U_LIB.S9S_MB_2U(SCH_1):M_H_CPU0_SB_DQ(3)
    U2 DG31 DDR7_SB_DQ3 SOCKET4677_AZIF0045P001C01CS-SA   I169 @S9S_MB_2U_LIB.S9S_MB_2U(SCH_1):PAGE27
   J15  247  DQ3_B SCONN288_ADR50017P130CC-SCONN2A    I48 @S9S_MB_2U_LIB.S9S_MB_2U(SCH_1):PAGE96
   J16  247  DQ3_B SCONN288_ADR50017P087CC-SCONN2A     I6 @S9S_MB_2U_LIB.S9S_MB_2U(SCH_1):PAGE97

M_H_CPU0_SB_DQ<4> @S9S_MB_2U_LIB.S9S_MB_2U(SCH_1):M_H_CPU0_SB_DQ(4)
    U2 DC29 DDR7_SB_DQ4 SOCKET4677_AZIF0045P001C01CS-SA   I169 @S9S_MB_2U_LIB.S9S_MB_2U(SCH_1):PAGE27
   J15  107  DQ4_B SCONN288_ADR50017P130CC-SCONN2A    I48 @S9S_MB_2U_LIB.S9S_MB_2U(SCH_1):PAGE96
   J16  107  DQ4_B SCONN288_ADR50017P087CC-SCONN2A     I6 @S9S_MB_2U_LIB.S9S_MB_2U(SCH_1):PAGE97

M_H_CPU0_SB_DQ<5> @S9S_MB_2U_LIB.S9S_MB_2U(SCH_1):M_H_CPU0_SB_DQ(5)
    U2 DF28 DDR7_SB_DQ5 SOCKET4677_AZIF0045P001C01CS-SA   I169 @S9S_MB_2U_LIB.S9S_MB_2U(SCH_1):PAGE27
   J15  109  DQ5_B SCONN288_ADR50017P130CC-SCONN2A    I48 @S9S_MB_2U_LIB.S9S_MB_2U(SCH_1):PAGE96
   J16  109  DQ5_B SCONN288_ADR50017P087CC-SCONN2A     I6 @S9S_MB_2U_LIB.S9S_MB_2U(SCH_1):PAGE97

M_H_CPU0_SB_DQ<6> @S9S_MB_2U_LIB.S9S_MB_2U(SCH_1):M_H_CPU0_SB_DQ(6)
    U2 DG29 DDR7_SB_DQ6 SOCKET4677_AZIF0045P001C01CS-SA   I169 @S9S_MB_2U_LIB.S9S_MB_2U(SCH_1):PAGE27
   J15  252  DQ6_B SCONN288_ADR50017P130CC-SCONN2A    I48 @S9S_MB_2U_LIB.S9S_MB_2U(SCH_1):PAGE96
   J16  252  DQ6_B SCONN288_ADR50017P087CC-SCONN2A     I6 @S9S_MB_2U_LIB.S9S_MB_2U(SCH_1):PAGE97

M_H_CPU0_SB_DQ<7> @S9S_MB_2U_LIB.S9S_MB_2U(SCH_1):M_H_CPU0_SB_DQ(7)
    U2 DD28 DDR7_SB_DQ7 SOCKET4677_AZIF0045P001C01CS-SA   I169 @S9S_MB_2U_LIB.S9S_MB_2U(SCH_1):PAGE27
   J15  254  DQ7_B SCONN288_ADR50017P130CC-SCONN2A    I48 @S9S_MB_2U_LIB.S9S_MB_2U(SCH_1):PAGE96
   J16  254  DQ7_B SCONN288_ADR50017P087CC-SCONN2A     I6 @S9S_MB_2U_LIB.S9S_MB_2U(SCH_1):PAGE97

M_H_CPU0_SB_DQ<8> @S9S_MB_2U_LIB.S9S_MB_2U(SCH_1):M_H_CPU0_SB_DQ(8)
    U2 DD26 DDR7_SB_DQ8 SOCKET4677_AZIF0045P001C01CS-SA   I169 @S9S_MB_2U_LIB.S9S_MB_2U(SCH_1):PAGE27
   J15  111  DQ8_B SCONN288_ADR50017P130CC-SCONN2A    I48 @S9S_MB_2U_LIB.S9S_MB_2U(SCH_1):PAGE96
   J16  111  DQ8_B SCONN288_ADR50017P087CC-SCONN2A     I6 @S9S_MB_2U_LIB.S9S_MB_2U(SCH_1):PAGE97

M_H_CPU0_SB_DQ<9> @S9S_MB_2U_LIB.S9S_MB_2U(SCH_1):M_H_CPU0_SB_DQ(9)
    U2 DC25 DDR7_SB_DQ9 SOCKET4677_AZIF0045P001C01CS-SA   I169 @S9S_MB_2U_LIB.S9S_MB_2U(SCH_1):PAGE27
   J15  113  DQ9_B SCONN288_ADR50017P130CC-SCONN2A    I48 @S9S_MB_2U_LIB.S9S_MB_2U(SCH_1):PAGE96
   J16  113  DQ9_B SCONN288_ADR50017P087CC-SCONN2A     I6 @S9S_MB_2U_LIB.S9S_MB_2U(SCH_1):PAGE97

M_H_CPU0_SB_DQS_DN<0> @S9S_MB_2U_LIB.S9S_MB_2U(SCH_1):M_H_CPU0_SB_DQS_DN(0)
    U2 DD30 DDR7_SB_DQS_DN0 SOCKET4677_AZIF0045P001C01CS-SA   I169 @S9S_MB_2U_LIB.S9S_MB_2U(SCH_1):PAGE27
   J15  105 DQS0_B_C SCONN288_ADR50017P130CC-SCONN2A   I178 @S9S_MB_2U_LIB.S9S_MB_2U(SCH_1):PAGE96
   J16  105 DQS0_B_C SCONN288_ADR50017P087CC-SCONN2A   I178 @S9S_MB_2U_LIB.S9S_MB_2U(SCH_1):PAGE97

M_H_CPU0_SB_DQS_DN<1> @S9S_MB_2U_LIB.S9S_MB_2U(SCH_1):M_H_CPU0_SB_DQS_DN(1)
    U2 DD24 DDR7_SB_DQS_DN1 SOCKET4677_AZIF0045P001C01CS-SA   I169 @S9S_MB_2U_LIB.S9S_MB_2U(SCH_1):PAGE27
   J15  116 DQS1_B_C SCONN288_ADR50017P130CC-SCONN2A   I178 @S9S_MB_2U_LIB.S9S_MB_2U(SCH_1):PAGE96
   J16  116 DQS1_B_C SCONN288_ADR50017P087CC-SCONN2A   I178 @S9S_MB_2U_LIB.S9S_MB_2U(SCH_1):PAGE97

M_H_CPU0_SB_DQS_DN<2> @S9S_MB_2U_LIB.S9S_MB_2U(SCH_1):M_H_CPU0_SB_DQS_DN(2)
    U2 DL21 DDR7_SB_DQS_DN2 SOCKET4677_AZIF0045P001C01CS-SA   I169 @S9S_MB_2U_LIB.S9S_MB_2U(SCH_1):PAGE27
   J15  127 DQS2_B_C SCONN288_ADR50017P130CC-SCONN2A   I178 @S9S_MB_2U_LIB.S9S_MB_2U(SCH_1):PAGE96
   J16  127 DQS2_B_C SCONN288_ADR50017P087CC-SCONN2A   I178 @S9S_MB_2U_LIB.S9S_MB_2U(SCH_1):PAGE97

M_H_CPU0_SB_DQS_DN<3> @S9S_MB_2U_LIB.S9S_MB_2U(SCH_1):M_H_CPU0_SB_DQS_DN(3)
    U2 DB18 DDR7_SB_DQS_DN3 SOCKET4677_AZIF0045P001C01CS-SA   I169 @S9S_MB_2U_LIB.S9S_MB_2U(SCH_1):PAGE27
   J15  138 DQS3_B_C SCONN288_ADR50017P130CC-SCONN2A   I178 @S9S_MB_2U_LIB.S9S_MB_2U(SCH_1):PAGE96
   J16  138 DQS3_B_C SCONN288_ADR50017P087CC-SCONN2A   I178 @S9S_MB_2U_LIB.S9S_MB_2U(SCH_1):PAGE97

M_H_CPU0_SB_DQS_DN<4> @S9S_MB_2U_LIB.S9S_MB_2U(SCH_1):M_H_CPU0_SB_DQS_DN(4)
    U2 DH36 DDR7_SB_DQS_DN4 SOCKET4677_AZIF0045P001C01CS-SA   I169 @S9S_MB_2U_LIB.S9S_MB_2U(SCH_1):PAGE27
   J15  238 DQS4_B_C SCONN288_ADR50017P130CC-SCONN2A   I178 @S9S_MB_2U_LIB.S9S_MB_2U(SCH_1):PAGE96
   J16  238 DQS4_B_C SCONN288_ADR50017P087CC-SCONN2A   I178 @S9S_MB_2U_LIB.S9S_MB_2U(SCH_1):PAGE97

M_H_CPU0_SB_DQS_DN<5> @S9S_MB_2U_LIB.S9S_MB_2U(SCH_1):M_H_CPU0_SB_DQS_DN(5)
    U2 DH30 DDR7_SB_DQS_DN5 SOCKET4677_AZIF0045P001C01CS-SA   I169 @S9S_MB_2U_LIB.S9S_MB_2U(SCH_1):PAGE27
   J15  249 DQS5_B_C||TDQS5_B_C SCONN288_ADR50017P130CC-SCONN2A   I178 @S9S_MB_2U_LIB.S9S_MB_2U(SCH_1):PAGE96
   J16  249 DQS5_B_C||TDQS5_B_C SCONN288_ADR50017P087CC-SCONN2A   I178 @S9S_MB_2U_LIB.S9S_MB_2U(SCH_1):PAGE97

M_H_CPU0_SB_DQS_DN<6> @S9S_MB_2U_LIB.S9S_MB_2U(SCH_1):M_H_CPU0_SB_DQS_DN(6)
    U2 DH24 DDR7_SB_DQS_DN6 SOCKET4677_AZIF0045P001C01CS-SA   I169 @S9S_MB_2U_LIB.S9S_MB_2U(SCH_1):PAGE27
   J15  260 DQS6_B_C||TDQS6_B_C SCONN288_ADR50017P130CC-SCONN2A   I178 @S9S_MB_2U_LIB.S9S_MB_2U(SCH_1):PAGE96
   J16  260 DQS6_B_C||TDQS6_B_C SCONN288_ADR50017P087CC-SCONN2A   I178 @S9S_MB_2U_LIB.S9S_MB_2U(SCH_1):PAGE97

M_H_CPU0_SB_DQS_DN<7> @S9S_MB_2U_LIB.S9S_MB_2U(SCH_1):M_H_CPU0_SB_DQS_DN(7)
    U2 DR21 DDR7_SB_DQS_DN7 SOCKET4677_AZIF0045P001C01CS-SA   I169 @S9S_MB_2U_LIB.S9S_MB_2U(SCH_1):PAGE27
   J15  271 DQS7_B_C||TDQS7_B_C SCONN288_ADR50017P130CC-SCONN2A   I178 @S9S_MB_2U_LIB.S9S_MB_2U(SCH_1):PAGE96
   J16  271 DQS7_B_C||TDQS7_B_C SCONN288_ADR50017P087CC-SCONN2A   I178 @S9S_MB_2U_LIB.S9S_MB_2U(SCH_1):PAGE97

M_H_CPU0_SB_DQS_DN<8> @S9S_MB_2U_LIB.S9S_MB_2U(SCH_1):M_H_CPU0_SB_DQS_DN(8)
    U2 DF18 DDR7_SB_DQS_DN8 SOCKET4677_AZIF0045P001C01CS-SA   I169 @S9S_MB_2U_LIB.S9S_MB_2U(SCH_1):PAGE27
   J15  282 DQS8_B_C||TDQS8_B_C SCONN288_ADR50017P130CC-SCONN2A   I178 @S9S_MB_2U_LIB.S9S_MB_2U(SCH_1):PAGE96
   J16  282 DQS8_B_C||TDQS8_B_C SCONN288_ADR50017P087CC-SCONN2A   I178 @S9S_MB_2U_LIB.S9S_MB_2U(SCH_1):PAGE97

M_H_CPU0_SB_DQS_DN<9> @S9S_MB_2U_LIB.S9S_MB_2U(SCH_1):M_H_CPU0_SB_DQS_DN(9)
    U2 DD36 DDR7_SB_DQS_DN9 SOCKET4677_AZIF0045P001C01CS-SA   I169 @S9S_MB_2U_LIB.S9S_MB_2U(SCH_1):PAGE27
   J15   94 DQS9_B_C||TDQS9_B_C SCONN288_ADR50017P130CC-SCONN2A   I178 @S9S_MB_2U_LIB.S9S_MB_2U(SCH_1):PAGE96
   J16   94 DQS9_B_C||TDQS9_B_C SCONN288_ADR50017P087CC-SCONN2A   I178 @S9S_MB_2U_LIB.S9S_MB_2U(SCH_1):PAGE97

M_H_CPU0_SB_DQS_DP<0> @S9S_MB_2U_LIB.S9S_MB_2U(SCH_1):M_H_CPU0_SB_DQS_DP(0)
    U2 DB30 DDR7_SB_DQS_DP0 SOCKET4677_AZIF0045P001C01CS-SA   I169 @S9S_MB_2U_LIB.S9S_MB_2U(SCH_1):PAGE27
   J15  104 DQS0_B_T SCONN288_ADR50017P130CC-SCONN2A   I178 @S9S_MB_2U_LIB.S9S_MB_2U(SCH_1):PAGE96
   J16  104 DQS0_B_T SCONN288_ADR50017P087CC-SCONN2A   I178 @S9S_MB_2U_LIB.S9S_MB_2U(SCH_1):PAGE97

M_H_CPU0_SB_DQS_DP<1> @S9S_MB_2U_LIB.S9S_MB_2U(SCH_1):M_H_CPU0_SB_DQS_DP(1)
    U2 DB24 DDR7_SB_DQS_DP1 SOCKET4677_AZIF0045P001C01CS-SA   I169 @S9S_MB_2U_LIB.S9S_MB_2U(SCH_1):PAGE27
   J15  115 DQS1_B_T SCONN288_ADR50017P130CC-SCONN2A   I178 @S9S_MB_2U_LIB.S9S_MB_2U(SCH_1):PAGE96
   J16  115 DQS1_B_T SCONN288_ADR50017P087CC-SCONN2A   I178 @S9S_MB_2U_LIB.S9S_MB_2U(SCH_1):PAGE97

M_H_CPU0_SB_DQS_DP<2> @S9S_MB_2U_LIB.S9S_MB_2U(SCH_1):M_H_CPU0_SB_DQS_DP(2)
    U2 DJ21 DDR7_SB_DQS_DP2 SOCKET4677_AZIF0045P001C01CS-SA   I169 @S9S_MB_2U_LIB.S9S_MB_2U(SCH_1):PAGE27
   J15  126 DQS2_B_T SCONN288_ADR50017P130CC-SCONN2A   I178 @S9S_MB_2U_LIB.S9S_MB_2U(SCH_1):PAGE96
   J16  126 DQS2_B_T SCONN288_ADR50017P087CC-SCONN2A   I178 @S9S_MB_2U_LIB.S9S_MB_2U(SCH_1):PAGE97

M_H_CPU0_SB_DQS_DP<3> @S9S_MB_2U_LIB.S9S_MB_2U(SCH_1):M_H_CPU0_SB_DQS_DP(3)
    U2 DD18 DDR7_SB_DQS_DP3 SOCKET4677_AZIF0045P001C01CS-SA   I169 @S9S_MB_2U_LIB.S9S_MB_2U(SCH_1):PAGE27
   J15  137 DQS3_B_T SCONN288_ADR50017P130CC-SCONN2A   I178 @S9S_MB_2U_LIB.S9S_MB_2U(SCH_1):PAGE96
   J16  137 DQS3_B_T SCONN288_ADR50017P087CC-SCONN2A   I178 @S9S_MB_2U_LIB.S9S_MB_2U(SCH_1):PAGE97

M_H_CPU0_SB_DQS_DP<4> @S9S_MB_2U_LIB.S9S_MB_2U(SCH_1):M_H_CPU0_SB_DQS_DP(4)
    U2 DF36 DDR7_SB_DQS_DP4 SOCKET4677_AZIF0045P001C01CS-SA   I169 @S9S_MB_2U_LIB.S9S_MB_2U(SCH_1):PAGE27
   J15  239 DQS4_B_T SCONN288_ADR50017P130CC-SCONN2A   I178 @S9S_MB_2U_LIB.S9S_MB_2U(SCH_1):PAGE96
   J16  239 DQS4_B_T SCONN288_ADR50017P087CC-SCONN2A   I178 @S9S_MB_2U_LIB.S9S_MB_2U(SCH_1):PAGE97

M_H_CPU0_SB_DQS_DP<5> @S9S_MB_2U_LIB.S9S_MB_2U(SCH_1):M_H_CPU0_SB_DQS_DP(5)
    U2 DF30 DDR7_SB_DQS_DP5 SOCKET4677_AZIF0045P001C01CS-SA   I169 @S9S_MB_2U_LIB.S9S_MB_2U(SCH_1):PAGE27
   J15  250 DQS5_B_T||TDQS5_B_T SCONN288_ADR50017P130CC-SCONN2A   I178 @S9S_MB_2U_LIB.S9S_MB_2U(SCH_1):PAGE96
   J16  250 DQS5_B_T||TDQS5_B_T SCONN288_ADR50017P087CC-SCONN2A   I178 @S9S_MB_2U_LIB.S9S_MB_2U(SCH_1):PAGE97

M_H_CPU0_SB_DQS_DP<6> @S9S_MB_2U_LIB.S9S_MB_2U(SCH_1):M_H_CPU0_SB_DQS_DP(6)
    U2 DF24 DDR7_SB_DQS_DP6 SOCKET4677_AZIF0045P001C01CS-SA   I169 @S9S_MB_2U_LIB.S9S_MB_2U(SCH_1):PAGE27
   J15  261 DQS6_B_T||TDQS6_B_T SCONN288_ADR50017P130CC-SCONN2A   I178 @S9S_MB_2U_LIB.S9S_MB_2U(SCH_1):PAGE96
   J16  261 DQS6_B_T||TDQS6_B_T SCONN288_ADR50017P087CC-SCONN2A   I178 @S9S_MB_2U_LIB.S9S_MB_2U(SCH_1):PAGE97

M_H_CPU0_SB_DQS_DP<7> @S9S_MB_2U_LIB.S9S_MB_2U(SCH_1):M_H_CPU0_SB_DQS_DP(7)
    U2 DN21 DDR7_SB_DQS_DP7 SOCKET4677_AZIF0045P001C01CS-SA   I169 @S9S_MB_2U_LIB.S9S_MB_2U(SCH_1):PAGE27
   J15  272 DQS7_B_T||TDQS7_B_T SCONN288_ADR50017P130CC-SCONN2A   I178 @S9S_MB_2U_LIB.S9S_MB_2U(SCH_1):PAGE96
   J16  272 DQS7_B_T||TDQS7_B_T SCONN288_ADR50017P087CC-SCONN2A   I178 @S9S_MB_2U_LIB.S9S_MB_2U(SCH_1):PAGE97

M_H_CPU0_SB_DQS_DP<8> @S9S_MB_2U_LIB.S9S_MB_2U(SCH_1):M_H_CPU0_SB_DQS_DP(8)
    U2 DH18 DDR7_SB_DQS_DP8 SOCKET4677_AZIF0045P001C01CS-SA   I169 @S9S_MB_2U_LIB.S9S_MB_2U(SCH_1):PAGE27
   J15  283 DQS8_B_T||TDQS8_B_T SCONN288_ADR50017P130CC-SCONN2A   I178 @S9S_MB_2U_LIB.S9S_MB_2U(SCH_1):PAGE96
   J16  283 DQS8_B_T||TDQS8_B_T SCONN288_ADR50017P087CC-SCONN2A   I178 @S9S_MB_2U_LIB.S9S_MB_2U(SCH_1):PAGE97

M_H_CPU0_SB_DQS_DP<9> @S9S_MB_2U_LIB.S9S_MB_2U(SCH_1):M_H_CPU0_SB_DQS_DP(9)
    U2 DB36 DDR7_SB_DQS_DP9 SOCKET4677_AZIF0045P001C01CS-SA   I169 @S9S_MB_2U_LIB.S9S_MB_2U(SCH_1):PAGE27
   J15   93 DQS9_B_T||TDQS9_B_T||DBI4_B_N SCONN288_ADR50017P130CC-SCONN2A   I178 @S9S_MB_2U_LIB.S9S_MB_2U(SCH_1):PAGE96
   J16   93 DQS9_B_T||TDQS9_B_T||DBI4_B_N SCONN288_ADR50017P087CC-SCONN2A   I178 @S9S_MB_2U_LIB.S9S_MB_2U(SCH_1):PAGE97

M_H_CPU0_SB_PAR @S9S_MB_2U_LIB.S9S_MB_2U(SCH_1):M_H_CPU0_SB_PAR
    U2 DR39 DDR7_SB_PAR SOCKET4677_AZIF0045P001C01CS-SA   I169 @S9S_MB_2U_LIB.S9S_MB_2U(SCH_1):PAGE27
   J15  227  PAR_B SCONN288_ADR50017P130CC-SCONN2A    I48 @S9S_MB_2U_LIB.S9S_MB_2U(SCH_1):PAGE96
   J16  227  PAR_B SCONN288_ADR50017P087CC-SCONN2A     I6 @S9S_MB_2U_LIB.S9S_MB_2U(SCH_1):PAGE97

M_H_CPU0_SB_RSP<0> @S9S_MB_2U_LIB.S9S_MB_2U(SCH_1):M_H_CPU0_SB_RSP(0)
    U2 EE48 DDR7_B_RSP0 SOCKET4677_AZIF0045P001C01CS-SA   I169 @S9S_MB_2U_LIB.S9S_MB_2U(SCH_1):PAGE27
   J15   87 LBS||RSP_B_N SCONN288_ADR50017P130CC-SCONN2A    I48 @S9S_MB_2U_LIB.S9S_MB_2U(SCH_1):PAGE96

M_H_CPU0_SB_RSP<1> @S9S_MB_2U_LIB.S9S_MB_2U(SCH_1):M_H_CPU0_SB_RSP(1)
    U2 ED47 DDR7_B_RSP1 SOCKET4677_AZIF0045P001C01CS-SA   I169 @S9S_MB_2U_LIB.S9S_MB_2U(SCH_1):PAGE27
   J16   87 LBS||RSP_B_N SCONN288_ADR50017P087CC-SCONN2A     I6 @S9S_MB_2U_LIB.S9S_MB_2U(SCH_1):PAGE97

M_H_CPU1_ALERT_N @S9S_MB_2U_LIB.S9S_MB_2U(SCH_1):M_H_CPU1_ALERT_N
    U1 CY51 DDR7_ALERT_N SOCKET4677_AZIF0045P001C01CS-SA    I20 @S9S_MB_2U_LIB.S9S_MB_2U(SCH_1):PAGE58
   J31   62 ALERT_N SCONN288_ADR50017P130CC-SCONN2A   I180 @S9S_MB_2U_LIB.S9S_MB_2U(SCH_1):PAGE112
   J32   62 ALERT_N SCONN288_ADR50017P087CC-SCONN2A   I179 @S9S_MB_2U_LIB.S9S_MB_2U(SCH_1):PAGE113

M_H_CPU1_CLK_DN<0> @S9S_MB_2U_LIB.S9S_MB_2U(SCH_1):M_H_CPU1_CLK_DN(0)
    U1 DH42 DDR7_CLK_DN0 SOCKET4677_AZIF0045P001C01CS-SA    I20 @S9S_MB_2U_LIB.S9S_MB_2U(SCH_1):PAGE58
   J31  218   CK_C SCONN288_ADR50017P130CC-SCONN2A   I180 @S9S_MB_2U_LIB.S9S_MB_2U(SCH_1):PAGE112

M_H_CPU1_CLK_DN<1> @S9S_MB_2U_LIB.S9S_MB_2U(SCH_1):M_H_CPU1_CLK_DN(1)
    U1 DD42 DDR7_CLK_DN1 SOCKET4677_AZIF0045P001C01CS-SA    I20 @S9S_MB_2U_LIB.S9S_MB_2U(SCH_1):PAGE58
   J32  218   CK_C SCONN288_ADR50017P087CC-SCONN2A   I179 @S9S_MB_2U_LIB.S9S_MB_2U(SCH_1):PAGE113

M_H_CPU1_CLK_DP<0> @S9S_MB_2U_LIB.S9S_MB_2U(SCH_1):M_H_CPU1_CLK_DP(0)
    U1 DF42 DDR7_CLK_DP0 SOCKET4677_AZIF0045P001C01CS-SA    I20 @S9S_MB_2U_LIB.S9S_MB_2U(SCH_1):PAGE58
   J31  217   CK_T SCONN288_ADR50017P130CC-SCONN2A   I180 @S9S_MB_2U_LIB.S9S_MB_2U(SCH_1):PAGE112

M_H_CPU1_CLK_DP<1> @S9S_MB_2U_LIB.S9S_MB_2U(SCH_1):M_H_CPU1_CLK_DP(1)
    U1 DB42 DDR7_CLK_DP1 SOCKET4677_AZIF0045P001C01CS-SA    I20 @S9S_MB_2U_LIB.S9S_MB_2U(SCH_1):PAGE58
   J32  217   CK_T SCONN288_ADR50017P087CC-SCONN2A   I179 @S9S_MB_2U_LIB.S9S_MB_2U(SCH_1):PAGE113

M_H_CPU1_SA_CA<0> @S9S_MB_2U_LIB.S9S_MB_2U(SCH_1):M_H_CPU1_SA_CA(0)
    U1 DB49 DDR7_SA_CA0 SOCKET4677_AZIF0045P001C01CS-SA    I20 @S9S_MB_2U_LIB.S9S_MB_2U(SCH_1):PAGE58
   J31   66  CA0_A SCONN288_ADR50017P130CC-SCONN2A   I180 @S9S_MB_2U_LIB.S9S_MB_2U(SCH_1):PAGE112
   J32   66  CA0_A SCONN288_ADR50017P087CC-SCONN2A   I179 @S9S_MB_2U_LIB.S9S_MB_2U(SCH_1):PAGE113

M_H_CPU1_SA_CA<1> @S9S_MB_2U_LIB.S9S_MB_2U(SCH_1):M_H_CPU1_SA_CA(1)
    U1 DH49 DDR7_SA_CA1 SOCKET4677_AZIF0045P001C01CS-SA    I20 @S9S_MB_2U_LIB.S9S_MB_2U(SCH_1):PAGE58
   J31  211  CA1_A SCONN288_ADR50017P130CC-SCONN2A   I180 @S9S_MB_2U_LIB.S9S_MB_2U(SCH_1):PAGE112
   J32  211  CA1_A SCONN288_ADR50017P087CC-SCONN2A   I179 @S9S_MB_2U_LIB.S9S_MB_2U(SCH_1):PAGE113

M_H_CPU1_SA_CA<2> @S9S_MB_2U_LIB.S9S_MB_2U(SCH_1):M_H_CPU1_SA_CA(2)
    U1 DC48 DDR7_SA_CA2 SOCKET4677_AZIF0045P001C01CS-SA    I20 @S9S_MB_2U_LIB.S9S_MB_2U(SCH_1):PAGE58
   J31   68  CA2_A SCONN288_ADR50017P130CC-SCONN2A   I180 @S9S_MB_2U_LIB.S9S_MB_2U(SCH_1):PAGE112
   J32   68  CA2_A SCONN288_ADR50017P087CC-SCONN2A   I179 @S9S_MB_2U_LIB.S9S_MB_2U(SCH_1):PAGE113

M_H_CPU1_SA_CA<3> @S9S_MB_2U_LIB.S9S_MB_2U(SCH_1):M_H_CPU1_SA_CA(3)
    U1 DG48 DDR7_SA_CA3 SOCKET4677_AZIF0045P001C01CS-SA    I20 @S9S_MB_2U_LIB.S9S_MB_2U(SCH_1):PAGE58
   J31  213  CA3_A SCONN288_ADR50017P130CC-SCONN2A   I180 @S9S_MB_2U_LIB.S9S_MB_2U(SCH_1):PAGE112
   J32  213  CA3_A SCONN288_ADR50017P087CC-SCONN2A   I179 @S9S_MB_2U_LIB.S9S_MB_2U(SCH_1):PAGE113

M_H_CPU1_SA_CA<4> @S9S_MB_2U_LIB.S9S_MB_2U(SCH_1):M_H_CPU1_SA_CA(4)
    U1 DD47 DDR7_SA_CA4 SOCKET4677_AZIF0045P001C01CS-SA    I20 @S9S_MB_2U_LIB.S9S_MB_2U(SCH_1):PAGE58
   J31   70  CA4_A SCONN288_ADR50017P130CC-SCONN2A   I180 @S9S_MB_2U_LIB.S9S_MB_2U(SCH_1):PAGE112
   J32   70  CA4_A SCONN288_ADR50017P087CC-SCONN2A   I179 @S9S_MB_2U_LIB.S9S_MB_2U(SCH_1):PAGE113

M_H_CPU1_SA_CA<5> @S9S_MB_2U_LIB.S9S_MB_2U(SCH_1):M_H_CPU1_SA_CA(5)
    U1 DF47 DDR7_SA_CA5 SOCKET4677_AZIF0045P001C01CS-SA    I20 @S9S_MB_2U_LIB.S9S_MB_2U(SCH_1):PAGE58
   J31  215  CA5_A SCONN288_ADR50017P130CC-SCONN2A   I180 @S9S_MB_2U_LIB.S9S_MB_2U(SCH_1):PAGE112
   J32  215  CA5_A SCONN288_ADR50017P087CC-SCONN2A   I179 @S9S_MB_2U_LIB.S9S_MB_2U(SCH_1):PAGE113

M_H_CPU1_SA_CA<6> @S9S_MB_2U_LIB.S9S_MB_2U(SCH_1):M_H_CPU1_SA_CA(6)
    U1 DC41 DDR7_SA_CA6 SOCKET4677_AZIF0045P001C01CS-SA    I20 @S9S_MB_2U_LIB.S9S_MB_2U(SCH_1):PAGE58
   J31   72  CA6_A SCONN288_ADR50017P130CC-SCONN2A   I180 @S9S_MB_2U_LIB.S9S_MB_2U(SCH_1):PAGE112
   J32   72  CA6_A SCONN288_ADR50017P087CC-SCONN2A   I179 @S9S_MB_2U_LIB.S9S_MB_2U(SCH_1):PAGE113

M_H_CPU1_SA_CB<0> @S9S_MB_2U_LIB.S9S_MB_2U(SCH_1):M_H_CPU1_SA_CB(0)
    U1 DD57 DDR7_SA_ECC0 SOCKET4677_AZIF0045P001C01CS-SA    I20 @S9S_MB_2U_LIB.S9S_MB_2U(SCH_1):PAGE58
   J31   51  CB0_A SCONN288_ADR50017P130CC-SCONN2A   I180 @S9S_MB_2U_LIB.S9S_MB_2U(SCH_1):PAGE112
   J32   51  CB0_A SCONN288_ADR50017P087CC-SCONN2A   I179 @S9S_MB_2U_LIB.S9S_MB_2U(SCH_1):PAGE113

M_H_CPU1_SA_CB<1> @S9S_MB_2U_LIB.S9S_MB_2U(SCH_1):M_H_CPU1_SA_CB(1)
    U1 DC56 DDR7_SA_ECC1 SOCKET4677_AZIF0045P001C01CS-SA    I20 @S9S_MB_2U_LIB.S9S_MB_2U(SCH_1):PAGE58
   J31   53  CB1_A SCONN288_ADR50017P130CC-SCONN2A   I180 @S9S_MB_2U_LIB.S9S_MB_2U(SCH_1):PAGE112
   J32   53  CB1_A SCONN288_ADR50017P087CC-SCONN2A   I179 @S9S_MB_2U_LIB.S9S_MB_2U(SCH_1):PAGE113

M_H_CPU1_SA_CB<2> @S9S_MB_2U_LIB.S9S_MB_2U(SCH_1):M_H_CPU1_SA_CB(2)
    U1 DF57 DDR7_SA_ECC2 SOCKET4677_AZIF0045P001C01CS-SA    I20 @S9S_MB_2U_LIB.S9S_MB_2U(SCH_1):PAGE58
   J31  196  CB2_A SCONN288_ADR50017P130CC-SCONN2A   I180 @S9S_MB_2U_LIB.S9S_MB_2U(SCH_1):PAGE112
   J32  196  CB2_A SCONN288_ADR50017P087CC-SCONN2A   I179 @S9S_MB_2U_LIB.S9S_MB_2U(SCH_1):PAGE113

M_H_CPU1_SA_CB<3> @S9S_MB_2U_LIB.S9S_MB_2U(SCH_1):M_H_CPU1_SA_CB(3)
    U1 DG56 DDR7_SA_ECC3 SOCKET4677_AZIF0045P001C01CS-SA    I20 @S9S_MB_2U_LIB.S9S_MB_2U(SCH_1):PAGE58
   J31  198  CB3_A SCONN288_ADR50017P130CC-SCONN2A   I180 @S9S_MB_2U_LIB.S9S_MB_2U(SCH_1):PAGE112
   J32  198  CB3_A SCONN288_ADR50017P087CC-SCONN2A   I179 @S9S_MB_2U_LIB.S9S_MB_2U(SCH_1):PAGE113

M_H_CPU1_SA_CB<4> @S9S_MB_2U_LIB.S9S_MB_2U(SCH_1):M_H_CPU1_SA_CB(4)
    U1 DC54 DDR7_SA_ECC4 SOCKET4677_AZIF0045P001C01CS-SA    I20 @S9S_MB_2U_LIB.S9S_MB_2U(SCH_1):PAGE58
   J31   58  CB4_A SCONN288_ADR50017P130CC-SCONN2A   I180 @S9S_MB_2U_LIB.S9S_MB_2U(SCH_1):PAGE112
   J32   58  CB4_A SCONN288_ADR50017P087CC-SCONN2A   I179 @S9S_MB_2U_LIB.S9S_MB_2U(SCH_1):PAGE113

M_H_CPU1_SA_CB<5> @S9S_MB_2U_LIB.S9S_MB_2U(SCH_1):M_H_CPU1_SA_CB(5)
    U1 DD53 DDR7_SA_ECC5 SOCKET4677_AZIF0045P001C01CS-SA    I20 @S9S_MB_2U_LIB.S9S_MB_2U(SCH_1):PAGE58
   J31   60  CB5_A SCONN288_ADR50017P130CC-SCONN2A   I180 @S9S_MB_2U_LIB.S9S_MB_2U(SCH_1):PAGE112
   J32   60  CB5_A SCONN288_ADR50017P087CC-SCONN2A   I179 @S9S_MB_2U_LIB.S9S_MB_2U(SCH_1):PAGE113

M_H_CPU1_SA_CB<6> @S9S_MB_2U_LIB.S9S_MB_2U(SCH_1):M_H_CPU1_SA_CB(6)
    U1 DG54 DDR7_SA_ECC6 SOCKET4677_AZIF0045P001C01CS-SA    I20 @S9S_MB_2U_LIB.S9S_MB_2U(SCH_1):PAGE58
   J31  203  CB6_A SCONN288_ADR50017P130CC-SCONN2A   I180 @S9S_MB_2U_LIB.S9S_MB_2U(SCH_1):PAGE112
   J32  203  CB6_A SCONN288_ADR50017P087CC-SCONN2A   I179 @S9S_MB_2U_LIB.S9S_MB_2U(SCH_1):PAGE113

M_H_CPU1_SA_CB<7> @S9S_MB_2U_LIB.S9S_MB_2U(SCH_1):M_H_CPU1_SA_CB(7)
    U1 DF53 DDR7_SA_ECC7 SOCKET4677_AZIF0045P001C01CS-SA    I20 @S9S_MB_2U_LIB.S9S_MB_2U(SCH_1):PAGE58
   J31  205  CB7_A SCONN288_ADR50017P130CC-SCONN2A   I180 @S9S_MB_2U_LIB.S9S_MB_2U(SCH_1):PAGE112
   J32  205  CB7_A SCONN288_ADR50017P087CC-SCONN2A   I179 @S9S_MB_2U_LIB.S9S_MB_2U(SCH_1):PAGE113

M_H_CPU1_SA_CS_N<0> @S9S_MB_2U_LIB.S9S_MB_2U(SCH_1):M_H_CPU1_SA_CS_N(0)
    U1 DF51 DDR7_SA_CS_N0 SOCKET4677_AZIF0045P001C01CS-SA    I20 @S9S_MB_2U_LIB.S9S_MB_2U(SCH_1):PAGE58
   J31   64 CS0_A_N SCONN288_ADR50017P130CC-SCONN2A   I180 @S9S_MB_2U_LIB.S9S_MB_2U(SCH_1):PAGE112

M_H_CPU1_SA_CS_N<1> @S9S_MB_2U_LIB.S9S_MB_2U(SCH_1):M_H_CPU1_SA_CS_N(1)
    U1 DG50 DDR7_SA_CS_N1 SOCKET4677_AZIF0045P001C01CS-SA    I20 @S9S_MB_2U_LIB.S9S_MB_2U(SCH_1):PAGE58
   J31  209 CS1_A_N SCONN288_ADR50017P130CC-SCONN2A   I180 @S9S_MB_2U_LIB.S9S_MB_2U(SCH_1):PAGE112

M_H_CPU1_SA_CS_N<2> @S9S_MB_2U_LIB.S9S_MB_2U(SCH_1):M_H_CPU1_SA_CS_N(2)
    U1 DD51 DDR7_SA_CS_N2 SOCKET4677_AZIF0045P001C01CS-SA    I20 @S9S_MB_2U_LIB.S9S_MB_2U(SCH_1):PAGE58
   J32   64 CS0_A_N SCONN288_ADR50017P087CC-SCONN2A   I179 @S9S_MB_2U_LIB.S9S_MB_2U(SCH_1):PAGE113

M_H_CPU1_SA_CS_N<3> @S9S_MB_2U_LIB.S9S_MB_2U(SCH_1):M_H_CPU1_SA_CS_N(3)
    U1 DC50 DDR7_SA_CS_N3 SOCKET4677_AZIF0045P001C01CS-SA    I20 @S9S_MB_2U_LIB.S9S_MB_2U(SCH_1):PAGE58
   J32  209 CS1_A_N SCONN288_ADR50017P087CC-SCONN2A   I179 @S9S_MB_2U_LIB.S9S_MB_2U(SCH_1):PAGE113

M_H_CPU1_SA_DQ<0> @S9S_MB_2U_LIB.S9S_MB_2U(SCH_1):M_H_CPU1_SA_DQ(0)
    U1 DY79 DDR7_SA_DQ0 SOCKET4677_AZIF0045P001C01CS-SA    I20 @S9S_MB_2U_LIB.S9S_MB_2U(SCH_1):PAGE58
   J31    7  DQ0_A SCONN288_ADR50017P130CC-SCONN2A   I180 @S9S_MB_2U_LIB.S9S_MB_2U(SCH_1):PAGE112
   J32    7  DQ0_A SCONN288_ADR50017P087CC-SCONN2A   I179 @S9S_MB_2U_LIB.S9S_MB_2U(SCH_1):PAGE113

M_H_CPU1_SA_DQ<10> @S9S_MB_2U_LIB.S9S_MB_2U(SCH_1):M_H_CPU1_SA_DQ(10)
    U1 DF75 DDR7_SA_DQ10 SOCKET4677_AZIF0045P001C01CS-SA    I20 @S9S_MB_2U_LIB.S9S_MB_2U(SCH_1):PAGE58
   J31  163 DQ10_A SCONN288_ADR50017P130CC-SCONN2A   I180 @S9S_MB_2U_LIB.S9S_MB_2U(SCH_1):PAGE112
   J32  163 DQ10_A SCONN288_ADR50017P087CC-SCONN2A   I179 @S9S_MB_2U_LIB.S9S_MB_2U(SCH_1):PAGE113

M_H_CPU1_SA_DQ<11> @S9S_MB_2U_LIB.S9S_MB_2U(SCH_1):M_H_CPU1_SA_DQ(11)
    U1 DG74 DDR7_SA_DQ11 SOCKET4677_AZIF0045P001C01CS-SA    I20 @S9S_MB_2U_LIB.S9S_MB_2U(SCH_1):PAGE58
   J31  165 DQ11_A SCONN288_ADR50017P130CC-SCONN2A   I180 @S9S_MB_2U_LIB.S9S_MB_2U(SCH_1):PAGE112
   J32  165 DQ11_A SCONN288_ADR50017P087CC-SCONN2A   I179 @S9S_MB_2U_LIB.S9S_MB_2U(SCH_1):PAGE113

M_H_CPU1_SA_DQ<12> @S9S_MB_2U_LIB.S9S_MB_2U(SCH_1):M_H_CPU1_SA_DQ(12)
    U1 DC72 DDR7_SA_DQ12 SOCKET4677_AZIF0045P001C01CS-SA    I20 @S9S_MB_2U_LIB.S9S_MB_2U(SCH_1):PAGE58
   J31   25 DQ12_A SCONN288_ADR50017P130CC-SCONN2A   I180 @S9S_MB_2U_LIB.S9S_MB_2U(SCH_1):PAGE112
   J32   25 DQ12_A SCONN288_ADR50017P087CC-SCONN2A   I179 @S9S_MB_2U_LIB.S9S_MB_2U(SCH_1):PAGE113

M_H_CPU1_SA_DQ<13> @S9S_MB_2U_LIB.S9S_MB_2U(SCH_1):M_H_CPU1_SA_DQ(13)
    U1 DD71 DDR7_SA_DQ13 SOCKET4677_AZIF0045P001C01CS-SA    I20 @S9S_MB_2U_LIB.S9S_MB_2U(SCH_1):PAGE58
   J31   27 DQ13_A SCONN288_ADR50017P130CC-SCONN2A   I180 @S9S_MB_2U_LIB.S9S_MB_2U(SCH_1):PAGE112
   J32   27 DQ13_A SCONN288_ADR50017P087CC-SCONN2A   I179 @S9S_MB_2U_LIB.S9S_MB_2U(SCH_1):PAGE113

M_H_CPU1_SA_DQ<14> @S9S_MB_2U_LIB.S9S_MB_2U(SCH_1):M_H_CPU1_SA_DQ(14)
    U1 DG72 DDR7_SA_DQ14 SOCKET4677_AZIF0045P001C01CS-SA    I20 @S9S_MB_2U_LIB.S9S_MB_2U(SCH_1):PAGE58
   J31  170 DQ14_A SCONN288_ADR50017P130CC-SCONN2A   I180 @S9S_MB_2U_LIB.S9S_MB_2U(SCH_1):PAGE112
   J32  170 DQ14_A SCONN288_ADR50017P087CC-SCONN2A   I179 @S9S_MB_2U_LIB.S9S_MB_2U(SCH_1):PAGE113

M_H_CPU1_SA_DQ<15> @S9S_MB_2U_LIB.S9S_MB_2U(SCH_1):M_H_CPU1_SA_DQ(15)
    U1 DF71 DDR7_SA_DQ15 SOCKET4677_AZIF0045P001C01CS-SA    I20 @S9S_MB_2U_LIB.S9S_MB_2U(SCH_1):PAGE58
   J31  172 DQ15_A SCONN288_ADR50017P130CC-SCONN2A   I180 @S9S_MB_2U_LIB.S9S_MB_2U(SCH_1):PAGE112
   J32  172 DQ15_A SCONN288_ADR50017P087CC-SCONN2A   I179 @S9S_MB_2U_LIB.S9S_MB_2U(SCH_1):PAGE113

M_H_CPU1_SA_DQ<16> @S9S_MB_2U_LIB.S9S_MB_2U(SCH_1):M_H_CPU1_SA_DQ(16)
    U1 DD69 DDR7_SA_DQ16 SOCKET4677_AZIF0045P001C01CS-SA    I20 @S9S_MB_2U_LIB.S9S_MB_2U(SCH_1):PAGE58
   J31   29 DQ16_A SCONN288_ADR50017P130CC-SCONN2A   I180 @S9S_MB_2U_LIB.S9S_MB_2U(SCH_1):PAGE112
   J32   29 DQ16_A SCONN288_ADR50017P087CC-SCONN2A   I179 @S9S_MB_2U_LIB.S9S_MB_2U(SCH_1):PAGE113

M_H_CPU1_SA_DQ<17> @S9S_MB_2U_LIB.S9S_MB_2U(SCH_1):M_H_CPU1_SA_DQ(17)
    U1 DC68 DDR7_SA_DQ17 SOCKET4677_AZIF0045P001C01CS-SA    I20 @S9S_MB_2U_LIB.S9S_MB_2U(SCH_1):PAGE58
   J31   31 DQ17_A SCONN288_ADR50017P130CC-SCONN2A   I180 @S9S_MB_2U_LIB.S9S_MB_2U(SCH_1):PAGE112
   J32   31 DQ17_A SCONN288_ADR50017P087CC-SCONN2A   I179 @S9S_MB_2U_LIB.S9S_MB_2U(SCH_1):PAGE113

M_H_CPU1_SA_DQ<18> @S9S_MB_2U_LIB.S9S_MB_2U(SCH_1):M_H_CPU1_SA_DQ(18)
    U1 DF69 DDR7_SA_DQ18 SOCKET4677_AZIF0045P001C01CS-SA    I20 @S9S_MB_2U_LIB.S9S_MB_2U(SCH_1):PAGE58
   J31  174 DQ18_A SCONN288_ADR50017P130CC-SCONN2A   I180 @S9S_MB_2U_LIB.S9S_MB_2U(SCH_1):PAGE112
   J32  174 DQ18_A SCONN288_ADR50017P087CC-SCONN2A   I179 @S9S_MB_2U_LIB.S9S_MB_2U(SCH_1):PAGE113

M_H_CPU1_SA_DQ<19> @S9S_MB_2U_LIB.S9S_MB_2U(SCH_1):M_H_CPU1_SA_DQ(19)
    U1 DG68 DDR7_SA_DQ19 SOCKET4677_AZIF0045P001C01CS-SA    I20 @S9S_MB_2U_LIB.S9S_MB_2U(SCH_1):PAGE58
   J31  176 DQ19_A SCONN288_ADR50017P130CC-SCONN2A   I180 @S9S_MB_2U_LIB.S9S_MB_2U(SCH_1):PAGE112
   J32  176 DQ19_A SCONN288_ADR50017P087CC-SCONN2A   I179 @S9S_MB_2U_LIB.S9S_MB_2U(SCH_1):PAGE113

M_H_CPU1_SA_DQ<1> @S9S_MB_2U_LIB.S9S_MB_2U(SCH_1):M_H_CPU1_SA_DQ(1)
    U1 DT77 DDR7_SA_DQ1 SOCKET4677_AZIF0045P001C01CS-SA    I20 @S9S_MB_2U_LIB.S9S_MB_2U(SCH_1):PAGE58
   J31    9  DQ1_A SCONN288_ADR50017P130CC-SCONN2A   I180 @S9S_MB_2U_LIB.S9S_MB_2U(SCH_1):PAGE112
   J32    9  DQ1_A SCONN288_ADR50017P087CC-SCONN2A   I179 @S9S_MB_2U_LIB.S9S_MB_2U(SCH_1):PAGE113

M_H_CPU1_SA_DQ<20> @S9S_MB_2U_LIB.S9S_MB_2U(SCH_1):M_H_CPU1_SA_DQ(20)
    U1 DC66 DDR7_SA_DQ20 SOCKET4677_AZIF0045P001C01CS-SA    I20 @S9S_MB_2U_LIB.S9S_MB_2U(SCH_1):PAGE58
   J31   36 DQ20_A SCONN288_ADR50017P130CC-SCONN2A   I180 @S9S_MB_2U_LIB.S9S_MB_2U(SCH_1):PAGE112
   J32   36 DQ20_A SCONN288_ADR50017P087CC-SCONN2A   I179 @S9S_MB_2U_LIB.S9S_MB_2U(SCH_1):PAGE113

M_H_CPU1_SA_DQ<21> @S9S_MB_2U_LIB.S9S_MB_2U(SCH_1):M_H_CPU1_SA_DQ(21)
    U1 DD65 DDR7_SA_DQ21 SOCKET4677_AZIF0045P001C01CS-SA    I20 @S9S_MB_2U_LIB.S9S_MB_2U(SCH_1):PAGE58
   J31   38 DQ21_A SCONN288_ADR50017P130CC-SCONN2A   I180 @S9S_MB_2U_LIB.S9S_MB_2U(SCH_1):PAGE112
   J32   38 DQ21_A SCONN288_ADR50017P087CC-SCONN2A   I179 @S9S_MB_2U_LIB.S9S_MB_2U(SCH_1):PAGE113

M_H_CPU1_SA_DQ<22> @S9S_MB_2U_LIB.S9S_MB_2U(SCH_1):M_H_CPU1_SA_DQ(22)
    U1 DG66 DDR7_SA_DQ22 SOCKET4677_AZIF0045P001C01CS-SA    I20 @S9S_MB_2U_LIB.S9S_MB_2U(SCH_1):PAGE58
   J31  181 DQ22_A SCONN288_ADR50017P130CC-SCONN2A   I180 @S9S_MB_2U_LIB.S9S_MB_2U(SCH_1):PAGE112
   J32  181 DQ22_A SCONN288_ADR50017P087CC-SCONN2A   I179 @S9S_MB_2U_LIB.S9S_MB_2U(SCH_1):PAGE113

M_H_CPU1_SA_DQ<23> @S9S_MB_2U_LIB.S9S_MB_2U(SCH_1):M_H_CPU1_SA_DQ(23)
    U1 DF65 DDR7_SA_DQ23 SOCKET4677_AZIF0045P001C01CS-SA    I20 @S9S_MB_2U_LIB.S9S_MB_2U(SCH_1):PAGE58
   J31  183 DQ23_A SCONN288_ADR50017P130CC-SCONN2A   I180 @S9S_MB_2U_LIB.S9S_MB_2U(SCH_1):PAGE112
   J32  183 DQ23_A SCONN288_ADR50017P087CC-SCONN2A   I179 @S9S_MB_2U_LIB.S9S_MB_2U(SCH_1):PAGE113

M_H_CPU1_SA_DQ<24> @S9S_MB_2U_LIB.S9S_MB_2U(SCH_1):M_H_CPU1_SA_DQ(24)
    U1 DD63 DDR7_SA_DQ24 SOCKET4677_AZIF0045P001C01CS-SA    I20 @S9S_MB_2U_LIB.S9S_MB_2U(SCH_1):PAGE58
   J31   40 DQ24_A SCONN288_ADR50017P130CC-SCONN2A   I180 @S9S_MB_2U_LIB.S9S_MB_2U(SCH_1):PAGE112
   J32   40 DQ24_A SCONN288_ADR50017P087CC-SCONN2A   I179 @S9S_MB_2U_LIB.S9S_MB_2U(SCH_1):PAGE113

M_H_CPU1_SA_DQ<25> @S9S_MB_2U_LIB.S9S_MB_2U(SCH_1):M_H_CPU1_SA_DQ(25)
    U1 DC62 DDR7_SA_DQ25 SOCKET4677_AZIF0045P001C01CS-SA    I20 @S9S_MB_2U_LIB.S9S_MB_2U(SCH_1):PAGE58
   J31   42 DQ25_A SCONN288_ADR50017P130CC-SCONN2A   I180 @S9S_MB_2U_LIB.S9S_MB_2U(SCH_1):PAGE112
   J32   42 DQ25_A SCONN288_ADR50017P087CC-SCONN2A   I179 @S9S_MB_2U_LIB.S9S_MB_2U(SCH_1):PAGE113

M_H_CPU1_SA_DQ<26> @S9S_MB_2U_LIB.S9S_MB_2U(SCH_1):M_H_CPU1_SA_DQ(26)
    U1 DF63 DDR7_SA_DQ26 SOCKET4677_AZIF0045P001C01CS-SA    I20 @S9S_MB_2U_LIB.S9S_MB_2U(SCH_1):PAGE58
   J31  185 DQ26_A SCONN288_ADR50017P130CC-SCONN2A   I180 @S9S_MB_2U_LIB.S9S_MB_2U(SCH_1):PAGE112
   J32  185 DQ26_A SCONN288_ADR50017P087CC-SCONN2A   I179 @S9S_MB_2U_LIB.S9S_MB_2U(SCH_1):PAGE113

M_H_CPU1_SA_DQ<27> @S9S_MB_2U_LIB.S9S_MB_2U(SCH_1):M_H_CPU1_SA_DQ(27)
    U1 DG62 DDR7_SA_DQ27 SOCKET4677_AZIF0045P001C01CS-SA    I20 @S9S_MB_2U_LIB.S9S_MB_2U(SCH_1):PAGE58
   J31  187 DQ27_A SCONN288_ADR50017P130CC-SCONN2A   I180 @S9S_MB_2U_LIB.S9S_MB_2U(SCH_1):PAGE112
   J32  187 DQ27_A SCONN288_ADR50017P087CC-SCONN2A   I179 @S9S_MB_2U_LIB.S9S_MB_2U(SCH_1):PAGE113

M_H_CPU1_SA_DQ<28> @S9S_MB_2U_LIB.S9S_MB_2U(SCH_1):M_H_CPU1_SA_DQ(28)
    U1 DC60 DDR7_SA_DQ28 SOCKET4677_AZIF0045P001C01CS-SA    I20 @S9S_MB_2U_LIB.S9S_MB_2U(SCH_1):PAGE58
   J31   47 DQ28_A SCONN288_ADR50017P130CC-SCONN2A   I180 @S9S_MB_2U_LIB.S9S_MB_2U(SCH_1):PAGE112
   J32   47 DQ28_A SCONN288_ADR50017P087CC-SCONN2A   I179 @S9S_MB_2U_LIB.S9S_MB_2U(SCH_1):PAGE113

M_H_CPU1_SA_DQ<29> @S9S_MB_2U_LIB.S9S_MB_2U(SCH_1):M_H_CPU1_SA_DQ(29)
    U1 DD59 DDR7_SA_DQ29 SOCKET4677_AZIF0045P001C01CS-SA    I20 @S9S_MB_2U_LIB.S9S_MB_2U(SCH_1):PAGE58
   J31   49 DQ29_A SCONN288_ADR50017P130CC-SCONN2A   I180 @S9S_MB_2U_LIB.S9S_MB_2U(SCH_1):PAGE112
   J32   49 DQ29_A SCONN288_ADR50017P087CC-SCONN2A   I179 @S9S_MB_2U_LIB.S9S_MB_2U(SCH_1):PAGE113

M_H_CPU1_SA_DQ<2> @S9S_MB_2U_LIB.S9S_MB_2U(SCH_1):M_H_CPU1_SA_DQ(2)
    U1 DW78 DDR7_SA_DQ2 SOCKET4677_AZIF0045P001C01CS-SA    I20 @S9S_MB_2U_LIB.S9S_MB_2U(SCH_1):PAGE58
   J31  152  DQ2_A SCONN288_ADR50017P130CC-SCONN2A   I180 @S9S_MB_2U_LIB.S9S_MB_2U(SCH_1):PAGE112
   J32  152  DQ2_A SCONN288_ADR50017P087CC-SCONN2A   I179 @S9S_MB_2U_LIB.S9S_MB_2U(SCH_1):PAGE113

M_H_CPU1_SA_DQ<30> @S9S_MB_2U_LIB.S9S_MB_2U(SCH_1):M_H_CPU1_SA_DQ(30)
    U1 DG60 DDR7_SA_DQ30 SOCKET4677_AZIF0045P001C01CS-SA    I20 @S9S_MB_2U_LIB.S9S_MB_2U(SCH_1):PAGE58
   J31  192 DQ30_A SCONN288_ADR50017P130CC-SCONN2A   I180 @S9S_MB_2U_LIB.S9S_MB_2U(SCH_1):PAGE112
   J32  192 DQ30_A SCONN288_ADR50017P087CC-SCONN2A   I179 @S9S_MB_2U_LIB.S9S_MB_2U(SCH_1):PAGE113

M_H_CPU1_SA_DQ<31> @S9S_MB_2U_LIB.S9S_MB_2U(SCH_1):M_H_CPU1_SA_DQ(31)
    U1 DF59 DDR7_SA_DQ31 SOCKET4677_AZIF0045P001C01CS-SA    I20 @S9S_MB_2U_LIB.S9S_MB_2U(SCH_1):PAGE58
   J31  194 DQ31_A SCONN288_ADR50017P130CC-SCONN2A   I180 @S9S_MB_2U_LIB.S9S_MB_2U(SCH_1):PAGE112
   J32  194 DQ31_A SCONN288_ADR50017P087CC-SCONN2A   I179 @S9S_MB_2U_LIB.S9S_MB_2U(SCH_1):PAGE113

M_H_CPU1_SA_DQ<3> @S9S_MB_2U_LIB.S9S_MB_2U(SCH_1):M_H_CPU1_SA_DQ(3)
    U1 DP77 DDR7_SA_DQ3 SOCKET4677_AZIF0045P001C01CS-SA    I20 @S9S_MB_2U_LIB.S9S_MB_2U(SCH_1):PAGE58
   J31  154  DQ3_A SCONN288_ADR50017P130CC-SCONN2A   I180 @S9S_MB_2U_LIB.S9S_MB_2U(SCH_1):PAGE112
   J32  154  DQ3_A SCONN288_ADR50017P087CC-SCONN2A   I179 @S9S_MB_2U_LIB.S9S_MB_2U(SCH_1):PAGE113

M_H_CPU1_SA_DQ<4> @S9S_MB_2U_LIB.S9S_MB_2U(SCH_1):M_H_CPU1_SA_DQ(4)
    U1 DK75 DDR7_SA_DQ4 SOCKET4677_AZIF0045P001C01CS-SA    I20 @S9S_MB_2U_LIB.S9S_MB_2U(SCH_1):PAGE58
   J31   14  DQ4_A SCONN288_ADR50017P130CC-SCONN2A   I180 @S9S_MB_2U_LIB.S9S_MB_2U(SCH_1):PAGE112
   J32   14  DQ4_A SCONN288_ADR50017P087CC-SCONN2A   I179 @S9S_MB_2U_LIB.S9S_MB_2U(SCH_1):PAGE113

M_H_CPU1_SA_DQ<5> @S9S_MB_2U_LIB.S9S_MB_2U(SCH_1):M_H_CPU1_SA_DQ(5)
    U1 DL74 DDR7_SA_DQ5 SOCKET4677_AZIF0045P001C01CS-SA    I20 @S9S_MB_2U_LIB.S9S_MB_2U(SCH_1):PAGE58
   J31   16  DQ5_A SCONN288_ADR50017P130CC-SCONN2A   I180 @S9S_MB_2U_LIB.S9S_MB_2U(SCH_1):PAGE112
   J32   16  DQ5_A SCONN288_ADR50017P087CC-SCONN2A   I179 @S9S_MB_2U_LIB.S9S_MB_2U(SCH_1):PAGE113

M_H_CPU1_SA_DQ<6> @S9S_MB_2U_LIB.S9S_MB_2U(SCH_1):M_H_CPU1_SA_DQ(6)
    U1 DP75 DDR7_SA_DQ6 SOCKET4677_AZIF0045P001C01CS-SA    I20 @S9S_MB_2U_LIB.S9S_MB_2U(SCH_1):PAGE58
   J31  159  DQ6_A SCONN288_ADR50017P130CC-SCONN2A   I180 @S9S_MB_2U_LIB.S9S_MB_2U(SCH_1):PAGE112
   J32  159  DQ6_A SCONN288_ADR50017P087CC-SCONN2A   I179 @S9S_MB_2U_LIB.S9S_MB_2U(SCH_1):PAGE113

M_H_CPU1_SA_DQ<7> @S9S_MB_2U_LIB.S9S_MB_2U(SCH_1):M_H_CPU1_SA_DQ(7)
    U1 DN74 DDR7_SA_DQ7 SOCKET4677_AZIF0045P001C01CS-SA    I20 @S9S_MB_2U_LIB.S9S_MB_2U(SCH_1):PAGE58
   J31  161  DQ7_A SCONN288_ADR50017P130CC-SCONN2A   I180 @S9S_MB_2U_LIB.S9S_MB_2U(SCH_1):PAGE112
   J32  161  DQ7_A SCONN288_ADR50017P087CC-SCONN2A   I179 @S9S_MB_2U_LIB.S9S_MB_2U(SCH_1):PAGE113

M_H_CPU1_SA_DQ<8> @S9S_MB_2U_LIB.S9S_MB_2U(SCH_1):M_H_CPU1_SA_DQ(8)
    U1 DD75 DDR7_SA_DQ8 SOCKET4677_AZIF0045P001C01CS-SA    I20 @S9S_MB_2U_LIB.S9S_MB_2U(SCH_1):PAGE58
   J31   18  DQ8_A SCONN288_ADR50017P130CC-SCONN2A   I180 @S9S_MB_2U_LIB.S9S_MB_2U(SCH_1):PAGE112
   J32   18  DQ8_A SCONN288_ADR50017P087CC-SCONN2A   I179 @S9S_MB_2U_LIB.S9S_MB_2U(SCH_1):PAGE113

M_H_CPU1_SA_DQ<9> @S9S_MB_2U_LIB.S9S_MB_2U(SCH_1):M_H_CPU1_SA_DQ(9)
    U1 DC74 DDR7_SA_DQ9 SOCKET4677_AZIF0045P001C01CS-SA    I20 @S9S_MB_2U_LIB.S9S_MB_2U(SCH_1):PAGE58
   J31   20  DQ9_A SCONN288_ADR50017P130CC-SCONN2A   I180 @S9S_MB_2U_LIB.S9S_MB_2U(SCH_1):PAGE112
   J32   20  DQ9_A SCONN288_ADR50017P087CC-SCONN2A   I179 @S9S_MB_2U_LIB.S9S_MB_2U(SCH_1):PAGE113

M_H_CPU1_SA_DQS_DN<0> @S9S_MB_2U_LIB.S9S_MB_2U(SCH_1):M_H_CPU1_SA_DQS_DN(0)
    U1 DJ76 DDR7_SA_DQS_DN0 SOCKET4677_AZIF0045P001C01CS-SA    I20 @S9S_MB_2U_LIB.S9S_MB_2U(SCH_1):PAGE58
   J31   12 DQS0_A_C SCONN288_ADR50017P130CC-SCONN2A   I181 @S9S_MB_2U_LIB.S9S_MB_2U(SCH_1):PAGE112
   J32   12 DQS0_A_C SCONN288_ADR50017P087CC-SCONN2A   I180 @S9S_MB_2U_LIB.S9S_MB_2U(SCH_1):PAGE113

M_H_CPU1_SA_DQS_DN<1> @S9S_MB_2U_LIB.S9S_MB_2U(SCH_1):M_H_CPU1_SA_DQS_DN(1)
    U1 DB73 DDR7_SA_DQS_DN1 SOCKET4677_AZIF0045P001C01CS-SA    I20 @S9S_MB_2U_LIB.S9S_MB_2U(SCH_1):PAGE58
   J31   23 DQS1_A_C SCONN288_ADR50017P130CC-SCONN2A   I181 @S9S_MB_2U_LIB.S9S_MB_2U(SCH_1):PAGE112
   J32   23 DQS1_A_C SCONN288_ADR50017P087CC-SCONN2A   I180 @S9S_MB_2U_LIB.S9S_MB_2U(SCH_1):PAGE113

M_H_CPU1_SA_DQS_DN<2> @S9S_MB_2U_LIB.S9S_MB_2U(SCH_1):M_H_CPU1_SA_DQS_DN(2)
    U1 DD67 DDR7_SA_DQS_DN2 SOCKET4677_AZIF0045P001C01CS-SA    I20 @S9S_MB_2U_LIB.S9S_MB_2U(SCH_1):PAGE58
   J31   34 DQS2_A_C SCONN288_ADR50017P130CC-SCONN2A   I181 @S9S_MB_2U_LIB.S9S_MB_2U(SCH_1):PAGE112
   J32   34 DQS2_A_C SCONN288_ADR50017P087CC-SCONN2A   I180 @S9S_MB_2U_LIB.S9S_MB_2U(SCH_1):PAGE113

M_H_CPU1_SA_DQS_DN<3> @S9S_MB_2U_LIB.S9S_MB_2U(SCH_1):M_H_CPU1_SA_DQS_DN(3)
    U1 DD61 DDR7_SA_DQS_DN3 SOCKET4677_AZIF0045P001C01CS-SA    I20 @S9S_MB_2U_LIB.S9S_MB_2U(SCH_1):PAGE58
   J31   45 DQS3_A_C SCONN288_ADR50017P130CC-SCONN2A   I181 @S9S_MB_2U_LIB.S9S_MB_2U(SCH_1):PAGE112
   J32   45 DQS3_A_C SCONN288_ADR50017P087CC-SCONN2A   I180 @S9S_MB_2U_LIB.S9S_MB_2U(SCH_1):PAGE113

M_H_CPU1_SA_DQS_DN<4> @S9S_MB_2U_LIB.S9S_MB_2U(SCH_1):M_H_CPU1_SA_DQS_DN(4)
    U1 DD55 DDR7_SA_DQS_DN4 SOCKET4677_AZIF0045P001C01CS-SA    I20 @S9S_MB_2U_LIB.S9S_MB_2U(SCH_1):PAGE58
   J31   56 DQS4_A_C SCONN288_ADR50017P130CC-SCONN2A   I181 @S9S_MB_2U_LIB.S9S_MB_2U(SCH_1):PAGE112
   J32   56 DQS4_A_C SCONN288_ADR50017P087CC-SCONN2A   I180 @S9S_MB_2U_LIB.S9S_MB_2U(SCH_1):PAGE113

M_H_CPU1_SA_DQS_DN<5> @S9S_MB_2U_LIB.S9S_MB_2U(SCH_1):M_H_CPU1_SA_DQS_DN(5)
    U1 DR76 DDR7_SA_DQS_DN5 SOCKET4677_AZIF0045P001C01CS-SA    I20 @S9S_MB_2U_LIB.S9S_MB_2U(SCH_1):PAGE58
   J31  156 DQS5_A_C||TDQS5_A_C||DQS5_A_T||TDQS5_A_T SCONN288_ADR50017P130CC-SCONN2A   I181 @S9S_MB_2U_LIB.S9S_MB_2U(SCH_1):PAGE112
   J32  156 DQS5_A_C||TDQS5_A_C||DQS5_A_T||TDQS5_A_T SCONN288_ADR50017P087CC-SCONN2A   I180 @S9S_MB_2U_LIB.S9S_MB_2U(SCH_1):PAGE113

M_H_CPU1_SA_DQS_DN<6> @S9S_MB_2U_LIB.S9S_MB_2U(SCH_1):M_H_CPU1_SA_DQS_DN(6)
    U1 DH73 DDR7_SA_DQS_DN6 SOCKET4677_AZIF0045P001C01CS-SA    I20 @S9S_MB_2U_LIB.S9S_MB_2U(SCH_1):PAGE58
   J31  167 DQS6_A_C||TDQS6_A_C||DQS6_A_T||TDQS6_A_T SCONN288_ADR50017P130CC-SCONN2A   I181 @S9S_MB_2U_LIB.S9S_MB_2U(SCH_1):PAGE112
   J32  167 DQS6_A_C||TDQS6_A_C||DQS6_A_T||TDQS6_A_T SCONN288_ADR50017P087CC-SCONN2A   I180 @S9S_MB_2U_LIB.S9S_MB_2U(SCH_1):PAGE113

M_H_CPU1_SA_DQS_DN<7> @S9S_MB_2U_LIB.S9S_MB_2U(SCH_1):M_H_CPU1_SA_DQS_DN(7)
    U1 DH67 DDR7_SA_DQS_DN7 SOCKET4677_AZIF0045P001C01CS-SA    I20 @S9S_MB_2U_LIB.S9S_MB_2U(SCH_1):PAGE58
   J31  178 DQS7_A_C||TDQS7_A_C SCONN288_ADR50017P130CC-SCONN2A   I181 @S9S_MB_2U_LIB.S9S_MB_2U(SCH_1):PAGE112
   J32  178 DQS7_A_C||TDQS7_A_C SCONN288_ADR50017P087CC-SCONN2A   I180 @S9S_MB_2U_LIB.S9S_MB_2U(SCH_1):PAGE113

M_H_CPU1_SA_DQS_DN<8> @S9S_MB_2U_LIB.S9S_MB_2U(SCH_1):M_H_CPU1_SA_DQS_DN(8)
    U1 DH61 DDR7_SA_DQS_DN8 SOCKET4677_AZIF0045P001C01CS-SA    I20 @S9S_MB_2U_LIB.S9S_MB_2U(SCH_1):PAGE58
   J31  189 DQS8_A_C||TDQS8_A_C SCONN288_ADR50017P130CC-SCONN2A   I181 @S9S_MB_2U_LIB.S9S_MB_2U(SCH_1):PAGE112
   J32  189 DQS8_A_C||TDQS8_A_C SCONN288_ADR50017P087CC-SCONN2A   I180 @S9S_MB_2U_LIB.S9S_MB_2U(SCH_1):PAGE113

M_H_CPU1_SA_DQS_DN<9> @S9S_MB_2U_LIB.S9S_MB_2U(SCH_1):M_H_CPU1_SA_DQS_DN(9)
    U1 DH55 DDR7_SA_DQS_DN9 SOCKET4677_AZIF0045P001C01CS-SA    I20 @S9S_MB_2U_LIB.S9S_MB_2U(SCH_1):PAGE58
   J31  200 DQS9_A_C||TDQS9_A_C SCONN288_ADR50017P130CC-SCONN2A   I181 @S9S_MB_2U_LIB.S9S_MB_2U(SCH_1):PAGE112
   J32  200 DQS9_A_C||TDQS9_A_C SCONN288_ADR50017P087CC-SCONN2A   I180 @S9S_MB_2U_LIB.S9S_MB_2U(SCH_1):PAGE113

M_H_CPU1_SA_DQS_DP<0> @S9S_MB_2U_LIB.S9S_MB_2U(SCH_1):M_H_CPU1_SA_DQS_DP(0)
    U1 DL76 DDR7_SA_DQS_DP0 SOCKET4677_AZIF0045P001C01CS-SA    I20 @S9S_MB_2U_LIB.S9S_MB_2U(SCH_1):PAGE58
   J31   11 DQS0_A_T SCONN288_ADR50017P130CC-SCONN2A   I181 @S9S_MB_2U_LIB.S9S_MB_2U(SCH_1):PAGE112
   J32   11 DQS0_A_T SCONN288_ADR50017P087CC-SCONN2A   I180 @S9S_MB_2U_LIB.S9S_MB_2U(SCH_1):PAGE113

M_H_CPU1_SA_DQS_DP<1> @S9S_MB_2U_LIB.S9S_MB_2U(SCH_1):M_H_CPU1_SA_DQS_DP(1)
    U1 DD73 DDR7_SA_DQS_DP1 SOCKET4677_AZIF0045P001C01CS-SA    I20 @S9S_MB_2U_LIB.S9S_MB_2U(SCH_1):PAGE58
   J31   22 DQS1_A_T SCONN288_ADR50017P130CC-SCONN2A   I181 @S9S_MB_2U_LIB.S9S_MB_2U(SCH_1):PAGE112
   J32   22 DQS1_A_T SCONN288_ADR50017P087CC-SCONN2A   I180 @S9S_MB_2U_LIB.S9S_MB_2U(SCH_1):PAGE113

M_H_CPU1_SA_DQS_DP<2> @S9S_MB_2U_LIB.S9S_MB_2U(SCH_1):M_H_CPU1_SA_DQS_DP(2)
    U1 DB67 DDR7_SA_DQS_DP2 SOCKET4677_AZIF0045P001C01CS-SA    I20 @S9S_MB_2U_LIB.S9S_MB_2U(SCH_1):PAGE58
   J31   33 DQS2_A_T SCONN288_ADR50017P130CC-SCONN2A   I181 @S9S_MB_2U_LIB.S9S_MB_2U(SCH_1):PAGE112
   J32   33 DQS2_A_T SCONN288_ADR50017P087CC-SCONN2A   I180 @S9S_MB_2U_LIB.S9S_MB_2U(SCH_1):PAGE113

M_H_CPU1_SA_DQS_DP<3> @S9S_MB_2U_LIB.S9S_MB_2U(SCH_1):M_H_CPU1_SA_DQS_DP(3)
    U1 DB61 DDR7_SA_DQS_DP3 SOCKET4677_AZIF0045P001C01CS-SA    I20 @S9S_MB_2U_LIB.S9S_MB_2U(SCH_1):PAGE58
   J31   44 DQS3_A_T SCONN288_ADR50017P130CC-SCONN2A   I181 @S9S_MB_2U_LIB.S9S_MB_2U(SCH_1):PAGE112
   J32   44 DQS3_A_T SCONN288_ADR50017P087CC-SCONN2A   I180 @S9S_MB_2U_LIB.S9S_MB_2U(SCH_1):PAGE113

M_H_CPU1_SA_DQS_DP<4> @S9S_MB_2U_LIB.S9S_MB_2U(SCH_1):M_H_CPU1_SA_DQS_DP(4)
    U1 DB55 DDR7_SA_DQS_DP4 SOCKET4677_AZIF0045P001C01CS-SA    I20 @S9S_MB_2U_LIB.S9S_MB_2U(SCH_1):PAGE58
   J31   55 DQS4_A_T SCONN288_ADR50017P130CC-SCONN2A   I181 @S9S_MB_2U_LIB.S9S_MB_2U(SCH_1):PAGE112
   J32   55 DQS4_A_T SCONN288_ADR50017P087CC-SCONN2A   I180 @S9S_MB_2U_LIB.S9S_MB_2U(SCH_1):PAGE113

M_H_CPU1_SA_DQS_DP<5> @S9S_MB_2U_LIB.S9S_MB_2U(SCH_1):M_H_CPU1_SA_DQS_DP(5)
    U1 DN76 DDR7_SA_DQS_DP5 SOCKET4677_AZIF0045P001C01CS-SA    I20 @S9S_MB_2U_LIB.S9S_MB_2U(SCH_1):PAGE58
   J31  157 DQS5_A_T||TDQS5_A_T SCONN288_ADR50017P130CC-SCONN2A   I181 @S9S_MB_2U_LIB.S9S_MB_2U(SCH_1):PAGE112
   J32  157 DQS5_A_T||TDQS5_A_T SCONN288_ADR50017P087CC-SCONN2A   I180 @S9S_MB_2U_LIB.S9S_MB_2U(SCH_1):PAGE113

M_H_CPU1_SA_DQS_DP<6> @S9S_MB_2U_LIB.S9S_MB_2U(SCH_1):M_H_CPU1_SA_DQS_DP(6)
    U1 DF73 DDR7_SA_DQS_DP6 SOCKET4677_AZIF0045P001C01CS-SA    I20 @S9S_MB_2U_LIB.S9S_MB_2U(SCH_1):PAGE58
   J31  168 DQS6_A_T||TDQS6_A_T SCONN288_ADR50017P130CC-SCONN2A   I181 @S9S_MB_2U_LIB.S9S_MB_2U(SCH_1):PAGE112
   J32  168 DQS6_A_T||TDQS6_A_T SCONN288_ADR50017P087CC-SCONN2A   I180 @S9S_MB_2U_LIB.S9S_MB_2U(SCH_1):PAGE113

M_H_CPU1_SA_DQS_DP<7> @S9S_MB_2U_LIB.S9S_MB_2U(SCH_1):M_H_CPU1_SA_DQS_DP(7)
    U1 DF67 DDR7_SA_DQS_DP7 SOCKET4677_AZIF0045P001C01CS-SA    I20 @S9S_MB_2U_LIB.S9S_MB_2U(SCH_1):PAGE58
   J31  179 DQS7_A_T||TDQS7_A_T SCONN288_ADR50017P130CC-SCONN2A   I181 @S9S_MB_2U_LIB.S9S_MB_2U(SCH_1):PAGE112
   J32  179 DQS7_A_T||TDQS7_A_T SCONN288_ADR50017P087CC-SCONN2A   I180 @S9S_MB_2U_LIB.S9S_MB_2U(SCH_1):PAGE113

M_H_CPU1_SA_DQS_DP<8> @S9S_MB_2U_LIB.S9S_MB_2U(SCH_1):M_H_CPU1_SA_DQS_DP(8)
    U1 DF61 DDR7_SA_DQS_DP8 SOCKET4677_AZIF0045P001C01CS-SA    I20 @S9S_MB_2U_LIB.S9S_MB_2U(SCH_1):PAGE58
   J31  190 DQS8_A_T||TDQS8_A_T SCONN288_ADR50017P130CC-SCONN2A   I181 @S9S_MB_2U_LIB.S9S_MB_2U(SCH_1):PAGE112
   J32  190 DQS8_A_T||TDQS8_A_T SCONN288_ADR50017P087CC-SCONN2A   I180 @S9S_MB_2U_LIB.S9S_MB_2U(SCH_1):PAGE113

M_H_CPU1_SA_DQS_DP<9> @S9S_MB_2U_LIB.S9S_MB_2U(SCH_1):M_H_CPU1_SA_DQS_DP(9)
    U1 DF55 DDR7_SA_DQS_DP9 SOCKET4677_AZIF0045P001C01CS-SA    I20 @S9S_MB_2U_LIB.S9S_MB_2U(SCH_1):PAGE58
   J31  201 DQS9_A_T||TDQS9_A_T SCONN288_ADR50017P130CC-SCONN2A   I181 @S9S_MB_2U_LIB.S9S_MB_2U(SCH_1):PAGE112
   J32  201 DQS9_A_T||TDQS9_A_T SCONN288_ADR50017P087CC-SCONN2A   I180 @S9S_MB_2U_LIB.S9S_MB_2U(SCH_1):PAGE113

M_H_CPU1_SA_PAR @S9S_MB_2U_LIB.S9S_MB_2U(SCH_1):M_H_CPU1_SA_PAR
    U1 DD40 DDR7_SA_PAR SOCKET4677_AZIF0045P001C01CS-SA    I20 @S9S_MB_2U_LIB.S9S_MB_2U(SCH_1):PAGE58
   J31   74  PAR_A SCONN288_ADR50017P130CC-SCONN2A   I180 @S9S_MB_2U_LIB.S9S_MB_2U(SCH_1):PAGE112
   J32   74  PAR_A SCONN288_ADR50017P087CC-SCONN2A   I179 @S9S_MB_2U_LIB.S9S_MB_2U(SCH_1):PAGE113

M_H_CPU1_SA_RSP<0> @S9S_MB_2U_LIB.S9S_MB_2U(SCH_1):M_H_CPU1_SA_RSP(0)
    U1 EG48 DDR7_A_RSP0 SOCKET4677_AZIF0045P001C01CS-SA    I20 @S9S_MB_2U_LIB.S9S_MB_2U(SCH_1):PAGE58
   J31   86 LBD||RSP_A_N SCONN288_ADR50017P130CC-SCONN2A   I180 @S9S_MB_2U_LIB.S9S_MB_2U(SCH_1):PAGE112

M_H_CPU1_SA_RSP<1> @S9S_MB_2U_LIB.S9S_MB_2U(SCH_1):M_H_CPU1_SA_RSP(1)
    U1 EH47 DDR7_A_RSP1 SOCKET4677_AZIF0045P001C01CS-SA    I20 @S9S_MB_2U_LIB.S9S_MB_2U(SCH_1):PAGE58
   J32   86 LBD||RSP_A_N SCONN288_ADR50017P087CC-SCONN2A   I179 @S9S_MB_2U_LIB.S9S_MB_2U(SCH_1):PAGE113

M_H_CPU1_SB_CA<0> @S9S_MB_2U_LIB.S9S_MB_2U(SCH_1):M_H_CPU1_SB_CA(0)
    U1 DF40 DDR7_SB_CA0 SOCKET4677_AZIF0045P001C01CS-SA    I20 @S9S_MB_2U_LIB.S9S_MB_2U(SCH_1):PAGE58
   J31   76  CA0_B SCONN288_ADR50017P130CC-SCONN2A   I180 @S9S_MB_2U_LIB.S9S_MB_2U(SCH_1):PAGE112
   J32   76  CA0_B SCONN288_ADR50017P087CC-SCONN2A   I179 @S9S_MB_2U_LIB.S9S_MB_2U(SCH_1):PAGE113

M_H_CPU1_SB_CA<1> @S9S_MB_2U_LIB.S9S_MB_2U(SCH_1):M_H_CPU1_SB_CA(1)
    U1 DG41 DDR7_SB_CA1 SOCKET4677_AZIF0045P001C01CS-SA    I20 @S9S_MB_2U_LIB.S9S_MB_2U(SCH_1):PAGE58
   J31  221  CA1_B SCONN288_ADR50017P130CC-SCONN2A   I180 @S9S_MB_2U_LIB.S9S_MB_2U(SCH_1):PAGE112
   J32  221  CA1_B SCONN288_ADR50017P087CC-SCONN2A   I179 @S9S_MB_2U_LIB.S9S_MB_2U(SCH_1):PAGE113

M_H_CPU1_SB_CA<2> @S9S_MB_2U_LIB.S9S_MB_2U(SCH_1):M_H_CPU1_SB_CA(2)
    U1 DL41 DDR7_SB_CA2 SOCKET4677_AZIF0045P001C01CS-SA    I20 @S9S_MB_2U_LIB.S9S_MB_2U(SCH_1):PAGE58
   J31   78  CA2_B SCONN288_ADR50017P130CC-SCONN2A   I180 @S9S_MB_2U_LIB.S9S_MB_2U(SCH_1):PAGE112
   J32   78  CA2_B SCONN288_ADR50017P087CC-SCONN2A   I179 @S9S_MB_2U_LIB.S9S_MB_2U(SCH_1):PAGE113

M_H_CPU1_SB_CA<3> @S9S_MB_2U_LIB.S9S_MB_2U(SCH_1):M_H_CPU1_SB_CA(3)
    U1 DN41 DDR7_SB_CA3 SOCKET4677_AZIF0045P001C01CS-SA    I20 @S9S_MB_2U_LIB.S9S_MB_2U(SCH_1):PAGE58
   J31  223  CA3_B SCONN288_ADR50017P130CC-SCONN2A   I180 @S9S_MB_2U_LIB.S9S_MB_2U(SCH_1):PAGE112
   J32  223  CA3_B SCONN288_ADR50017P087CC-SCONN2A   I179 @S9S_MB_2U_LIB.S9S_MB_2U(SCH_1):PAGE113

M_H_CPU1_SB_CA<4> @S9S_MB_2U_LIB.S9S_MB_2U(SCH_1):M_H_CPU1_SB_CA(4)
    U1 DK40 DDR7_SB_CA4 SOCKET4677_AZIF0045P001C01CS-SA    I20 @S9S_MB_2U_LIB.S9S_MB_2U(SCH_1):PAGE58
   J31   80  CA4_B SCONN288_ADR50017P130CC-SCONN2A   I180 @S9S_MB_2U_LIB.S9S_MB_2U(SCH_1):PAGE112
   J32   80  CA4_B SCONN288_ADR50017P087CC-SCONN2A   I179 @S9S_MB_2U_LIB.S9S_MB_2U(SCH_1):PAGE113

M_H_CPU1_SB_CA<5> @S9S_MB_2U_LIB.S9S_MB_2U(SCH_1):M_H_CPU1_SB_CA(5)
    U1 DP40 DDR7_SB_CA5 SOCKET4677_AZIF0045P001C01CS-SA    I20 @S9S_MB_2U_LIB.S9S_MB_2U(SCH_1):PAGE58
   J31  225  CA5_B SCONN288_ADR50017P130CC-SCONN2A   I180 @S9S_MB_2U_LIB.S9S_MB_2U(SCH_1):PAGE112
   J32  225  CA5_B SCONN288_ADR50017P087CC-SCONN2A   I179 @S9S_MB_2U_LIB.S9S_MB_2U(SCH_1):PAGE113

M_H_CPU1_SB_CA<6> @S9S_MB_2U_LIB.S9S_MB_2U(SCH_1):M_H_CPU1_SB_CA(6)
    U1 DJ39 DDR7_SB_CA6 SOCKET4677_AZIF0045P001C01CS-SA    I20 @S9S_MB_2U_LIB.S9S_MB_2U(SCH_1):PAGE58
   J31   82  CA6_B SCONN288_ADR50017P130CC-SCONN2A   I180 @S9S_MB_2U_LIB.S9S_MB_2U(SCH_1):PAGE112
   J32   82  CA6_B SCONN288_ADR50017P087CC-SCONN2A   I179 @S9S_MB_2U_LIB.S9S_MB_2U(SCH_1):PAGE113

M_H_CPU1_SB_CB<0> @S9S_MB_2U_LIB.S9S_MB_2U(SCH_1):M_H_CPU1_SB_CB(0)
    U1 DC35 DDR7_SB_ECC0 SOCKET4677_AZIF0045P001C01CS-SA    I20 @S9S_MB_2U_LIB.S9S_MB_2U(SCH_1):PAGE58
   J31   96  CB0_B SCONN288_ADR50017P130CC-SCONN2A   I180 @S9S_MB_2U_LIB.S9S_MB_2U(SCH_1):PAGE112
   J32   96  CB0_B SCONN288_ADR50017P087CC-SCONN2A   I179 @S9S_MB_2U_LIB.S9S_MB_2U(SCH_1):PAGE113

M_H_CPU1_SB_CB<1> @S9S_MB_2U_LIB.S9S_MB_2U(SCH_1):M_H_CPU1_SB_CB(1)
    U1 DD34 DDR7_SB_ECC1 SOCKET4677_AZIF0045P001C01CS-SA    I20 @S9S_MB_2U_LIB.S9S_MB_2U(SCH_1):PAGE58
   J31   98  CB1_B SCONN288_ADR50017P130CC-SCONN2A   I180 @S9S_MB_2U_LIB.S9S_MB_2U(SCH_1):PAGE112
   J32   98  CB1_B SCONN288_ADR50017P087CC-SCONN2A   I179 @S9S_MB_2U_LIB.S9S_MB_2U(SCH_1):PAGE113

M_H_CPU1_SB_CB<2> @S9S_MB_2U_LIB.S9S_MB_2U(SCH_1):M_H_CPU1_SB_CB(2)
    U1 DG35 DDR7_SB_ECC2 SOCKET4677_AZIF0045P001C01CS-SA    I20 @S9S_MB_2U_LIB.S9S_MB_2U(SCH_1):PAGE58
   J31  241  CB2_B SCONN288_ADR50017P130CC-SCONN2A   I180 @S9S_MB_2U_LIB.S9S_MB_2U(SCH_1):PAGE112
   J32  241  CB2_B SCONN288_ADR50017P087CC-SCONN2A   I179 @S9S_MB_2U_LIB.S9S_MB_2U(SCH_1):PAGE113

M_H_CPU1_SB_CB<3> @S9S_MB_2U_LIB.S9S_MB_2U(SCH_1):M_H_CPU1_SB_CB(3)
    U1 DF34 DDR7_SB_ECC3 SOCKET4677_AZIF0045P001C01CS-SA    I20 @S9S_MB_2U_LIB.S9S_MB_2U(SCH_1):PAGE58
   J31  243  CB3_B SCONN288_ADR50017P130CC-SCONN2A   I180 @S9S_MB_2U_LIB.S9S_MB_2U(SCH_1):PAGE112
   J32  243  CB3_B SCONN288_ADR50017P087CC-SCONN2A   I179 @S9S_MB_2U_LIB.S9S_MB_2U(SCH_1):PAGE113

M_H_CPU1_SB_CB<4> @S9S_MB_2U_LIB.S9S_MB_2U(SCH_1):M_H_CPU1_SB_CB(4)
    U1 DF38 DDR7_SB_ECC4 SOCKET4677_AZIF0045P001C01CS-SA    I20 @S9S_MB_2U_LIB.S9S_MB_2U(SCH_1):PAGE58
   J31   89  CB4_B SCONN288_ADR50017P130CC-SCONN2A   I180 @S9S_MB_2U_LIB.S9S_MB_2U(SCH_1):PAGE112
   J32   89  CB4_B SCONN288_ADR50017P087CC-SCONN2A   I179 @S9S_MB_2U_LIB.S9S_MB_2U(SCH_1):PAGE113

M_H_CPU1_SB_CB<5> @S9S_MB_2U_LIB.S9S_MB_2U(SCH_1):M_H_CPU1_SB_CB(5)
    U1 DG37 DDR7_SB_ECC5 SOCKET4677_AZIF0045P001C01CS-SA    I20 @S9S_MB_2U_LIB.S9S_MB_2U(SCH_1):PAGE58
   J31   91  CB5_B SCONN288_ADR50017P130CC-SCONN2A   I180 @S9S_MB_2U_LIB.S9S_MB_2U(SCH_1):PAGE112
   J32   91  CB5_B SCONN288_ADR50017P087CC-SCONN2A   I179 @S9S_MB_2U_LIB.S9S_MB_2U(SCH_1):PAGE113

M_H_CPU1_SB_CB<6> @S9S_MB_2U_LIB.S9S_MB_2U(SCH_1):M_H_CPU1_SB_CB(6)
    U1 DD38 DDR7_SB_ECC6 SOCKET4677_AZIF0045P001C01CS-SA    I20 @S9S_MB_2U_LIB.S9S_MB_2U(SCH_1):PAGE58
   J31  234  CB6_B SCONN288_ADR50017P130CC-SCONN2A   I180 @S9S_MB_2U_LIB.S9S_MB_2U(SCH_1):PAGE112
   J32  234  CB6_B SCONN288_ADR50017P087CC-SCONN2A   I179 @S9S_MB_2U_LIB.S9S_MB_2U(SCH_1):PAGE113

M_H_CPU1_SB_CB<7> @S9S_MB_2U_LIB.S9S_MB_2U(SCH_1):M_H_CPU1_SB_CB(7)
    U1 DC37 DDR7_SB_ECC7 SOCKET4677_AZIF0045P001C01CS-SA    I20 @S9S_MB_2U_LIB.S9S_MB_2U(SCH_1):PAGE58
   J31  236  CB7_B SCONN288_ADR50017P130CC-SCONN2A   I180 @S9S_MB_2U_LIB.S9S_MB_2U(SCH_1):PAGE112
   J32  236  CB7_B SCONN288_ADR50017P087CC-SCONN2A   I179 @S9S_MB_2U_LIB.S9S_MB_2U(SCH_1):PAGE113

M_H_CPU1_SB_CS_N<0> @S9S_MB_2U_LIB.S9S_MB_2U(SCH_1):M_H_CPU1_SB_CS_N(0)
    U1 DL37 DDR7_SB_CS_N0 SOCKET4677_AZIF0045P001C01CS-SA    I20 @S9S_MB_2U_LIB.S9S_MB_2U(SCH_1):PAGE58
   J31   84 CS0_B_N SCONN288_ADR50017P130CC-SCONN2A   I180 @S9S_MB_2U_LIB.S9S_MB_2U(SCH_1):PAGE112

M_H_CPU1_SB_CS_N<1> @S9S_MB_2U_LIB.S9S_MB_2U(SCH_1):M_H_CPU1_SB_CS_N(1)
    U1 DN37 DDR7_SB_CS_N1 SOCKET4677_AZIF0045P001C01CS-SA    I20 @S9S_MB_2U_LIB.S9S_MB_2U(SCH_1):PAGE58
   J31  229 CS1_B_N SCONN288_ADR50017P130CC-SCONN2A   I180 @S9S_MB_2U_LIB.S9S_MB_2U(SCH_1):PAGE112

M_H_CPU1_SB_CS_N<2> @S9S_MB_2U_LIB.S9S_MB_2U(SCH_1):M_H_CPU1_SB_CS_N(2)
    U1 DK38 DDR7_SB_CS_N2 SOCKET4677_AZIF0045P001C01CS-SA    I20 @S9S_MB_2U_LIB.S9S_MB_2U(SCH_1):PAGE58
   J32   84 CS0_B_N SCONN288_ADR50017P087CC-SCONN2A   I179 @S9S_MB_2U_LIB.S9S_MB_2U(SCH_1):PAGE113

M_H_CPU1_SB_CS_N<3> @S9S_MB_2U_LIB.S9S_MB_2U(SCH_1):M_H_CPU1_SB_CS_N(3)
    U1 DP38 DDR7_SB_CS_N3 SOCKET4677_AZIF0045P001C01CS-SA    I20 @S9S_MB_2U_LIB.S9S_MB_2U(SCH_1):PAGE58
   J32  229 CS1_B_N SCONN288_ADR50017P087CC-SCONN2A   I179 @S9S_MB_2U_LIB.S9S_MB_2U(SCH_1):PAGE113

M_H_CPU1_SB_DQ<0> @S9S_MB_2U_LIB.S9S_MB_2U(SCH_1):M_H_CPU1_SB_DQ(0)
    U1 DD32 DDR7_SB_DQ0 SOCKET4677_AZIF0045P001C01CS-SA    I20 @S9S_MB_2U_LIB.S9S_MB_2U(SCH_1):PAGE58
   J31  100  DQ0_B SCONN288_ADR50017P130CC-SCONN2A   I180 @S9S_MB_2U_LIB.S9S_MB_2U(SCH_1):PAGE112
   J32  100  DQ0_B SCONN288_ADR50017P087CC-SCONN2A   I179 @S9S_MB_2U_LIB.S9S_MB_2U(SCH_1):PAGE113

M_H_CPU1_SB_DQ<10> @S9S_MB_2U_LIB.S9S_MB_2U(SCH_1):M_H_CPU1_SB_DQ(10)
    U1 DF26 DDR7_SB_DQ10 SOCKET4677_AZIF0045P001C01CS-SA    I20 @S9S_MB_2U_LIB.S9S_MB_2U(SCH_1):PAGE58
   J31  256 DQ10_B SCONN288_ADR50017P130CC-SCONN2A   I180 @S9S_MB_2U_LIB.S9S_MB_2U(SCH_1):PAGE112
   J32  256 DQ10_B SCONN288_ADR50017P087CC-SCONN2A   I179 @S9S_MB_2U_LIB.S9S_MB_2U(SCH_1):PAGE113

M_H_CPU1_SB_DQ<11> @S9S_MB_2U_LIB.S9S_MB_2U(SCH_1):M_H_CPU1_SB_DQ(11)
    U1 DG25 DDR7_SB_DQ11 SOCKET4677_AZIF0045P001C01CS-SA    I20 @S9S_MB_2U_LIB.S9S_MB_2U(SCH_1):PAGE58
   J31  258 DQ11_B SCONN288_ADR50017P130CC-SCONN2A   I180 @S9S_MB_2U_LIB.S9S_MB_2U(SCH_1):PAGE112
   J32  258 DQ11_B SCONN288_ADR50017P087CC-SCONN2A   I179 @S9S_MB_2U_LIB.S9S_MB_2U(SCH_1):PAGE113

M_H_CPU1_SB_DQ<12> @S9S_MB_2U_LIB.S9S_MB_2U(SCH_1):M_H_CPU1_SB_DQ(12)
    U1 DC23 DDR7_SB_DQ12 SOCKET4677_AZIF0045P001C01CS-SA    I20 @S9S_MB_2U_LIB.S9S_MB_2U(SCH_1):PAGE58
   J31  118 DQ12_B SCONN288_ADR50017P130CC-SCONN2A   I180 @S9S_MB_2U_LIB.S9S_MB_2U(SCH_1):PAGE112
   J32  118 DQ12_B SCONN288_ADR50017P087CC-SCONN2A   I179 @S9S_MB_2U_LIB.S9S_MB_2U(SCH_1):PAGE113

M_H_CPU1_SB_DQ<13> @S9S_MB_2U_LIB.S9S_MB_2U(SCH_1):M_H_CPU1_SB_DQ(13)
    U1 DD22 DDR7_SB_DQ13 SOCKET4677_AZIF0045P001C01CS-SA    I20 @S9S_MB_2U_LIB.S9S_MB_2U(SCH_1):PAGE58
   J31  120 DQ13_B SCONN288_ADR50017P130CC-SCONN2A   I180 @S9S_MB_2U_LIB.S9S_MB_2U(SCH_1):PAGE112
   J32  120 DQ13_B SCONN288_ADR50017P087CC-SCONN2A   I179 @S9S_MB_2U_LIB.S9S_MB_2U(SCH_1):PAGE113

M_H_CPU1_SB_DQ<14> @S9S_MB_2U_LIB.S9S_MB_2U(SCH_1):M_H_CPU1_SB_DQ(14)
    U1 DG23 DDR7_SB_DQ14 SOCKET4677_AZIF0045P001C01CS-SA    I20 @S9S_MB_2U_LIB.S9S_MB_2U(SCH_1):PAGE58
   J31  263 DQ14_B SCONN288_ADR50017P130CC-SCONN2A   I180 @S9S_MB_2U_LIB.S9S_MB_2U(SCH_1):PAGE112
   J32  263 DQ14_B SCONN288_ADR50017P087CC-SCONN2A   I179 @S9S_MB_2U_LIB.S9S_MB_2U(SCH_1):PAGE113

M_H_CPU1_SB_DQ<15> @S9S_MB_2U_LIB.S9S_MB_2U(SCH_1):M_H_CPU1_SB_DQ(15)
    U1 DF22 DDR7_SB_DQ15 SOCKET4677_AZIF0045P001C01CS-SA    I20 @S9S_MB_2U_LIB.S9S_MB_2U(SCH_1):PAGE58
   J31  265 DQ15_B SCONN288_ADR50017P130CC-SCONN2A   I180 @S9S_MB_2U_LIB.S9S_MB_2U(SCH_1):PAGE112
   J32  265 DQ15_B SCONN288_ADR50017P087CC-SCONN2A   I179 @S9S_MB_2U_LIB.S9S_MB_2U(SCH_1):PAGE113

M_H_CPU1_SB_DQ<16> @S9S_MB_2U_LIB.S9S_MB_2U(SCH_1):M_H_CPU1_SB_DQ(16)
    U1 DL23 DDR7_SB_DQ16 SOCKET4677_AZIF0045P001C01CS-SA    I20 @S9S_MB_2U_LIB.S9S_MB_2U(SCH_1):PAGE58
   J31  122 DQ16_B SCONN288_ADR50017P130CC-SCONN2A   I180 @S9S_MB_2U_LIB.S9S_MB_2U(SCH_1):PAGE112
   J32  122 DQ16_B SCONN288_ADR50017P087CC-SCONN2A   I179 @S9S_MB_2U_LIB.S9S_MB_2U(SCH_1):PAGE113

M_H_CPU1_SB_DQ<17> @S9S_MB_2U_LIB.S9S_MB_2U(SCH_1):M_H_CPU1_SB_DQ(17)
    U1 DK22 DDR7_SB_DQ17 SOCKET4677_AZIF0045P001C01CS-SA    I20 @S9S_MB_2U_LIB.S9S_MB_2U(SCH_1):PAGE58
   J31  124 DQ17_B SCONN288_ADR50017P130CC-SCONN2A   I180 @S9S_MB_2U_LIB.S9S_MB_2U(SCH_1):PAGE112
   J32  124 DQ17_B SCONN288_ADR50017P087CC-SCONN2A   I179 @S9S_MB_2U_LIB.S9S_MB_2U(SCH_1):PAGE113

M_H_CPU1_SB_DQ<18> @S9S_MB_2U_LIB.S9S_MB_2U(SCH_1):M_H_CPU1_SB_DQ(18)
    U1 DN23 DDR7_SB_DQ18 SOCKET4677_AZIF0045P001C01CS-SA    I20 @S9S_MB_2U_LIB.S9S_MB_2U(SCH_1):PAGE58
   J31  267 DQ18_B SCONN288_ADR50017P130CC-SCONN2A   I180 @S9S_MB_2U_LIB.S9S_MB_2U(SCH_1):PAGE112
   J32  267 DQ18_B SCONN288_ADR50017P087CC-SCONN2A   I179 @S9S_MB_2U_LIB.S9S_MB_2U(SCH_1):PAGE113

M_H_CPU1_SB_DQ<19> @S9S_MB_2U_LIB.S9S_MB_2U(SCH_1):M_H_CPU1_SB_DQ(19)
    U1 DP22 DDR7_SB_DQ19 SOCKET4677_AZIF0045P001C01CS-SA    I20 @S9S_MB_2U_LIB.S9S_MB_2U(SCH_1):PAGE58
   J31  269 DQ19_B SCONN288_ADR50017P130CC-SCONN2A   I180 @S9S_MB_2U_LIB.S9S_MB_2U(SCH_1):PAGE112
   J32  269 DQ19_B SCONN288_ADR50017P087CC-SCONN2A   I179 @S9S_MB_2U_LIB.S9S_MB_2U(SCH_1):PAGE113

M_H_CPU1_SB_DQ<1> @S9S_MB_2U_LIB.S9S_MB_2U(SCH_1):M_H_CPU1_SB_DQ(1)
    U1 DC31 DDR7_SB_DQ1 SOCKET4677_AZIF0045P001C01CS-SA    I20 @S9S_MB_2U_LIB.S9S_MB_2U(SCH_1):PAGE58
   J31  102  DQ1_B SCONN288_ADR50017P130CC-SCONN2A   I180 @S9S_MB_2U_LIB.S9S_MB_2U(SCH_1):PAGE112
   J32  102  DQ1_B SCONN288_ADR50017P087CC-SCONN2A   I179 @S9S_MB_2U_LIB.S9S_MB_2U(SCH_1):PAGE113

M_H_CPU1_SB_DQ<20> @S9S_MB_2U_LIB.S9S_MB_2U(SCH_1):M_H_CPU1_SB_DQ(20)
    U1 DK20 DDR7_SB_DQ20 SOCKET4677_AZIF0045P001C01CS-SA    I20 @S9S_MB_2U_LIB.S9S_MB_2U(SCH_1):PAGE58
   J31  129 DQ20_B SCONN288_ADR50017P130CC-SCONN2A   I180 @S9S_MB_2U_LIB.S9S_MB_2U(SCH_1):PAGE112
   J32  129 DQ20_B SCONN288_ADR50017P087CC-SCONN2A   I179 @S9S_MB_2U_LIB.S9S_MB_2U(SCH_1):PAGE113

M_H_CPU1_SB_DQ<21> @S9S_MB_2U_LIB.S9S_MB_2U(SCH_1):M_H_CPU1_SB_DQ(21)
    U1 DL19 DDR7_SB_DQ21 SOCKET4677_AZIF0045P001C01CS-SA    I20 @S9S_MB_2U_LIB.S9S_MB_2U(SCH_1):PAGE58
   J31  131 DQ21_B SCONN288_ADR50017P130CC-SCONN2A   I180 @S9S_MB_2U_LIB.S9S_MB_2U(SCH_1):PAGE112
   J32  131 DQ21_B SCONN288_ADR50017P087CC-SCONN2A   I179 @S9S_MB_2U_LIB.S9S_MB_2U(SCH_1):PAGE113

M_H_CPU1_SB_DQ<22> @S9S_MB_2U_LIB.S9S_MB_2U(SCH_1):M_H_CPU1_SB_DQ(22)
    U1 DP20 DDR7_SB_DQ22 SOCKET4677_AZIF0045P001C01CS-SA    I20 @S9S_MB_2U_LIB.S9S_MB_2U(SCH_1):PAGE58
   J31  274 DQ22_B SCONN288_ADR50017P130CC-SCONN2A   I180 @S9S_MB_2U_LIB.S9S_MB_2U(SCH_1):PAGE112
   J32  274 DQ22_B SCONN288_ADR50017P087CC-SCONN2A   I179 @S9S_MB_2U_LIB.S9S_MB_2U(SCH_1):PAGE113

M_H_CPU1_SB_DQ<23> @S9S_MB_2U_LIB.S9S_MB_2U(SCH_1):M_H_CPU1_SB_DQ(23)
    U1 DN19 DDR7_SB_DQ23 SOCKET4677_AZIF0045P001C01CS-SA    I20 @S9S_MB_2U_LIB.S9S_MB_2U(SCH_1):PAGE58
   J31  276 DQ23_B SCONN288_ADR50017P130CC-SCONN2A   I180 @S9S_MB_2U_LIB.S9S_MB_2U(SCH_1):PAGE112
   J32  276 DQ23_B SCONN288_ADR50017P087CC-SCONN2A   I179 @S9S_MB_2U_LIB.S9S_MB_2U(SCH_1):PAGE113

M_H_CPU1_SB_DQ<24> @S9S_MB_2U_LIB.S9S_MB_2U(SCH_1):M_H_CPU1_SB_DQ(24)
    U1 DD20 DDR7_SB_DQ24 SOCKET4677_AZIF0045P001C01CS-SA    I20 @S9S_MB_2U_LIB.S9S_MB_2U(SCH_1):PAGE58
   J31  133 DQ24_B SCONN288_ADR50017P130CC-SCONN2A   I180 @S9S_MB_2U_LIB.S9S_MB_2U(SCH_1):PAGE112
   J32  133 DQ24_B SCONN288_ADR50017P087CC-SCONN2A   I179 @S9S_MB_2U_LIB.S9S_MB_2U(SCH_1):PAGE113

M_H_CPU1_SB_DQ<25> @S9S_MB_2U_LIB.S9S_MB_2U(SCH_1):M_H_CPU1_SB_DQ(25)
    U1 DC19 DDR7_SB_DQ25 SOCKET4677_AZIF0045P001C01CS-SA    I20 @S9S_MB_2U_LIB.S9S_MB_2U(SCH_1):PAGE58
   J31  135 DQ25_B SCONN288_ADR50017P130CC-SCONN2A   I180 @S9S_MB_2U_LIB.S9S_MB_2U(SCH_1):PAGE112
   J32  135 DQ25_B SCONN288_ADR50017P087CC-SCONN2A   I179 @S9S_MB_2U_LIB.S9S_MB_2U(SCH_1):PAGE113

M_H_CPU1_SB_DQ<26> @S9S_MB_2U_LIB.S9S_MB_2U(SCH_1):M_H_CPU1_SB_DQ(26)
    U1 DF20 DDR7_SB_DQ26 SOCKET4677_AZIF0045P001C01CS-SA    I20 @S9S_MB_2U_LIB.S9S_MB_2U(SCH_1):PAGE58
   J31  278 DQ26_B SCONN288_ADR50017P130CC-SCONN2A   I180 @S9S_MB_2U_LIB.S9S_MB_2U(SCH_1):PAGE112
   J32  278 DQ26_B SCONN288_ADR50017P087CC-SCONN2A   I179 @S9S_MB_2U_LIB.S9S_MB_2U(SCH_1):PAGE113

M_H_CPU1_SB_DQ<27> @S9S_MB_2U_LIB.S9S_MB_2U(SCH_1):M_H_CPU1_SB_DQ(27)
    U1 DG19 DDR7_SB_DQ27 SOCKET4677_AZIF0045P001C01CS-SA    I20 @S9S_MB_2U_LIB.S9S_MB_2U(SCH_1):PAGE58
   J31  280 DQ27_B SCONN288_ADR50017P130CC-SCONN2A   I180 @S9S_MB_2U_LIB.S9S_MB_2U(SCH_1):PAGE112
   J32  280 DQ27_B SCONN288_ADR50017P087CC-SCONN2A   I179 @S9S_MB_2U_LIB.S9S_MB_2U(SCH_1):PAGE113

M_H_CPU1_SB_DQ<28> @S9S_MB_2U_LIB.S9S_MB_2U(SCH_1):M_H_CPU1_SB_DQ(28)
    U1 DG17 DDR7_SB_DQ28 SOCKET4677_AZIF0045P001C01CS-SA    I20 @S9S_MB_2U_LIB.S9S_MB_2U(SCH_1):PAGE58
   J31  140 DQ28_B SCONN288_ADR50017P130CC-SCONN2A   I180 @S9S_MB_2U_LIB.S9S_MB_2U(SCH_1):PAGE112
   J32  140 DQ28_B SCONN288_ADR50017P087CC-SCONN2A   I179 @S9S_MB_2U_LIB.S9S_MB_2U(SCH_1):PAGE113

M_H_CPU1_SB_DQ<29> @S9S_MB_2U_LIB.S9S_MB_2U(SCH_1):M_H_CPU1_SB_DQ(29)
    U1 DA17 DDR7_SB_DQ29 SOCKET4677_AZIF0045P001C01CS-SA    I20 @S9S_MB_2U_LIB.S9S_MB_2U(SCH_1):PAGE58
   J31  142 DQ29_B SCONN288_ADR50017P130CC-SCONN2A   I180 @S9S_MB_2U_LIB.S9S_MB_2U(SCH_1):PAGE112
   J32  142 DQ29_B SCONN288_ADR50017P087CC-SCONN2A   I179 @S9S_MB_2U_LIB.S9S_MB_2U(SCH_1):PAGE113

M_H_CPU1_SB_DQ<2> @S9S_MB_2U_LIB.S9S_MB_2U(SCH_1):M_H_CPU1_SB_DQ(2)
    U1 DF32 DDR7_SB_DQ2 SOCKET4677_AZIF0045P001C01CS-SA    I20 @S9S_MB_2U_LIB.S9S_MB_2U(SCH_1):PAGE58
   J31  245  DQ2_B SCONN288_ADR50017P130CC-SCONN2A   I180 @S9S_MB_2U_LIB.S9S_MB_2U(SCH_1):PAGE112
   J32  245  DQ2_B SCONN288_ADR50017P087CC-SCONN2A   I179 @S9S_MB_2U_LIB.S9S_MB_2U(SCH_1):PAGE113

M_H_CPU1_SB_DQ<30> @S9S_MB_2U_LIB.S9S_MB_2U(SCH_1):M_H_CPU1_SB_DQ(30)
    U1 DJ17 DDR7_SB_DQ30 SOCKET4677_AZIF0045P001C01CS-SA    I20 @S9S_MB_2U_LIB.S9S_MB_2U(SCH_1):PAGE58
   J31  285 DQ30_B SCONN288_ADR50017P130CC-SCONN2A   I180 @S9S_MB_2U_LIB.S9S_MB_2U(SCH_1):PAGE112
   J32  285 DQ30_B SCONN288_ADR50017P087CC-SCONN2A   I179 @S9S_MB_2U_LIB.S9S_MB_2U(SCH_1):PAGE113

M_H_CPU1_SB_DQ<31> @S9S_MB_2U_LIB.S9S_MB_2U(SCH_1):M_H_CPU1_SB_DQ(31)
    U1 DC17 DDR7_SB_DQ31 SOCKET4677_AZIF0045P001C01CS-SA    I20 @S9S_MB_2U_LIB.S9S_MB_2U(SCH_1):PAGE58
   J31  287 DQ31_B SCONN288_ADR50017P130CC-SCONN2A   I180 @S9S_MB_2U_LIB.S9S_MB_2U(SCH_1):PAGE112
   J32  287 DQ31_B SCONN288_ADR50017P087CC-SCONN2A   I179 @S9S_MB_2U_LIB.S9S_MB_2U(SCH_1):PAGE113

M_H_CPU1_SB_DQ<3> @S9S_MB_2U_LIB.S9S_MB_2U(SCH_1):M_H_CPU1_SB_DQ(3)
    U1 DG31 DDR7_SB_DQ3 SOCKET4677_AZIF0045P001C01CS-SA    I20 @S9S_MB_2U_LIB.S9S_MB_2U(SCH_1):PAGE58
   J31  247  DQ3_B SCONN288_ADR50017P130CC-SCONN2A   I180 @S9S_MB_2U_LIB.S9S_MB_2U(SCH_1):PAGE112
   J32  247  DQ3_B SCONN288_ADR50017P087CC-SCONN2A   I179 @S9S_MB_2U_LIB.S9S_MB_2U(SCH_1):PAGE113

M_H_CPU1_SB_DQ<4> @S9S_MB_2U_LIB.S9S_MB_2U(SCH_1):M_H_CPU1_SB_DQ(4)
    U1 DC29 DDR7_SB_DQ4 SOCKET4677_AZIF0045P001C01CS-SA    I20 @S9S_MB_2U_LIB.S9S_MB_2U(SCH_1):PAGE58
   J31  107  DQ4_B SCONN288_ADR50017P130CC-SCONN2A   I180 @S9S_MB_2U_LIB.S9S_MB_2U(SCH_1):PAGE112
   J32  107  DQ4_B SCONN288_ADR50017P087CC-SCONN2A   I179 @S9S_MB_2U_LIB.S9S_MB_2U(SCH_1):PAGE113

M_H_CPU1_SB_DQ<5> @S9S_MB_2U_LIB.S9S_MB_2U(SCH_1):M_H_CPU1_SB_DQ(5)
    U1 DF28 DDR7_SB_DQ5 SOCKET4677_AZIF0045P001C01CS-SA    I20 @S9S_MB_2U_LIB.S9S_MB_2U(SCH_1):PAGE58
   J31  109  DQ5_B SCONN288_ADR50017P130CC-SCONN2A   I180 @S9S_MB_2U_LIB.S9S_MB_2U(SCH_1):PAGE112
   J32  109  DQ5_B SCONN288_ADR50017P087CC-SCONN2A   I179 @S9S_MB_2U_LIB.S9S_MB_2U(SCH_1):PAGE113

M_H_CPU1_SB_DQ<6> @S9S_MB_2U_LIB.S9S_MB_2U(SCH_1):M_H_CPU1_SB_DQ(6)
    U1 DG29 DDR7_SB_DQ6 SOCKET4677_AZIF0045P001C01CS-SA    I20 @S9S_MB_2U_LIB.S9S_MB_2U(SCH_1):PAGE58
   J31  252  DQ6_B SCONN288_ADR50017P130CC-SCONN2A   I180 @S9S_MB_2U_LIB.S9S_MB_2U(SCH_1):PAGE112
   J32  252  DQ6_B SCONN288_ADR50017P087CC-SCONN2A   I179 @S9S_MB_2U_LIB.S9S_MB_2U(SCH_1):PAGE113

M_H_CPU1_SB_DQ<7> @S9S_MB_2U_LIB.S9S_MB_2U(SCH_1):M_H_CPU1_SB_DQ(7)
    U1 DD28 DDR7_SB_DQ7 SOCKET4677_AZIF0045P001C01CS-SA    I20 @S9S_MB_2U_LIB.S9S_MB_2U(SCH_1):PAGE58
   J31  254  DQ7_B SCONN288_ADR50017P130CC-SCONN2A   I180 @S9S_MB_2U_LIB.S9S_MB_2U(SCH_1):PAGE112
   J32  254  DQ7_B SCONN288_ADR50017P087CC-SCONN2A   I179 @S9S_MB_2U_LIB.S9S_MB_2U(SCH_1):PAGE113

M_H_CPU1_SB_DQ<8> @S9S_MB_2U_LIB.S9S_MB_2U(SCH_1):M_H_CPU1_SB_DQ(8)
    U1 DD26 DDR7_SB_DQ8 SOCKET4677_AZIF0045P001C01CS-SA    I20 @S9S_MB_2U_LIB.S9S_MB_2U(SCH_1):PAGE58
   J31  111  DQ8_B SCONN288_ADR50017P130CC-SCONN2A   I180 @S9S_MB_2U_LIB.S9S_MB_2U(SCH_1):PAGE112
   J32  111  DQ8_B SCONN288_ADR50017P087CC-SCONN2A   I179 @S9S_MB_2U_LIB.S9S_MB_2U(SCH_1):PAGE113

M_H_CPU1_SB_DQ<9> @S9S_MB_2U_LIB.S9S_MB_2U(SCH_1):M_H_CPU1_SB_DQ(9)
    U1 DC25 DDR7_SB_DQ9 SOCKET4677_AZIF0045P001C01CS-SA    I20 @S9S_MB_2U_LIB.S9S_MB_2U(SCH_1):PAGE58
   J31  113  DQ9_B SCONN288_ADR50017P130CC-SCONN2A   I180 @S9S_MB_2U_LIB.S9S_MB_2U(SCH_1):PAGE112
   J32  113  DQ9_B SCONN288_ADR50017P087CC-SCONN2A   I179 @S9S_MB_2U_LIB.S9S_MB_2U(SCH_1):PAGE113

M_H_CPU1_SB_DQS_DN<0> @S9S_MB_2U_LIB.S9S_MB_2U(SCH_1):M_H_CPU1_SB_DQS_DN(0)
    U1 DD30 DDR7_SB_DQS_DN0 SOCKET4677_AZIF0045P001C01CS-SA    I20 @S9S_MB_2U_LIB.S9S_MB_2U(SCH_1):PAGE58
   J31  105 DQS0_B_C SCONN288_ADR50017P130CC-SCONN2A   I181 @S9S_MB_2U_LIB.S9S_MB_2U(SCH_1):PAGE112
   J32  105 DQS0_B_C SCONN288_ADR50017P087CC-SCONN2A   I180 @S9S_MB_2U_LIB.S9S_MB_2U(SCH_1):PAGE113

M_H_CPU1_SB_DQS_DN<1> @S9S_MB_2U_LIB.S9S_MB_2U(SCH_1):M_H_CPU1_SB_DQS_DN(1)
    U1 DD24 DDR7_SB_DQS_DN1 SOCKET4677_AZIF0045P001C01CS-SA    I20 @S9S_MB_2U_LIB.S9S_MB_2U(SCH_1):PAGE58
   J31  116 DQS1_B_C SCONN288_ADR50017P130CC-SCONN2A   I181 @S9S_MB_2U_LIB.S9S_MB_2U(SCH_1):PAGE112
   J32  116 DQS1_B_C SCONN288_ADR50017P087CC-SCONN2A   I180 @S9S_MB_2U_LIB.S9S_MB_2U(SCH_1):PAGE113

M_H_CPU1_SB_DQS_DN<2> @S9S_MB_2U_LIB.S9S_MB_2U(SCH_1):M_H_CPU1_SB_DQS_DN(2)
    U1 DL21 DDR7_SB_DQS_DN2 SOCKET4677_AZIF0045P001C01CS-SA    I20 @S9S_MB_2U_LIB.S9S_MB_2U(SCH_1):PAGE58
   J31  127 DQS2_B_C SCONN288_ADR50017P130CC-SCONN2A   I181 @S9S_MB_2U_LIB.S9S_MB_2U(SCH_1):PAGE112
   J32  127 DQS2_B_C SCONN288_ADR50017P087CC-SCONN2A   I180 @S9S_MB_2U_LIB.S9S_MB_2U(SCH_1):PAGE113

M_H_CPU1_SB_DQS_DN<3> @S9S_MB_2U_LIB.S9S_MB_2U(SCH_1):M_H_CPU1_SB_DQS_DN(3)
    U1 DB18 DDR7_SB_DQS_DN3 SOCKET4677_AZIF0045P001C01CS-SA    I20 @S9S_MB_2U_LIB.S9S_MB_2U(SCH_1):PAGE58
   J31  138 DQS3_B_C SCONN288_ADR50017P130CC-SCONN2A   I181 @S9S_MB_2U_LIB.S9S_MB_2U(SCH_1):PAGE112
   J32  138 DQS3_B_C SCONN288_ADR50017P087CC-SCONN2A   I180 @S9S_MB_2U_LIB.S9S_MB_2U(SCH_1):PAGE113

M_H_CPU1_SB_DQS_DN<4> @S9S_MB_2U_LIB.S9S_MB_2U(SCH_1):M_H_CPU1_SB_DQS_DN(4)
    U1 DH36 DDR7_SB_DQS_DN4 SOCKET4677_AZIF0045P001C01CS-SA    I20 @S9S_MB_2U_LIB.S9S_MB_2U(SCH_1):PAGE58
   J31  238 DQS4_B_C SCONN288_ADR50017P130CC-SCONN2A   I181 @S9S_MB_2U_LIB.S9S_MB_2U(SCH_1):PAGE112
   J32  238 DQS4_B_C SCONN288_ADR50017P087CC-SCONN2A   I180 @S9S_MB_2U_LIB.S9S_MB_2U(SCH_1):PAGE113

M_H_CPU1_SB_DQS_DN<5> @S9S_MB_2U_LIB.S9S_MB_2U(SCH_1):M_H_CPU1_SB_DQS_DN(5)
    U1 DH30 DDR7_SB_DQS_DN5 SOCKET4677_AZIF0045P001C01CS-SA    I20 @S9S_MB_2U_LIB.S9S_MB_2U(SCH_1):PAGE58
   J31  249 DQS5_B_C||TDQS5_B_C SCONN288_ADR50017P130CC-SCONN2A   I181 @S9S_MB_2U_LIB.S9S_MB_2U(SCH_1):PAGE112
   J32  249 DQS5_B_C||TDQS5_B_C SCONN288_ADR50017P087CC-SCONN2A   I180 @S9S_MB_2U_LIB.S9S_MB_2U(SCH_1):PAGE113

M_H_CPU1_SB_DQS_DN<6> @S9S_MB_2U_LIB.S9S_MB_2U(SCH_1):M_H_CPU1_SB_DQS_DN(6)
    U1 DH24 DDR7_SB_DQS_DN6 SOCKET4677_AZIF0045P001C01CS-SA    I20 @S9S_MB_2U_LIB.S9S_MB_2U(SCH_1):PAGE58
   J31  260 DQS6_B_C||TDQS6_B_C SCONN288_ADR50017P130CC-SCONN2A   I181 @S9S_MB_2U_LIB.S9S_MB_2U(SCH_1):PAGE112
   J32  260 DQS6_B_C||TDQS6_B_C SCONN288_ADR50017P087CC-SCONN2A   I180 @S9S_MB_2U_LIB.S9S_MB_2U(SCH_1):PAGE113

M_H_CPU1_SB_DQS_DN<7> @S9S_MB_2U_LIB.S9S_MB_2U(SCH_1):M_H_CPU1_SB_DQS_DN(7)
    U1 DR21 DDR7_SB_DQS_DN7 SOCKET4677_AZIF0045P001C01CS-SA    I20 @S9S_MB_2U_LIB.S9S_MB_2U(SCH_1):PAGE58
   J31  271 DQS7_B_C||TDQS7_B_C SCONN288_ADR50017P130CC-SCONN2A   I181 @S9S_MB_2U_LIB.S9S_MB_2U(SCH_1):PAGE112
   J32  271 DQS7_B_C||TDQS7_B_C SCONN288_ADR50017P087CC-SCONN2A   I180 @S9S_MB_2U_LIB.S9S_MB_2U(SCH_1):PAGE113

M_H_CPU1_SB_DQS_DN<8> @S9S_MB_2U_LIB.S9S_MB_2U(SCH_1):M_H_CPU1_SB_DQS_DN(8)
    U1 DF18 DDR7_SB_DQS_DN8 SOCKET4677_AZIF0045P001C01CS-SA    I20 @S9S_MB_2U_LIB.S9S_MB_2U(SCH_1):PAGE58
   J31  282 DQS8_B_C||TDQS8_B_C SCONN288_ADR50017P130CC-SCONN2A   I181 @S9S_MB_2U_LIB.S9S_MB_2U(SCH_1):PAGE112
   J32  282 DQS8_B_C||TDQS8_B_C SCONN288_ADR50017P087CC-SCONN2A   I180 @S9S_MB_2U_LIB.S9S_MB_2U(SCH_1):PAGE113

M_H_CPU1_SB_DQS_DN<9> @S9S_MB_2U_LIB.S9S_MB_2U(SCH_1):M_H_CPU1_SB_DQS_DN(9)
    U1 DD36 DDR7_SB_DQS_DN9 SOCKET4677_AZIF0045P001C01CS-SA    I20 @S9S_MB_2U_LIB.S9S_MB_2U(SCH_1):PAGE58
   J31   94 DQS9_B_C||TDQS9_B_C SCONN288_ADR50017P130CC-SCONN2A   I181 @S9S_MB_2U_LIB.S9S_MB_2U(SCH_1):PAGE112
   J32   94 DQS9_B_C||TDQS9_B_C SCONN288_ADR50017P087CC-SCONN2A   I180 @S9S_MB_2U_LIB.S9S_MB_2U(SCH_1):PAGE113

M_H_CPU1_SB_DQS_DP<0> @S9S_MB_2U_LIB.S9S_MB_2U(SCH_1):M_H_CPU1_SB_DQS_DP(0)
    U1 DB30 DDR7_SB_DQS_DP0 SOCKET4677_AZIF0045P001C01CS-SA    I20 @S9S_MB_2U_LIB.S9S_MB_2U(SCH_1):PAGE58
   J31  104 DQS0_B_T SCONN288_ADR50017P130CC-SCONN2A   I181 @S9S_MB_2U_LIB.S9S_MB_2U(SCH_1):PAGE112
   J32  104 DQS0_B_T SCONN288_ADR50017P087CC-SCONN2A   I180 @S9S_MB_2U_LIB.S9S_MB_2U(SCH_1):PAGE113

M_H_CPU1_SB_DQS_DP<1> @S9S_MB_2U_LIB.S9S_MB_2U(SCH_1):M_H_CPU1_SB_DQS_DP(1)
    U1 DB24 DDR7_SB_DQS_DP1 SOCKET4677_AZIF0045P001C01CS-SA    I20 @S9S_MB_2U_LIB.S9S_MB_2U(SCH_1):PAGE58
   J31  115 DQS1_B_T SCONN288_ADR50017P130CC-SCONN2A   I181 @S9S_MB_2U_LIB.S9S_MB_2U(SCH_1):PAGE112
   J32  115 DQS1_B_T SCONN288_ADR50017P087CC-SCONN2A   I180 @S9S_MB_2U_LIB.S9S_MB_2U(SCH_1):PAGE113

M_H_CPU1_SB_DQS_DP<2> @S9S_MB_2U_LIB.S9S_MB_2U(SCH_1):M_H_CPU1_SB_DQS_DP(2)
    U1 DJ21 DDR7_SB_DQS_DP2 SOCKET4677_AZIF0045P001C01CS-SA    I20 @S9S_MB_2U_LIB.S9S_MB_2U(SCH_1):PAGE58
   J31  126 DQS2_B_T SCONN288_ADR50017P130CC-SCONN2A   I181 @S9S_MB_2U_LIB.S9S_MB_2U(SCH_1):PAGE112
   J32  126 DQS2_B_T SCONN288_ADR50017P087CC-SCONN2A   I180 @S9S_MB_2U_LIB.S9S_MB_2U(SCH_1):PAGE113

M_H_CPU1_SB_DQS_DP<3> @S9S_MB_2U_LIB.S9S_MB_2U(SCH_1):M_H_CPU1_SB_DQS_DP(3)
    U1 DD18 DDR7_SB_DQS_DP3 SOCKET4677_AZIF0045P001C01CS-SA    I20 @S9S_MB_2U_LIB.S9S_MB_2U(SCH_1):PAGE58
   J31  137 DQS3_B_T SCONN288_ADR50017P130CC-SCONN2A   I181 @S9S_MB_2U_LIB.S9S_MB_2U(SCH_1):PAGE112
   J32  137 DQS3_B_T SCONN288_ADR50017P087CC-SCONN2A   I180 @S9S_MB_2U_LIB.S9S_MB_2U(SCH_1):PAGE113

M_H_CPU1_SB_DQS_DP<4> @S9S_MB_2U_LIB.S9S_MB_2U(SCH_1):M_H_CPU1_SB_DQS_DP(4)
    U1 DF36 DDR7_SB_DQS_DP4 SOCKET4677_AZIF0045P001C01CS-SA    I20 @S9S_MB_2U_LIB.S9S_MB_2U(SCH_1):PAGE58
   J31  239 DQS4_B_T SCONN288_ADR50017P130CC-SCONN2A   I181 @S9S_MB_2U_LIB.S9S_MB_2U(SCH_1):PAGE112
   J32  239 DQS4_B_T SCONN288_ADR50017P087CC-SCONN2A   I180 @S9S_MB_2U_LIB.S9S_MB_2U(SCH_1):PAGE113

M_H_CPU1_SB_DQS_DP<5> @S9S_MB_2U_LIB.S9S_MB_2U(SCH_1):M_H_CPU1_SB_DQS_DP(5)
    U1 DF30 DDR7_SB_DQS_DP5 SOCKET4677_AZIF0045P001C01CS-SA    I20 @S9S_MB_2U_LIB.S9S_MB_2U(SCH_1):PAGE58
   J31  250 DQS5_B_T||TDQS5_B_T SCONN288_ADR50017P130CC-SCONN2A   I181 @S9S_MB_2U_LIB.S9S_MB_2U(SCH_1):PAGE112
   J32  250 DQS5_B_T||TDQS5_B_T SCONN288_ADR50017P087CC-SCONN2A   I180 @S9S_MB_2U_LIB.S9S_MB_2U(SCH_1):PAGE113

M_H_CPU1_SB_DQS_DP<6> @S9S_MB_2U_LIB.S9S_MB_2U(SCH_1):M_H_CPU1_SB_DQS_DP(6)
    U1 DF24 DDR7_SB_DQS_DP6 SOCKET4677_AZIF0045P001C01CS-SA    I20 @S9S_MB_2U_LIB.S9S_MB_2U(SCH_1):PAGE58
   J31  261 DQS6_B_T||TDQS6_B_T SCONN288_ADR50017P130CC-SCONN2A   I181 @S9S_MB_2U_LIB.S9S_MB_2U(SCH_1):PAGE112
   J32  261 DQS6_B_T||TDQS6_B_T SCONN288_ADR50017P087CC-SCONN2A   I180 @S9S_MB_2U_LIB.S9S_MB_2U(SCH_1):PAGE113

M_H_CPU1_SB_DQS_DP<7> @S9S_MB_2U_LIB.S9S_MB_2U(SCH_1):M_H_CPU1_SB_DQS_DP(7)
    U1 DN21 DDR7_SB_DQS_DP7 SOCKET4677_AZIF0045P001C01CS-SA    I20 @S9S_MB_2U_LIB.S9S_MB_2U(SCH_1):PAGE58
   J31  272 DQS7_B_T||TDQS7_B_T SCONN288_ADR50017P130CC-SCONN2A   I181 @S9S_MB_2U_LIB.S9S_MB_2U(SCH_1):PAGE112
   J32  272 DQS7_B_T||TDQS7_B_T SCONN288_ADR50017P087CC-SCONN2A   I180 @S9S_MB_2U_LIB.S9S_MB_2U(SCH_1):PAGE113

M_H_CPU1_SB_DQS_DP<8> @S9S_MB_2U_LIB.S9S_MB_2U(SCH_1):M_H_CPU1_SB_DQS_DP(8)
    U1 DH18 DDR7_SB_DQS_DP8 SOCKET4677_AZIF0045P001C01CS-SA    I20 @S9S_MB_2U_LIB.S9S_MB_2U(SCH_1):PAGE58
   J31  283 DQS8_B_T||TDQS8_B_T SCONN288_ADR50017P130CC-SCONN2A   I181 @S9S_MB_2U_LIB.S9S_MB_2U(SCH_1):PAGE112
   J32  283 DQS8_B_T||TDQS8_B_T SCONN288_ADR50017P087CC-SCONN2A   I180 @S9S_MB_2U_LIB.S9S_MB_2U(SCH_1):PAGE113

M_H_CPU1_SB_DQS_DP<9> @S9S_MB_2U_LIB.S9S_MB_2U(SCH_1):M_H_CPU1_SB_DQS_DP(9)
    U1 DB36 DDR7_SB_DQS_DP9 SOCKET4677_AZIF0045P001C01CS-SA    I20 @S9S_MB_2U_LIB.S9S_MB_2U(SCH_1):PAGE58
   J31   93 DQS9_B_T||TDQS9_B_T||DBI4_B_N SCONN288_ADR50017P130CC-SCONN2A   I181 @S9S_MB_2U_LIB.S9S_MB_2U(SCH_1):PAGE112
   J32   93 DQS9_B_T||TDQS9_B_T||DBI4_B_N SCONN288_ADR50017P087CC-SCONN2A   I180 @S9S_MB_2U_LIB.S9S_MB_2U(SCH_1):PAGE113

M_H_CPU1_SB_PAR @S9S_MB_2U_LIB.S9S_MB_2U(SCH_1):M_H_CPU1_SB_PAR
    U1 DR39 DDR7_SB_PAR SOCKET4677_AZIF0045P001C01CS-SA    I20 @S9S_MB_2U_LIB.S9S_MB_2U(SCH_1):PAGE58
   J31  227  PAR_B SCONN288_ADR50017P130CC-SCONN2A   I180 @S9S_MB_2U_LIB.S9S_MB_2U(SCH_1):PAGE112
   J32  227  PAR_B SCONN288_ADR50017P087CC-SCONN2A   I179 @S9S_MB_2U_LIB.S9S_MB_2U(SCH_1):PAGE113

M_H_CPU1_SB_RSP<0> @S9S_MB_2U_LIB.S9S_MB_2U(SCH_1):M_H_CPU1_SB_RSP(0)
    U1 EE48 DDR7_B_RSP0 SOCKET4677_AZIF0045P001C01CS-SA    I20 @S9S_MB_2U_LIB.S9S_MB_2U(SCH_1):PAGE58
   J31   87 LBS||RSP_B_N SCONN288_ADR50017P130CC-SCONN2A   I180 @S9S_MB_2U_LIB.S9S_MB_2U(SCH_1):PAGE112

M_H_CPU1_SB_RSP<1> @S9S_MB_2U_LIB.S9S_MB_2U(SCH_1):M_H_CPU1_SB_RSP(1)
    U1 ED47 DDR7_B_RSP1 SOCKET4677_AZIF0045P001C01CS-SA    I20 @S9S_MB_2U_LIB.S9S_MB_2U(SCH_1):PAGE58
   J32   87 LBS||RSP_B_N SCONN288_ADR50017P087CC-SCONN2A   I179 @S9S_MB_2U_LIB.S9S_MB_2U(SCH_1):PAGE113

NC         NC
    U2 EH85 UPI3_TX_DN0 SOCKET4677_AZIF0045P001C01CS-SA   I102 @S9S_MB_2U_LIB.S9S_MB_2U(SCH_1):PAGE35
    U2 EL84 UPI3_TX_DN1 SOCKET4677_AZIF0045P001C01CS-SA   I102 @S9S_MB_2U_LIB.S9S_MB_2U(SCH_1):PAGE35
    U2 EP85 UPI3_TX_DN2 SOCKET4677_AZIF0045P001C01CS-SA   I102 @S9S_MB_2U_LIB.S9S_MB_2U(SCH_1):PAGE35
    U2 EM87 UPI3_TX_DN3 SOCKET4677_AZIF0045P001C01CS-SA   I102 @S9S_MB_2U_LIB.S9S_MB_2U(SCH_1):PAGE35
    U2 EJ86 UPI3_TX_DN4 SOCKET4677_AZIF0045P001C01CS-SA   I102 @S9S_MB_2U_LIB.S9S_MB_2U(SCH_1):PAGE35
    U2 EK87 UPI3_TX_DN5 SOCKET4677_AZIF0045P001C01CS-SA   I102 @S9S_MB_2U_LIB.S9S_MB_2U(SCH_1):PAGE35
    U2 DU80 UPI3_TX_DN6 SOCKET4677_AZIF0045P001C01CS-SA   I102 @S9S_MB_2U_LIB.S9S_MB_2U(SCH_1):PAGE35
    U2 DR82 UPI3_TX_DN7 SOCKET4677_AZIF0045P001C01CS-SA   I102 @S9S_MB_2U_LIB.S9S_MB_2U(SCH_1):PAGE35
    U2 DP79 UPI3_TX_DN8 SOCKET4677_AZIF0045P001C01CS-SA   I102 @S9S_MB_2U_LIB.S9S_MB_2U(SCH_1):PAGE35
    U2 DN82 UPI3_TX_DN9 SOCKET4677_AZIF0045P001C01CS-SA   I102 @S9S_MB_2U_LIB.S9S_MB_2U(SCH_1):PAGE35
    U2 DM81 UPI3_TX_DN10 SOCKET4677_AZIF0045P001C01CS-SA   I102 @S9S_MB_2U_LIB.S9S_MB_2U(SCH_1):PAGE35
    U2 DL80 UPI3_TX_DN11 SOCKET4677_AZIF0045P001C01CS-SA   I102 @S9S_MB_2U_LIB.S9S_MB_2U(SCH_1):PAGE35
    U2 CW76 UPI3_TX_DN12 SOCKET4677_AZIF0045P001C01CS-SA   I102 @S9S_MB_2U_LIB.S9S_MB_2U(SCH_1):PAGE35
    U2 CU76 UPI3_TX_DN13 SOCKET4677_AZIF0045P001C01CS-SA   I102 @S9S_MB_2U_LIB.S9S_MB_2U(SCH_1):PAGE35
    U2 CT75 UPI3_TX_DN14 SOCKET4677_AZIF0045P001C01CS-SA   I102 @S9S_MB_2U_LIB.S9S_MB_2U(SCH_1):PAGE35
    U2 CR74 UPI3_TX_DN15 SOCKET4677_AZIF0045P001C01CS-SA   I102 @S9S_MB_2U_LIB.S9S_MB_2U(SCH_1):PAGE35
    U2 CK77 UPI3_TX_DN16 SOCKET4677_AZIF0045P001C01CS-SA   I102 @S9S_MB_2U_LIB.S9S_MB_2U(SCH_1):PAGE35
    U2 CH77 UPI3_TX_DN17 SOCKET4677_AZIF0045P001C01CS-SA   I102 @S9S_MB_2U_LIB.S9S_MB_2U(SCH_1):PAGE35
    U2 CM75 UPI3_TX_DN18 SOCKET4677_AZIF0045P001C01CS-SA   I102 @S9S_MB_2U_LIB.S9S_MB_2U(SCH_1):PAGE35
    U2 CG76 UPI3_TX_DN19 SOCKET4677_AZIF0045P001C01CS-SA   I102 @S9S_MB_2U_LIB.S9S_MB_2U(SCH_1):PAGE35
    U2 CF75 UPI3_TX_DN20 SOCKET4677_AZIF0045P001C01CS-SA   I102 @S9S_MB_2U_LIB.S9S_MB_2U(SCH_1):PAGE35
    U2 CJ74 UPI3_TX_DN21 SOCKET4677_AZIF0045P001C01CS-SA   I102 @S9S_MB_2U_LIB.S9S_MB_2U(SCH_1):PAGE35
    U2 CV73 UPI3_TX_DN22 SOCKET4677_AZIF0045P001C01CS-SA   I102 @S9S_MB_2U_LIB.S9S_MB_2U(SCH_1):PAGE35
    U2 CF73 UPI3_TX_DN23 SOCKET4677_AZIF0045P001C01CS-SA   I102 @S9S_MB_2U_LIB.S9S_MB_2U(SCH_1):PAGE35
    U2 EK85 UPI3_TX_DP0 SOCKET4677_AZIF0045P001C01CS-SA   I102 @S9S_MB_2U_LIB.S9S_MB_2U(SCH_1):PAGE35
    U2 EM85 UPI3_TX_DP1 SOCKET4677_AZIF0045P001C01CS-SA   I102 @S9S_MB_2U_LIB.S9S_MB_2U(SCH_1):PAGE35
    U2 EN86 UPI3_TX_DP2 SOCKET4677_AZIF0045P001C01CS-SA   I102 @S9S_MB_2U_LIB.S9S_MB_2U(SCH_1):PAGE35
    U2 EP87 UPI3_TX_DP3 SOCKET4677_AZIF0045P001C01CS-SA   I102 @S9S_MB_2U_LIB.S9S_MB_2U(SCH_1):PAGE35
    U2 EH87 UPI3_TX_DP4 SOCKET4677_AZIF0045P001C01CS-SA   I102 @S9S_MB_2U_LIB.S9S_MB_2U(SCH_1):PAGE35
    U2 EL88 UPI3_TX_DP5 SOCKET4677_AZIF0045P001C01CS-SA   I102 @S9S_MB_2U_LIB.S9S_MB_2U(SCH_1):PAGE35
    U2 DT81 UPI3_TX_DP6 SOCKET4677_AZIF0045P001C01CS-SA   I102 @S9S_MB_2U_LIB.S9S_MB_2U(SCH_1):PAGE35
    U2 DU82 UPI3_TX_DP7 SOCKET4677_AZIF0045P001C01CS-SA   I102 @S9S_MB_2U_LIB.S9S_MB_2U(SCH_1):PAGE35
    U2 DR80 UPI3_TX_DP8 SOCKET4677_AZIF0045P001C01CS-SA   I102 @S9S_MB_2U_LIB.S9S_MB_2U(SCH_1):PAGE35
    U2 DP83 UPI3_TX_DP9 SOCKET4677_AZIF0045P001C01CS-SA   I102 @S9S_MB_2U_LIB.S9S_MB_2U(SCH_1):PAGE35
    U2 DL82 UPI3_TX_DP10 SOCKET4677_AZIF0045P001C01CS-SA   I102 @S9S_MB_2U_LIB.S9S_MB_2U(SCH_1):PAGE35
    U2 DN80 UPI3_TX_DP11 SOCKET4677_AZIF0045P001C01CS-SA   I102 @S9S_MB_2U_LIB.S9S_MB_2U(SCH_1):PAGE35
    U2 DA76 UPI3_TX_DP12 SOCKET4677_AZIF0045P001C01CS-SA   I102 @S9S_MB_2U_LIB.S9S_MB_2U(SCH_1):PAGE35
    U2 CV77 UPI3_TX_DP13 SOCKET4677_AZIF0045P001C01CS-SA   I102 @S9S_MB_2U_LIB.S9S_MB_2U(SCH_1):PAGE35
    U2 CR76 UPI3_TX_DP14 SOCKET4677_AZIF0045P001C01CS-SA   I102 @S9S_MB_2U_LIB.S9S_MB_2U(SCH_1):PAGE35
    U2 CU74 UPI3_TX_DP15 SOCKET4677_AZIF0045P001C01CS-SA   I102 @S9S_MB_2U_LIB.S9S_MB_2U(SCH_1):PAGE35
    U2 CM77 UPI3_TX_DP16 SOCKET4677_AZIF0045P001C01CS-SA   I102 @S9S_MB_2U_LIB.S9S_MB_2U(SCH_1):PAGE35
    U2 CJ78 UPI3_TX_DP17 SOCKET4677_AZIF0045P001C01CS-SA   I102 @S9S_MB_2U_LIB.S9S_MB_2U(SCH_1):PAGE35
    U2 CL76 UPI3_TX_DP18 SOCKET4677_AZIF0045P001C01CS-SA   I102 @S9S_MB_2U_LIB.S9S_MB_2U(SCH_1):PAGE35
    U2 CF77 UPI3_TX_DP19 SOCKET4677_AZIF0045P001C01CS-SA   I102 @S9S_MB_2U_LIB.S9S_MB_2U(SCH_1):PAGE35
    U2 CH75 UPI3_TX_DP20 SOCKET4677_AZIF0045P001C01CS-SA   I102 @S9S_MB_2U_LIB.S9S_MB_2U(SCH_1):PAGE35
    U2 CK75 UPI3_TX_DP21 SOCKET4677_AZIF0045P001C01CS-SA   I102 @S9S_MB_2U_LIB.S9S_MB_2U(SCH_1):PAGE35
    U2 CW74 UPI3_TX_DP22 SOCKET4677_AZIF0045P001C01CS-SA   I102 @S9S_MB_2U_LIB.S9S_MB_2U(SCH_1):PAGE35
    U2 CD73 UPI3_TX_DP23 SOCKET4677_AZIF0045P001C01CS-SA   I102 @S9S_MB_2U_LIB.S9S_MB_2U(SCH_1):PAGE35
    U1 EH85 UPI3_TX_DN0 SOCKET4677_AZIF0045P001C01CS-SA    I16 @S9S_MB_2U_LIB.S9S_MB_2U(SCH_1):PAGE66
    U1 EL84 UPI3_TX_DN1 SOCKET4677_AZIF0045P001C01CS-SA    I16 @S9S_MB_2U_LIB.S9S_MB_2U(SCH_1):PAGE66
    U1 EP85 UPI3_TX_DN2 SOCKET4677_AZIF0045P001C01CS-SA    I16 @S9S_MB_2U_LIB.S9S_MB_2U(SCH_1):PAGE66
    U1 EM87 UPI3_TX_DN3 SOCKET4677_AZIF0045P001C01CS-SA    I16 @S9S_MB_2U_LIB.S9S_MB_2U(SCH_1):PAGE66
    U1 EJ86 UPI3_TX_DN4 SOCKET4677_AZIF0045P001C01CS-SA    I16 @S9S_MB_2U_LIB.S9S_MB_2U(SCH_1):PAGE66
    U1 EK87 UPI3_TX_DN5 SOCKET4677_AZIF0045P001C01CS-SA    I16 @S9S_MB_2U_LIB.S9S_MB_2U(SCH_1):PAGE66
    U1 DU80 UPI3_TX_DN6 SOCKET4677_AZIF0045P001C01CS-SA    I16 @S9S_MB_2U_LIB.S9S_MB_2U(SCH_1):PAGE66
    U1 DR82 UPI3_TX_DN7 SOCKET4677_AZIF0045P001C01CS-SA    I16 @S9S_MB_2U_LIB.S9S_MB_2U(SCH_1):PAGE66
    U1 DP79 UPI3_TX_DN8 SOCKET4677_AZIF0045P001C01CS-SA    I16 @S9S_MB_2U_LIB.S9S_MB_2U(SCH_1):PAGE66
    U1 DN82 UPI3_TX_DN9 SOCKET4677_AZIF0045P001C01CS-SA    I16 @S9S_MB_2U_LIB.S9S_MB_2U(SCH_1):PAGE66
    U1 DM81 UPI3_TX_DN10 SOCKET4677_AZIF0045P001C01CS-SA    I16 @S9S_MB_2U_LIB.S9S_MB_2U(SCH_1):PAGE66
    U1 DL80 UPI3_TX_DN11 SOCKET4677_AZIF0045P001C01CS-SA    I16 @S9S_MB_2U_LIB.S9S_MB_2U(SCH_1):PAGE66
    U1 CW76 UPI3_TX_DN12 SOCKET4677_AZIF0045P001C01CS-SA    I16 @S9S_MB_2U_LIB.S9S_MB_2U(SCH_1):PAGE66
    U1 CU76 UPI3_TX_DN13 SOCKET4677_AZIF0045P001C01CS-SA    I16 @S9S_MB_2U_LIB.S9S_MB_2U(SCH_1):PAGE66
    U1 CT75 UPI3_TX_DN14 SOCKET4677_AZIF0045P001C01CS-SA    I16 @S9S_MB_2U_LIB.S9S_MB_2U(SCH_1):PAGE66
    U1 CR74 UPI3_TX_DN15 SOCKET4677_AZIF0045P001C01CS-SA    I16 @S9S_MB_2U_LIB.S9S_MB_2U(SCH_1):PAGE66
    U1 CK77 UPI3_TX_DN16 SOCKET4677_AZIF0045P001C01CS-SA    I16 @S9S_MB_2U_LIB.S9S_MB_2U(SCH_1):PAGE66
    U1 CH77 UPI3_TX_DN17 SOCKET4677_AZIF0045P001C01CS-SA    I16 @S9S_MB_2U_LIB.S9S_MB_2U(SCH_1):PAGE66
    U1 CM75 UPI3_TX_DN18 SOCKET4677_AZIF0045P001C01CS-SA    I16 @S9S_MB_2U_LIB.S9S_MB_2U(SCH_1):PAGE66
    U1 CG76 UPI3_TX_DN19 SOCKET4677_AZIF0045P001C01CS-SA    I16 @S9S_MB_2U_LIB.S9S_MB_2U(SCH_1):PAGE66
    U1 CF75 UPI3_TX_DN20 SOCKET4677_AZIF0045P001C01CS-SA    I16 @S9S_MB_2U_LIB.S9S_MB_2U(SCH_1):PAGE66
    U1 CJ74 UPI3_TX_DN21 SOCKET4677_AZIF0045P001C01CS-SA    I16 @S9S_MB_2U_LIB.S9S_MB_2U(SCH_1):PAGE66
    U1 CV73 UPI3_TX_DN22 SOCKET4677_AZIF0045P001C01CS-SA    I16 @S9S_MB_2U_LIB.S9S_MB_2U(SCH_1):PAGE66
    U1 CF73 UPI3_TX_DN23 SOCKET4677_AZIF0045P001C01CS-SA    I16 @S9S_MB_2U_LIB.S9S_MB_2U(SCH_1):PAGE66
    U1 EK85 UPI3_TX_DP0 SOCKET4677_AZIF0045P001C01CS-SA    I16 @S9S_MB_2U_LIB.S9S_MB_2U(SCH_1):PAGE66
    U1 EM85 UPI3_TX_DP1 SOCKET4677_AZIF0045P001C01CS-SA    I16 @S9S_MB_2U_LIB.S9S_MB_2U(SCH_1):PAGE66
    U1 EN86 UPI3_TX_DP2 SOCKET4677_AZIF0045P001C01CS-SA    I16 @S9S_MB_2U_LIB.S9S_MB_2U(SCH_1):PAGE66
    U1 EP87 UPI3_TX_DP3 SOCKET4677_AZIF0045P001C01CS-SA    I16 @S9S_MB_2U_LIB.S9S_MB_2U(SCH_1):PAGE66
    U1 EH87 UPI3_TX_DP4 SOCKET4677_AZIF0045P001C01CS-SA    I16 @S9S_MB_2U_LIB.S9S_MB_2U(SCH_1):PAGE66
    U1 EL88 UPI3_TX_DP5 SOCKET4677_AZIF0045P001C01CS-SA    I16 @S9S_MB_2U_LIB.S9S_MB_2U(SCH_1):PAGE66
    U1 DT81 UPI3_TX_DP6 SOCKET4677_AZIF0045P001C01CS-SA    I16 @S9S_MB_2U_LIB.S9S_MB_2U(SCH_1):PAGE66
    U1 DU82 UPI3_TX_DP7 SOCKET4677_AZIF0045P001C01CS-SA    I16 @S9S_MB_2U_LIB.S9S_MB_2U(SCH_1):PAGE66
    U1 DR80 UPI3_TX_DP8 SOCKET4677_AZIF0045P001C01CS-SA    I16 @S9S_MB_2U_LIB.S9S_MB_2U(SCH_1):PAGE66
    U1 DP83 UPI3_TX_DP9 SOCKET4677_AZIF0045P001C01CS-SA    I16 @S9S_MB_2U_LIB.S9S_MB_2U(SCH_1):PAGE66
    U1 DL82 UPI3_TX_DP10 SOCKET4677_AZIF0045P001C01CS-SA    I16 @S9S_MB_2U_LIB.S9S_MB_2U(SCH_1):PAGE66
    U1 DN80 UPI3_TX_DP11 SOCKET4677_AZIF0045P001C01CS-SA    I16 @S9S_MB_2U_LIB.S9S_MB_2U(SCH_1):PAGE66
    U1 DA76 UPI3_TX_DP12 SOCKET4677_AZIF0045P001C01CS-SA    I16 @S9S_MB_2U_LIB.S9S_MB_2U(SCH_1):PAGE66
    U1 CV77 UPI3_TX_DP13 SOCKET4677_AZIF0045P001C01CS-SA    I16 @S9S_MB_2U_LIB.S9S_MB_2U(SCH_1):PAGE66
    U1 CR76 UPI3_TX_DP14 SOCKET4677_AZIF0045P001C01CS-SA    I16 @S9S_MB_2U_LIB.S9S_MB_2U(SCH_1):PAGE66
    U1 CU74 UPI3_TX_DP15 SOCKET4677_AZIF0045P001C01CS-SA    I16 @S9S_MB_2U_LIB.S9S_MB_2U(SCH_1):PAGE66
    U1 CM77 UPI3_TX_DP16 SOCKET4677_AZIF0045P001C01CS-SA    I16 @S9S_MB_2U_LIB.S9S_MB_2U(SCH_1):PAGE66
    U1 CJ78 UPI3_TX_DP17 SOCKET4677_AZIF0045P001C01CS-SA    I16 @S9S_MB_2U_LIB.S9S_MB_2U(SCH_1):PAGE66
    U1 CL76 UPI3_TX_DP18 SOCKET4677_AZIF0045P001C01CS-SA    I16 @S9S_MB_2U_LIB.S9S_MB_2U(SCH_1):PAGE66
    U1 CF77 UPI3_TX_DP19 SOCKET4677_AZIF0045P001C01CS-SA    I16 @S9S_MB_2U_LIB.S9S_MB_2U(SCH_1):PAGE66
    U1 CH75 UPI3_TX_DP20 SOCKET4677_AZIF0045P001C01CS-SA    I16 @S9S_MB_2U_LIB.S9S_MB_2U(SCH_1):PAGE66
    U1 CK75 UPI3_TX_DP21 SOCKET4677_AZIF0045P001C01CS-SA    I16 @S9S_MB_2U_LIB.S9S_MB_2U(SCH_1):PAGE66
    U1 CW74 UPI3_TX_DP22 SOCKET4677_AZIF0045P001C01CS-SA    I16 @S9S_MB_2U_LIB.S9S_MB_2U(SCH_1):PAGE66
    U1 CD73 UPI3_TX_DP23 SOCKET4677_AZIF0045P001C01CS-SA    I16 @S9S_MB_2U_LIB.S9S_MB_2U(SCH_1):PAGE66
   U75    1     NC 74LVC1G17GW-74LVC1G17GW,SMLF,IA     I1 @S9S_MB_2U_LIB.S9S_MB_2U(SCH_1):PAGE152
PU13_P0_1   31    DNC ISL99390FRZTR5935-ISL99390FRZ-A    I40 @S9S_MB_2U_LIB.S9S_MB_2U(SCH_1):PAGE253
PU13_P0_1    6    GL1 ISL99390FRZTR5935-ISL99390FRZ-A    I40 @S9S_MB_2U_LIB.S9S_MB_2U(SCH_1):PAGE253
PU13_P0_1   41    GL2 ISL99390FRZTR5935-ISL99390FRZ-A    I40 @S9S_MB_2U_LIB.S9S_MB_2U(SCH_1):PAGE253
PU10_P0_4   31    DNC ISL99390FRZTR5935-ISL99390FRZ-A    I13 @S9S_MB_2U_LIB.S9S_MB_2U(SCH_1):PAGE254
PU10_P0_4    6    GL1 ISL99390FRZTR5935-ISL99390FRZ-A    I13 @S9S_MB_2U_LIB.S9S_MB_2U(SCH_1):PAGE254
PU10_P0_4   41    GL2 ISL99390FRZTR5935-ISL99390FRZ-A    I13 @S9S_MB_2U_LIB.S9S_MB_2U(SCH_1):PAGE254
PU8_P0_6   31    DNC ISL99390FRZTR5935-ISL99390FRZ-A    I12 @S9S_MB_2U_LIB.S9S_MB_2U(SCH_1):PAGE255
PU8_P0_6    6    GL1 ISL99390FRZTR5935-ISL99390FRZ-A    I12 @S9S_MB_2U_LIB.S9S_MB_2U(SCH_1):PAGE255
PU8_P0_6   41    GL2 ISL99390FRZTR5935-ISL99390FRZ-A    I12 @S9S_MB_2U_LIB.S9S_MB_2U(SCH_1):PAGE255
PU6_P0_8   31    DNC ISL99390FRZTR5935-ISL99390FRZ-A     I2 @S9S_MB_2U_LIB.S9S_MB_2U(SCH_1):PAGE256
PU6_P0_8    6    GL1 ISL99390FRZTR5935-ISL99390FRZ-A     I2 @S9S_MB_2U_LIB.S9S_MB_2U(SCH_1):PAGE256
PU6_P0_8   41    GL2 ISL99390FRZTR5935-ISL99390FRZ-A     I2 @S9S_MB_2U_LIB.S9S_MB_2U(SCH_1):PAGE256
PU26_P1_5   31    DNC ISL99390FRZTR5935-ISL99390FRZ-A    I23 @S9S_MB_2U_LIB.S9S_MB_2U(SCH_1):PAGE273
PU26_P1_5    6    GL1 ISL99390FRZTR5935-ISL99390FRZ-A    I23 @S9S_MB_2U_LIB.S9S_MB_2U(SCH_1):PAGE273
PU26_P1_5   41    GL2 ISL99390FRZTR5935-ISL99390FRZ-A    I23 @S9S_MB_2U_LIB.S9S_MB_2U(SCH_1):PAGE273
PU50_P1_1   31    DNC ISL99390FRZTR5935-ISL99390FRZ-A    I38 @S9S_MB_2U_LIB.S9S_MB_2U(SCH_1):PAGE279
PU50_P1_1    6    GL1 ISL99390FRZTR5935-ISL99390FRZ-A    I38 @S9S_MB_2U_LIB.S9S_MB_2U(SCH_1):PAGE279
PU50_P1_1   41    GL2 ISL99390FRZTR5935-ISL99390FRZ-A    I38 @S9S_MB_2U_LIB.S9S_MB_2U(SCH_1):PAGE279
  PU49   27    GL2 RAA2213404GNPHB0-RAA2213404GNPA    I14 @S9S_MB_2U_LIB.S9S_MB_2U(SCH_1):PAGE280
   H30    1      1 HOLE_TH-EMPTY,DUMMY50     I7 @S9S_MB_2U_LIB.S9S_MB_2U(SCH_1):PAGE289
   H29    1      1 HOLE_TH-EMPTY,DUMMY50     I8 @S9S_MB_2U_LIB.S9S_MB_2U(SCH_1):PAGE289
   H38    1      1 HOLE_TH-EMPTY,TMP-Q_HOLE78     I9 @S9S_MB_2U_LIB.S9S_MB_2U(SCH_1):PAGE289
   H36    1      1 HOLE_TH-EMPTY,TMP-Q_HOLE78    I10 @S9S_MB_2U_LIB.S9S_MB_2U(SCH_1):PAGE289
   H28    1      1 HOLE_TH-EMPTY,DUMMY50    I11 @S9S_MB_2U_LIB.S9S_MB_2U(SCH_1):PAGE289
   H27    1      1 HOLE_TH-EMPTY,DUMMY50    I12 @S9S_MB_2U_LIB.S9S_MB_2U(SCH_1):PAGE289
   H26    1      1 HOLE_TH-EMPTY,HOLE1079    I19 @S9S_MB_2U_LIB.S9S_MB_2U(SCH_1):PAGE289
   H24    1      1 HOLE_TH-EMPTY,HOLE1079    I20 @S9S_MB_2U_LIB.S9S_MB_2U(SCH_1):PAGE289
   H22    1      1 HOLE_TH-EMPTY,HOLE1079    I21 @S9S_MB_2U_LIB.S9S_MB_2U(SCH_1):PAGE289
   H75    1      1 HOLE_TH-EMPTY,HOLE1247    I57 @S9S_MB_2U_LIB.S9S_MB_2U(SCH_1):PAGE289
   H74    1      1 HOLE_TH-EMPTY,HOLE1247    I58 @S9S_MB_2U_LIB.S9S_MB_2U(SCH_1):PAGE289
   H20    1      1 HOLE_TH-EMPTY,HOLE1079    I60 @S9S_MB_2U_LIB.S9S_MB_2U(SCH_1):PAGE289
   H18    1      1 HOLE_TH-EMPTY,HOLE1079    I61 @S9S_MB_2U_LIB.S9S_MB_2U(SCH_1):PAGE289
   H16    1      1 HOLE_TH-EMPTY,HOLE1079    I63 @S9S_MB_2U_LIB.S9S_MB_2U(SCH_1):PAGE289
   H25    1      1 HOLE_TH-EMPTY,HOLE1079    I64 @S9S_MB_2U_LIB.S9S_MB_2U(SCH_1):PAGE289
   H23    1      1 HOLE_TH-EMPTY,HOLE1079    I72 @S9S_MB_2U_LIB.S9S_MB_2U(SCH_1):PAGE289
   H21    1      1 HOLE_TH-EMPTY,HOLE1079    I73 @S9S_MB_2U_LIB.S9S_MB_2U(SCH_1):PAGE289
   H19    1      1 HOLE_TH-EMPTY,HOLE1079    I74 @S9S_MB_2U_LIB.S9S_MB_2U(SCH_1):PAGE289
   H17    1      1 HOLE_TH-EMPTY,HOLE1079    I75 @S9S_MB_2U_LIB.S9S_MB_2U(SCH_1):PAGE289
   H15    1      1 HOLE_TH-EMPTY,HOLE1079    I83 @S9S_MB_2U_LIB.S9S_MB_2U(SCH_1):PAGE289
  DM13    1      1 DUMMY_SYMBOL-BATTERY_SYMBOL,MEA    I17 @S9S_MB_2U_LIB.S9S_MB_2U(SCH_1):PAGE290
   DM9    1      1 DUMMY_SYMBOL-MECHANIC_SYMBOL,MA    I23 @S9S_MB_2U_LIB.S9S_MB_2U(SCH_1):PAGE290
 U1_BL    1     TP TP_TP_BOM ONLY-NA,TP12_BOM    I40 @S9S_MB_2U_LIB.S9S_MB_2U(SCH_1):PAGE290
 U2_BL    1     TP TP_TP_BOM ONLY-NA,TP12_BOM    I41 @S9S_MB_2U_LIB.S9S_MB_2U(SCH_1):PAGE290
 U2_BP    1     TP TP_TP_BOM ONLY-NA,TP12_BOM    I42 @S9S_MB_2U_LIB.S9S_MB_2U(SCH_1):PAGE290
 U1_BP    1     TP TP_TP_BOM ONLY-NA,TP12_BOM    I43 @S9S_MB_2U_LIB.S9S_MB_2U(SCH_1):PAGE290
 U2_DC    1     TP TP_TP_BOM ONLY-NA,TP12_BOM    I45 @S9S_MB_2U_LIB.S9S_MB_2U(SCH_1):PAGE290
 U1_DC    1     TP TP_TP_BOM ONLY-NA,TP12_BOM    I47 @S9S_MB_2U_LIB.S9S_MB_2U(SCH_1):PAGE290
  J100   14     14 SCONN20_513860200CV01-SCONN20_A    I32 @S9S_MB_2U_LIB.S9S_MB_2U(SCH_1):PAGE215
  J100   20     20 SCONN20_513860200CV01-SCONN20_A    I32 @S9S_MB_2U_LIB.S9S_MB_2U(SCH_1):PAGE215
  U207    1     NC 74LVC1G17GW-74LVC1G17GW,SMLF,IA    I35 @S9S_MB_2U_LIB.S9S_MB_2U(SCH_1):PAGE156
  U249   E1   PL6A LCMXO3LF9400C5BG484C-LCMXO3LF-A    I33 @S9S_MB_2U_LIB.S9S_MB_2U(SCH_1):PAGE311
  U249   F1   PL6B LCMXO3LF9400C5BG484C-LCMXO3LF-A    I33 @S9S_MB_2U_LIB.S9S_MB_2U(SCH_1):PAGE311
  U249   G3   PL6C LCMXO3LF9400C5BG484C-LCMXO3LF-A    I33 @S9S_MB_2U_LIB.S9S_MB_2U(SCH_1):PAGE311
  U249   G4   PL6D LCMXO3LF9400C5BG484C-LCMXO3LF-A    I33 @S9S_MB_2U_LIB.S9S_MB_2U(SCH_1):PAGE311
  U249   L1 PL16A||PCLKT4_0 LCMXO3LF9400C5BG484C-LCMXO3LF-A    I33 @S9S_MB_2U_LIB.S9S_MB_2U(SCH_1):PAGE311
  U249   M2 PL16B||PCLKC4_0 LCMXO3LF9400C5BG484C-LCMXO3LF-A    I33 @S9S_MB_2U_LIB.S9S_MB_2U(SCH_1):PAGE311
  U249   L3  PL16C LCMXO3LF9400C5BG484C-LCMXO3LF-A    I33 @S9S_MB_2U_LIB.S9S_MB_2U(SCH_1):PAGE311
  U249   L4  PL16D LCMXO3LF9400C5BG484C-LCMXO3LF-A    I33 @S9S_MB_2U_LIB.S9S_MB_2U(SCH_1):PAGE311
  U249   M1  PL17A LCMXO3LF9400C5BG484C-LCMXO3LF-A    I33 @S9S_MB_2U_LIB.S9S_MB_2U(SCH_1):PAGE311
  U249   N1  PL17B LCMXO3LF9400C5BG484C-LCMXO3LF-A    I33 @S9S_MB_2U_LIB.S9S_MB_2U(SCH_1):PAGE311
  U249   M6  PL17C LCMXO3LF9400C5BG484C-LCMXO3LF-A    I33 @S9S_MB_2U_LIB.S9S_MB_2U(SCH_1):PAGE311
  U249   M5  PL17D LCMXO3LF9400C5BG484C-LCMXO3LF-A    I33 @S9S_MB_2U_LIB.S9S_MB_2U(SCH_1):PAGE311
  U249   N2  PL18A LCMXO3LF9400C5BG484C-LCMXO3LF-A    I33 @S9S_MB_2U_LIB.S9S_MB_2U(SCH_1):PAGE311
  U249   P1  PL18B LCMXO3LF9400C5BG484C-LCMXO3LF-A    I33 @S9S_MB_2U_LIB.S9S_MB_2U(SCH_1):PAGE311
  U249   N3  PL18C LCMXO3LF9400C5BG484C-LCMXO3LF-A    I33 @S9S_MB_2U_LIB.S9S_MB_2U(SCH_1):PAGE311
  U249   N4  PL18D LCMXO3LF9400C5BG484C-LCMXO3LF-A    I33 @S9S_MB_2U_LIB.S9S_MB_2U(SCH_1):PAGE311
  U249   P2  PL19A LCMXO3LF9400C5BG484C-LCMXO3LF-A    I33 @S9S_MB_2U_LIB.S9S_MB_2U(SCH_1):PAGE311
  U249   R1  PL19B LCMXO3LF9400C5BG484C-LCMXO3LF-A    I33 @S9S_MB_2U_LIB.S9S_MB_2U(SCH_1):PAGE311
  U249   P3  PL19C LCMXO3LF9400C5BG484C-LCMXO3LF-A    I33 @S9S_MB_2U_LIB.S9S_MB_2U(SCH_1):PAGE311
  U249   M7  PL19D LCMXO3LF9400C5BG484C-LCMXO3LF-A    I33 @S9S_MB_2U_LIB.S9S_MB_2U(SCH_1):PAGE311
  U249   P4  PL20A LCMXO3LF9400C5BG484C-LCMXO3LF-A    I33 @S9S_MB_2U_LIB.S9S_MB_2U(SCH_1):PAGE311
  U249   N5  PL20B LCMXO3LF9400C5BG484C-LCMXO3LF-A    I33 @S9S_MB_2U_LIB.S9S_MB_2U(SCH_1):PAGE311
  U249   N6  PL20C LCMXO3LF9400C5BG484C-LCMXO3LF-A    I33 @S9S_MB_2U_LIB.S9S_MB_2U(SCH_1):PAGE311
  U249   N7  PL20D LCMXO3LF9400C5BG484C-LCMXO3LF-A    I33 @S9S_MB_2U_LIB.S9S_MB_2U(SCH_1):PAGE311
  U249   R2  PL21A LCMXO3LF9400C5BG484C-LCMXO3LF-A    I33 @S9S_MB_2U_LIB.S9S_MB_2U(SCH_1):PAGE311
  U249   T1  PL21B LCMXO3LF9400C5BG484C-LCMXO3LF-A    I33 @S9S_MB_2U_LIB.S9S_MB_2U(SCH_1):PAGE311
  U249   P6  PL21D LCMXO3LF9400C5BG484C-LCMXO3LF-A    I33 @S9S_MB_2U_LIB.S9S_MB_2U(SCH_1):PAGE311
  U249   R3  PL24A LCMXO3LF9400C5BG484C-LCMXO3LF-A    I33 @S9S_MB_2U_LIB.S9S_MB_2U(SCH_1):PAGE311
  U249   R4  PL24B LCMXO3LF9400C5BG484C-LCMXO3LF-A    I33 @S9S_MB_2U_LIB.S9S_MB_2U(SCH_1):PAGE311
  U249   R5  PL24C LCMXO3LF9400C5BG484C-LCMXO3LF-A    I33 @S9S_MB_2U_LIB.S9S_MB_2U(SCH_1):PAGE311
  U249   U2 PL27A||PCLKT3_0 LCMXO3LF9400C5BG484C-LCMXO3LF-A    I33 @S9S_MB_2U_LIB.S9S_MB_2U(SCH_1):PAGE311
  U249   V1 PL27B||PCLKC3_0 LCMXO3LF9400C5BG484C-LCMXO3LF-A    I33 @S9S_MB_2U_LIB.S9S_MB_2U(SCH_1):PAGE311
  U249   U3  PL27C LCMXO3LF9400C5BG484C-LCMXO3LF-A    I33 @S9S_MB_2U_LIB.S9S_MB_2U(SCH_1):PAGE311
  U249   U4  PL27D LCMXO3LF9400C5BG484C-LCMXO3LF-A    I33 @S9S_MB_2U_LIB.S9S_MB_2U(SCH_1):PAGE311
PU76_P1_2   31    DNC ISL99390FRZTR5935-ISL99390FRZ-A     I9 @S9S_MB_2U_LIB.S9S_MB_2U(SCH_1):PAGE275
PU76_P1_2    6    GL1 ISL99390FRZTR5935-ISL99390FRZ-A     I9 @S9S_MB_2U_LIB.S9S_MB_2U(SCH_1):PAGE275
PU76_P1_2   41    GL2 ISL99390FRZTR5935-ISL99390FRZ-A     I9 @S9S_MB_2U_LIB.S9S_MB_2U(SCH_1):PAGE275
PU11_P0_3   31    DNC ISL99390FRZTR5935-ISL99390FRZ-A    I20 @S9S_MB_2U_LIB.S9S_MB_2U(SCH_1):PAGE254
PU11_P0_3    6    GL1 ISL99390FRZTR5935-ISL99390FRZ-A    I20 @S9S_MB_2U_LIB.S9S_MB_2U(SCH_1):PAGE254
PU11_P0_3   41    GL2 ISL99390FRZTR5935-ISL99390FRZ-A    I20 @S9S_MB_2U_LIB.S9S_MB_2U(SCH_1):PAGE254
PU9_P0_5   31    DNC ISL99390FRZTR5935-ISL99390FRZ-A    I66 @S9S_MB_2U_LIB.S9S_MB_2U(SCH_1):PAGE255
PU9_P0_5    6    GL1 ISL99390FRZTR5935-ISL99390FRZ-A    I66 @S9S_MB_2U_LIB.S9S_MB_2U(SCH_1):PAGE255
PU9_P0_5   41    GL2 ISL99390FRZTR5935-ISL99390FRZ-A    I66 @S9S_MB_2U_LIB.S9S_MB_2U(SCH_1):PAGE255
PU7_P0_7   31    DNC ISL99390FRZTR5935-ISL99390FRZ-A    I32 @S9S_MB_2U_LIB.S9S_MB_2U(SCH_1):PAGE256
PU7_P0_7    6    GL1 ISL99390FRZTR5935-ISL99390FRZ-A    I32 @S9S_MB_2U_LIB.S9S_MB_2U(SCH_1):PAGE256
PU7_P0_7   41    GL2 ISL99390FRZTR5935-ISL99390FRZ-A    I32 @S9S_MB_2U_LIB.S9S_MB_2U(SCH_1):PAGE256
PU44_P0_2   31    DNC ISL99390FRZTR5935-ISL99390FRZ-A    I12 @S9S_MB_2U_LIB.S9S_MB_2U(SCH_1):PAGE261
PU44_P0_2    6    GL1 ISL99390FRZTR5935-ISL99390FRZ-A    I12 @S9S_MB_2U_LIB.S9S_MB_2U(SCH_1):PAGE261
PU44_P0_2   41    GL2 ISL99390FRZTR5935-ISL99390FRZ-A    I12 @S9S_MB_2U_LIB.S9S_MB_2U(SCH_1):PAGE261
  PU36   31    DNC ISL99390FRZTR5935-ISL99390FRZ-A     I8 @S9S_MB_2U_LIB.S9S_MB_2U(SCH_1):PAGE265
  PU36    6    GL1 ISL99390FRZTR5935-ISL99390FRZ-A     I8 @S9S_MB_2U_LIB.S9S_MB_2U(SCH_1):PAGE265
  PU36   41    GL2 ISL99390FRZTR5935-ISL99390FRZ-A     I8 @S9S_MB_2U_LIB.S9S_MB_2U(SCH_1):PAGE265
PU27_P1_4   31    DNC ISL99390FRZTR5935-ISL99390FRZ-A    I10 @S9S_MB_2U_LIB.S9S_MB_2U(SCH_1):PAGE272
PU27_P1_4    6    GL1 ISL99390FRZTR5935-ISL99390FRZ-A    I10 @S9S_MB_2U_LIB.S9S_MB_2U(SCH_1):PAGE272
PU27_P1_4   41    GL2 ISL99390FRZTR5935-ISL99390FRZ-A    I10 @S9S_MB_2U_LIB.S9S_MB_2U(SCH_1):PAGE272
PU28_P1_3   31    DNC ISL99390FRZTR5935-ISL99390FRZ-A    I66 @S9S_MB_2U_LIB.S9S_MB_2U(SCH_1):PAGE272
PU28_P1_3    6    GL1 ISL99390FRZTR5935-ISL99390FRZ-A    I66 @S9S_MB_2U_LIB.S9S_MB_2U(SCH_1):PAGE272
PU28_P1_3   41    GL2 ISL99390FRZTR5935-ISL99390FRZ-A    I66 @S9S_MB_2U_LIB.S9S_MB_2U(SCH_1):PAGE272
PU25_P1_6   31    DNC ISL99390FRZTR5935-ISL99390FRZ-A    I16 @S9S_MB_2U_LIB.S9S_MB_2U(SCH_1):PAGE273
PU25_P1_6    6    GL1 ISL99390FRZTR5935-ISL99390FRZ-A    I16 @S9S_MB_2U_LIB.S9S_MB_2U(SCH_1):PAGE273
PU25_P1_6   41    GL2 ISL99390FRZTR5935-ISL99390FRZ-A    I16 @S9S_MB_2U_LIB.S9S_MB_2U(SCH_1):PAGE273
PU23_P1_8   31    DNC ISL99390FRZTR5935-ISL99390FRZ-A    I11 @S9S_MB_2U_LIB.S9S_MB_2U(SCH_1):PAGE274
PU23_P1_8    6    GL1 ISL99390FRZTR5935-ISL99390FRZ-A    I11 @S9S_MB_2U_LIB.S9S_MB_2U(SCH_1):PAGE274
PU23_P1_8   41    GL2 ISL99390FRZTR5935-ISL99390FRZ-A    I11 @S9S_MB_2U_LIB.S9S_MB_2U(SCH_1):PAGE274
PU24_P1_7   31    DNC ISL99390FRZTR5935-ISL99390FRZ-A    I20 @S9S_MB_2U_LIB.S9S_MB_2U(SCH_1):PAGE274
PU24_P1_7    6    GL1 ISL99390FRZTR5935-ISL99390FRZ-A    I20 @S9S_MB_2U_LIB.S9S_MB_2U(SCH_1):PAGE274
PU24_P1_7   41    GL2 ISL99390FRZTR5935-ISL99390FRZ-A    I20 @S9S_MB_2U_LIB.S9S_MB_2U(SCH_1):PAGE274
PU78_P1_4   31    DNC ISL99390FRZTR5935-ISL99390FRZ-A    I15 @S9S_MB_2U_LIB.S9S_MB_2U(SCH_1):PAGE276
PU78_P1_4    6    GL1 ISL99390FRZTR5935-ISL99390FRZ-A    I15 @S9S_MB_2U_LIB.S9S_MB_2U(SCH_1):PAGE276
PU78_P1_4   41    GL2 ISL99390FRZTR5935-ISL99390FRZ-A    I15 @S9S_MB_2U_LIB.S9S_MB_2U(SCH_1):PAGE276
PU51_P1_2   31    DNC ISL99390FRZTR5935-ISL99390FRZ-A    I29 @S9S_MB_2U_LIB.S9S_MB_2U(SCH_1):PAGE279
PU51_P1_2    6    GL1 ISL99390FRZTR5935-ISL99390FRZ-A    I29 @S9S_MB_2U_LIB.S9S_MB_2U(SCH_1):PAGE279
PU51_P1_2   41    GL2 ISL99390FRZTR5935-ISL99390FRZ-A    I29 @S9S_MB_2U_LIB.S9S_MB_2U(SCH_1):PAGE279
PU70_P0_2   31    DNC ISL99390FRZTR5935-ISL99390FRZ-A    I16 @S9S_MB_2U_LIB.S9S_MB_2U(SCH_1):PAGE257
PU70_P0_2    6    GL1 ISL99390FRZTR5935-ISL99390FRZ-A    I16 @S9S_MB_2U_LIB.S9S_MB_2U(SCH_1):PAGE257
PU70_P0_2   41    GL2 ISL99390FRZTR5935-ISL99390FRZ-A    I16 @S9S_MB_2U_LIB.S9S_MB_2U(SCH_1):PAGE257
PU43_P0_1   31    DNC ISL99390FRZTR5935-ISL99390FRZ-A    I79 @S9S_MB_2U_LIB.S9S_MB_2U(SCH_1):PAGE261
PU43_P0_1    6    GL1 ISL99390FRZTR5935-ISL99390FRZ-A    I79 @S9S_MB_2U_LIB.S9S_MB_2U(SCH_1):PAGE261
PU43_P0_1   41    GL2 ISL99390FRZTR5935-ISL99390FRZ-A    I79 @S9S_MB_2U_LIB.S9S_MB_2U(SCH_1):PAGE261
PU31_P1_1   31    DNC ISL99390FRZTR5935-ISL99390FRZ-A    I40 @S9S_MB_2U_LIB.S9S_MB_2U(SCH_1):PAGE271
PU31_P1_1    6    GL1 ISL99390FRZTR5935-ISL99390FRZ-A    I40 @S9S_MB_2U_LIB.S9S_MB_2U(SCH_1):PAGE271
PU31_P1_1   41    GL2 ISL99390FRZTR5935-ISL99390FRZ-A    I40 @S9S_MB_2U_LIB.S9S_MB_2U(SCH_1):PAGE271
  U308    3     2A 74LVC2G07DW7-74LVC2G07DW-7,SMLA    I37 @S9S_MB_2U_LIB.S9S_MB_2U(SCH_1):PAGE230
  U308    4     2Y 74LVC2G07DW7-74LVC2G07DW-7,SMLA    I37 @S9S_MB_2U_LIB.S9S_MB_2U(SCH_1):PAGE230
  PU17   31    DNC ISL99390FRZTR5935-ISL99390FRZ-A    I10 @S9S_MB_2U_LIB.S9S_MB_2U(SCH_1):PAGE283
  PU17    6    GL1 ISL99390FRZTR5935-ISL99390FRZ-A    I10 @S9S_MB_2U_LIB.S9S_MB_2U(SCH_1):PAGE283
  PU17   41    GL2 ISL99390FRZTR5935-ISL99390FRZ-A    I10 @S9S_MB_2U_LIB.S9S_MB_2U(SCH_1):PAGE283
  H120    1      1 HOLE_TH-EMPTY,TMP-C_T2I_ALEX_1A   I224 @S9S_MB_2U_LIB.S9S_MB_2U(SCH_1):PAGE289
  H122    1      1 HOLE_TH-EMPTY,TMP-C_T2I_ALEX_1A   I225 @S9S_MB_2U_LIB.S9S_MB_2U(SCH_1):PAGE289
  H124    1      1 HOLE_TH-EMPTY,TMP-C_T2I_ALEX_1A   I226 @S9S_MB_2U_LIB.S9S_MB_2U(SCH_1):PAGE289
  H126    1      1 HOLE_TH-EMPTY,TMP-C_T2I_ALEX_1A   I227 @S9S_MB_2U_LIB.S9S_MB_2U(SCH_1):PAGE289
  H127    1      1 HOLE_TH-EMPTY,TMP-C_T2I_ALEX_1A   I228 @S9S_MB_2U_LIB.S9S_MB_2U(SCH_1):PAGE289
  H125    1      1 HOLE_TH-EMPTY,TMP-C_T2I_ALEX_1A   I229 @S9S_MB_2U_LIB.S9S_MB_2U(SCH_1):PAGE289
J90_CON    1     TP TP_TP_BOM ONLY-NA,TP12_BOM    I69 @S9S_MB_2U_LIB.S9S_MB_2U(SCH_1):PAGE290
JP4003_12    1     TP TP_TP_BOM ONLY-NA,TP12_BOM    I70 @S9S_MB_2U_LIB.S9S_MB_2U(SCH_1):PAGE290
  J122 SCR_H1    NC1 CONN1_10165288101LF-CONN1_1016A   I238 @S9S_MB_2U_LIB.S9S_MB_2U(SCH_1):PAGE289
  J123 SCR_H1    NC1 CONN1_10165288101LF-CONN1_1016A   I239 @S9S_MB_2U_LIB.S9S_MB_2U(SCH_1):PAGE289
PU71_P0_3   31    DNC ISL99390FRZTR5935-ISL99390FRZ-A    I82 @S9S_MB_2U_LIB.S9S_MB_2U(SCH_1):PAGE258
PU71_P0_3    6    GL1 ISL99390FRZTR5935-ISL99390FRZ-A    I82 @S9S_MB_2U_LIB.S9S_MB_2U(SCH_1):PAGE258
PU71_P0_3   41    GL2 ISL99390FRZTR5935-ISL99390FRZ-A    I82 @S9S_MB_2U_LIB.S9S_MB_2U(SCH_1):PAGE258
PU77_P1_3   31    DNC ISL99390FRZTR5935-ISL99390FRZ-A    I24 @S9S_MB_2U_LIB.S9S_MB_2U(SCH_1):PAGE276
PU77_P1_3    6    GL1 ISL99390FRZTR5935-ISL99390FRZ-A    I24 @S9S_MB_2U_LIB.S9S_MB_2U(SCH_1):PAGE276
PU77_P1_3   41    GL2 ISL99390FRZTR5935-ISL99390FRZ-A    I24 @S9S_MB_2U_LIB.S9S_MB_2U(SCH_1):PAGE276
   U39   16    SC5 TCA9548APWR-TCA9548APWR,SMLF,IA   I103 @S9S_MB_2U_LIB.S9S_MB_2U(SCH_1):PAGE221
   U39   18    SC6 TCA9548APWR-TCA9548APWR,SMLF,IA   I103 @S9S_MB_2U_LIB.S9S_MB_2U(SCH_1):PAGE221
   U39   20    SC7 TCA9548APWR-TCA9548APWR,SMLF,IA   I103 @S9S_MB_2U_LIB.S9S_MB_2U(SCH_1):PAGE221
   U39   15    SD5 TCA9548APWR-TCA9548APWR,SMLF,IA   I103 @S9S_MB_2U_LIB.S9S_MB_2U(SCH_1):PAGE221
   U39   17    SD6 TCA9548APWR-TCA9548APWR,SMLF,IA   I103 @S9S_MB_2U_LIB.S9S_MB_2U(SCH_1):PAGE221
   U39   19    SD7 TCA9548APWR-TCA9548APWR,SMLF,IA   I103 @S9S_MB_2U_LIB.S9S_MB_2U(SCH_1):PAGE221
JP15_23    1     TP TP_TP_BOM ONLY-NA,TP12_BOM    I71 @S9S_MB_2U_LIB.S9S_MB_2U(SCH_1):PAGE290
PU75_P1_1   31    DNC ISL99390FRZTR5935-ISL99390FRZ-A    I89 @S9S_MB_2U_LIB.S9S_MB_2U(SCH_1):PAGE275
PU75_P1_1    6    GL1 ISL99390FRZTR5935-ISL99390FRZ-A    I89 @S9S_MB_2U_LIB.S9S_MB_2U(SCH_1):PAGE275
PU75_P1_1   41    GL2 ISL99390FRZTR5935-ISL99390FRZ-A    I89 @S9S_MB_2U_LIB.S9S_MB_2U(SCH_1):PAGE275
  PU42   27    GL2 RAA2213404GNPHB0-RAA2213404GNPA    I14 @S9S_MB_2U_LIB.S9S_MB_2U(SCH_1):PAGE262
PU12_P0_2   31    DNC ISL99390FRZTR5935-ISL99390FRZ-A     I6 @S9S_MB_2U_LIB.S9S_MB_2U(SCH_1):PAGE253
PU12_P0_2    6    GL1 ISL99390FRZTR5935-ISL99390FRZ-A     I6 @S9S_MB_2U_LIB.S9S_MB_2U(SCH_1):PAGE253
PU12_P0_2   41    GL2 ISL99390FRZTR5935-ISL99390FRZ-A     I6 @S9S_MB_2U_LIB.S9S_MB_2U(SCH_1):PAGE253
PU69_P0_1   31    DNC ISL99390FRZTR5935-ISL99390FRZ-A    I25 @S9S_MB_2U_LIB.S9S_MB_2U(SCH_1):PAGE257
PU69_P0_1    6    GL1 ISL99390FRZTR5935-ISL99390FRZ-A    I25 @S9S_MB_2U_LIB.S9S_MB_2U(SCH_1):PAGE257
PU69_P0_1   41    GL2 ISL99390FRZTR5935-ISL99390FRZ-A    I25 @S9S_MB_2U_LIB.S9S_MB_2U(SCH_1):PAGE257
PU72_P0_4   31    DNC ISL99390FRZTR5935-ISL99390FRZ-A    I10 @S9S_MB_2U_LIB.S9S_MB_2U(SCH_1):PAGE258
PU72_P0_4    6    GL1 ISL99390FRZTR5935-ISL99390FRZ-A    I10 @S9S_MB_2U_LIB.S9S_MB_2U(SCH_1):PAGE258
PU72_P0_4   41    GL2 ISL99390FRZTR5935-ISL99390FRZ-A    I10 @S9S_MB_2U_LIB.S9S_MB_2U(SCH_1):PAGE258
PU30_P1_2   31    DNC ISL99390FRZTR5935-ISL99390FRZ-A     I7 @S9S_MB_2U_LIB.S9S_MB_2U(SCH_1):PAGE271
PU30_P1_2    6    GL1 ISL99390FRZTR5935-ISL99390FRZ-A     I7 @S9S_MB_2U_LIB.S9S_MB_2U(SCH_1):PAGE271
PU30_P1_2   41    GL2 ISL99390FRZTR5935-ISL99390FRZ-A     I7 @S9S_MB_2U_LIB.S9S_MB_2U(SCH_1):PAGE271
JP16_23    1     TP TP_TP_BOM ONLY-NA,TP12_BOM    I72 @S9S_MB_2U_LIB.S9S_MB_2U(SCH_1):PAGE290
JP4003    1      1 CONN3_210HP1030BR1-CONN3_210-HB    I12 @S9S_MB_2U_LIB.S9S_MB_2U(SCH_1):PAGE303
  U337    3      3 LM4040AIM3X25NOPB-LM4040AIM3X-A     I3 @S9S_MB_2U_LIB.S9S_MB_2U(SCH_1):PAGE329
  U338    3      3 LM4040AIM3X25NOPB-LM4040AIM3X-A    I43 @S9S_MB_2U_LIB.S9S_MB_2U(SCH_1):PAGE329
  U341    3      3 LM4040AIM3X25NOPB-LM4040AIM3X-A    I63 @S9S_MB_2U_LIB.S9S_MB_2U(SCH_1):PAGE329
  U343    3      3 LM4040AIM3X25NOPB-LM4040AIM3X-A    I56 @S9S_MB_2U_LIB.S9S_MB_2U(SCH_1):PAGE326
   H90    1      1 HOLE_TH-EMPTY,HOLE372   I254 @S9S_MB_2U_LIB.S9S_MB_2U(SCH_1):PAGE289
   U95    1    NC1 74LVC1G07SE7-74LVC1G07SE-7,SMLA    I11 @S9S_MB_2U_LIB.S9S_MB_2U(SCH_1):PAGE232
  U192    5  READY LTC4307CMS8-LTC4307CMS8,SMLF,IA    I16 @S9S_MB_2U_LIB.S9S_MB_2U(SCH_1):PAGE233
  U200    5  READY LTC4307CMS8-LTC4307CMS8,SMLF,IA    I11 @S9S_MB_2U_LIB.S9S_MB_2U(SCH_1):PAGE222
  U176    5  READY LTC4307CMS8-LTC4307CMS8,SMLF,EA    I31 @S9S_MB_2U_LIB.S9S_MB_2U(SCH_1):PAGE222
  U175    5  READY LTC4307CMS8-LTC4307CMS8,SMLF,IA    I50 @S9S_MB_2U_LIB.S9S_MB_2U(SCH_1):PAGE222
  U194    5  READY LTC4307CMS8-LTC4307CMS8,SMLF,IA    I63 @S9S_MB_2U_LIB.S9S_MB_2U(SCH_1):PAGE222
   U36    5    SC0 TCA9548APWR-TCA9548APWR,SMLF,IA    I45 @S9S_MB_2U_LIB.S9S_MB_2U(SCH_1):PAGE219
   U36   20    SC7 TCA9548APWR-TCA9548APWR,SMLF,IA    I45 @S9S_MB_2U_LIB.S9S_MB_2U(SCH_1):PAGE219
   U36    4    SD0 TCA9548APWR-TCA9548APWR,SMLF,IA    I45 @S9S_MB_2U_LIB.S9S_MB_2U(SCH_1):PAGE219
   U36   19    SD7 TCA9548APWR-TCA9548APWR,SMLF,IA    I45 @S9S_MB_2U_LIB.S9S_MB_2U(SCH_1):PAGE219

NCSI_BMC_CRS_DV_R @S9S_MB_2U_LIB.S9S_MB_2U(SCH_1):NCSI_BMC_CRS_DV_R
   U67    9     3A 74CBTLV3126PW-74CBTLV3126PW,SMA    I39 @S9S_MB_2U_LIB.S9S_MB_2U(SCH_1):PAGE151
 R1291    1      A Q_RES_0402LF-22,1%,1/16W,CHIP,A    I69 @S9S_MB_2U_LIB.S9S_MB_2U(SCH_1):PAGE151

NCSI_BMC_CRS_DV_R1 @S9S_MB_2U_LIB.S9S_MB_2U(SCH_1):NCSI_BMC_CRS_DV_R1
  U222    9     3A 74CBTLV3126PW-74CBTLV3126PW,SMA    I32 @S9S_MB_2U_LIB.S9S_MB_2U(SCH_1):PAGE307
 R3210    1      A Q_RES_0402LF-22,1%,1/16W,EMPTYA    I65 @S9S_MB_2U_LIB.S9S_MB_2U(SCH_1):PAGE307

NCSI_BMC_RXD0_R @S9S_MB_2U_LIB.S9S_MB_2U(SCH_1):NCSI_BMC_RXD0_R
   U67    5     2A 74CBTLV3126PW-74CBTLV3126PW,SMA    I39 @S9S_MB_2U_LIB.S9S_MB_2U(SCH_1):PAGE151
 R1292    1      A Q_RES_0402LF-22,1%,1/16W,CHIP,A    I68 @S9S_MB_2U_LIB.S9S_MB_2U(SCH_1):PAGE151

NCSI_BMC_RXD0_R1 @S9S_MB_2U_LIB.S9S_MB_2U(SCH_1):NCSI_BMC_RXD0_R1
  U222    5     2A 74CBTLV3126PW-74CBTLV3126PW,SMA    I32 @S9S_MB_2U_LIB.S9S_MB_2U(SCH_1):PAGE307
 R3211    1      A Q_RES_0402LF-22,1%,1/16W,EMPTYA    I63 @S9S_MB_2U_LIB.S9S_MB_2U(SCH_1):PAGE307

NCSI_BMC_RXD1_R @S9S_MB_2U_LIB.S9S_MB_2U(SCH_1):NCSI_BMC_RXD1_R
   U67    2     1A 74CBTLV3126PW-74CBTLV3126PW,SMA    I39 @S9S_MB_2U_LIB.S9S_MB_2U(SCH_1):PAGE151
 R1293    1      A Q_RES_0402LF-22,1%,1/16W,CHIP,A    I67 @S9S_MB_2U_LIB.S9S_MB_2U(SCH_1):PAGE151

NCSI_BMC_RXD1_R1 @S9S_MB_2U_LIB.S9S_MB_2U(SCH_1):NCSI_BMC_RXD1_R1
  U222    2     1A 74CBTLV3126PW-74CBTLV3126PW,SMA    I32 @S9S_MB_2U_LIB.S9S_MB_2U(SCH_1):PAGE307
 R3212    1      A Q_RES_0402LF-22,1%,1/16W,EMPTYA    I62 @S9S_MB_2U_LIB.S9S_MB_2U(SCH_1):PAGE307

NCSI_BMC_TXD0_R @S9S_MB_2U_LIB.S9S_MB_2U(SCH_1):NCSI_BMC_TXD0_R
   U68    5     2A 74CBTLV3126PW-74CBTLV3126PW,SMA    I30 @S9S_MB_2U_LIB.S9S_MB_2U(SCH_1):PAGE151
 R1295    1      A Q_RES_0402LF-0,5%,1/16W,CHIP,CA    I65 @S9S_MB_2U_LIB.S9S_MB_2U(SCH_1):PAGE151

NCSI_BMC_TXD0_R1 @S9S_MB_2U_LIB.S9S_MB_2U(SCH_1):NCSI_BMC_TXD0_R1
 R3214    1      A Q_RES_0402LF-0,5%,1/16W,EMPTY,A    I60 @S9S_MB_2U_LIB.S9S_MB_2U(SCH_1):PAGE307
  U223    5     2A 74CBTLV3126PW-74CBTLV3126PW,SMA    I78 @S9S_MB_2U_LIB.S9S_MB_2U(SCH_1):PAGE307

NCSI_BMC_TXD1_R @S9S_MB_2U_LIB.S9S_MB_2U(SCH_1):NCSI_BMC_TXD1_R
   U68    2     1A 74CBTLV3126PW-74CBTLV3126PW,SMA    I30 @S9S_MB_2U_LIB.S9S_MB_2U(SCH_1):PAGE151
 R1296    1      A Q_RES_0402LF-0,5%,1/16W,CHIP,CA    I61 @S9S_MB_2U_LIB.S9S_MB_2U(SCH_1):PAGE151

NCSI_BMC_TXD1_R1 @S9S_MB_2U_LIB.S9S_MB_2U(SCH_1):NCSI_BMC_TXD1_R1
 R3215    1      A Q_RES_0402LF-0,5%,1/16W,EMPTY,A    I56 @S9S_MB_2U_LIB.S9S_MB_2U(SCH_1):PAGE307
  U223    2     1A 74CBTLV3126PW-74CBTLV3126PW,SMA    I78 @S9S_MB_2U_LIB.S9S_MB_2U(SCH_1):PAGE307

NCSI_BMC_TX_EN_R @S9S_MB_2U_LIB.S9S_MB_2U(SCH_1):NCSI_BMC_TX_EN_R
   U68    9     3A 74CBTLV3126PW-74CBTLV3126PW,SMA    I30 @S9S_MB_2U_LIB.S9S_MB_2U(SCH_1):PAGE151
 R1294    1      A Q_RES_0402LF-0,5%,1/16W,CHIP,CA    I66 @S9S_MB_2U_LIB.S9S_MB_2U(SCH_1):PAGE151

NCSI_BMC_TX_EN_R1 @S9S_MB_2U_LIB.S9S_MB_2U(SCH_1):NCSI_BMC_TX_EN_R1
 R3213    1      A Q_RES_0402LF-0,5%,1/16W,EMPTY,A    I61 @S9S_MB_2U_LIB.S9S_MB_2U(SCH_1):PAGE307
  U223    9     3A 74CBTLV3126PW-74CBTLV3126PW,SMA    I78 @S9S_MB_2U_LIB.S9S_MB_2U(SCH_1):PAGE307

NCSI_OCP_SFF_CRS_DV @S9S_MB_2U_LIB.S9S_MB_2U(SCH_1):NCSI_OCP_SFF_CRS_DV
   J37 OB14 RBT_CRS_DV SCONN168_ME1016810202011-SCONNA   I199 @S9S_MB_2U_LIB.S9S_MB_2U(SCH_1):PAGE150
   U67    8     3B 74CBTLV3126PW-74CBTLV3126PW,SMA    I39 @S9S_MB_2U_LIB.S9S_MB_2U(SCH_1):PAGE151

NCSI_OCP_SFF_RXD0 @S9S_MB_2U_LIB.S9S_MB_2U(SCH_1):NCSI_OCP_SFF_RXD0
   J37  OB9 RBT_RXD0 SCONN168_ME1016810202011-SCONNA   I199 @S9S_MB_2U_LIB.S9S_MB_2U(SCH_1):PAGE150
   U67    6     2B 74CBTLV3126PW-74CBTLV3126PW,SMA    I39 @S9S_MB_2U_LIB.S9S_MB_2U(SCH_1):PAGE151

NCSI_OCP_SFF_RXD1 @S9S_MB_2U_LIB.S9S_MB_2U(SCH_1):NCSI_OCP_SFF_RXD1
   J37  OB8 RBT_RXD1 SCONN168_ME1016810202011-SCONNA   I199 @S9S_MB_2U_LIB.S9S_MB_2U(SCH_1):PAGE150
   U67    3     1B 74CBTLV3126PW-74CBTLV3126PW,SMA    I39 @S9S_MB_2U_LIB.S9S_MB_2U(SCH_1):PAGE151

NCSI_OCP_SFF_TXD0 @S9S_MB_2U_LIB.S9S_MB_2U(SCH_1):NCSI_OCP_SFF_TXD0
   J37  OA9 RBT_TXD0 SCONN168_ME1016810202011-SCONNA   I199 @S9S_MB_2U_LIB.S9S_MB_2U(SCH_1):PAGE150
   U68    6     2B 74CBTLV3126PW-74CBTLV3126PW,SMA    I30 @S9S_MB_2U_LIB.S9S_MB_2U(SCH_1):PAGE151

NCSI_OCP_SFF_TXD1 @S9S_MB_2U_LIB.S9S_MB_2U(SCH_1):NCSI_OCP_SFF_TXD1
   J37  OA8 RBT_TXD1 SCONN168_ME1016810202011-SCONNA   I199 @S9S_MB_2U_LIB.S9S_MB_2U(SCH_1):PAGE150
   U68    3     1B 74CBTLV3126PW-74CBTLV3126PW,SMA    I30 @S9S_MB_2U_LIB.S9S_MB_2U(SCH_1):PAGE151

NCSI_OCP_SFF_TX_EN @S9S_MB_2U_LIB.S9S_MB_2U(SCH_1):NCSI_OCP_SFF_TX_EN
   J37  OA7 RBT_TX_EN SCONN168_ME1016810202011-SCONNA   I199 @S9S_MB_2U_LIB.S9S_MB_2U(SCH_1):PAGE150
   U68    8     3B 74CBTLV3126PW-74CBTLV3126PW,SMA    I30 @S9S_MB_2U_LIB.S9S_MB_2U(SCH_1):PAGE151

NCSI_OCP_V3_2_CRS_DV @S9S_MB_2U_LIB.S9S_MB_2U(SCH_1):NCSI_OCP_V3_2_CRS_DV
  U222    8     3B 74CBTLV3126PW-74CBTLV3126PW,SMA    I32 @S9S_MB_2U_LIB.S9S_MB_2U(SCH_1):PAGE307
   J35 OB14 RBT_CRS_DV SCONN168_ME1016810202011-SCONNA   I303 @S9S_MB_2U_LIB.S9S_MB_2U(SCH_1):PAGE146

NCSI_OCP_V3_2_RXD0 @S9S_MB_2U_LIB.S9S_MB_2U(SCH_1):NCSI_OCP_V3_2_RXD0
  U222    6     2B 74CBTLV3126PW-74CBTLV3126PW,SMA    I32 @S9S_MB_2U_LIB.S9S_MB_2U(SCH_1):PAGE307
   J35  OB9 RBT_RXD0 SCONN168_ME1016810202011-SCONNA   I303 @S9S_MB_2U_LIB.S9S_MB_2U(SCH_1):PAGE146

NCSI_OCP_V3_2_RXD1 @S9S_MB_2U_LIB.S9S_MB_2U(SCH_1):NCSI_OCP_V3_2_RXD1
  U222    3     1B 74CBTLV3126PW-74CBTLV3126PW,SMA    I32 @S9S_MB_2U_LIB.S9S_MB_2U(SCH_1):PAGE307
   J35  OB8 RBT_RXD1 SCONN168_ME1016810202011-SCONNA   I303 @S9S_MB_2U_LIB.S9S_MB_2U(SCH_1):PAGE146

NCSI_OCP_V3_2_TXD0 @S9S_MB_2U_LIB.S9S_MB_2U(SCH_1):NCSI_OCP_V3_2_TXD0
  U223    6     2B 74CBTLV3126PW-74CBTLV3126PW,SMA    I78 @S9S_MB_2U_LIB.S9S_MB_2U(SCH_1):PAGE307
   J35  OA9 RBT_TXD0 SCONN168_ME1016810202011-SCONNA   I303 @S9S_MB_2U_LIB.S9S_MB_2U(SCH_1):PAGE146

NCSI_OCP_V3_2_TXD1 @S9S_MB_2U_LIB.S9S_MB_2U(SCH_1):NCSI_OCP_V3_2_TXD1
  U223    3     1B 74CBTLV3126PW-74CBTLV3126PW,SMA    I78 @S9S_MB_2U_LIB.S9S_MB_2U(SCH_1):PAGE307
   J35  OA8 RBT_TXD1 SCONN168_ME1016810202011-SCONNA   I303 @S9S_MB_2U_LIB.S9S_MB_2U(SCH_1):PAGE146

NCSI_OCP_V3_2_TX_EN @S9S_MB_2U_LIB.S9S_MB_2U(SCH_1):NCSI_OCP_V3_2_TX_EN
  U223    8     3B 74CBTLV3126PW-74CBTLV3126PW,SMA    I78 @S9S_MB_2U_LIB.S9S_MB_2U(SCH_1):PAGE307
   J35  OA7 RBT_TX_EN SCONN168_ME1016810202011-SCONNA   I303 @S9S_MB_2U_LIB.S9S_MB_2U(SCH_1):PAGE146

NC_CK440_A15 @S9S_MB_2U_LIB.S9S_MB_2U(SCH_1):NC_CK440_A15
   U13  A15 NC_A15 9SQ440NQQI8-9SQ440NQQI8,SMLF,IA   I288 @S9S_MB_2U_LIB.S9S_MB_2U(SCH_1):PAGE197

NC_CK440_B13 @S9S_MB_2U_LIB.S9S_MB_2U(SCH_1):NC_CK440_B13
   U13  B13 NC_B13 9SQ440NQQI8-9SQ440NQQI8,SMLF,IA   I288 @S9S_MB_2U_LIB.S9S_MB_2U(SCH_1):PAGE197

NC_CK440_B16 @S9S_MB_2U_LIB.S9S_MB_2U(SCH_1):NC_CK440_B16
   U13  B16 NC_B16 9SQ440NQQI8-9SQ440NQQI8,SMLF,IA   I288 @S9S_MB_2U_LIB.S9S_MB_2U(SCH_1):PAGE197

NC_CK440_B18 @S9S_MB_2U_LIB.S9S_MB_2U(SCH_1):NC_CK440_B18
   U13  B18 NC_B18 9SQ440NQQI8-9SQ440NQQI8,SMLF,IA   I288 @S9S_MB_2U_LIB.S9S_MB_2U(SCH_1):PAGE197

NC_CK440_B2 @S9S_MB_2U_LIB.S9S_MB_2U(SCH_1):NC_CK440_B2
   U13   B2  NC_B2 9SQ440NQQI8-9SQ440NQQI8,SMLF,IA   I288 @S9S_MB_2U_LIB.S9S_MB_2U(SCH_1):PAGE197

NC_CK440_B20 @S9S_MB_2U_LIB.S9S_MB_2U(SCH_1):NC_CK440_B20
   U13  B20 NC_B20 9SQ440NQQI8-9SQ440NQQI8,SMLF,IA   I288 @S9S_MB_2U_LIB.S9S_MB_2U(SCH_1):PAGE197

NC_CK440_B22 @S9S_MB_2U_LIB.S9S_MB_2U(SCH_1):NC_CK440_B22
   U13  B22 NC_B22 9SQ440NQQI8-9SQ440NQQI8,SMLF,IA   I288 @S9S_MB_2U_LIB.S9S_MB_2U(SCH_1):PAGE197

NC_CK440_B24 @S9S_MB_2U_LIB.S9S_MB_2U(SCH_1):NC_CK440_B24
   U13  B24 NC_B24 9SQ440NQQI8-9SQ440NQQI8,SMLF,IA   I288 @S9S_MB_2U_LIB.S9S_MB_2U(SCH_1):PAGE197

NC_CK440_B25 @S9S_MB_2U_LIB.S9S_MB_2U(SCH_1):NC_CK440_B25
   U13  B25 NC_B25 9SQ440NQQI8-9SQ440NQQI8,SMLF,IA   I288 @S9S_MB_2U_LIB.S9S_MB_2U(SCH_1):PAGE197

NC_CK440_B26 @S9S_MB_2U_LIB.S9S_MB_2U(SCH_1):NC_CK440_B26
   U13  B26 NC_B26 9SQ440NQQI8-9SQ440NQQI8,SMLF,IA   I288 @S9S_MB_2U_LIB.S9S_MB_2U(SCH_1):PAGE197

NC_CK440_B28 @S9S_MB_2U_LIB.S9S_MB_2U(SCH_1):NC_CK440_B28
   U13  B28 NC_B28 9SQ440NQQI8-9SQ440NQQI8,SMLF,IA   I288 @S9S_MB_2U_LIB.S9S_MB_2U(SCH_1):PAGE197

NC_CK440_B3 @S9S_MB_2U_LIB.S9S_MB_2U(SCH_1):NC_CK440_B3
   U13   B3  NC_B3 9SQ440NQQI8-9SQ440NQQI8,SMLF,IA   I288 @S9S_MB_2U_LIB.S9S_MB_2U(SCH_1):PAGE197

NC_CK440_B30 @S9S_MB_2U_LIB.S9S_MB_2U(SCH_1):NC_CK440_B30
   U13  B30 NC_B30 9SQ440NQQI8-9SQ440NQQI8,SMLF,IA   I288 @S9S_MB_2U_LIB.S9S_MB_2U(SCH_1):PAGE197

NC_CK440_B31 @S9S_MB_2U_LIB.S9S_MB_2U(SCH_1):NC_CK440_B31
   U13  B31 NC_B31 9SQ440NQQI8-9SQ440NQQI8,SMLF,IA   I288 @S9S_MB_2U_LIB.S9S_MB_2U(SCH_1):PAGE197

NC_CK440_B33 @S9S_MB_2U_LIB.S9S_MB_2U(SCH_1):NC_CK440_B33
   U13  B33 NC_B33 9SQ440NQQI8-9SQ440NQQI8,SMLF,IA   I288 @S9S_MB_2U_LIB.S9S_MB_2U(SCH_1):PAGE197

NC_CK440_B34 @S9S_MB_2U_LIB.S9S_MB_2U(SCH_1):NC_CK440_B34
   U13  B34 NC_B34 9SQ440NQQI8-9SQ440NQQI8,SMLF,IA   I288 @S9S_MB_2U_LIB.S9S_MB_2U(SCH_1):PAGE197

NC_CK440_B36 @S9S_MB_2U_LIB.S9S_MB_2U(SCH_1):NC_CK440_B36
   U13  B36 NC_B36 9SQ440NQQI8-9SQ440NQQI8,SMLF,IA   I288 @S9S_MB_2U_LIB.S9S_MB_2U(SCH_1):PAGE197

NC_CK440_B37 @S9S_MB_2U_LIB.S9S_MB_2U(SCH_1):NC_CK440_B37
   U13  B37 NC_B37 9SQ440NQQI8-9SQ440NQQI8,SMLF,IA   I288 @S9S_MB_2U_LIB.S9S_MB_2U(SCH_1):PAGE197

NC_CK440_B39 @S9S_MB_2U_LIB.S9S_MB_2U(SCH_1):NC_CK440_B39
   U13  B39 NC_B39 9SQ440NQQI8-9SQ440NQQI8,SMLF,IA   I288 @S9S_MB_2U_LIB.S9S_MB_2U(SCH_1):PAGE197

NC_CK440_B41 @S9S_MB_2U_LIB.S9S_MB_2U(SCH_1):NC_CK440_B41
   U13  B41 NC_B41 9SQ440NQQI8-9SQ440NQQI8,SMLF,IA   I288 @S9S_MB_2U_LIB.S9S_MB_2U(SCH_1):PAGE197

NC_CK440_B44 @S9S_MB_2U_LIB.S9S_MB_2U(SCH_1):NC_CK440_B44
   U13  B44 NC_B44 9SQ440NQQI8-9SQ440NQQI8,SMLF,IA   I288 @S9S_MB_2U_LIB.S9S_MB_2U(SCH_1):PAGE197

NC_CK440_B5 @S9S_MB_2U_LIB.S9S_MB_2U(SCH_1):NC_CK440_B5
   U13   B5  NC_B5 9SQ440NQQI8-9SQ440NQQI8,SMLF,IA   I288 @S9S_MB_2U_LIB.S9S_MB_2U(SCH_1):PAGE197

NC_CK440_B7 @S9S_MB_2U_LIB.S9S_MB_2U(SCH_1):NC_CK440_B7
   U13   B7  NC_B7 9SQ440NQQI8-9SQ440NQQI8,SMLF,IA   I288 @S9S_MB_2U_LIB.S9S_MB_2U(SCH_1):PAGE197

NC_CLK_100M_DB2000_NC1 @S9S_MB_2U_LIB.S9S_MB_2U(SCH_1):NC_CLK_100M_DB2000_NC1
   U38   B3    NC1 9QXL2001BNHGI8-9QXL2001BNHGI8,A   I119 @S9S_MB_2U_LIB.S9S_MB_2U(SCH_1):PAGE195

NC_CLK_100M_DB2000_NC10 @S9S_MB_2U_LIB.S9S_MB_2U(SCH_1):NC_CLK_100M_DB2000_NC10
   U38   G2   NC10 9QXL2001BNHGI8-9QXL2001BNHGI8,A   I119 @S9S_MB_2U_LIB.S9S_MB_2U(SCH_1):PAGE195

NC_CLK_100M_DB2000_NC11 @S9S_MB_2U_LIB.S9S_MB_2U(SCH_1):NC_CLK_100M_DB2000_NC11
   U38  G11   NC11 9QXL2001BNHGI8-9QXL2001BNHGI8,A   I119 @S9S_MB_2U_LIB.S9S_MB_2U(SCH_1):PAGE195

NC_CLK_100M_DB2000_NC12 @S9S_MB_2U_LIB.S9S_MB_2U(SCH_1):NC_CLK_100M_DB2000_NC12
   U38   J2   NC12 9QXL2001BNHGI8-9QXL2001BNHGI8,A   I119 @S9S_MB_2U_LIB.S9S_MB_2U(SCH_1):PAGE195

NC_CLK_100M_DB2000_NC13 @S9S_MB_2U_LIB.S9S_MB_2U(SCH_1):NC_CLK_100M_DB2000_NC13
   U38  J11   NC13 9QXL2001BNHGI8-9QXL2001BNHGI8,A   I119 @S9S_MB_2U_LIB.S9S_MB_2U(SCH_1):PAGE195

NC_CLK_100M_DB2000_NC14 @S9S_MB_2U_LIB.S9S_MB_2U(SCH_1):NC_CLK_100M_DB2000_NC14
   U38   K2   NC14 9QXL2001BNHGI8-9QXL2001BNHGI8,A   I119 @S9S_MB_2U_LIB.S9S_MB_2U(SCH_1):PAGE195

NC_CLK_100M_DB2000_NC15 @S9S_MB_2U_LIB.S9S_MB_2U(SCH_1):NC_CLK_100M_DB2000_NC15
   U38   L6   NC15 9QXL2001BNHGI8-9QXL2001BNHGI8,A   I119 @S9S_MB_2U_LIB.S9S_MB_2U(SCH_1):PAGE195

NC_CLK_100M_DB2000_NC16 @S9S_MB_2U_LIB.S9S_MB_2U(SCH_1):NC_CLK_100M_DB2000_NC16
   U38   L7   NC16 9QXL2001BNHGI8-9QXL2001BNHGI8,A   I119 @S9S_MB_2U_LIB.S9S_MB_2U(SCH_1):PAGE195

NC_CLK_100M_DB2000_NC17 @S9S_MB_2U_LIB.S9S_MB_2U(SCH_1):NC_CLK_100M_DB2000_NC17
   U38   L3   NC17 9QXL2001BNHGI8-9QXL2001BNHGI8,A   I119 @S9S_MB_2U_LIB.S9S_MB_2U(SCH_1):PAGE195

NC_CLK_100M_DB2000_NC18 @S9S_MB_2U_LIB.S9S_MB_2U(SCH_1):NC_CLK_100M_DB2000_NC18
   U38   L9   NC18 9QXL2001BNHGI8-9QXL2001BNHGI8,A   I119 @S9S_MB_2U_LIB.S9S_MB_2U(SCH_1):PAGE195

NC_CLK_100M_DB2000_NC2 @S9S_MB_2U_LIB.S9S_MB_2U(SCH_1):NC_CLK_100M_DB2000_NC2
   U38   B5    NC2 9QXL2001BNHGI8-9QXL2001BNHGI8,A   I119 @S9S_MB_2U_LIB.S9S_MB_2U(SCH_1):PAGE195

NC_CLK_100M_DB2000_NC3 @S9S_MB_2U_LIB.S9S_MB_2U(SCH_1):NC_CLK_100M_DB2000_NC3
   U38   B7    NC3 9QXL2001BNHGI8-9QXL2001BNHGI8,A   I119 @S9S_MB_2U_LIB.S9S_MB_2U(SCH_1):PAGE195

NC_CLK_100M_DB2000_NC4 @S9S_MB_2U_LIB.S9S_MB_2U(SCH_1):NC_CLK_100M_DB2000_NC4
   U38   B9    NC4 9QXL2001BNHGI8-9QXL2001BNHGI8,A   I119 @S9S_MB_2U_LIB.S9S_MB_2U(SCH_1):PAGE195

NC_CLK_100M_DB2000_NC5 @S9S_MB_2U_LIB.S9S_MB_2U(SCH_1):NC_CLK_100M_DB2000_NC5
   U38   C2    NC5 9QXL2001BNHGI8-9QXL2001BNHGI8,A   I119 @S9S_MB_2U_LIB.S9S_MB_2U(SCH_1):PAGE195

NC_CLK_100M_DB2000_NC6 @S9S_MB_2U_LIB.S9S_MB_2U(SCH_1):NC_CLK_100M_DB2000_NC6
   U38   D2    NC6 9QXL2001BNHGI8-9QXL2001BNHGI8,A   I119 @S9S_MB_2U_LIB.S9S_MB_2U(SCH_1):PAGE195

NC_CLK_100M_DB2000_NC7 @S9S_MB_2U_LIB.S9S_MB_2U(SCH_1):NC_CLK_100M_DB2000_NC7
   U38  D11    NC7 9QXL2001BNHGI8-9QXL2001BNHGI8,A   I119 @S9S_MB_2U_LIB.S9S_MB_2U(SCH_1):PAGE195

NC_CLK_100M_DB2000_NC8 @S9S_MB_2U_LIB.S9S_MB_2U(SCH_1):NC_CLK_100M_DB2000_NC8
   U38   F2    NC8 9QXL2001BNHGI8-9QXL2001BNHGI8,A   I119 @S9S_MB_2U_LIB.S9S_MB_2U(SCH_1):PAGE195

NC_CLK_100M_DB2000_NC9 @S9S_MB_2U_LIB.S9S_MB_2U(SCH_1):NC_CLK_100M_DB2000_NC9
   U38  F11    NC9 9QXL2001BNHGI8-9QXL2001BNHGI8,A   I119 @S9S_MB_2U_LIB.S9S_MB_2U(SCH_1):PAGE195

NC_CLK_CK440_100M1_DN @S9S_MB_2U_LIB.S9S_MB_2U(SCH_1):NC_CLK_CK440_100M1_DN
   U13  A31 100M1# 9SQ440NQQI8-9SQ440NQQI8,SMLF,IA   I180 @S9S_MB_2U_LIB.S9S_MB_2U(SCH_1):PAGE197

NC_CLK_CK440_100M1_DP @S9S_MB_2U_LIB.S9S_MB_2U(SCH_1):NC_CLK_CK440_100M1_DP
   U13  A32  100M1 9SQ440NQQI8-9SQ440NQQI8,SMLF,IA   I180 @S9S_MB_2U_LIB.S9S_MB_2U(SCH_1):PAGE197

NC_CLK_CK440_100M2_DN @S9S_MB_2U_LIB.S9S_MB_2U(SCH_1):NC_CLK_CK440_100M2_DN
   U13  A27 100M2# 9SQ440NQQI8-9SQ440NQQI8,SMLF,IA   I180 @S9S_MB_2U_LIB.S9S_MB_2U(SCH_1):PAGE197

NC_CLK_CK440_100M2_DP @S9S_MB_2U_LIB.S9S_MB_2U(SCH_1):NC_CLK_CK440_100M2_DP
   U13  A28  100M2 9SQ440NQQI8-9SQ440NQQI8,SMLF,IA   I180 @S9S_MB_2U_LIB.S9S_MB_2U(SCH_1):PAGE197

NC_CLK_CK440_100M3_DN @S9S_MB_2U_LIB.S9S_MB_2U(SCH_1):NC_CLK_CK440_100M3_DN
   U13  A24 100M3# 9SQ440NQQI8-9SQ440NQQI8,SMLF,IA   I180 @S9S_MB_2U_LIB.S9S_MB_2U(SCH_1):PAGE197

NC_CLK_CK440_100M3_DP @S9S_MB_2U_LIB.S9S_MB_2U(SCH_1):NC_CLK_CK440_100M3_DP
   U13  A25  100M3 9SQ440NQQI8-9SQ440NQQI8,SMLF,IA   I180 @S9S_MB_2U_LIB.S9S_MB_2U(SCH_1):PAGE197

NC_CLK_CK440_100M4_DN @S9S_MB_2U_LIB.S9S_MB_2U(SCH_1):NC_CLK_CK440_100M4_DN
   U13  A22 100M4# 9SQ440NQQI8-9SQ440NQQI8,SMLF,IA   I180 @S9S_MB_2U_LIB.S9S_MB_2U(SCH_1):PAGE197

NC_CLK_CK440_100M4_DP @S9S_MB_2U_LIB.S9S_MB_2U(SCH_1):NC_CLK_CK440_100M4_DP
   U13  A23  100M4 9SQ440NQQI8-9SQ440NQQI8,SMLF,IA   I180 @S9S_MB_2U_LIB.S9S_MB_2U(SCH_1):PAGE197

NC_CLK_CK440_100M5_DN @S9S_MB_2U_LIB.S9S_MB_2U(SCH_1):NC_CLK_CK440_100M5_DN
   U13  A20 100M5# 9SQ440NQQI8-9SQ440NQQI8,SMLF,IA   I180 @S9S_MB_2U_LIB.S9S_MB_2U(SCH_1):PAGE197

NC_CLK_CK440_100M5_DP @S9S_MB_2U_LIB.S9S_MB_2U(SCH_1):NC_CLK_CK440_100M5_DP
   U13  A21  100M5 9SQ440NQQI8-9SQ440NQQI8,SMLF,IA   I180 @S9S_MB_2U_LIB.S9S_MB_2U(SCH_1):PAGE197

NC_CLK_CK440_100M6_DN @S9S_MB_2U_LIB.S9S_MB_2U(SCH_1):NC_CLK_CK440_100M6_DN
   U13  A18 100M6# 9SQ440NQQI8-9SQ440NQQI8,SMLF,IA   I180 @S9S_MB_2U_LIB.S9S_MB_2U(SCH_1):PAGE197

NC_CLK_CK440_100M6_DP @S9S_MB_2U_LIB.S9S_MB_2U(SCH_1):NC_CLK_CK440_100M6_DP
   U13  A19  100M6 9SQ440NQQI8-9SQ440NQQI8,SMLF,IA   I180 @S9S_MB_2U_LIB.S9S_MB_2U(SCH_1):PAGE197

NC_CLK_CK440_MXCK0_DN @S9S_MB_2U_LIB.S9S_MB_2U(SCH_1):NC_CLK_CK440_MXCK0_DN
   U13  A51 MXCK0# 9SQ440NQQI8-9SQ440NQQI8,SMLF,IA   I180 @S9S_MB_2U_LIB.S9S_MB_2U(SCH_1):PAGE197

NC_CLK_CK440_MXCK0_DP @S9S_MB_2U_LIB.S9S_MB_2U(SCH_1):NC_CLK_CK440_MXCK0_DP
   U13  A52  MXCK0 9SQ440NQQI8-9SQ440NQQI8,SMLF,IA   I180 @S9S_MB_2U_LIB.S9S_MB_2U(SCH_1):PAGE197

NC_CLK_CK440_MXCK1_DN @S9S_MB_2U_LIB.S9S_MB_2U(SCH_1):NC_CLK_CK440_MXCK1_DN
   U13  A49 MXCK1# 9SQ440NQQI8-9SQ440NQQI8,SMLF,IA   I180 @S9S_MB_2U_LIB.S9S_MB_2U(SCH_1):PAGE197

NC_CLK_CK440_MXCK1_DP @S9S_MB_2U_LIB.S9S_MB_2U(SCH_1):NC_CLK_CK440_MXCK1_DP
   U13  A50  MXCK1 9SQ440NQQI8-9SQ440NQQI8,SMLF,IA   I180 @S9S_MB_2U_LIB.S9S_MB_2U(SCH_1):PAGE197

NC_CLK_CK440_MXCK3_DN @S9S_MB_2U_LIB.S9S_MB_2U(SCH_1):NC_CLK_CK440_MXCK3_DN
   U13  A45 MXCK3# 9SQ440NQQI8-9SQ440NQQI8,SMLF,IA   I180 @S9S_MB_2U_LIB.S9S_MB_2U(SCH_1):PAGE197

NC_CLK_CK440_MXCK3_DP @S9S_MB_2U_LIB.S9S_MB_2U(SCH_1):NC_CLK_CK440_MXCK3_DP
   U13  A46  MXCK3 9SQ440NQQI8-9SQ440NQQI8,SMLF,IA   I180 @S9S_MB_2U_LIB.S9S_MB_2U(SCH_1):PAGE197

NC_CLK_CK440_MXCK4_DN @S9S_MB_2U_LIB.S9S_MB_2U(SCH_1):NC_CLK_CK440_MXCK4_DN
   U13  A43 MXCK4# 9SQ440NQQI8-9SQ440NQQI8,SMLF,IA   I180 @S9S_MB_2U_LIB.S9S_MB_2U(SCH_1):PAGE197

NC_CLK_CK440_MXCK4_DP @S9S_MB_2U_LIB.S9S_MB_2U(SCH_1):NC_CLK_CK440_MXCK4_DP
   U13  A44  MXCK4 9SQ440NQQI8-9SQ440NQQI8,SMLF,IA   I180 @S9S_MB_2U_LIB.S9S_MB_2U(SCH_1):PAGE197

NC_CLK_CK440_MXCK5_DN @S9S_MB_2U_LIB.S9S_MB_2U(SCH_1):NC_CLK_CK440_MXCK5_DN
   U13  A41 MXCK5# 9SQ440NQQI8-9SQ440NQQI8,SMLF,IA   I180 @S9S_MB_2U_LIB.S9S_MB_2U(SCH_1):PAGE197

NC_CLK_CK440_MXCK5_DP @S9S_MB_2U_LIB.S9S_MB_2U(SCH_1):NC_CLK_CK440_MXCK5_DP
   U13  A42  MXCK5 9SQ440NQQI8-9SQ440NQQI8,SMLF,IA   I180 @S9S_MB_2U_LIB.S9S_MB_2U(SCH_1):PAGE197

NC_CLK_CK440_MXCK6_DN @S9S_MB_2U_LIB.S9S_MB_2U(SCH_1):NC_CLK_CK440_MXCK6_DN
   U13  A39 MXCK6# 9SQ440NQQI8-9SQ440NQQI8,SMLF,IA   I180 @S9S_MB_2U_LIB.S9S_MB_2U(SCH_1):PAGE197

NC_CLK_CK440_MXCK6_DP @S9S_MB_2U_LIB.S9S_MB_2U(SCH_1):NC_CLK_CK440_MXCK6_DP
   U13  A40  MXCK6 9SQ440NQQI8-9SQ440NQQI8,SMLF,IA   I180 @S9S_MB_2U_LIB.S9S_MB_2U(SCH_1):PAGE197

NC_CLK_CK440_MXCK7_DN @S9S_MB_2U_LIB.S9S_MB_2U(SCH_1):NC_CLK_CK440_MXCK7_DN
   U13  A37 MXCK7# 9SQ440NQQI8-9SQ440NQQI8,SMLF,IA   I180 @S9S_MB_2U_LIB.S9S_MB_2U(SCH_1):PAGE197

NC_CLK_CK440_MXCK7_DP @S9S_MB_2U_LIB.S9S_MB_2U(SCH_1):NC_CLK_CK440_MXCK7_DP
   U13  A38  MXCK7 9SQ440NQQI8-9SQ440NQQI8,SMLF,IA   I180 @S9S_MB_2U_LIB.S9S_MB_2U(SCH_1):PAGE197

NC_CLK_CK440_MXCK8_DN @S9S_MB_2U_LIB.S9S_MB_2U(SCH_1):NC_CLK_CK440_MXCK8_DN
   U13  A35 MXCK8# 9SQ440NQQI8-9SQ440NQQI8,SMLF,IA   I180 @S9S_MB_2U_LIB.S9S_MB_2U(SCH_1):PAGE197

NC_CLK_CK440_MXCK8_DP @S9S_MB_2U_LIB.S9S_MB_2U(SCH_1):NC_CLK_CK440_MXCK8_DP
   U13  A36  MXCK8 9SQ440NQQI8-9SQ440NQQI8,SMLF,IA   I180 @S9S_MB_2U_LIB.S9S_MB_2U(SCH_1):PAGE197

NC_CLK_PFT_OUT_CPU0_DN @S9S_MB_2U_LIB.S9S_MB_2U(SCH_1):NC_CLK_PFT_OUT_CPU0_DN
    U2 CE70 RSVD91 SOCKET4677_AZIF0045P001C01CS-SA    I57 @S9S_MB_2U_LIB.S9S_MB_2U(SCH_1):PAGE13

NC_CLK_PFT_OUT_CPU0_DP @S9S_MB_2U_LIB.S9S_MB_2U(SCH_1):NC_CLK_PFT_OUT_CPU0_DP
    U2 CD71 RSVD88 SOCKET4677_AZIF0045P001C01CS-SA    I57 @S9S_MB_2U_LIB.S9S_MB_2U(SCH_1):PAGE13

NC_CPU0_DDR01_VIEWDIG0 @S9S_MB_2U_LIB.S9S_MB_2U(SCH_1):NC_CPU0_DDR01_VIEWDIG0
    U2 AU58 RSVD10 SOCKET4677_AZIF0045P001C01CS-SA     I1 @S9S_MB_2U_LIB.S9S_MB_2U(SCH_1):PAGE16

NC_CPU0_DDR01_VIEWDIG1 @S9S_MB_2U_LIB.S9S_MB_2U(SCH_1):NC_CPU0_DDR01_VIEWDIG1
    U2 AU56  RSVD9 SOCKET4677_AZIF0045P001C01CS-SA     I1 @S9S_MB_2U_LIB.S9S_MB_2U(SCH_1):PAGE16

NC_CPU0_DDR23_VIEWDIG0 @S9S_MB_2U_LIB.S9S_MB_2U(SCH_1):NC_CPU0_DDR23_VIEWDIG0
    U2 AV32 RSVD16 SOCKET4677_AZIF0045P001C01CS-SA     I1 @S9S_MB_2U_LIB.S9S_MB_2U(SCH_1):PAGE16

NC_CPU0_DDR23_VIEWDIG1 @S9S_MB_2U_LIB.S9S_MB_2U(SCH_1):NC_CPU0_DDR23_VIEWDIG1
    U2 AU33  RSVD7 SOCKET4677_AZIF0045P001C01CS-SA     I1 @S9S_MB_2U_LIB.S9S_MB_2U(SCH_1):PAGE16

NC_CPU0_DDR45_VIEWDIG0 @S9S_MB_2U_LIB.S9S_MB_2U(SCH_1):NC_CPU0_DDR45_VIEWDIG0
    U2 CY24 RSVD151 SOCKET4677_AZIF0045P001C01CS-SA     I1 @S9S_MB_2U_LIB.S9S_MB_2U(SCH_1):PAGE16

NC_CPU0_DDR45_VIEWDIG1 @S9S_MB_2U_LIB.S9S_MB_2U(SCH_1):NC_CPU0_DDR45_VIEWDIG1
    U2 CY38 RSVD152 SOCKET4677_AZIF0045P001C01CS-SA     I1 @S9S_MB_2U_LIB.S9S_MB_2U(SCH_1):PAGE16

NC_CPU0_DDR67_VIEWDIG0 @S9S_MB_2U_LIB.S9S_MB_2U(SCH_1):NC_CPU0_DDR67_VIEWDIG0
    U2 DA45 RSVD158 SOCKET4677_AZIF0045P001C01CS-SA     I1 @S9S_MB_2U_LIB.S9S_MB_2U(SCH_1):PAGE16

NC_CPU0_DDR67_VIEWDIG1 @S9S_MB_2U_LIB.S9S_MB_2U(SCH_1):NC_CPU0_DDR67_VIEWDIG1
    U2 CY49 RSVD153 SOCKET4677_AZIF0045P001C01CS-SA     I1 @S9S_MB_2U_LIB.S9S_MB_2U(SCH_1):PAGE16

NC_CPU0_DMI_APROBE<0> @S9S_MB_2U_LIB.S9S_MB_2U(SCH_1):NC_CPU0_DMI_APROBE(0)
    U2 CA21 RSVD77 SOCKET4677_AZIF0045P001C01CS-SA     I1 @S9S_MB_2U_LIB.S9S_MB_2U(SCH_1):PAGE19

NC_CPU0_DMI_APROBE<1> @S9S_MB_2U_LIB.S9S_MB_2U(SCH_1):NC_CPU0_DMI_APROBE(1)
    U2 BW21 RSVD74 SOCKET4677_AZIF0045P001C01CS-SA     I1 @S9S_MB_2U_LIB.S9S_MB_2U(SCH_1):PAGE19

NC_CPU0_HBM0_VIEWDIG0 @S9S_MB_2U_LIB.S9S_MB_2U(SCH_1):NC_CPU0_HBM0_VIEWDIG0
    U2  U17 RSVD164 SOCKET4677_AZIF0045P001C01CS-SA     I1 @S9S_MB_2U_LIB.S9S_MB_2U(SCH_1):PAGE17

NC_CPU0_HBM0_VIEWDIG1 @S9S_MB_2U_LIB.S9S_MB_2U(SCH_1):NC_CPU0_HBM0_VIEWDIG1
    U2 EG17 RSVD160 SOCKET4677_AZIF0045P001C01CS-SA     I1 @S9S_MB_2U_LIB.S9S_MB_2U(SCH_1):PAGE17

NC_CPU0_HBM1_VIEWDIG0 @S9S_MB_2U_LIB.S9S_MB_2U(SCH_1):NC_CPU0_HBM1_VIEWDIG0
    U2  W17 RSVD165 SOCKET4677_AZIF0045P001C01CS-SA     I1 @S9S_MB_2U_LIB.S9S_MB_2U(SCH_1):PAGE17

NC_CPU0_HBM1_VIEWDIG1 @S9S_MB_2U_LIB.S9S_MB_2U(SCH_1):NC_CPU0_HBM1_VIEWDIG1
    U2 CW41 RSVD147 SOCKET4677_AZIF0045P001C01CS-SA     I1 @S9S_MB_2U_LIB.S9S_MB_2U(SCH_1):PAGE17

NC_CPU0_HBM2_VIEWDIG0 @S9S_MB_2U_LIB.S9S_MB_2U(SCH_1):NC_CPU0_HBM2_VIEWDIG0
    U2 AC78  RSVD0 SOCKET4677_AZIF0045P001C01CS-SA     I1 @S9S_MB_2U_LIB.S9S_MB_2U(SCH_1):PAGE17

NC_CPU0_HBM2_VIEWDIG1 @S9S_MB_2U_LIB.S9S_MB_2U(SCH_1):NC_CPU0_HBM2_VIEWDIG1
    U2 AD77  RSVD1 SOCKET4677_AZIF0045P001C01CS-SA     I1 @S9S_MB_2U_LIB.S9S_MB_2U(SCH_1):PAGE17

NC_CPU0_HBM3_VIEWDIG0 @S9S_MB_2U_LIB.S9S_MB_2U(SCH_1):NC_CPU0_HBM3_VIEWDIG0
    U2 BG78 RSVD54 SOCKET4677_AZIF0045P001C01CS-SA     I1 @S9S_MB_2U_LIB.S9S_MB_2U(SCH_1):PAGE17

NC_CPU0_HBM3_VIEWDIG1 @S9S_MB_2U_LIB.S9S_MB_2U(SCH_1):NC_CPU0_HBM3_VIEWDIG1
    U2 BL60 RSVD63 SOCKET4677_AZIF0045P001C01CS-SA     I1 @S9S_MB_2U_LIB.S9S_MB_2U(SCH_1):PAGE17

NC_CPU0_LGSSPARE0 @S9S_MB_2U_LIB.S9S_MB_2U(SCH_1):NC_CPU0_LGSSPARE0
    U2 CR60 RSVD134 SOCKET4677_AZIF0045P001C01CS-SA     I1 @S9S_MB_2U_LIB.S9S_MB_2U(SCH_1):PAGE16

NC_CPU0_LGSSPARE1 @S9S_MB_2U_LIB.S9S_MB_2U(SCH_1):NC_CPU0_LGSSPARE1
    U2 CN60 RSVD125 SOCKET4677_AZIF0045P001C01CS-SA     I1 @S9S_MB_2U_LIB.S9S_MB_2U(SCH_1):PAGE16

NC_CPU0_LGSSPARE2 @S9S_MB_2U_LIB.S9S_MB_2U(SCH_1):NC_CPU0_LGSSPARE2
    U2 CU62 RSVD139 SOCKET4677_AZIF0045P001C01CS-SA     I1 @S9S_MB_2U_LIB.S9S_MB_2U(SCH_1):PAGE16

NC_CPU0_LGSSPARE3 @S9S_MB_2U_LIB.S9S_MB_2U(SCH_1):NC_CPU0_LGSSPARE3
    U2 CE62 RSVD90 SOCKET4677_AZIF0045P001C01CS-SA     I1 @S9S_MB_2U_LIB.S9S_MB_2U(SCH_1):PAGE16

NC_CPU0_LGSSPARE4 @S9S_MB_2U_LIB.S9S_MB_2U(SCH_1):NC_CPU0_LGSSPARE4
    U2 CC64 RSVD81 SOCKET4677_AZIF0045P001C01CS-SA     I1 @S9S_MB_2U_LIB.S9S_MB_2U(SCH_1):PAGE16

NC_CPU0_LGSSPARE5 @S9S_MB_2U_LIB.S9S_MB_2U(SCH_1):NC_CPU0_LGSSPARE5
    U2 CP61 RSVD129 SOCKET4677_AZIF0045P001C01CS-SA     I1 @S9S_MB_2U_LIB.S9S_MB_2U(SCH_1):PAGE16

NC_CPU0_MDFI_DIE00_EW0 @S9S_MB_2U_LIB.S9S_MB_2U(SCH_1):NC_CPU0_MDFI_DIE00_EW0
    U2 BP22 RSVD67 SOCKET4677_AZIF0045P001C01CS-SA     I1 @S9S_MB_2U_LIB.S9S_MB_2U(SCH_1):PAGE17

NC_CPU0_MDFI_DIE00_EW1 @S9S_MB_2U_LIB.S9S_MB_2U(SCH_1):NC_CPU0_MDFI_DIE00_EW1
    U2 BR21 RSVD71 SOCKET4677_AZIF0045P001C01CS-SA     I1 @S9S_MB_2U_LIB.S9S_MB_2U(SCH_1):PAGE17

NC_CPU0_MDFI_DIE00_NS0 @S9S_MB_2U_LIB.S9S_MB_2U(SCH_1):NC_CPU0_MDFI_DIE00_NS0
    U2 BK22 RSVD60 SOCKET4677_AZIF0045P001C01CS-SA     I1 @S9S_MB_2U_LIB.S9S_MB_2U(SCH_1):PAGE17

NC_CPU0_MDFI_DIE00_NS1 @S9S_MB_2U_LIB.S9S_MB_2U(SCH_1):NC_CPU0_MDFI_DIE00_NS1
    U2 BJ21 RSVD57 SOCKET4677_AZIF0045P001C01CS-SA     I1 @S9S_MB_2U_LIB.S9S_MB_2U(SCH_1):PAGE17

NC_CPU0_MDFI_DIE01_EW0 @S9S_MB_2U_LIB.S9S_MB_2U(SCH_1):NC_CPU0_MDFI_DIE01_EW0
    U2 AV65 RSVD21 SOCKET4677_AZIF0045P001C01CS-SA     I1 @S9S_MB_2U_LIB.S9S_MB_2U(SCH_1):PAGE17

NC_CPU0_MDFI_DIE01_EW1 @S9S_MB_2U_LIB.S9S_MB_2U(SCH_1):NC_CPU0_MDFI_DIE01_EW1
    U2 CC66 RSVD82 SOCKET4677_AZIF0045P001C01CS-SA     I1 @S9S_MB_2U_LIB.S9S_MB_2U(SCH_1):PAGE17

NC_CPU0_MDFI_DIE01_NS0 @S9S_MB_2U_LIB.S9S_MB_2U(SCH_1):NC_CPU0_MDFI_DIE01_NS0
    U2 BF71 RSVD51 SOCKET4677_AZIF0045P001C01CS-SA     I1 @S9S_MB_2U_LIB.S9S_MB_2U(SCH_1):PAGE17

NC_CPU0_MDFI_DIE01_NS1 @S9S_MB_2U_LIB.S9S_MB_2U(SCH_1):NC_CPU0_MDFI_DIE01_NS1
    U2 BD71 RSVD43 SOCKET4677_AZIF0045P001C01CS-SA     I1 @S9S_MB_2U_LIB.S9S_MB_2U(SCH_1):PAGE17

NC_CPU0_MDFI_DIE10_EW0 @S9S_MB_2U_LIB.S9S_MB_2U(SCH_1):NC_CPU0_MDFI_DIE10_EW0
    U2 CD26 RSVD84 SOCKET4677_AZIF0045P001C01CS-SA     I1 @S9S_MB_2U_LIB.S9S_MB_2U(SCH_1):PAGE17

NC_CPU0_MDFI_DIE10_EW1 @S9S_MB_2U_LIB.S9S_MB_2U(SCH_1):NC_CPU0_MDFI_DIE10_EW1
    U2 CD30 RSVD85 SOCKET4677_AZIF0045P001C01CS-SA     I1 @S9S_MB_2U_LIB.S9S_MB_2U(SCH_1):PAGE17

NC_CPU0_MDFI_DIE10_NS0 @S9S_MB_2U_LIB.S9S_MB_2U(SCH_1):NC_CPU0_MDFI_DIE10_NS0
    U2 CF22 RSVD92 SOCKET4677_AZIF0045P001C01CS-SA     I1 @S9S_MB_2U_LIB.S9S_MB_2U(SCH_1):PAGE17

NC_CPU0_MDFI_DIE10_NS1 @S9S_MB_2U_LIB.S9S_MB_2U(SCH_1):NC_CPU0_MDFI_DIE10_NS1
    U2 CD22 RSVD83 SOCKET4677_AZIF0045P001C01CS-SA     I1 @S9S_MB_2U_LIB.S9S_MB_2U(SCH_1):PAGE17

NC_CPU0_MDFI_DIE11_EW0 @S9S_MB_2U_LIB.S9S_MB_2U(SCH_1):NC_CPU0_MDFI_DIE11_EW0
    U2 CJ70 RSVD107 SOCKET4677_AZIF0045P001C01CS-SA     I1 @S9S_MB_2U_LIB.S9S_MB_2U(SCH_1):PAGE17

NC_CPU0_MDFI_DIE11_EW1 @S9S_MB_2U_LIB.S9S_MB_2U(SCH_1):NC_CPU0_MDFI_DIE11_EW1
    U2 CH69 RSVD99 SOCKET4677_AZIF0045P001C01CS-SA     I1 @S9S_MB_2U_LIB.S9S_MB_2U(SCH_1):PAGE17

NC_CPU0_MDFI_DIE11_NS0 @S9S_MB_2U_LIB.S9S_MB_2U(SCH_1):NC_CPU0_MDFI_DIE11_NS0
    U2 CJ68 RSVD106 SOCKET4677_AZIF0045P001C01CS-SA     I1 @S9S_MB_2U_LIB.S9S_MB_2U(SCH_1):PAGE17

NC_CPU0_MDFI_DIE11_NS1 @S9S_MB_2U_LIB.S9S_MB_2U(SCH_1):NC_CPU0_MDFI_DIE11_NS1
    U2 CK67 RSVD112 SOCKET4677_AZIF0045P001C01CS-SA     I1 @S9S_MB_2U_LIB.S9S_MB_2U(SCH_1):PAGE17

NC_CPU0_PE0_APROBE<0> @S9S_MB_2U_LIB.S9S_MB_2U(SCH_1):NC_CPU0_PE0_APROBE(0)
    U2 BN21 RSVD66 SOCKET4677_AZIF0045P001C01CS-SA     I1 @S9S_MB_2U_LIB.S9S_MB_2U(SCH_1):PAGE19

NC_CPU0_PE0_APROBE<1> @S9S_MB_2U_LIB.S9S_MB_2U(SCH_1):NC_CPU0_PE0_APROBE(1)
    U2 BL21 RSVD62 SOCKET4677_AZIF0045P001C01CS-SA     I1 @S9S_MB_2U_LIB.S9S_MB_2U(SCH_1):PAGE19

NC_CPU0_PE1_APROBE<0> @S9S_MB_2U_LIB.S9S_MB_2U(SCH_1):NC_CPU0_PE1_APROBE(0)
    U2 CE21 RSVD89 SOCKET4677_AZIF0045P001C01CS-SA     I1 @S9S_MB_2U_LIB.S9S_MB_2U(SCH_1):PAGE19

NC_CPU0_PE1_APROBE<1> @S9S_MB_2U_LIB.S9S_MB_2U(SCH_1):NC_CPU0_PE1_APROBE(1)
    U2 CC21 RSVD79 SOCKET4677_AZIF0045P001C01CS-SA     I1 @S9S_MB_2U_LIB.S9S_MB_2U(SCH_1):PAGE19

NC_CPU0_PE2_APROBE<0> @S9S_MB_2U_LIB.S9S_MB_2U(SCH_1):NC_CPU0_PE2_APROBE(0)
    U2 CC23 RSVD80 SOCKET4677_AZIF0045P001C01CS-SA     I1 @S9S_MB_2U_LIB.S9S_MB_2U(SCH_1):PAGE19

NC_CPU0_PE2_APROBE<1> @S9S_MB_2U_LIB.S9S_MB_2U(SCH_1):NC_CPU0_PE2_APROBE(1)
    U2 BW23 RSVD75 SOCKET4677_AZIF0045P001C01CS-SA     I1 @S9S_MB_2U_LIB.S9S_MB_2U(SCH_1):PAGE19

NC_CPU0_PE3_APROBE<0> @S9S_MB_2U_LIB.S9S_MB_2U(SCH_1):NC_CPU0_PE3_APROBE(0)
    U2 CL68 RSVD118 SOCKET4677_AZIF0045P001C01CS-SA     I1 @S9S_MB_2U_LIB.S9S_MB_2U(SCH_1):PAGE19

NC_CPU0_PE3_APROBE<1> @S9S_MB_2U_LIB.S9S_MB_2U(SCH_1):NC_CPU0_PE3_APROBE(1)
    U2 CM69 RSVD122 SOCKET4677_AZIF0045P001C01CS-SA     I1 @S9S_MB_2U_LIB.S9S_MB_2U(SCH_1):PAGE19

NC_CPU0_PE4_APROBE<0> @S9S_MB_2U_LIB.S9S_MB_2U(SCH_1):NC_CPU0_PE4_APROBE(0)
    U2 AV67 RSVD22 SOCKET4677_AZIF0045P001C01CS-SA     I1 @S9S_MB_2U_LIB.S9S_MB_2U(SCH_1):PAGE19

NC_CPU0_PE4_APROBE<1> @S9S_MB_2U_LIB.S9S_MB_2U(SCH_1):NC_CPU0_PE4_APROBE(1)
    U2 AU66 RSVD13 SOCKET4677_AZIF0045P001C01CS-SA     I1 @S9S_MB_2U_LIB.S9S_MB_2U(SCH_1):PAGE19

NC_CPU0_RSVD<144> @S9S_MB_2U_LIB.S9S_MB_2U(SCH_1):NC_CPU0_RSVD(144)
    U2 CW68 RSVD150 SOCKET4677_AZIF0045P001C01CS-SA     I1 @S9S_MB_2U_LIB.S9S_MB_2U(SCH_1):PAGE14

NC_CPU0_SOC_SPARE0 @S9S_MB_2U_LIB.S9S_MB_2U(SCH_1):NC_CPU0_SOC_SPARE0
    U2 AY24 RSVD26 SOCKET4677_AZIF0045P001C01CS-SA     I1 @S9S_MB_2U_LIB.S9S_MB_2U(SCH_1):PAGE17

NC_CPU0_SOC_SPARE1 @S9S_MB_2U_LIB.S9S_MB_2U(SCH_1):NC_CPU0_SOC_SPARE1
    U2 BM65 RSVD65 SOCKET4677_AZIF0045P001C01CS-SA     I1 @S9S_MB_2U_LIB.S9S_MB_2U(SCH_1):PAGE17

NC_CPU0_SOC_SPARE4 @S9S_MB_2U_LIB.S9S_MB_2U(SCH_1):NC_CPU0_SOC_SPARE4
    U2 BA25 RSVD31 SOCKET4677_AZIF0045P001C01CS-SA     I1 @S9S_MB_2U_LIB.S9S_MB_2U(SCH_1):PAGE17

NC_CPU0_SOC_SPARE5 @S9S_MB_2U_LIB.S9S_MB_2U(SCH_1):NC_CPU0_SOC_SPARE5
    U2 BP65 RSVD68 SOCKET4677_AZIF0045P001C01CS-SA     I1 @S9S_MB_2U_LIB.S9S_MB_2U(SCH_1):PAGE17

NC_CPU0_THERMADA @S9S_MB_2U_LIB.S9S_MB_2U(SCH_1):NC_CPU0_THERMADA
    U2 AV40 RSVD18 SOCKET4677_AZIF0045P001C01CS-SA     I1 @S9S_MB_2U_LIB.S9S_MB_2U(SCH_1):PAGE16

NC_CPU0_THERMADC @S9S_MB_2U_LIB.S9S_MB_2U(SCH_1):NC_CPU0_THERMADC
    U2 AV38 RSVD17 SOCKET4677_AZIF0045P001C01CS-SA     I1 @S9S_MB_2U_LIB.S9S_MB_2U(SCH_1):PAGE16

NC_CPU0_UPI0_APROBE<0> @S9S_MB_2U_LIB.S9S_MB_2U(SCH_1):NC_CPU0_UPI0_APROBE(0)
    U2 AN17  RSVD2 SOCKET4677_AZIF0045P001C01CS-SA     I1 @S9S_MB_2U_LIB.S9S_MB_2U(SCH_1):PAGE19

NC_CPU0_UPI0_APROBE<1> @S9S_MB_2U_LIB.S9S_MB_2U(SCH_1):NC_CPU0_UPI0_APROBE(1)
    U2 AR17  RSVD3 SOCKET4677_AZIF0045P001C01CS-SA     I1 @S9S_MB_2U_LIB.S9S_MB_2U(SCH_1):PAGE19

NC_CPU0_UPI1_APROBE<0> @S9S_MB_2U_LIB.S9S_MB_2U(SCH_1):NC_CPU0_UPI1_APROBE(0)
    U2 BV22 RSVD73 SOCKET4677_AZIF0045P001C01CS-SA     I1 @S9S_MB_2U_LIB.S9S_MB_2U(SCH_1):PAGE19

NC_CPU0_UPI1_APROBE<1> @S9S_MB_2U_LIB.S9S_MB_2U(SCH_1):NC_CPU0_UPI1_APROBE(1)
    U2 CA23 RSVD78 SOCKET4677_AZIF0045P001C01CS-SA     I1 @S9S_MB_2U_LIB.S9S_MB_2U(SCH_1):PAGE19

NC_CPU0_UPI2_APROBE<0> @S9S_MB_2U_LIB.S9S_MB_2U(SCH_1):NC_CPU0_UPI2_APROBE(0)
    U2 AU68 RSVD14 SOCKET4677_AZIF0045P001C01CS-SA     I1 @S9S_MB_2U_LIB.S9S_MB_2U(SCH_1):PAGE19

NC_CPU0_UPI2_APROBE<1> @S9S_MB_2U_LIB.S9S_MB_2U(SCH_1):NC_CPU0_UPI2_APROBE(1)
    U2 AT67  RSVD5 SOCKET4677_AZIF0045P001C01CS-SA     I1 @S9S_MB_2U_LIB.S9S_MB_2U(SCH_1):PAGE19

NC_CPU0_UPI3_APROBE<0> @S9S_MB_2U_LIB.S9S_MB_2U(SCH_1):NC_CPU0_UPI3_APROBE(0)
    U2 CP69 RSVD130 SOCKET4677_AZIF0045P001C01CS-SA     I1 @S9S_MB_2U_LIB.S9S_MB_2U(SCH_1):PAGE19

NC_CPU0_UPI3_APROBE<1> @S9S_MB_2U_LIB.S9S_MB_2U(SCH_1):NC_CPU0_UPI3_APROBE(1)
    U2 CR68 RSVD135 SOCKET4677_AZIF0045P001C01CS-SA     I1 @S9S_MB_2U_LIB.S9S_MB_2U(SCH_1):PAGE19

NC_CPU0_VIEWPIN_DIE00<0> @S9S_MB_2U_LIB.S9S_MB_2U(SCH_1):NC_CPU0_VIEWPIN_DIE00(0)
    U2 AY26 RSVD27 SOCKET4677_AZIF0045P001C01CS-SA     I1 @S9S_MB_2U_LIB.S9S_MB_2U(SCH_1):PAGE14

NC_CPU0_VIEWPIN_DIE00<1> @S9S_MB_2U_LIB.S9S_MB_2U(SCH_1):NC_CPU0_VIEWPIN_DIE00(1)
    U2 AT24  RSVD4 SOCKET4677_AZIF0045P001C01CS-SA     I1 @S9S_MB_2U_LIB.S9S_MB_2U(SCH_1):PAGE14

NC_CPU0_VIEWPIN_DIE00<2> @S9S_MB_2U_LIB.S9S_MB_2U(SCH_1):NC_CPU0_VIEWPIN_DIE00(2)
    U2 AU25  RSVD6 SOCKET4677_AZIF0045P001C01CS-SA     I1 @S9S_MB_2U_LIB.S9S_MB_2U(SCH_1):PAGE14

NC_CPU0_VIEWPIN_DIE00<3> @S9S_MB_2U_LIB.S9S_MB_2U(SCH_1):NC_CPU0_VIEWPIN_DIE00(3)
    U2 AV26 RSVD15 SOCKET4677_AZIF0045P001C01CS-SA     I1 @S9S_MB_2U_LIB.S9S_MB_2U(SCH_1):PAGE14

NC_CPU0_VIEWPIN_DIE01<0> @S9S_MB_2U_LIB.S9S_MB_2U(SCH_1):NC_CPU0_VIEWPIN_DIE01(0)
    U2 BP69 RSVD70 SOCKET4677_AZIF0045P001C01CS-SA     I1 @S9S_MB_2U_LIB.S9S_MB_2U(SCH_1):PAGE14

NC_CPU0_VIEWPIN_DIE01<1> @S9S_MB_2U_LIB.S9S_MB_2U(SCH_1):NC_CPU0_VIEWPIN_DIE01(1)
    U2 BP67 RSVD69 SOCKET4677_AZIF0045P001C01CS-SA     I1 @S9S_MB_2U_LIB.S9S_MB_2U(SCH_1):PAGE14

NC_CPU0_VIEWPIN_DIE01<2> @S9S_MB_2U_LIB.S9S_MB_2U(SCH_1):NC_CPU0_VIEWPIN_DIE01(2)
    U2 AY65 RSVD29 SOCKET4677_AZIF0045P001C01CS-SA     I1 @S9S_MB_2U_LIB.S9S_MB_2U(SCH_1):PAGE14

NC_CPU0_VIEWPIN_DIE01<3> @S9S_MB_2U_LIB.S9S_MB_2U(SCH_1):NC_CPU0_VIEWPIN_DIE01(3)
    U2 BJ70 RSVD59 SOCKET4677_AZIF0045P001C01CS-SA     I1 @S9S_MB_2U_LIB.S9S_MB_2U(SCH_1):PAGE14

NC_CPU0_VIEWPIN_DIE10<0> @S9S_MB_2U_LIB.S9S_MB_2U(SCH_1):NC_CPU0_VIEWPIN_DIE10(0)
    U2 CR23 RSVD132 SOCKET4677_AZIF0045P001C01CS-SA     I1 @S9S_MB_2U_LIB.S9S_MB_2U(SCH_1):PAGE14

NC_CPU0_VIEWPIN_DIE10<1> @S9S_MB_2U_LIB.S9S_MB_2U(SCH_1):NC_CPU0_VIEWPIN_DIE10(1)
    U2 CW25 RSVD146 SOCKET4677_AZIF0045P001C01CS-SA     I1 @S9S_MB_2U_LIB.S9S_MB_2U(SCH_1):PAGE14

NC_CPU0_VIEWPIN_DIE10<2> @S9S_MB_2U_LIB.S9S_MB_2U(SCH_1):NC_CPU0_VIEWPIN_DIE10(2)
    U2 CV24 RSVD141 SOCKET4677_AZIF0045P001C01CS-SA     I1 @S9S_MB_2U_LIB.S9S_MB_2U(SCH_1):PAGE14

NC_CPU0_VIEWPIN_DIE10<3> @S9S_MB_2U_LIB.S9S_MB_2U(SCH_1):NC_CPU0_VIEWPIN_DIE10(3)
    U2 CW23 RSVD145 SOCKET4677_AZIF0045P001C01CS-SA     I1 @S9S_MB_2U_LIB.S9S_MB_2U(SCH_1):PAGE14

NC_CPU0_VIEWPIN_DIE11<0> @S9S_MB_2U_LIB.S9S_MB_2U(SCH_1):NC_CPU0_VIEWPIN_DIE11(0)
    U2 CJ62 RSVD104 SOCKET4677_AZIF0045P001C01CS-SA     I1 @S9S_MB_2U_LIB.S9S_MB_2U(SCH_1):PAGE14

NC_CPU0_VIEWPIN_DIE11<1> @S9S_MB_2U_LIB.S9S_MB_2U(SCH_1):NC_CPU0_VIEWPIN_DIE11(1)
    U2 CN62 RSVD126 SOCKET4677_AZIF0045P001C01CS-SA     I1 @S9S_MB_2U_LIB.S9S_MB_2U(SCH_1):PAGE14

NC_CPU0_VIEWPIN_DIE11<2> @S9S_MB_2U_LIB.S9S_MB_2U(SCH_1):NC_CPU0_VIEWPIN_DIE11(2)
    U2 CM63 RSVD121 SOCKET4677_AZIF0045P001C01CS-SA     I1 @S9S_MB_2U_LIB.S9S_MB_2U(SCH_1):PAGE14

NC_CPU0_VIEWPIN_DIE11<3> @S9S_MB_2U_LIB.S9S_MB_2U(SCH_1):NC_CPU0_VIEWPIN_DIE11(3)
    U2 CL64 RSVD116 SOCKET4677_AZIF0045P001C01CS-SA     I1 @S9S_MB_2U_LIB.S9S_MB_2U(SCH_1):PAGE14

NC_CPU0_VIEWPIN_GNR0 @S9S_MB_2U_LIB.S9S_MB_2U(SCH_1):NC_CPU0_VIEWPIN_GNR0
    U2 CT26 RSVD138 SOCKET4677_AZIF0045P001C01CS-SA     I1 @S9S_MB_2U_LIB.S9S_MB_2U(SCH_1):PAGE17

NC_CPU0_VIEWPIN_GNR1 @S9S_MB_2U_LIB.S9S_MB_2U(SCH_1):NC_CPU0_VIEWPIN_GNR1
    U2 CW58 RSVD149 SOCKET4677_AZIF0045P001C01CS-SA     I1 @S9S_MB_2U_LIB.S9S_MB_2U(SCH_1):PAGE17

NC_CPU0_VIEWPIN_GNR2 @S9S_MB_2U_LIB.S9S_MB_2U(SCH_1):NC_CPU0_VIEWPIN_GNR2
    U2 CR25 RSVD133 SOCKET4677_AZIF0045P001C01CS-SA     I1 @S9S_MB_2U_LIB.S9S_MB_2U(SCH_1):PAGE17

NC_CPU0_VIEWPIN_GNR3 @S9S_MB_2U_LIB.S9S_MB_2U(SCH_1):NC_CPU0_VIEWPIN_GNR3
    U2 CY57 RSVD154 SOCKET4677_AZIF0045P001C01CS-SA     I1 @S9S_MB_2U_LIB.S9S_MB_2U(SCH_1):PAGE17

NC_CPU1_DDR01_VIEWDIG0 @S9S_MB_2U_LIB.S9S_MB_2U(SCH_1):NC_CPU1_DDR01_VIEWDIG0
    U1 AU58 RSVD10 SOCKET4677_AZIF0045P001C01CS-SA    I16 @S9S_MB_2U_LIB.S9S_MB_2U(SCH_1):PAGE47

NC_CPU1_DDR01_VIEWDIG1 @S9S_MB_2U_LIB.S9S_MB_2U(SCH_1):NC_CPU1_DDR01_VIEWDIG1
    U1 AU56  RSVD9 SOCKET4677_AZIF0045P001C01CS-SA    I16 @S9S_MB_2U_LIB.S9S_MB_2U(SCH_1):PAGE47

NC_CPU1_DDR23_VIEWDIG0 @S9S_MB_2U_LIB.S9S_MB_2U(SCH_1):NC_CPU1_DDR23_VIEWDIG0
    U1 AV32 RSVD16 SOCKET4677_AZIF0045P001C01CS-SA    I16 @S9S_MB_2U_LIB.S9S_MB_2U(SCH_1):PAGE47

NC_CPU1_DDR23_VIEWDIG1 @S9S_MB_2U_LIB.S9S_MB_2U(SCH_1):NC_CPU1_DDR23_VIEWDIG1
    U1 AU33  RSVD7 SOCKET4677_AZIF0045P001C01CS-SA    I16 @S9S_MB_2U_LIB.S9S_MB_2U(SCH_1):PAGE47

NC_CPU1_DDR45_VIEWDIG0 @S9S_MB_2U_LIB.S9S_MB_2U(SCH_1):NC_CPU1_DDR45_VIEWDIG0
    U1 CY24 RSVD151 SOCKET4677_AZIF0045P001C01CS-SA    I16 @S9S_MB_2U_LIB.S9S_MB_2U(SCH_1):PAGE47

NC_CPU1_DDR45_VIEWDIG1 @S9S_MB_2U_LIB.S9S_MB_2U(SCH_1):NC_CPU1_DDR45_VIEWDIG1
    U1 CY38 RSVD152 SOCKET4677_AZIF0045P001C01CS-SA    I16 @S9S_MB_2U_LIB.S9S_MB_2U(SCH_1):PAGE47

NC_CPU1_DDR67_VIEWDIG0 @S9S_MB_2U_LIB.S9S_MB_2U(SCH_1):NC_CPU1_DDR67_VIEWDIG0
    U1 DA45 RSVD158 SOCKET4677_AZIF0045P001C01CS-SA    I16 @S9S_MB_2U_LIB.S9S_MB_2U(SCH_1):PAGE47

NC_CPU1_DDR67_VIEWDIG1 @S9S_MB_2U_LIB.S9S_MB_2U(SCH_1):NC_CPU1_DDR67_VIEWDIG1
    U1 CY49 RSVD153 SOCKET4677_AZIF0045P001C01CS-SA    I16 @S9S_MB_2U_LIB.S9S_MB_2U(SCH_1):PAGE47

NC_CPU1_DMI_APROBE<0> @S9S_MB_2U_LIB.S9S_MB_2U(SCH_1):NC_CPU1_DMI_APROBE(0)
    U1 CA21 RSVD77 SOCKET4677_AZIF0045P001C01CS-SA    I23 @S9S_MB_2U_LIB.S9S_MB_2U(SCH_1):PAGE50

NC_CPU1_DMI_APROBE<1> @S9S_MB_2U_LIB.S9S_MB_2U(SCH_1):NC_CPU1_DMI_APROBE(1)
    U1 BW21 RSVD74 SOCKET4677_AZIF0045P001C01CS-SA    I23 @S9S_MB_2U_LIB.S9S_MB_2U(SCH_1):PAGE50

NC_CPU1_HBM0_VIEWDIG0 @S9S_MB_2U_LIB.S9S_MB_2U(SCH_1):NC_CPU1_HBM0_VIEWDIG0
    U1  U17 RSVD164 SOCKET4677_AZIF0045P001C01CS-SA     I1 @S9S_MB_2U_LIB.S9S_MB_2U(SCH_1):PAGE48

NC_CPU1_HBM0_VIEWDIG1 @S9S_MB_2U_LIB.S9S_MB_2U(SCH_1):NC_CPU1_HBM0_VIEWDIG1
    U1 EG17 RSVD160 SOCKET4677_AZIF0045P001C01CS-SA     I1 @S9S_MB_2U_LIB.S9S_MB_2U(SCH_1):PAGE48

NC_CPU1_HBM1_VIEWDIG0 @S9S_MB_2U_LIB.S9S_MB_2U(SCH_1):NC_CPU1_HBM1_VIEWDIG0
    U1  W17 RSVD165 SOCKET4677_AZIF0045P001C01CS-SA     I1 @S9S_MB_2U_LIB.S9S_MB_2U(SCH_1):PAGE48

NC_CPU1_HBM1_VIEWDIG1 @S9S_MB_2U_LIB.S9S_MB_2U(SCH_1):NC_CPU1_HBM1_VIEWDIG1
    U1 CW41 RSVD147 SOCKET4677_AZIF0045P001C01CS-SA     I1 @S9S_MB_2U_LIB.S9S_MB_2U(SCH_1):PAGE48

NC_CPU1_HBM2_VIEWDIG0 @S9S_MB_2U_LIB.S9S_MB_2U(SCH_1):NC_CPU1_HBM2_VIEWDIG0
    U1 AC78  RSVD0 SOCKET4677_AZIF0045P001C01CS-SA     I1 @S9S_MB_2U_LIB.S9S_MB_2U(SCH_1):PAGE48

NC_CPU1_HBM2_VIEWDIG1 @S9S_MB_2U_LIB.S9S_MB_2U(SCH_1):NC_CPU1_HBM2_VIEWDIG1
    U1 AD77  RSVD1 SOCKET4677_AZIF0045P001C01CS-SA     I1 @S9S_MB_2U_LIB.S9S_MB_2U(SCH_1):PAGE48

NC_CPU1_HBM3_VIEWDIG0 @S9S_MB_2U_LIB.S9S_MB_2U(SCH_1):NC_CPU1_HBM3_VIEWDIG0
    U1 BG78 RSVD54 SOCKET4677_AZIF0045P001C01CS-SA     I1 @S9S_MB_2U_LIB.S9S_MB_2U(SCH_1):PAGE48

NC_CPU1_HBM3_VIEWDIG1 @S9S_MB_2U_LIB.S9S_MB_2U(SCH_1):NC_CPU1_HBM3_VIEWDIG1
    U1 BL60 RSVD63 SOCKET4677_AZIF0045P001C01CS-SA     I1 @S9S_MB_2U_LIB.S9S_MB_2U(SCH_1):PAGE48

NC_CPU1_LGSSPARE0 @S9S_MB_2U_LIB.S9S_MB_2U(SCH_1):NC_CPU1_LGSSPARE0
    U1 CR60 RSVD134 SOCKET4677_AZIF0045P001C01CS-SA    I16 @S9S_MB_2U_LIB.S9S_MB_2U(SCH_1):PAGE47

NC_CPU1_LGSSPARE1 @S9S_MB_2U_LIB.S9S_MB_2U(SCH_1):NC_CPU1_LGSSPARE1
    U1 CN60 RSVD125 SOCKET4677_AZIF0045P001C01CS-SA    I16 @S9S_MB_2U_LIB.S9S_MB_2U(SCH_1):PAGE47

NC_CPU1_LGSSPARE2 @S9S_MB_2U_LIB.S9S_MB_2U(SCH_1):NC_CPU1_LGSSPARE2
    U1 CU62 RSVD139 SOCKET4677_AZIF0045P001C01CS-SA    I16 @S9S_MB_2U_LIB.S9S_MB_2U(SCH_1):PAGE47

NC_CPU1_LGSSPARE3 @S9S_MB_2U_LIB.S9S_MB_2U(SCH_1):NC_CPU1_LGSSPARE3
    U1 CE62 RSVD90 SOCKET4677_AZIF0045P001C01CS-SA    I16 @S9S_MB_2U_LIB.S9S_MB_2U(SCH_1):PAGE47

NC_CPU1_LGSSPARE4 @S9S_MB_2U_LIB.S9S_MB_2U(SCH_1):NC_CPU1_LGSSPARE4
    U1 CC64 RSVD81 SOCKET4677_AZIF0045P001C01CS-SA    I16 @S9S_MB_2U_LIB.S9S_MB_2U(SCH_1):PAGE47

NC_CPU1_LGSSPARE5 @S9S_MB_2U_LIB.S9S_MB_2U(SCH_1):NC_CPU1_LGSSPARE5
    U1 CP61 RSVD129 SOCKET4677_AZIF0045P001C01CS-SA    I16 @S9S_MB_2U_LIB.S9S_MB_2U(SCH_1):PAGE47

NC_CPU1_MDFI_DIE00_EW0 @S9S_MB_2U_LIB.S9S_MB_2U(SCH_1):NC_CPU1_MDFI_DIE00_EW0
    U1 BP22 RSVD67 SOCKET4677_AZIF0045P001C01CS-SA     I1 @S9S_MB_2U_LIB.S9S_MB_2U(SCH_1):PAGE48

NC_CPU1_MDFI_DIE00_EW1 @S9S_MB_2U_LIB.S9S_MB_2U(SCH_1):NC_CPU1_MDFI_DIE00_EW1
    U1 BR21 RSVD71 SOCKET4677_AZIF0045P001C01CS-SA     I1 @S9S_MB_2U_LIB.S9S_MB_2U(SCH_1):PAGE48

NC_CPU1_MDFI_DIE00_NS0 @S9S_MB_2U_LIB.S9S_MB_2U(SCH_1):NC_CPU1_MDFI_DIE00_NS0
    U1 BK22 RSVD60 SOCKET4677_AZIF0045P001C01CS-SA     I1 @S9S_MB_2U_LIB.S9S_MB_2U(SCH_1):PAGE48

NC_CPU1_MDFI_DIE00_NS1 @S9S_MB_2U_LIB.S9S_MB_2U(SCH_1):NC_CPU1_MDFI_DIE00_NS1
    U1 BJ21 RSVD57 SOCKET4677_AZIF0045P001C01CS-SA     I1 @S9S_MB_2U_LIB.S9S_MB_2U(SCH_1):PAGE48

NC_CPU1_MDFI_DIE01_EW0 @S9S_MB_2U_LIB.S9S_MB_2U(SCH_1):NC_CPU1_MDFI_DIE01_EW0
    U1 AV65 RSVD21 SOCKET4677_AZIF0045P001C01CS-SA     I1 @S9S_MB_2U_LIB.S9S_MB_2U(SCH_1):PAGE48

NC_CPU1_MDFI_DIE01_EW1 @S9S_MB_2U_LIB.S9S_MB_2U(SCH_1):NC_CPU1_MDFI_DIE01_EW1
    U1 CC66 RSVD82 SOCKET4677_AZIF0045P001C01CS-SA     I1 @S9S_MB_2U_LIB.S9S_MB_2U(SCH_1):PAGE48

NC_CPU1_MDFI_DIE01_NS0 @S9S_MB_2U_LIB.S9S_MB_2U(SCH_1):NC_CPU1_MDFI_DIE01_NS0
    U1 BF71 RSVD51 SOCKET4677_AZIF0045P001C01CS-SA     I1 @S9S_MB_2U_LIB.S9S_MB_2U(SCH_1):PAGE48

NC_CPU1_MDFI_DIE01_NS1 @S9S_MB_2U_LIB.S9S_MB_2U(SCH_1):NC_CPU1_MDFI_DIE01_NS1
    U1 BD71 RSVD43 SOCKET4677_AZIF0045P001C01CS-SA     I1 @S9S_MB_2U_LIB.S9S_MB_2U(SCH_1):PAGE48

NC_CPU1_MDFI_DIE10_EW0 @S9S_MB_2U_LIB.S9S_MB_2U(SCH_1):NC_CPU1_MDFI_DIE10_EW0
    U1 CD26 RSVD84 SOCKET4677_AZIF0045P001C01CS-SA     I1 @S9S_MB_2U_LIB.S9S_MB_2U(SCH_1):PAGE48

NC_CPU1_MDFI_DIE10_EW1 @S9S_MB_2U_LIB.S9S_MB_2U(SCH_1):NC_CPU1_MDFI_DIE10_EW1
    U1 CD30 RSVD85 SOCKET4677_AZIF0045P001C01CS-SA     I1 @S9S_MB_2U_LIB.S9S_MB_2U(SCH_1):PAGE48

NC_CPU1_MDFI_DIE10_NS0 @S9S_MB_2U_LIB.S9S_MB_2U(SCH_1):NC_CPU1_MDFI_DIE10_NS0
    U1 CF22 RSVD92 SOCKET4677_AZIF0045P001C01CS-SA     I1 @S9S_MB_2U_LIB.S9S_MB_2U(SCH_1):PAGE48

NC_CPU1_MDFI_DIE10_NS1 @S9S_MB_2U_LIB.S9S_MB_2U(SCH_1):NC_CPU1_MDFI_DIE10_NS1
    U1 CD22 RSVD83 SOCKET4677_AZIF0045P001C01CS-SA     I1 @S9S_MB_2U_LIB.S9S_MB_2U(SCH_1):PAGE48

NC_CPU1_MDFI_DIE11_EW0 @S9S_MB_2U_LIB.S9S_MB_2U(SCH_1):NC_CPU1_MDFI_DIE11_EW0
    U1 CJ70 RSVD107 SOCKET4677_AZIF0045P001C01CS-SA     I1 @S9S_MB_2U_LIB.S9S_MB_2U(SCH_1):PAGE48

NC_CPU1_MDFI_DIE11_EW1 @S9S_MB_2U_LIB.S9S_MB_2U(SCH_1):NC_CPU1_MDFI_DIE11_EW1
    U1 CH69 RSVD99 SOCKET4677_AZIF0045P001C01CS-SA     I1 @S9S_MB_2U_LIB.S9S_MB_2U(SCH_1):PAGE48

NC_CPU1_MDFI_DIE11_NS0 @S9S_MB_2U_LIB.S9S_MB_2U(SCH_1):NC_CPU1_MDFI_DIE11_NS0
    U1 CJ68 RSVD106 SOCKET4677_AZIF0045P001C01CS-SA     I1 @S9S_MB_2U_LIB.S9S_MB_2U(SCH_1):PAGE48

NC_CPU1_MDFI_DIE11_NS1 @S9S_MB_2U_LIB.S9S_MB_2U(SCH_1):NC_CPU1_MDFI_DIE11_NS1
    U1 CK67 RSVD112 SOCKET4677_AZIF0045P001C01CS-SA     I1 @S9S_MB_2U_LIB.S9S_MB_2U(SCH_1):PAGE48

NC_CPU1_PE0_APROBE<0> @S9S_MB_2U_LIB.S9S_MB_2U(SCH_1):NC_CPU1_PE0_APROBE(0)
    U1 BN21 RSVD66 SOCKET4677_AZIF0045P001C01CS-SA    I23 @S9S_MB_2U_LIB.S9S_MB_2U(SCH_1):PAGE50

NC_CPU1_PE0_APROBE<1> @S9S_MB_2U_LIB.S9S_MB_2U(SCH_1):NC_CPU1_PE0_APROBE(1)
    U1 BL21 RSVD62 SOCKET4677_AZIF0045P001C01CS-SA    I23 @S9S_MB_2U_LIB.S9S_MB_2U(SCH_1):PAGE50

NC_CPU1_PE1_APROBE<0> @S9S_MB_2U_LIB.S9S_MB_2U(SCH_1):NC_CPU1_PE1_APROBE(0)
    U1 CE21 RSVD89 SOCKET4677_AZIF0045P001C01CS-SA    I23 @S9S_MB_2U_LIB.S9S_MB_2U(SCH_1):PAGE50

NC_CPU1_PE1_APROBE<1> @S9S_MB_2U_LIB.S9S_MB_2U(SCH_1):NC_CPU1_PE1_APROBE(1)
    U1 CC21 RSVD79 SOCKET4677_AZIF0045P001C01CS-SA    I23 @S9S_MB_2U_LIB.S9S_MB_2U(SCH_1):PAGE50

NC_CPU1_PE2_APROBE<0> @S9S_MB_2U_LIB.S9S_MB_2U(SCH_1):NC_CPU1_PE2_APROBE(0)
    U1 CC23 RSVD80 SOCKET4677_AZIF0045P001C01CS-SA    I23 @S9S_MB_2U_LIB.S9S_MB_2U(SCH_1):PAGE50

NC_CPU1_PE2_APROBE<1> @S9S_MB_2U_LIB.S9S_MB_2U(SCH_1):NC_CPU1_PE2_APROBE(1)
    U1 BW23 RSVD75 SOCKET4677_AZIF0045P001C01CS-SA    I23 @S9S_MB_2U_LIB.S9S_MB_2U(SCH_1):PAGE50

NC_CPU1_PE3_APROBE<0> @S9S_MB_2U_LIB.S9S_MB_2U(SCH_1):NC_CPU1_PE3_APROBE(0)
    U1 CL68 RSVD118 SOCKET4677_AZIF0045P001C01CS-SA    I23 @S9S_MB_2U_LIB.S9S_MB_2U(SCH_1):PAGE50

NC_CPU1_PE3_APROBE<1> @S9S_MB_2U_LIB.S9S_MB_2U(SCH_1):NC_CPU1_PE3_APROBE(1)
    U1 CM69 RSVD122 SOCKET4677_AZIF0045P001C01CS-SA    I23 @S9S_MB_2U_LIB.S9S_MB_2U(SCH_1):PAGE50

NC_CPU1_PE4_APROBE<0> @S9S_MB_2U_LIB.S9S_MB_2U(SCH_1):NC_CPU1_PE4_APROBE(0)
    U1 AV67 RSVD22 SOCKET4677_AZIF0045P001C01CS-SA    I23 @S9S_MB_2U_LIB.S9S_MB_2U(SCH_1):PAGE50

NC_CPU1_PE4_APROBE<1> @S9S_MB_2U_LIB.S9S_MB_2U(SCH_1):NC_CPU1_PE4_APROBE(1)
    U1 AU66 RSVD13 SOCKET4677_AZIF0045P001C01CS-SA    I23 @S9S_MB_2U_LIB.S9S_MB_2U(SCH_1):PAGE50

NC_CPU1_SOC_SPARE0 @S9S_MB_2U_LIB.S9S_MB_2U(SCH_1):NC_CPU1_SOC_SPARE0
    U1 AY24 RSVD26 SOCKET4677_AZIF0045P001C01CS-SA     I1 @S9S_MB_2U_LIB.S9S_MB_2U(SCH_1):PAGE48

NC_CPU1_SOC_SPARE1 @S9S_MB_2U_LIB.S9S_MB_2U(SCH_1):NC_CPU1_SOC_SPARE1
    U1 BM65 RSVD65 SOCKET4677_AZIF0045P001C01CS-SA     I1 @S9S_MB_2U_LIB.S9S_MB_2U(SCH_1):PAGE48

NC_CPU1_SOC_SPARE4 @S9S_MB_2U_LIB.S9S_MB_2U(SCH_1):NC_CPU1_SOC_SPARE4
    U1 BA25 RSVD31 SOCKET4677_AZIF0045P001C01CS-SA     I1 @S9S_MB_2U_LIB.S9S_MB_2U(SCH_1):PAGE48

NC_CPU1_SOC_SPARE5 @S9S_MB_2U_LIB.S9S_MB_2U(SCH_1):NC_CPU1_SOC_SPARE5
    U1 BP65 RSVD68 SOCKET4677_AZIF0045P001C01CS-SA     I1 @S9S_MB_2U_LIB.S9S_MB_2U(SCH_1):PAGE48

NC_CPU1_THERMADA @S9S_MB_2U_LIB.S9S_MB_2U(SCH_1):NC_CPU1_THERMADA
    U1 AV40 RSVD18 SOCKET4677_AZIF0045P001C01CS-SA    I16 @S9S_MB_2U_LIB.S9S_MB_2U(SCH_1):PAGE47

NC_CPU1_THERMADC @S9S_MB_2U_LIB.S9S_MB_2U(SCH_1):NC_CPU1_THERMADC
    U1 AV38 RSVD17 SOCKET4677_AZIF0045P001C01CS-SA    I16 @S9S_MB_2U_LIB.S9S_MB_2U(SCH_1):PAGE47

NC_CPU1_UPI0_APROBE<0> @S9S_MB_2U_LIB.S9S_MB_2U(SCH_1):NC_CPU1_UPI0_APROBE(0)
    U1 AN17  RSVD2 SOCKET4677_AZIF0045P001C01CS-SA    I23 @S9S_MB_2U_LIB.S9S_MB_2U(SCH_1):PAGE50

NC_CPU1_UPI0_APROBE<1> @S9S_MB_2U_LIB.S9S_MB_2U(SCH_1):NC_CPU1_UPI0_APROBE(1)
    U1 AR17  RSVD3 SOCKET4677_AZIF0045P001C01CS-SA    I23 @S9S_MB_2U_LIB.S9S_MB_2U(SCH_1):PAGE50

NC_CPU1_UPI1_APROBE<0> @S9S_MB_2U_LIB.S9S_MB_2U(SCH_1):NC_CPU1_UPI1_APROBE(0)
    U1 BV22 RSVD73 SOCKET4677_AZIF0045P001C01CS-SA    I23 @S9S_MB_2U_LIB.S9S_MB_2U(SCH_1):PAGE50

NC_CPU1_UPI1_APROBE<1> @S9S_MB_2U_LIB.S9S_MB_2U(SCH_1):NC_CPU1_UPI1_APROBE(1)
    U1 CA23 RSVD78 SOCKET4677_AZIF0045P001C01CS-SA    I23 @S9S_MB_2U_LIB.S9S_MB_2U(SCH_1):PAGE50

NC_CPU1_UPI2_APROBE<0> @S9S_MB_2U_LIB.S9S_MB_2U(SCH_1):NC_CPU1_UPI2_APROBE(0)
    U1 AU68 RSVD14 SOCKET4677_AZIF0045P001C01CS-SA    I23 @S9S_MB_2U_LIB.S9S_MB_2U(SCH_1):PAGE50

NC_CPU1_UPI2_APROBE<1> @S9S_MB_2U_LIB.S9S_MB_2U(SCH_1):NC_CPU1_UPI2_APROBE(1)
    U1 AT67  RSVD5 SOCKET4677_AZIF0045P001C01CS-SA    I23 @S9S_MB_2U_LIB.S9S_MB_2U(SCH_1):PAGE50

NC_CPU1_UPI3_APROBE<0> @S9S_MB_2U_LIB.S9S_MB_2U(SCH_1):NC_CPU1_UPI3_APROBE(0)
    U1 CP69 RSVD130 SOCKET4677_AZIF0045P001C01CS-SA    I23 @S9S_MB_2U_LIB.S9S_MB_2U(SCH_1):PAGE50

NC_CPU1_UPI3_APROBE<1> @S9S_MB_2U_LIB.S9S_MB_2U(SCH_1):NC_CPU1_UPI3_APROBE(1)
    U1 CR68 RSVD135 SOCKET4677_AZIF0045P001C01CS-SA    I23 @S9S_MB_2U_LIB.S9S_MB_2U(SCH_1):PAGE50

NC_CPU1_VIEWPIN_GNR0 @S9S_MB_2U_LIB.S9S_MB_2U(SCH_1):NC_CPU1_VIEWPIN_GNR0
    U1 CT26 RSVD138 SOCKET4677_AZIF0045P001C01CS-SA     I1 @S9S_MB_2U_LIB.S9S_MB_2U(SCH_1):PAGE48

NC_CPU1_VIEWPIN_GNR1 @S9S_MB_2U_LIB.S9S_MB_2U(SCH_1):NC_CPU1_VIEWPIN_GNR1
    U1 CW58 RSVD149 SOCKET4677_AZIF0045P001C01CS-SA     I1 @S9S_MB_2U_LIB.S9S_MB_2U(SCH_1):PAGE48

NC_CPU1_VIEWPIN_GNR2 @S9S_MB_2U_LIB.S9S_MB_2U(SCH_1):NC_CPU1_VIEWPIN_GNR2
    U1 CR25 RSVD133 SOCKET4677_AZIF0045P001C01CS-SA     I1 @S9S_MB_2U_LIB.S9S_MB_2U(SCH_1):PAGE48

NC_CPU1_VIEWPIN_GNR3 @S9S_MB_2U_LIB.S9S_MB_2U(SCH_1):NC_CPU1_VIEWPIN_GNR3
    U1 CY57 RSVD154 SOCKET4677_AZIF0045P001C01CS-SA     I1 @S9S_MB_2U_LIB.S9S_MB_2U(SCH_1):PAGE48

NC_DBP_P18 @S9S_MB_2U_LIB.S9S_MB_2U(SCH_1):NC_DBP_P18
   J42   18     18 SCONN60_ASP21410801-SCONN60_ASA    I44 @S9S_MB_2U_LIB.S9S_MB_2U(SCH_1):PAGE133

NC_DBP_P20 @S9S_MB_2U_LIB.S9S_MB_2U(SCH_1):NC_DBP_P20
   J42   20     20 SCONN60_ASP21410801-SCONN60_ASA    I44 @S9S_MB_2U_LIB.S9S_MB_2U(SCH_1):PAGE133

NC_DBP_P22 @S9S_MB_2U_LIB.S9S_MB_2U(SCH_1):NC_DBP_P22
   J42   22     22 SCONN60_ASP21410801-SCONN60_ASA    I44 @S9S_MB_2U_LIB.S9S_MB_2U(SCH_1):PAGE133

NC_DBP_P24 @S9S_MB_2U_LIB.S9S_MB_2U(SCH_1):NC_DBP_P24
   J42   24     24 SCONN60_ASP21410801-SCONN60_ASA    I44 @S9S_MB_2U_LIB.S9S_MB_2U(SCH_1):PAGE133

NC_DBP_P26 @S9S_MB_2U_LIB.S9S_MB_2U(SCH_1):NC_DBP_P26
   J42   26     26 SCONN60_ASP21410801-SCONN60_ASA    I44 @S9S_MB_2U_LIB.S9S_MB_2U(SCH_1):PAGE133

NC_DBP_P28 @S9S_MB_2U_LIB.S9S_MB_2U(SCH_1):NC_DBP_P28
   J42   28     28 SCONN60_ASP21410801-SCONN60_ASA    I44 @S9S_MB_2U_LIB.S9S_MB_2U(SCH_1):PAGE133

NC_DBP_P30 @S9S_MB_2U_LIB.S9S_MB_2U(SCH_1):NC_DBP_P30
   J42   30     30 SCONN60_ASP21410801-SCONN60_ASA    I44 @S9S_MB_2U_LIB.S9S_MB_2U(SCH_1):PAGE133

NC_DBP_P32 @S9S_MB_2U_LIB.S9S_MB_2U(SCH_1):NC_DBP_P32
   J42   32     32 SCONN60_ASP21410801-SCONN60_ASA    I44 @S9S_MB_2U_LIB.S9S_MB_2U(SCH_1):PAGE133

NC_DBP_P34 @S9S_MB_2U_LIB.S9S_MB_2U(SCH_1):NC_DBP_P34
   J42   34     34 SCONN60_ASP21410801-SCONN60_ASA    I44 @S9S_MB_2U_LIB.S9S_MB_2U(SCH_1):PAGE133

NC_DBP_P44 @S9S_MB_2U_LIB.S9S_MB_2U(SCH_1):NC_DBP_P44
   J42   44     44 SCONN60_ASP21410801-SCONN60_ASA    I44 @S9S_MB_2U_LIB.S9S_MB_2U(SCH_1):PAGE133

NC_DBP_P46 @S9S_MB_2U_LIB.S9S_MB_2U(SCH_1):NC_DBP_P46
   J42   46     46 SCONN60_ASP21410801-SCONN60_ASA    I44 @S9S_MB_2U_LIB.S9S_MB_2U(SCH_1):PAGE133

NC_DBP_P54 @S9S_MB_2U_LIB.S9S_MB_2U(SCH_1):NC_DBP_P54
   J42   54     54 SCONN60_ASP21410801-SCONN60_ASA    I44 @S9S_MB_2U_LIB.S9S_MB_2U(SCH_1):PAGE133

NC_DBP_P56 @S9S_MB_2U_LIB.S9S_MB_2U(SCH_1):NC_DBP_P56
   J42   56     56 SCONN60_ASP21410801-SCONN60_ASA    I44 @S9S_MB_2U_LIB.S9S_MB_2U(SCH_1):PAGE133

NC_ESPI_IBL_CPU1_ALERT0_N @S9S_MB_2U_LIB.S9S_MB_2U(SCH_1):NC_ESPI_IBL_CPU1_ALERT0_N
    U1 BE62 RSVD48 SOCKET4677_AZIF0045P001C01CS-SA     I5 @S9S_MB_2U_LIB.S9S_MB_2U(SCH_1):PAGE46

NC_ESPI_IBL_CPU1_ALERT1_N @S9S_MB_2U_LIB.S9S_MB_2U(SCH_1):NC_ESPI_IBL_CPU1_ALERT1_N
    U1 BD63 RSVD41 SOCKET4677_AZIF0045P001C01CS-SA     I5 @S9S_MB_2U_LIB.S9S_MB_2U(SCH_1):PAGE46

NC_ESPI_IBL_CPU1_CLK @S9S_MB_2U_LIB.S9S_MB_2U(SCH_1):NC_ESPI_IBL_CPU1_CLK
    U1 BG62 RSVD52 SOCKET4677_AZIF0045P001C01CS-SA     I5 @S9S_MB_2U_LIB.S9S_MB_2U(SCH_1):PAGE46

NC_ESPI_IBL_CPU1_CS0_N @S9S_MB_2U_LIB.S9S_MB_2U(SCH_1):NC_ESPI_IBL_CPU1_CS0_N
    U1 BF65 RSVD50 SOCKET4677_AZIF0045P001C01CS-SA     I5 @S9S_MB_2U_LIB.S9S_MB_2U(SCH_1):PAGE46

NC_ESPI_IBL_CPU1_CS1_N @S9S_MB_2U_LIB.S9S_MB_2U(SCH_1):NC_ESPI_IBL_CPU1_CS1_N
    U1 BH65 RSVD56 SOCKET4677_AZIF0045P001C01CS-SA     I5 @S9S_MB_2U_LIB.S9S_MB_2U(SCH_1):PAGE46

NC_ESPI_IBL_CPU1_IO0 @S9S_MB_2U_LIB.S9S_MB_2U(SCH_1):NC_ESPI_IBL_CPU1_IO0
    U1 BK63 RSVD61 SOCKET4677_AZIF0045P001C01CS-SA     I5 @S9S_MB_2U_LIB.S9S_MB_2U(SCH_1):PAGE46

NC_ESPI_IBL_CPU1_IO1 @S9S_MB_2U_LIB.S9S_MB_2U(SCH_1):NC_ESPI_IBL_CPU1_IO1
    U1 BJ64 RSVD58 SOCKET4677_AZIF0045P001C01CS-SA     I5 @S9S_MB_2U_LIB.S9S_MB_2U(SCH_1):PAGE46

NC_ESPI_IBL_CPU1_IO2 @S9S_MB_2U_LIB.S9S_MB_2U(SCH_1):NC_ESPI_IBL_CPU1_IO2
    U1 AU64 RSVD12 SOCKET4677_AZIF0045P001C01CS-SA     I5 @S9S_MB_2U_LIB.S9S_MB_2U(SCH_1):PAGE46

NC_ESPI_IBL_CPU1_IO3 @S9S_MB_2U_LIB.S9S_MB_2U(SCH_1):NC_ESPI_IBL_CPU1_IO3
    U1 BM63 RSVD64 SOCKET4677_AZIF0045P001C01CS-SA     I5 @S9S_MB_2U_LIB.S9S_MB_2U(SCH_1):PAGE46

NC_ESPI_IBL_CPU1_OE_N @S9S_MB_2U_LIB.S9S_MB_2U(SCH_1):NC_ESPI_IBL_CPU1_OE_N
    U1 BH63 RSVD55 SOCKET4677_AZIF0045P001C01CS-SA     I5 @S9S_MB_2U_LIB.S9S_MB_2U(SCH_1):PAGE46

NC_ESPI_IBL_CPU1_RESET_N @S9S_MB_2U_LIB.S9S_MB_2U(SCH_1):NC_ESPI_IBL_CPU1_RESET_N
    U1 BG64 RSVD53 SOCKET4677_AZIF0045P001C01CS-SA     I5 @S9S_MB_2U_LIB.S9S_MB_2U(SCH_1):PAGE46

NC_ESPI_PLD_R_EN_BUF @S9S_MB_2U_LIB.S9S_MB_2U(SCH_1):NC_ESPI_PLD_R_EN_BUF
  U154    1    NC1 74LVC1G07SE7-74LVC1G07SE-7,SMLA    I95 @S9S_MB_2U_LIB.S9S_MB_2U(SCH_1):PAGE190

NC_FM_IBL_ADR_ACK_CPU1 @S9S_MB_2U_LIB.S9S_MB_2U(SCH_1):NC_FM_IBL_ADR_ACK_CPU1
    U1 CN23 RSVD124 SOCKET4677_AZIF0045P001C01CS-SA     I5 @S9S_MB_2U_LIB.S9S_MB_2U(SCH_1):PAGE46

NC_FM_IBL_ADR_COMPLETE_CPU1_R @S9S_MB_2U_LIB.S9S_MB_2U(SCH_1):NC_FM_IBL_ADR_COMPLETE_CPU1_R
    U1 CP24 RSVD128 SOCKET4677_AZIF0045P001C01CS-SA     I5 @S9S_MB_2U_LIB.S9S_MB_2U(SCH_1):PAGE46

NC_FM_IBL_ADR_TRIGGER_CPU1_R @S9S_MB_2U_LIB.S9S_MB_2U(SCH_1):NC_FM_IBL_ADR_TRIGGER_CPU1_R
    U1 CT24 RSVD137 SOCKET4677_AZIF0045P001C01CS-SA     I5 @S9S_MB_2U_LIB.S9S_MB_2U(SCH_1):PAGE46

NC_FPGA_PB22B @S9S_MB_2U_LIB.S9S_MB_2U(SCH_1):NC_FPGA_PB22B
  U249 AB10 PB22B||PCLKC2_0 LCMXO3LF9400C5BG484C-LCMXO3LF-A     I1 @S9S_MB_2U_LIB.S9S_MB_2U(SCH_1):PAGE312

NC_FPGA_PB32D @S9S_MB_2U_LIB.S9S_MB_2U(SCH_1):NC_FPGA_PB32D
  U249  V14  PB32D LCMXO3LF9400C5BG484C-LCMXO3LF-A     I1 @S9S_MB_2U_LIB.S9S_MB_2U(SCH_1):PAGE312

NC_FPGA_PB35B @S9S_MB_2U_LIB.S9S_MB_2U(SCH_1):NC_FPGA_PB35B
  U249 AA15  PB35B LCMXO3LF9400C5BG484C-LCMXO3LF-A     I1 @S9S_MB_2U_LIB.S9S_MB_2U(SCH_1):PAGE312

NC_FPGA_PB43D @S9S_MB_2U_LIB.S9S_MB_2U(SCH_1):NC_FPGA_PB43D
  U249  U16  PB43D LCMXO3LF9400C5BG484C-LCMXO3LF-A     I1 @S9S_MB_2U_LIB.S9S_MB_2U(SCH_1):PAGE312

NC_FPGA_PB46B @S9S_MB_2U_LIB.S9S_MB_2U(SCH_1):NC_FPGA_PB46B
  U249 AA21 PB46B||SI||SISPI LCMXO3LF9400C5BG484C-LCMXO3LF-A     I1 @S9S_MB_2U_LIB.S9S_MB_2U(SCH_1):PAGE312

NC_FPGA_PB7D @S9S_MB_2U_LIB.S9S_MB_2U(SCH_1):NC_FPGA_PB7D
  U249   W5   PB7D LCMXO3LF9400C5BG484C-LCMXO3LF-A     I1 @S9S_MB_2U_LIB.S9S_MB_2U(SCH_1):PAGE312

NC_FPGA_PR13A @S9S_MB_2U_LIB.S9S_MB_2U(SCH_1):NC_FPGA_PR13A
  U249  K19  PR13A LCMXO3LF9400C5BG484C-LCMXO3LF-A     I1 @S9S_MB_2U_LIB.S9S_MB_2U(SCH_1):PAGE313

NC_FPGA_PR14A @S9S_MB_2U_LIB.S9S_MB_2U(SCH_1):NC_FPGA_PR14A
  U249  L17  PR14A LCMXO3LF9400C5BG484C-LCMXO3LF-A     I1 @S9S_MB_2U_LIB.S9S_MB_2U(SCH_1):PAGE313

NC_FPGA_PR14B @S9S_MB_2U_LIB.S9S_MB_2U(SCH_1):NC_FPGA_PR14B
  U249  L16  PR14B LCMXO3LF9400C5BG484C-LCMXO3LF-A     I1 @S9S_MB_2U_LIB.S9S_MB_2U(SCH_1):PAGE313

NC_FPGA_PR16C @S9S_MB_2U_LIB.S9S_MB_2U(SCH_1):NC_FPGA_PR16C
  U249  L22  PR16C LCMXO3LF9400C5BG484C-LCMXO3LF-A     I1 @S9S_MB_2U_LIB.S9S_MB_2U(SCH_1):PAGE313

NC_FPGA_PR16D @S9S_MB_2U_LIB.S9S_MB_2U(SCH_1):NC_FPGA_PR16D
  U249  M17  PR16D LCMXO3LF9400C5BG484C-LCMXO3LF-A     I1 @S9S_MB_2U_LIB.S9S_MB_2U(SCH_1):PAGE313

NC_FPGA_PR30D @S9S_MB_2U_LIB.S9S_MB_2U(SCH_1):NC_FPGA_PR30D
  U249  Y20  PR30D LCMXO3LF9400C5BG484C-LCMXO3LF-A     I1 @S9S_MB_2U_LIB.S9S_MB_2U(SCH_1):PAGE313

NC_FPGA_PT41D @S9S_MB_2U_LIB.S9S_MB_2U(SCH_1):NC_FPGA_PT41D
  U249  D18  PT41D LCMXO3LF9400C5BG484C-LCMXO3LF-A   I188 @S9S_MB_2U_LIB.S9S_MB_2U(SCH_1):PAGE314

NC_FPGA_PT42D @S9S_MB_2U_LIB.S9S_MB_2U(SCH_1):NC_FPGA_PT42D
  U249  G15  PT42D LCMXO3LF9400C5BG484C-LCMXO3LF-A   I188 @S9S_MB_2U_LIB.S9S_MB_2U(SCH_1):PAGE314

NC_FPGA_PT43A @S9S_MB_2U_LIB.S9S_MB_2U(SCH_1):NC_FPGA_PT43A
  U249  A20 PT43A||R_GPLLT LCMXO3LF9400C5BG484C-LCMXO3LF-A   I188 @S9S_MB_2U_LIB.S9S_MB_2U(SCH_1):PAGE314

NC_FPGA_PT43B @S9S_MB_2U_LIB.S9S_MB_2U(SCH_1):NC_FPGA_PT43B
  U249  B21 PT43B||R_GPLLC LCMXO3LF9400C5BG484C-LCMXO3LF-A   I188 @S9S_MB_2U_LIB.S9S_MB_2U(SCH_1):PAGE314

NC_FPGA_PT43C @S9S_MB_2U_LIB.S9S_MB_2U(SCH_1):NC_FPGA_PT43C
  U249  C19  PT43C LCMXO3LF9400C5BG484C-LCMXO3LF-A   I188 @S9S_MB_2U_LIB.S9S_MB_2U(SCH_1):PAGE314

NC_FPGA_PT43D @S9S_MB_2U_LIB.S9S_MB_2U(SCH_1):NC_FPGA_PT43D
  U249  C20  PT43D LCMXO3LF9400C5BG484C-LCMXO3LF-A   I188 @S9S_MB_2U_LIB.S9S_MB_2U(SCH_1):PAGE314

NC_FPGA_PT44A @S9S_MB_2U_LIB.S9S_MB_2U(SCH_1):NC_FPGA_PT44A
  U249  A21 PT44A||R_GPLLT LCMXO3LF9400C5BG484C-LCMXO3LF-A   I188 @S9S_MB_2U_LIB.S9S_MB_2U(SCH_1):PAGE314

NC_FPGA_PT44B @S9S_MB_2U_LIB.S9S_MB_2U(SCH_1):NC_FPGA_PT44B
  U249  B22 PT44B||R_GPLLC LCMXO3LF9400C5BG484C-LCMXO3LF-A   I188 @S9S_MB_2U_LIB.S9S_MB_2U(SCH_1):PAGE314

NC_FPGA_PT44C @S9S_MB_2U_LIB.S9S_MB_2U(SCH_1):NC_FPGA_PT44C
  U249  F16 PT44C||INITN LCMXO3LF9400C5BG484C-LCMXO3LF-A    I70 @S9S_MB_2U_LIB.S9S_MB_2U(SCH_1):PAGE311

NC_FPGA_PT44D @S9S_MB_2U_LIB.S9S_MB_2U(SCH_1):NC_FPGA_PT44D
  U249  E17 PT44D||DONE LCMXO3LF9400C5BG484C-LCMXO3LF-A    I70 @S9S_MB_2U_LIB.S9S_MB_2U(SCH_1):PAGE311

NC_HICCUP @S9S_MB_2U_LIB.S9S_MB_2U(SCH_1):NC_HICCUP
   PU9   35    NC4 IR3889MTRPBF-IR3889MTRPBF,SMLFA    I95 @S9S_MB_2U_LIB.S9S_MB_2U(SCH_1):PAGE245

NC_HSC_TYPE_NC0 @S9S_MB_2U_LIB.S9S_MB_2U(SCH_1):NC_HSC_TYPE_NC0
  U331    6    NC0 INA230AIRGTR-INA230AIRGTR,SMLFA    I39 @S9S_MB_2U_LIB.S9S_MB_2U(SCH_1):PAGE240

NC_HSC_TYPE_NC1 @S9S_MB_2U_LIB.S9S_MB_2U(SCH_1):NC_HSC_TYPE_NC1
  U331    7    NC1 INA230AIRGTR-INA230AIRGTR,SMLFA    I39 @S9S_MB_2U_LIB.S9S_MB_2U(SCH_1):PAGE240

NC_HSC_TYPE_NC2 @S9S_MB_2U_LIB.S9S_MB_2U(SCH_1):NC_HSC_TYPE_NC2
  U331    8    NC2 INA230AIRGTR-INA230AIRGTR,SMLFA    I39 @S9S_MB_2U_LIB.S9S_MB_2U(SCH_1):PAGE240

NC_HSC_TYPE_NC3 @S9S_MB_2U_LIB.S9S_MB_2U(SCH_1):NC_HSC_TYPE_NC3
  U331   14    NC3 INA230AIRGTR-INA230AIRGTR,SMLFA    I39 @S9S_MB_2U_LIB.S9S_MB_2U(SCH_1):PAGE240

NC_HSC_TYPE_NC4 @S9S_MB_2U_LIB.S9S_MB_2U(SCH_1):NC_HSC_TYPE_NC4
  U331   15    NC4 INA230AIRGTR-INA230AIRGTR,SMLFA    I39 @S9S_MB_2U_LIB.S9S_MB_2U(SCH_1):PAGE240

NC_HSC_TYPE_NC5 @S9S_MB_2U_LIB.S9S_MB_2U(SCH_1):NC_HSC_TYPE_NC5
  U331   16    NC5 INA230AIRGTR-INA230AIRGTR,SMLFA    I39 @S9S_MB_2U_LIB.S9S_MB_2U(SCH_1):PAGE240

NC_HSC_TYPE_VINM @S9S_MB_2U_LIB.S9S_MB_2U(SCH_1):NC_HSC_TYPE_VINM
  U331   12    IN- INA230AIRGTR-INA230AIRGTR,SMLFA    I39 @S9S_MB_2U_LIB.S9S_MB_2U(SCH_1):PAGE240

NC_HSC_TYPE_VINP @S9S_MB_2U_LIB.S9S_MB_2U(SCH_1):NC_HSC_TYPE_VINP
  U331   13    IN+ INA230AIRGTR-INA230AIRGTR,SMLFA    I39 @S9S_MB_2U_LIB.S9S_MB_2U(SCH_1):PAGE240

NC_INA230_1_NC0 @S9S_MB_2U_LIB.S9S_MB_2U(SCH_1):NC_INA230_1_NC0
  U266    6    NC0 INA230AIRGTR-INA230AIRGTR,SMLFB    I30 @S9S_MB_2U_LIB.S9S_MB_2U(SCH_1):PAGE295

NC_INA230_1_NC1 @S9S_MB_2U_LIB.S9S_MB_2U(SCH_1):NC_INA230_1_NC1
  U266    7    NC1 INA230AIRGTR-INA230AIRGTR,SMLFB    I30 @S9S_MB_2U_LIB.S9S_MB_2U(SCH_1):PAGE295

NC_INA230_1_NC2 @S9S_MB_2U_LIB.S9S_MB_2U(SCH_1):NC_INA230_1_NC2
  U266    8    NC2 INA230AIRGTR-INA230AIRGTR,SMLFB    I30 @S9S_MB_2U_LIB.S9S_MB_2U(SCH_1):PAGE295

NC_INA230_1_NC3 @S9S_MB_2U_LIB.S9S_MB_2U(SCH_1):NC_INA230_1_NC3
  U266   14    NC3 INA230AIRGTR-INA230AIRGTR,SMLFB    I30 @S9S_MB_2U_LIB.S9S_MB_2U(SCH_1):PAGE295

NC_INA230_1_NC4 @S9S_MB_2U_LIB.S9S_MB_2U(SCH_1):NC_INA230_1_NC4
  U266   15    NC4 INA230AIRGTR-INA230AIRGTR,SMLFB    I30 @S9S_MB_2U_LIB.S9S_MB_2U(SCH_1):PAGE295

NC_INA230_1_NC5 @S9S_MB_2U_LIB.S9S_MB_2U(SCH_1):NC_INA230_1_NC5
  U266   16    NC5 INA230AIRGTR-INA230AIRGTR,SMLFB    I30 @S9S_MB_2U_LIB.S9S_MB_2U(SCH_1):PAGE295

NC_INA230_2_NC0 @S9S_MB_2U_LIB.S9S_MB_2U(SCH_1):NC_INA230_2_NC0
  U276    6    NC0 INA230AIRGTR-INA230AIRGTR,SMLFB   I129 @S9S_MB_2U_LIB.S9S_MB_2U(SCH_1):PAGE295

NC_INA230_2_NC1 @S9S_MB_2U_LIB.S9S_MB_2U(SCH_1):NC_INA230_2_NC1
  U276    7    NC1 INA230AIRGTR-INA230AIRGTR,SMLFB   I129 @S9S_MB_2U_LIB.S9S_MB_2U(SCH_1):PAGE295

NC_INA230_2_NC2 @S9S_MB_2U_LIB.S9S_MB_2U(SCH_1):NC_INA230_2_NC2
  U276    8    NC2 INA230AIRGTR-INA230AIRGTR,SMLFB   I129 @S9S_MB_2U_LIB.S9S_MB_2U(SCH_1):PAGE295

NC_INA230_2_NC3 @S9S_MB_2U_LIB.S9S_MB_2U(SCH_1):NC_INA230_2_NC3
  U276   14    NC3 INA230AIRGTR-INA230AIRGTR,SMLFB   I129 @S9S_MB_2U_LIB.S9S_MB_2U(SCH_1):PAGE295

NC_INA230_2_NC4 @S9S_MB_2U_LIB.S9S_MB_2U(SCH_1):NC_INA230_2_NC4
  U276   15    NC4 INA230AIRGTR-INA230AIRGTR,SMLFB   I129 @S9S_MB_2U_LIB.S9S_MB_2U(SCH_1):PAGE295

NC_INA230_2_NC5 @S9S_MB_2U_LIB.S9S_MB_2U(SCH_1):NC_INA230_2_NC5
  U276   16    NC5 INA230AIRGTR-INA230AIRGTR,SMLFB   I129 @S9S_MB_2U_LIB.S9S_MB_2U(SCH_1):PAGE295

NC_INA230_3_NC0 @S9S_MB_2U_LIB.S9S_MB_2U(SCH_1):NC_INA230_3_NC0
  U263    6    NC0 INA230AIRGTR-INA230AIRGTR,SMLFB    I94 @S9S_MB_2U_LIB.S9S_MB_2U(SCH_1):PAGE163

NC_INA230_3_NC1 @S9S_MB_2U_LIB.S9S_MB_2U(SCH_1):NC_INA230_3_NC1
  U263    7    NC1 INA230AIRGTR-INA230AIRGTR,SMLFB    I94 @S9S_MB_2U_LIB.S9S_MB_2U(SCH_1):PAGE163

NC_INA230_3_NC2 @S9S_MB_2U_LIB.S9S_MB_2U(SCH_1):NC_INA230_3_NC2
  U263    8    NC2 INA230AIRGTR-INA230AIRGTR,SMLFB    I94 @S9S_MB_2U_LIB.S9S_MB_2U(SCH_1):PAGE163

NC_INA230_3_NC3 @S9S_MB_2U_LIB.S9S_MB_2U(SCH_1):NC_INA230_3_NC3
  U263   14    NC3 INA230AIRGTR-INA230AIRGTR,SMLFB    I94 @S9S_MB_2U_LIB.S9S_MB_2U(SCH_1):PAGE163

NC_INA230_3_NC4 @S9S_MB_2U_LIB.S9S_MB_2U(SCH_1):NC_INA230_3_NC4
  U263   15    NC4 INA230AIRGTR-INA230AIRGTR,SMLFB    I94 @S9S_MB_2U_LIB.S9S_MB_2U(SCH_1):PAGE163

NC_INA230_3_NC5 @S9S_MB_2U_LIB.S9S_MB_2U(SCH_1):NC_INA230_3_NC5
  U263   16    NC5 INA230AIRGTR-INA230AIRGTR,SMLFB    I94 @S9S_MB_2U_LIB.S9S_MB_2U(SCH_1):PAGE163

NC_INA230_4_NC0 @S9S_MB_2U_LIB.S9S_MB_2U(SCH_1):NC_INA230_4_NC0
  U264    6    NC0 INA230AIRGTR-INA230AIRGTR,SMLFB    I46 @S9S_MB_2U_LIB.S9S_MB_2U(SCH_1):PAGE163

NC_INA230_4_NC1 @S9S_MB_2U_LIB.S9S_MB_2U(SCH_1):NC_INA230_4_NC1
  U264    7    NC1 INA230AIRGTR-INA230AIRGTR,SMLFB    I46 @S9S_MB_2U_LIB.S9S_MB_2U(SCH_1):PAGE163

NC_INA230_4_NC2 @S9S_MB_2U_LIB.S9S_MB_2U(SCH_1):NC_INA230_4_NC2
  U264    8    NC2 INA230AIRGTR-INA230AIRGTR,SMLFB    I46 @S9S_MB_2U_LIB.S9S_MB_2U(SCH_1):PAGE163

NC_INA230_4_NC3 @S9S_MB_2U_LIB.S9S_MB_2U(SCH_1):NC_INA230_4_NC3
  U264   14    NC3 INA230AIRGTR-INA230AIRGTR,SMLFB    I46 @S9S_MB_2U_LIB.S9S_MB_2U(SCH_1):PAGE163

NC_INA230_4_NC4 @S9S_MB_2U_LIB.S9S_MB_2U(SCH_1):NC_INA230_4_NC4
  U264   15    NC4 INA230AIRGTR-INA230AIRGTR,SMLFB    I46 @S9S_MB_2U_LIB.S9S_MB_2U(SCH_1):PAGE163

NC_INA230_4_NC5 @S9S_MB_2U_LIB.S9S_MB_2U(SCH_1):NC_INA230_4_NC5
  U264   16    NC5 INA230AIRGTR-INA230AIRGTR,SMLFB    I46 @S9S_MB_2U_LIB.S9S_MB_2U(SCH_1):PAGE163

NC_INA230_5_NC0 @S9S_MB_2U_LIB.S9S_MB_2U(SCH_1):NC_INA230_5_NC0
  U265    6    NC0 INA230AIRGTR-INA230AIRGTR,SMLFB    I69 @S9S_MB_2U_LIB.S9S_MB_2U(SCH_1):PAGE163

NC_INA230_5_NC1 @S9S_MB_2U_LIB.S9S_MB_2U(SCH_1):NC_INA230_5_NC1
  U265    7    NC1 INA230AIRGTR-INA230AIRGTR,SMLFB    I69 @S9S_MB_2U_LIB.S9S_MB_2U(SCH_1):PAGE163

NC_INA230_5_NC2 @S9S_MB_2U_LIB.S9S_MB_2U(SCH_1):NC_INA230_5_NC2
  U265    8    NC2 INA230AIRGTR-INA230AIRGTR,SMLFB    I69 @S9S_MB_2U_LIB.S9S_MB_2U(SCH_1):PAGE163

NC_INA230_5_NC3 @S9S_MB_2U_LIB.S9S_MB_2U(SCH_1):NC_INA230_5_NC3
  U265   14    NC3 INA230AIRGTR-INA230AIRGTR,SMLFB    I69 @S9S_MB_2U_LIB.S9S_MB_2U(SCH_1):PAGE163

NC_INA230_5_NC4 @S9S_MB_2U_LIB.S9S_MB_2U(SCH_1):NC_INA230_5_NC4
  U265   15    NC4 INA230AIRGTR-INA230AIRGTR,SMLFB    I69 @S9S_MB_2U_LIB.S9S_MB_2U(SCH_1):PAGE163

NC_INA230_5_NC5 @S9S_MB_2U_LIB.S9S_MB_2U(SCH_1):NC_INA230_5_NC5
  U265   16    NC5 INA230AIRGTR-INA230AIRGTR,SMLFB    I69 @S9S_MB_2U_LIB.S9S_MB_2U(SCH_1):PAGE163

NC_J106_A5 @S9S_MB_2U_LIB.S9S_MB_2U(SCH_1):NC_J106_A5
  J106   A5     A5 CONN112_10137002101LF-CONN112_A    I68 @S9S_MB_2U_LIB.S9S_MB_2U(SCH_1):PAGE144

NC_J107_A1 @S9S_MB_2U_LIB.S9S_MB_2U(SCH_1):NC_J107_A1
  J107   A1     A1 CONN112_10137002101LF-CONN112_A    I58 @S9S_MB_2U_LIB.S9S_MB_2U(SCH_1):PAGE317

NC_J107_A3 @S9S_MB_2U_LIB.S9S_MB_2U(SCH_1):NC_J107_A3
  J107   A3     A3 CONN112_10137002101LF-CONN112_A    I58 @S9S_MB_2U_LIB.S9S_MB_2U(SCH_1):PAGE317

NC_J107_A5 @S9S_MB_2U_LIB.S9S_MB_2U(SCH_1):NC_J107_A5
  J107   A5     A5 CONN112_10137002101LF-CONN112_A    I38 @S9S_MB_2U_LIB.S9S_MB_2U(SCH_1):PAGE317

NC_J107_N4 @S9S_MB_2U_LIB.S9S_MB_2U(SCH_1):NC_J107_N4
  J107   N4     N4 CONN112_10137002101LF-CONN112_A    I58 @S9S_MB_2U_LIB.S9S_MB_2U(SCH_1):PAGE317

NC_J107_N6 @S9S_MB_2U_LIB.S9S_MB_2U(SCH_1):NC_J107_N6
  J107   N6     N6 CONN112_10137002101LF-CONN112_A    I38 @S9S_MB_2U_LIB.S9S_MB_2U(SCH_1):PAGE317

NC_J108_N2 @S9S_MB_2U_LIB.S9S_MB_2U(SCH_1):NC_J108_N2
  J108   N2     N2 CONN112_10137002101LF-CONN112_A    I57 @S9S_MB_2U_LIB.S9S_MB_2U(SCH_1):PAGE320

NC_J108_N4 @S9S_MB_2U_LIB.S9S_MB_2U(SCH_1):NC_J108_N4
  J108   N4     N4 CONN112_10137002101LF-CONN112_A    I57 @S9S_MB_2U_LIB.S9S_MB_2U(SCH_1):PAGE320

NC_J108_N6 @S9S_MB_2U_LIB.S9S_MB_2U(SCH_1):NC_J108_N6
  J108   N6     N6 CONN112_10137002101LF-CONN112_A    I76 @S9S_MB_2U_LIB.S9S_MB_2U(SCH_1):PAGE320

NC_J112_N2 @S9S_MB_2U_LIB.S9S_MB_2U(SCH_1):NC_J112_N2
  J112   N2     N2 CONN160_10131762101LF-CONN160_A    I76 @S9S_MB_2U_LIB.S9S_MB_2U(SCH_1):PAGE149

NC_J112_O2 @S9S_MB_2U_LIB.S9S_MB_2U(SCH_1):NC_J112_O2
  J112   O2     O2 CONN160_10131762101LF-CONN160_A    I76 @S9S_MB_2U_LIB.S9S_MB_2U(SCH_1):PAGE149

NC_J112_O5 @S9S_MB_2U_LIB.S9S_MB_2U(SCH_1):NC_J112_O5
  J112   O5     O5 CONN160_10131762101LF-CONN160_A    I75 @S9S_MB_2U_LIB.S9S_MB_2U(SCH_1):PAGE149

NC_J112_P5 @S9S_MB_2U_LIB.S9S_MB_2U(SCH_1):NC_J112_P5
  J112   P5     P5 CONN160_10131762101LF-CONN160_A    I75 @S9S_MB_2U_LIB.S9S_MB_2U(SCH_1):PAGE149

NC_J112_R5 @S9S_MB_2U_LIB.S9S_MB_2U(SCH_1):NC_J112_R5
  J112   R5     R5 CONN160_10131762101LF-CONN160_A    I75 @S9S_MB_2U_LIB.S9S_MB_2U(SCH_1):PAGE149

NC_J112_S5 @S9S_MB_2U_LIB.S9S_MB_2U(SCH_1):NC_J112_S5
  J112   S5     S5 CONN160_10131762101LF-CONN160_A    I75 @S9S_MB_2U_LIB.S9S_MB_2U(SCH_1):PAGE149

NC_M2_0_NC1 @S9S_MB_2U_LIB.S9S_MB_2U(SCH_1):NC_M2_0_NC1
   J59    6    NC1 SCONN75K_APCI0155P004A-SCONN75A   I178 @S9S_MB_2U_LIB.S9S_MB_2U(SCH_1):PAGE182

NC_M2_0_NC10 @S9S_MB_2U_LIB.S9S_MB_2U(SCH_1):NC_M2_0_NC10
   J59   34   NC10 SCONN75K_APCI0155P004A-SCONN75A   I178 @S9S_MB_2U_LIB.S9S_MB_2U(SCH_1):PAGE182

NC_M2_0_NC11 @S9S_MB_2U_LIB.S9S_MB_2U(SCH_1):NC_M2_0_NC11
   J59   36   NC11 SCONN75K_APCI0155P004A-SCONN75A   I178 @S9S_MB_2U_LIB.S9S_MB_2U(SCH_1):PAGE182

NC_M2_0_NC14 @S9S_MB_2U_LIB.S9S_MB_2U(SCH_1):NC_M2_0_NC14
   J59   44   NC14 SCONN75K_APCI0155P004A-SCONN75A   I178 @S9S_MB_2U_LIB.S9S_MB_2U(SCH_1):PAGE182

NC_M2_0_NC15 @S9S_MB_2U_LIB.S9S_MB_2U(SCH_1):NC_M2_0_NC15
   J59   46   NC15 SCONN75K_APCI0155P004A-SCONN75A   I178 @S9S_MB_2U_LIB.S9S_MB_2U(SCH_1):PAGE182

NC_M2_0_NC16 @S9S_MB_2U_LIB.S9S_MB_2U(SCH_1):NC_M2_0_NC16
   J59   48   NC16 SCONN75K_APCI0155P004A-SCONN75A   I178 @S9S_MB_2U_LIB.S9S_MB_2U(SCH_1):PAGE182

NC_M2_0_NC17 @S9S_MB_2U_LIB.S9S_MB_2U(SCH_1):NC_M2_0_NC17
   J59   56   NC17 SCONN75K_APCI0155P004A-SCONN75A   I178 @S9S_MB_2U_LIB.S9S_MB_2U(SCH_1):PAGE182

NC_M2_0_NC18 @S9S_MB_2U_LIB.S9S_MB_2U(SCH_1):NC_M2_0_NC18
   J59   58   NC18 SCONN75K_APCI0155P004A-SCONN75A   I178 @S9S_MB_2U_LIB.S9S_MB_2U(SCH_1):PAGE182

NC_M2_0_NC19 @S9S_MB_2U_LIB.S9S_MB_2U(SCH_1):NC_M2_0_NC19
   J59   67   NC19 SCONN75K_APCI0155P004A-SCONN75A   I178 @S9S_MB_2U_LIB.S9S_MB_2U(SCH_1):PAGE182

NC_M2_0_NC2 @S9S_MB_2U_LIB.S9S_MB_2U(SCH_1):NC_M2_0_NC2
   J59    8    NC2 SCONN75K_APCI0155P004A-SCONN75A   I178 @S9S_MB_2U_LIB.S9S_MB_2U(SCH_1):PAGE182

NC_M2_0_NC3 @S9S_MB_2U_LIB.S9S_MB_2U(SCH_1):NC_M2_0_NC3
   J59   20    NC3 SCONN75K_APCI0155P004A-SCONN75A   I178 @S9S_MB_2U_LIB.S9S_MB_2U(SCH_1):PAGE182

NC_M2_0_NC4 @S9S_MB_2U_LIB.S9S_MB_2U(SCH_1):NC_M2_0_NC4
   J59   22    NC4 SCONN75K_APCI0155P004A-SCONN75A   I178 @S9S_MB_2U_LIB.S9S_MB_2U(SCH_1):PAGE182

NC_M2_0_NC5 @S9S_MB_2U_LIB.S9S_MB_2U(SCH_1):NC_M2_0_NC5
   J59   24    NC5 SCONN75K_APCI0155P004A-SCONN75A   I178 @S9S_MB_2U_LIB.S9S_MB_2U(SCH_1):PAGE182

NC_M2_0_NC6 @S9S_MB_2U_LIB.S9S_MB_2U(SCH_1):NC_M2_0_NC6
   J59   26    NC6 SCONN75K_APCI0155P004A-SCONN75A   I178 @S9S_MB_2U_LIB.S9S_MB_2U(SCH_1):PAGE182

NC_M2_0_NC7 @S9S_MB_2U_LIB.S9S_MB_2U(SCH_1):NC_M2_0_NC7
   J59   28    NC7 SCONN75K_APCI0155P004A-SCONN75A   I178 @S9S_MB_2U_LIB.S9S_MB_2U(SCH_1):PAGE182

NC_M2_0_NC8 @S9S_MB_2U_LIB.S9S_MB_2U(SCH_1):NC_M2_0_NC8
   J59   30    NC8 SCONN75K_APCI0155P004A-SCONN75A   I178 @S9S_MB_2U_LIB.S9S_MB_2U(SCH_1):PAGE182

NC_M2_0_NC9 @S9S_MB_2U_LIB.S9S_MB_2U(SCH_1):NC_M2_0_NC9
   J59   32    NC9 SCONN75K_APCI0155P004A-SCONN75A   I178 @S9S_MB_2U_LIB.S9S_MB_2U(SCH_1):PAGE182

NC_M2_0_SUSCLK @S9S_MB_2U_LIB.S9S_MB_2U(SCH_1):NC_M2_0_SUSCLK
   J59   68 SUSCLK SCONN75K_APCI0155P004A-SCONN75A   I178 @S9S_MB_2U_LIB.S9S_MB_2U(SCH_1):PAGE182

NC_MIPI60_P9 @S9S_MB_2U_LIB.S9S_MB_2U(SCH_1):NC_MIPI60_P9
   J42    9      9 SCONN60_ASP21410801-SCONN60_ASA    I44 @S9S_MB_2U_LIB.S9S_MB_2U(SCH_1):PAGE133

NC_PCH_RSVD<10> @S9S_MB_2U_LIB.S9S_MB_2U(SCH_1):NC_PCH_RSVD(10)
    U4  N40 RSVD_N40 EMMITSBURG_REV0P9-GFNOCPU04302A   I110 @S9S_MB_2U_LIB.S9S_MB_2U(SCH_1):PAGE173

NC_PCH_RSVD<11> @S9S_MB_2U_LIB.S9S_MB_2U(SCH_1):NC_PCH_RSVD(11)
    U4  N42 RSVD_N42 EMMITSBURG_REV0P9-GFNOCPU04302A   I110 @S9S_MB_2U_LIB.S9S_MB_2U(SCH_1):PAGE173

NC_PCH_RSVD<14> @S9S_MB_2U_LIB.S9S_MB_2U(SCH_1):NC_PCH_RSVD(14)
    U4 BC40 RSVD_BC40 EMMITSBURG_REV0P9-GFNOCPU04302A    I11 @S9S_MB_2U_LIB.S9S_MB_2U(SCH_1):PAGE172

NC_PCH_RSVD<17> @S9S_MB_2U_LIB.S9S_MB_2U(SCH_1):NC_PCH_RSVD(17)
    U4 BG36 RSVD_BG36 EMMITSBURG_REV0P9-GFNOCPU04302A    I36 @S9S_MB_2U_LIB.S9S_MB_2U(SCH_1):PAGE174

NC_PCH_RSVD<3> @S9S_MB_2U_LIB.S9S_MB_2U(SCH_1):NC_PCH_RSVD(3)
    U4 AW26 RSVD_AW23 EMMITSBURG_REV0P9-GFNOCPU04302A    I36 @S9S_MB_2U_LIB.S9S_MB_2U(SCH_1):PAGE174

NC_PCH_RSVD<4> @S9S_MB_2U_LIB.S9S_MB_2U(SCH_1):NC_PCH_RSVD(4)
    U4 AV21 RSVD_AV21 EMMITSBURG_REV0P9-GFNOCPU04302A    I36 @S9S_MB_2U_LIB.S9S_MB_2U(SCH_1):PAGE174

NC_PCH_RSVD<5> @S9S_MB_2U_LIB.S9S_MB_2U(SCH_1):NC_PCH_RSVD(5)
    U4 BF39 RSVD_BF39 EMMITSBURG_REV0P9-GFNOCPU04302A    I36 @S9S_MB_2U_LIB.S9S_MB_2U(SCH_1):PAGE174

NC_PCH_RSVD<8> @S9S_MB_2U_LIB.S9S_MB_2U(SCH_1):NC_PCH_RSVD(8)
    U4  C40 RSVD_C40 EMMITSBURG_REV0P9-GFNOCPU04302A   I110 @S9S_MB_2U_LIB.S9S_MB_2U(SCH_1):PAGE173

NC_PCH_RSVD<9> @S9S_MB_2U_LIB.S9S_MB_2U(SCH_1):NC_PCH_RSVD(9)
    U4  D39 RSVD_D39 EMMITSBURG_REV0P9-GFNOCPU04302A   I110 @S9S_MB_2U_LIB.S9S_MB_2U(SCH_1):PAGE173

NC_PU9_1 @S9S_MB_2U_LIB.S9S_MB_2U(SCH_1):NC_PU9_1
   PU9   33    NC2 IR3889MTRPBF-IR3889MTRPBF,SMLFA    I95 @S9S_MB_2U_LIB.S9S_MB_2U(SCH_1):PAGE245

NC_PU9_2 @S9S_MB_2U_LIB.S9S_MB_2U(SCH_1):NC_PU9_2
   PU9   34    NC3 IR3889MTRPBF-IR3889MTRPBF,SMLFA    I95 @S9S_MB_2U_LIB.S9S_MB_2U(SCH_1):PAGE245

NC_PU9_3 @S9S_MB_2U_LIB.S9S_MB_2U(SCH_1):NC_PU9_3
   PU9    6 GATEL1 IR3889MTRPBF-IR3889MTRPBF,SMLFA    I95 @S9S_MB_2U_LIB.S9S_MB_2U(SCH_1):PAGE245

NC_PU9_4 @S9S_MB_2U_LIB.S9S_MB_2U(SCH_1):NC_PU9_4
   PU9   37 GATEL2 IR3889MTRPBF-IR3889MTRPBF,SMLFA    I95 @S9S_MB_2U_LIB.S9S_MB_2U(SCH_1):PAGE245

NC_PVCCD_HV_CPU0_ACSP2 @S9S_MB_2U_LIB.S9S_MB_2U(SCH_1):NC_PVCCD_HV_CPU0_ACSP2
  PU35   24    CS6 ISL69260IRAZT-ISL69260IRAZ-T,SA    I53 @S9S_MB_2U_LIB.S9S_MB_2U(SCH_1):PAGE264
PR4230    1      A Q_RES_0402LF-0,5%,1/16W,CHIP,CA    I74 @S9S_MB_2U_LIB.S9S_MB_2U(SCH_1):PAGE264

NC_PVCCD_HV_CPU0_ACSP3 @S9S_MB_2U_LIB.S9S_MB_2U(SCH_1):NC_PVCCD_HV_CPU0_ACSP3
  PU35   25    CS5 ISL69260IRAZT-ISL69260IRAZ-T,SA    I53 @S9S_MB_2U_LIB.S9S_MB_2U(SCH_1):PAGE264
PR4231    1      A Q_RES_0402LF-0,5%,1/16W,CHIP,CA    I69 @S9S_MB_2U_LIB.S9S_MB_2U(SCH_1):PAGE264

NC_PVCCD_HV_CPU0_ACSP4 @S9S_MB_2U_LIB.S9S_MB_2U(SCH_1):NC_PVCCD_HV_CPU0_ACSP4
  PU35   26    CS4 ISL69260IRAZT-ISL69260IRAZ-T,SA    I53 @S9S_MB_2U_LIB.S9S_MB_2U(SCH_1):PAGE264
PR4232    1      A Q_RES_0402LF-0,5%,1/16W,CHIP,CA    I68 @S9S_MB_2U_LIB.S9S_MB_2U(SCH_1):PAGE264

NC_PVCCD_HV_CPU0_ACSP5 @S9S_MB_2U_LIB.S9S_MB_2U(SCH_1):NC_PVCCD_HV_CPU0_ACSP5
  PU35   27    CS3 ISL69260IRAZT-ISL69260IRAZ-T,SA    I53 @S9S_MB_2U_LIB.S9S_MB_2U(SCH_1):PAGE264
PR4233    1      A Q_RES_0402LF-0,5%,1/16W,CHIP,CA    I67 @S9S_MB_2U_LIB.S9S_MB_2U(SCH_1):PAGE264

NC_PVCCD_HV_CPU0_ACSP6 @S9S_MB_2U_LIB.S9S_MB_2U(SCH_1):NC_PVCCD_HV_CPU0_ACSP6
  PU35   28    CS2 ISL69260IRAZT-ISL69260IRAZ-T,SA    I53 @S9S_MB_2U_LIB.S9S_MB_2U(SCH_1):PAGE264
PR4234    1      A Q_RES_0402LF-0,5%,1/16W,CHIP,CA    I66 @S9S_MB_2U_LIB.S9S_MB_2U(SCH_1):PAGE264

NC_PVCCD_HV_CPU0_ACSP7 @S9S_MB_2U_LIB.S9S_MB_2U(SCH_1):NC_PVCCD_HV_CPU0_ACSP7
  PU35   29    CS1 ISL69260IRAZT-ISL69260IRAZ-T,SA    I53 @S9S_MB_2U_LIB.S9S_MB_2U(SCH_1):PAGE264
PR4235    1      A Q_RES_0402LF-0,5%,1/16W,CHIP,CA    I62 @S9S_MB_2U_LIB.S9S_MB_2U(SCH_1):PAGE264

NC_PVCCD_HV_CPU0_ACSP8 @S9S_MB_2U_LIB.S9S_MB_2U(SCH_1):NC_PVCCD_HV_CPU0_ACSP8
  PU35   30    CS0 ISL69260IRAZT-ISL69260IRAZ-T,SA    I53 @S9S_MB_2U_LIB.S9S_MB_2U(SCH_1):PAGE264
PR4236    1      A Q_RES_0402LF-0,5%,1/16W,CHIP,CA    I61 @S9S_MB_2U_LIB.S9S_MB_2U(SCH_1):PAGE264

NC_PVCCD_HV_CPU0_APWM2 @S9S_MB_2U_LIB.S9S_MB_2U(SCH_1):NC_PVCCD_HV_CPU0_APWM2
  PU35    7   PWM6 ISL69260IRAZT-ISL69260IRAZ-T,SA    I53 @S9S_MB_2U_LIB.S9S_MB_2U(SCH_1):PAGE264

NC_PVCCD_HV_CPU0_APWM3 @S9S_MB_2U_LIB.S9S_MB_2U(SCH_1):NC_PVCCD_HV_CPU0_APWM3
  PU35    6   PWM5 ISL69260IRAZT-ISL69260IRAZ-T,SA    I53 @S9S_MB_2U_LIB.S9S_MB_2U(SCH_1):PAGE264

NC_PVCCD_HV_CPU0_APWM4 @S9S_MB_2U_LIB.S9S_MB_2U(SCH_1):NC_PVCCD_HV_CPU0_APWM4
  PU35    5   PWM4 ISL69260IRAZT-ISL69260IRAZ-T,SA    I53 @S9S_MB_2U_LIB.S9S_MB_2U(SCH_1):PAGE264

NC_PVCCD_HV_CPU0_APWM5 @S9S_MB_2U_LIB.S9S_MB_2U(SCH_1):NC_PVCCD_HV_CPU0_APWM5
  PU35    4   PWM3 ISL69260IRAZT-ISL69260IRAZ-T,SA    I53 @S9S_MB_2U_LIB.S9S_MB_2U(SCH_1):PAGE264

NC_PVCCD_HV_CPU0_APWM6 @S9S_MB_2U_LIB.S9S_MB_2U(SCH_1):NC_PVCCD_HV_CPU0_APWM6
  PU35    3   PWM2 ISL69260IRAZT-ISL69260IRAZ-T,SA    I53 @S9S_MB_2U_LIB.S9S_MB_2U(SCH_1):PAGE264

NC_PVCCD_HV_CPU0_APWM7 @S9S_MB_2U_LIB.S9S_MB_2U(SCH_1):NC_PVCCD_HV_CPU0_APWM7
  PU35    2   PWM1 ISL69260IRAZT-ISL69260IRAZ-T,SA    I53 @S9S_MB_2U_LIB.S9S_MB_2U(SCH_1):PAGE264

NC_PVCCD_HV_CPU0_APWM8 @S9S_MB_2U_LIB.S9S_MB_2U(SCH_1):NC_PVCCD_HV_CPU0_APWM8
  PU35    1   PWM0 ISL69260IRAZT-ISL69260IRAZ-T,SA    I53 @S9S_MB_2U_LIB.S9S_MB_2U(SCH_1):PAGE264

NC_PVCCD_HV_CPU0_BVR_RDY @S9S_MB_2U_LIB.S9S_MB_2U(SCH_1):NC_PVCCD_HV_CPU0_BVR_RDY
  PU35   16    PG1 ISL69260IRAZT-ISL69260IRAZ-T,SA    I53 @S9S_MB_2U_LIB.S9S_MB_2U(SCH_1):PAGE264

NC_PVCCD_HV_CPU0_SMB_ALERT @S9S_MB_2U_LIB.S9S_MB_2U(SCH_1):NC_PVCCD_HV_CPU0_SMB_ALERT
  PU35   11 NPMALERT# ISL69260IRAZT-ISL69260IRAZ-T,SA    I53 @S9S_MB_2U_LIB.S9S_MB_2U(SCH_1):PAGE264

NC_PVCCD_HV_CPU1_ACSP2 @S9S_MB_2U_LIB.S9S_MB_2U(SCH_1):NC_PVCCD_HV_CPU1_ACSP2
  PU18   24    CS6 ISL69260IRAZT-ISL69260IRAZ-T,SA    I53 @S9S_MB_2U_LIB.S9S_MB_2U(SCH_1):PAGE282
PR4251    1      A Q_RES_0402LF-0,5%,1/16W,CHIP,CA    I70 @S9S_MB_2U_LIB.S9S_MB_2U(SCH_1):PAGE282

NC_PVCCD_HV_CPU1_ACSP3 @S9S_MB_2U_LIB.S9S_MB_2U(SCH_1):NC_PVCCD_HV_CPU1_ACSP3
  PU18   25    CS5 ISL69260IRAZT-ISL69260IRAZ-T,SA    I53 @S9S_MB_2U_LIB.S9S_MB_2U(SCH_1):PAGE282
PR4252    1      A Q_RES_0402LF-0,5%,1/16W,CHIP,CA    I64 @S9S_MB_2U_LIB.S9S_MB_2U(SCH_1):PAGE282

NC_PVCCD_HV_CPU1_ACSP4 @S9S_MB_2U_LIB.S9S_MB_2U(SCH_1):NC_PVCCD_HV_CPU1_ACSP4
  PU18   26    CS4 ISL69260IRAZT-ISL69260IRAZ-T,SA    I53 @S9S_MB_2U_LIB.S9S_MB_2U(SCH_1):PAGE282
PR4253    1      A Q_RES_0402LF-0,5%,1/16W,CHIP,CA    I65 @S9S_MB_2U_LIB.S9S_MB_2U(SCH_1):PAGE282

NC_PVCCD_HV_CPU1_ACSP5 @S9S_MB_2U_LIB.S9S_MB_2U(SCH_1):NC_PVCCD_HV_CPU1_ACSP5
  PU18   27    CS3 ISL69260IRAZT-ISL69260IRAZ-T,SA    I53 @S9S_MB_2U_LIB.S9S_MB_2U(SCH_1):PAGE282
PR4254    1      A Q_RES_0402LF-0,5%,1/16W,CHIP,CA    I66 @S9S_MB_2U_LIB.S9S_MB_2U(SCH_1):PAGE282

NC_PVCCD_HV_CPU1_ACSP6 @S9S_MB_2U_LIB.S9S_MB_2U(SCH_1):NC_PVCCD_HV_CPU1_ACSP6
  PU18   28    CS2 ISL69260IRAZT-ISL69260IRAZ-T,SA    I53 @S9S_MB_2U_LIB.S9S_MB_2U(SCH_1):PAGE282
PR4255    1      A Q_RES_0402LF-0,5%,1/16W,CHIP,CA    I62 @S9S_MB_2U_LIB.S9S_MB_2U(SCH_1):PAGE282

NC_PVCCD_HV_CPU1_ACSP7 @S9S_MB_2U_LIB.S9S_MB_2U(SCH_1):NC_PVCCD_HV_CPU1_ACSP7
  PU18   29    CS1 ISL69260IRAZT-ISL69260IRAZ-T,SA    I53 @S9S_MB_2U_LIB.S9S_MB_2U(SCH_1):PAGE282
PR4256    1      A Q_RES_0402LF-0,5%,1/16W,CHIP,CA    I63 @S9S_MB_2U_LIB.S9S_MB_2U(SCH_1):PAGE282

NC_PVCCD_HV_CPU1_ACSP8 @S9S_MB_2U_LIB.S9S_MB_2U(SCH_1):NC_PVCCD_HV_CPU1_ACSP8
  PU18   30    CS0 ISL69260IRAZT-ISL69260IRAZ-T,SA    I53 @S9S_MB_2U_LIB.S9S_MB_2U(SCH_1):PAGE282
PR4257    1      A Q_RES_0402LF-0,5%,1/16W,CHIP,CA    I59 @S9S_MB_2U_LIB.S9S_MB_2U(SCH_1):PAGE282

NC_PVCCD_HV_CPU1_APWM2 @S9S_MB_2U_LIB.S9S_MB_2U(SCH_1):NC_PVCCD_HV_CPU1_APWM2
  PU18    7   PWM6 ISL69260IRAZT-ISL69260IRAZ-T,SA    I53 @S9S_MB_2U_LIB.S9S_MB_2U(SCH_1):PAGE282

NC_PVCCD_HV_CPU1_APWM3 @S9S_MB_2U_LIB.S9S_MB_2U(SCH_1):NC_PVCCD_HV_CPU1_APWM3
  PU18    6   PWM5 ISL69260IRAZT-ISL69260IRAZ-T,SA    I53 @S9S_MB_2U_LIB.S9S_MB_2U(SCH_1):PAGE282

NC_PVCCD_HV_CPU1_APWM4 @S9S_MB_2U_LIB.S9S_MB_2U(SCH_1):NC_PVCCD_HV_CPU1_APWM4
  PU18    5   PWM4 ISL69260IRAZT-ISL69260IRAZ-T,SA    I53 @S9S_MB_2U_LIB.S9S_MB_2U(SCH_1):PAGE282

NC_PVCCD_HV_CPU1_APWM5 @S9S_MB_2U_LIB.S9S_MB_2U(SCH_1):NC_PVCCD_HV_CPU1_APWM5
  PU18    4   PWM3 ISL69260IRAZT-ISL69260IRAZ-T,SA    I53 @S9S_MB_2U_LIB.S9S_MB_2U(SCH_1):PAGE282

NC_PVCCD_HV_CPU1_APWM6 @S9S_MB_2U_LIB.S9S_MB_2U(SCH_1):NC_PVCCD_HV_CPU1_APWM6
  PU18    3   PWM2 ISL69260IRAZT-ISL69260IRAZ-T,SA    I53 @S9S_MB_2U_LIB.S9S_MB_2U(SCH_1):PAGE282

NC_PVCCD_HV_CPU1_APWM7 @S9S_MB_2U_LIB.S9S_MB_2U(SCH_1):NC_PVCCD_HV_CPU1_APWM7
  PU18    2   PWM1 ISL69260IRAZT-ISL69260IRAZ-T,SA    I53 @S9S_MB_2U_LIB.S9S_MB_2U(SCH_1):PAGE282

NC_PVCCD_HV_CPU1_APWM8 @S9S_MB_2U_LIB.S9S_MB_2U(SCH_1):NC_PVCCD_HV_CPU1_APWM8
  PU18    1   PWM0 ISL69260IRAZT-ISL69260IRAZ-T,SA    I53 @S9S_MB_2U_LIB.S9S_MB_2U(SCH_1):PAGE282

NC_PVCCD_HV_CPU1_BVR_RDY @S9S_MB_2U_LIB.S9S_MB_2U(SCH_1):NC_PVCCD_HV_CPU1_BVR_RDY
  PU18   16    PG1 ISL69260IRAZT-ISL69260IRAZ-T,SA    I53 @S9S_MB_2U_LIB.S9S_MB_2U(SCH_1):PAGE282

NC_PVCCD_HV_CPU1_SMB_ALERT @S9S_MB_2U_LIB.S9S_MB_2U(SCH_1):NC_PVCCD_HV_CPU1_SMB_ALERT
  PU18   11 NPMALERT# ISL69260IRAZT-ISL69260IRAZ-T,SA    I53 @S9S_MB_2U_LIB.S9S_MB_2U(SCH_1):PAGE282

NC_PVCCINFAON_CPU0_ACSP3 @S9S_MB_2U_LIB.S9S_MB_2U(SCH_1):NC_PVCCINFAON_CPU0_ACSP3
   PU5   25    CS5 ISL69260IRAZT-ISL69260IRAZ-T,SA    I65 @S9S_MB_2U_LIB.S9S_MB_2U(SCH_1):PAGE260
PR4221    1      A Q_RES_0402LF-0,5%,1/16W,CHIP,CA    I87 @S9S_MB_2U_LIB.S9S_MB_2U(SCH_1):PAGE260

NC_PVCCINFAON_CPU0_ACSP4 @S9S_MB_2U_LIB.S9S_MB_2U(SCH_1):NC_PVCCINFAON_CPU0_ACSP4
   PU5   26    CS4 ISL69260IRAZT-ISL69260IRAZ-T,SA    I65 @S9S_MB_2U_LIB.S9S_MB_2U(SCH_1):PAGE260
PR4222    1      A Q_RES_0402LF-0,5%,1/16W,CHIP,CA    I86 @S9S_MB_2U_LIB.S9S_MB_2U(SCH_1):PAGE260

NC_PVCCINFAON_CPU0_ACSP5 @S9S_MB_2U_LIB.S9S_MB_2U(SCH_1):NC_PVCCINFAON_CPU0_ACSP5
   PU5   27    CS3 ISL69260IRAZT-ISL69260IRAZ-T,SA    I65 @S9S_MB_2U_LIB.S9S_MB_2U(SCH_1):PAGE260
PR4223    1      A Q_RES_0402LF-0,5%,1/16W,CHIP,CA    I85 @S9S_MB_2U_LIB.S9S_MB_2U(SCH_1):PAGE260

NC_PVCCINFAON_CPU0_ACSP6 @S9S_MB_2U_LIB.S9S_MB_2U(SCH_1):NC_PVCCINFAON_CPU0_ACSP6
   PU5   28    CS2 ISL69260IRAZT-ISL69260IRAZ-T,SA    I65 @S9S_MB_2U_LIB.S9S_MB_2U(SCH_1):PAGE260
PR4224    1      A Q_RES_0402LF-0,5%,1/16W,CHIP,CA    I84 @S9S_MB_2U_LIB.S9S_MB_2U(SCH_1):PAGE260

NC_PVCCINFAON_CPU0_ACSP7 @S9S_MB_2U_LIB.S9S_MB_2U(SCH_1):NC_PVCCINFAON_CPU0_ACSP7
   PU5   29    CS1 ISL69260IRAZT-ISL69260IRAZ-T,SA    I65 @S9S_MB_2U_LIB.S9S_MB_2U(SCH_1):PAGE260
PR4225    1      A Q_RES_0402LF-0,5%,1/16W,CHIP,CA    I76 @S9S_MB_2U_LIB.S9S_MB_2U(SCH_1):PAGE260

NC_PVCCINFAON_CPU0_APWM3 @S9S_MB_2U_LIB.S9S_MB_2U(SCH_1):NC_PVCCINFAON_CPU0_APWM3
   PU5    6   PWM5 ISL69260IRAZT-ISL69260IRAZ-T,SA    I65 @S9S_MB_2U_LIB.S9S_MB_2U(SCH_1):PAGE260

NC_PVCCINFAON_CPU0_APWM4 @S9S_MB_2U_LIB.S9S_MB_2U(SCH_1):NC_PVCCINFAON_CPU0_APWM4
   PU5    5   PWM4 ISL69260IRAZT-ISL69260IRAZ-T,SA    I65 @S9S_MB_2U_LIB.S9S_MB_2U(SCH_1):PAGE260

NC_PVCCINFAON_CPU0_APWM5 @S9S_MB_2U_LIB.S9S_MB_2U(SCH_1):NC_PVCCINFAON_CPU0_APWM5
   PU5    4   PWM3 ISL69260IRAZT-ISL69260IRAZ-T,SA    I65 @S9S_MB_2U_LIB.S9S_MB_2U(SCH_1):PAGE260

NC_PVCCINFAON_CPU0_APWM6 @S9S_MB_2U_LIB.S9S_MB_2U(SCH_1):NC_PVCCINFAON_CPU0_APWM6
   PU5    3   PWM2 ISL69260IRAZT-ISL69260IRAZ-T,SA    I65 @S9S_MB_2U_LIB.S9S_MB_2U(SCH_1):PAGE260

NC_PVCCINFAON_CPU0_APWM7 @S9S_MB_2U_LIB.S9S_MB_2U(SCH_1):NC_PVCCINFAON_CPU0_APWM7
   PU5    2   PWM1 ISL69260IRAZT-ISL69260IRAZ-T,SA    I65 @S9S_MB_2U_LIB.S9S_MB_2U(SCH_1):PAGE260

NC_PVCCINFAON_CPU0_SMB_ALERT @S9S_MB_2U_LIB.S9S_MB_2U(SCH_1):NC_PVCCINFAON_CPU0_SMB_ALERT
   PU5   11 NPMALERT# ISL69260IRAZT-ISL69260IRAZ-T,SA    I65 @S9S_MB_2U_LIB.S9S_MB_2U(SCH_1):PAGE260

NC_PVCCINFAON_CPU1_ACSP3 @S9S_MB_2U_LIB.S9S_MB_2U(SCH_1):NC_PVCCINFAON_CPU1_ACSP3
  PU22   25    CS5 ISL69260IRAZT-ISL69260IRAZ-T,SA    I38 @S9S_MB_2U_LIB.S9S_MB_2U(SCH_1):PAGE278
PR4242    1      A Q_RES_0402LF-0,5%,1/16W,CHIP,CA    I89 @S9S_MB_2U_LIB.S9S_MB_2U(SCH_1):PAGE278

NC_PVCCINFAON_CPU1_ACSP4 @S9S_MB_2U_LIB.S9S_MB_2U(SCH_1):NC_PVCCINFAON_CPU1_ACSP4
PR4243    1      A Q_RES_0402LF-0,5%,1/16W,CHIP,CA    I81 @S9S_MB_2U_LIB.S9S_MB_2U(SCH_1):PAGE278
  PU22   26    CS4 ISL69260IRAZT-ISL69260IRAZ-T,SA    I38 @S9S_MB_2U_LIB.S9S_MB_2U(SCH_1):PAGE278

NC_PVCCINFAON_CPU1_ACSP5 @S9S_MB_2U_LIB.S9S_MB_2U(SCH_1):NC_PVCCINFAON_CPU1_ACSP5
PR4244    1      A Q_RES_0402LF-0,5%,1/16W,CHIP,CA    I80 @S9S_MB_2U_LIB.S9S_MB_2U(SCH_1):PAGE278
  PU22   27    CS3 ISL69260IRAZT-ISL69260IRAZ-T,SA    I38 @S9S_MB_2U_LIB.S9S_MB_2U(SCH_1):PAGE278

NC_PVCCINFAON_CPU1_ACSP6 @S9S_MB_2U_LIB.S9S_MB_2U(SCH_1):NC_PVCCINFAON_CPU1_ACSP6
PR4245    1      A Q_RES_0402LF-0,5%,1/16W,CHIP,CA    I79 @S9S_MB_2U_LIB.S9S_MB_2U(SCH_1):PAGE278
  PU22   28    CS2 ISL69260IRAZT-ISL69260IRAZ-T,SA    I38 @S9S_MB_2U_LIB.S9S_MB_2U(SCH_1):PAGE278

NC_PVCCINFAON_CPU1_ACSP7 @S9S_MB_2U_LIB.S9S_MB_2U(SCH_1):NC_PVCCINFAON_CPU1_ACSP7
PR4246    1      A Q_RES_0402LF-0,5%,1/16W,CHIP,CA    I78 @S9S_MB_2U_LIB.S9S_MB_2U(SCH_1):PAGE278
  PU22   29    CS1 ISL69260IRAZT-ISL69260IRAZ-T,SA    I38 @S9S_MB_2U_LIB.S9S_MB_2U(SCH_1):PAGE278

NC_PVCCINFAON_CPU1_APWM3 @S9S_MB_2U_LIB.S9S_MB_2U(SCH_1):NC_PVCCINFAON_CPU1_APWM3
  PU22    6   PWM5 ISL69260IRAZT-ISL69260IRAZ-T,SA    I38 @S9S_MB_2U_LIB.S9S_MB_2U(SCH_1):PAGE278

NC_PVCCINFAON_CPU1_APWM4 @S9S_MB_2U_LIB.S9S_MB_2U(SCH_1):NC_PVCCINFAON_CPU1_APWM4
  PU22    5   PWM4 ISL69260IRAZT-ISL69260IRAZ-T,SA    I38 @S9S_MB_2U_LIB.S9S_MB_2U(SCH_1):PAGE278

NC_PVCCINFAON_CPU1_APWM5 @S9S_MB_2U_LIB.S9S_MB_2U(SCH_1):NC_PVCCINFAON_CPU1_APWM5
  PU22    4   PWM3 ISL69260IRAZT-ISL69260IRAZ-T,SA    I38 @S9S_MB_2U_LIB.S9S_MB_2U(SCH_1):PAGE278

NC_PVCCINFAON_CPU1_APWM6 @S9S_MB_2U_LIB.S9S_MB_2U(SCH_1):NC_PVCCINFAON_CPU1_APWM6
  PU22    3   PWM2 ISL69260IRAZT-ISL69260IRAZ-T,SA    I38 @S9S_MB_2U_LIB.S9S_MB_2U(SCH_1):PAGE278

NC_PVCCINFAON_CPU1_APWM7 @S9S_MB_2U_LIB.S9S_MB_2U(SCH_1):NC_PVCCINFAON_CPU1_APWM7
  PU22    2   PWM1 ISL69260IRAZT-ISL69260IRAZ-T,SA    I38 @S9S_MB_2U_LIB.S9S_MB_2U(SCH_1):PAGE278

NC_PVCCINFAON_CPU1_SMB_ALERT @S9S_MB_2U_LIB.S9S_MB_2U(SCH_1):NC_PVCCINFAON_CPU1_SMB_ALERT
  PU22   11 NPMALERT# ISL69260IRAZT-ISL69260IRAZ-T,SA    I38 @S9S_MB_2U_LIB.S9S_MB_2U(SCH_1):PAGE278

NC_PVCCIN_CPU0_SMB_ALERT @S9S_MB_2U_LIB.S9S_MB_2U(SCH_1):NC_PVCCIN_CPU0_SMB_ALERT
  PU14   15 NPMALERT RAA229126GNPHA0-RAA229126GNP#HA    I63 @S9S_MB_2U_LIB.S9S_MB_2U(SCH_1):PAGE252

NC_PVCCIN_CPU1_SMB_ALERT @S9S_MB_2U_LIB.S9S_MB_2U(SCH_1):NC_PVCCIN_CPU1_SMB_ALERT
  PU29   15 NPMALERT RAA229126GNPHA0-RAA229126GNP#HA    I33 @S9S_MB_2U_LIB.S9S_MB_2U(SCH_1):PAGE270

NC_Q95_D2 @S9S_MB_2U_LIB.S9S_MB_2U(SCH_1):NC_Q95_D2
   Q95    3     D2 MOSFET_NCH_DUAL-PJT138K,SMLF,IA   I343 @S9S_MB_2U_LIB.S9S_MB_2U(SCH_1):PAGE182

NC_Q95_G2 @S9S_MB_2U_LIB.S9S_MB_2U(SCH_1):NC_Q95_G2
   Q95    5     G2 MOSFET_NCH_DUAL-PJT138K,SMLF,IA   I343 @S9S_MB_2U_LIB.S9S_MB_2U(SCH_1):PAGE182

NC_Q95_S2 @S9S_MB_2U_LIB.S9S_MB_2U(SCH_1):NC_Q95_S2
   Q95    4     S2 MOSFET_NCH_DUAL-PJT138K,SMLF,IA   I343 @S9S_MB_2U_LIB.S9S_MB_2U(SCH_1):PAGE182

NC_RES @S9S_MB_2U_LIB.S9S_MB_2U(SCH_1):NC_RES
  U328   13    RES DS125BR111RTWR-DS125BR111RTWR,A    I95 @S9S_MB_2U_LIB.S9S_MB_2U(SCH_1):PAGE159

NC_SPI_CPU1_NCM_CLK @S9S_MB_2U_LIB.S9S_MB_2U(SCH_1):NC_SPI_CPU1_NCM_CLK
    U1 AU62 RSVD11 SOCKET4677_AZIF0045P001C01CS-SA     I5 @S9S_MB_2U_LIB.S9S_MB_2U(SCH_1):PAGE46

NC_SPI_CPU1_NCM_CS0_N @S9S_MB_2U_LIB.S9S_MB_2U(SCH_1):NC_SPI_CPU1_NCM_CS0_N
    U1 AY67 RSVD30 SOCKET4677_AZIF0045P001C01CS-SA     I5 @S9S_MB_2U_LIB.S9S_MB_2U(SCH_1):PAGE46

NC_SPI_CPU1_NCM_IO0 @S9S_MB_2U_LIB.S9S_MB_2U(SCH_1):NC_SPI_CPU1_NCM_IO0
    U1 BA66 RSVD33 SOCKET4677_AZIF0045P001C01CS-SA     I5 @S9S_MB_2U_LIB.S9S_MB_2U(SCH_1):PAGE46

NC_SPI_CPU1_NCM_IO1 @S9S_MB_2U_LIB.S9S_MB_2U(SCH_1):NC_SPI_CPU1_NCM_IO1
    U1 AY61 RSVD28 SOCKET4677_AZIF0045P001C01CS-SA     I5 @S9S_MB_2U_LIB.S9S_MB_2U(SCH_1):PAGE46

NC_SPI_CPU1_NCM_OE_N @S9S_MB_2U_LIB.S9S_MB_2U(SCH_1):NC_SPI_CPU1_NCM_OE_N
    U1 BB67 RSVD36 SOCKET4677_AZIF0045P001C01CS-SA     I5 @S9S_MB_2U_LIB.S9S_MB_2U(SCH_1):PAGE46

NC_SPI_S3M_CPU1_CLK_LVC1_R @S9S_MB_2U_LIB.S9S_MB_2U(SCH_1):NC_SPI_S3M_CPU1_CLK_LVC1_R
    U1 BC64 RSVD39 SOCKET4677_AZIF0045P001C01CS-SA     I5 @S9S_MB_2U_LIB.S9S_MB_2U(SCH_1):PAGE46

NC_SPI_S3M_CPU1_CS0_LVC1_R_N @S9S_MB_2U_LIB.S9S_MB_2U(SCH_1):NC_SPI_S3M_CPU1_CS0_LVC1_R_N
    U1 BB61 RSVD35 SOCKET4677_AZIF0045P001C01CS-SA     I5 @S9S_MB_2U_LIB.S9S_MB_2U(SCH_1):PAGE46

NC_SPI_S3M_CPU1_CS1_LVC1_R_N @S9S_MB_2U_LIB.S9S_MB_2U(SCH_1):NC_SPI_S3M_CPU1_CS1_LVC1_R_N
    U1 AV63 RSVD20 SOCKET4677_AZIF0045P001C01CS-SA     I5 @S9S_MB_2U_LIB.S9S_MB_2U(SCH_1):PAGE46

NC_SPI_S3M_CPU1_IO0_LVC1_R @S9S_MB_2U_LIB.S9S_MB_2U(SCH_1):NC_SPI_S3M_CPU1_IO0_LVC1_R
    U1 BA62 RSVD32 SOCKET4677_AZIF0045P001C01CS-SA     I5 @S9S_MB_2U_LIB.S9S_MB_2U(SCH_1):PAGE46

NC_SPI_S3M_CPU1_IO1_LVC1_R @S9S_MB_2U_LIB.S9S_MB_2U(SCH_1):NC_SPI_S3M_CPU1_IO1_LVC1_R
    U1 AW64 RSVD24 SOCKET4677_AZIF0045P001C01CS-SA     I5 @S9S_MB_2U_LIB.S9S_MB_2U(SCH_1):PAGE46

NC_SPI_S3M_CPU1_IO2_LVC1_R @S9S_MB_2U_LIB.S9S_MB_2U(SCH_1):NC_SPI_S3M_CPU1_IO2_LVC1_R
    U1 BD65 RSVD42 SOCKET4677_AZIF0045P001C01CS-SA     I5 @S9S_MB_2U_LIB.S9S_MB_2U(SCH_1):PAGE46

NC_SPI_S3M_CPU1_IO3_LVC1_R @S9S_MB_2U_LIB.S9S_MB_2U(SCH_1):NC_SPI_S3M_CPU1_IO3_LVC1_R
    U1 BD61 RSVD40 SOCKET4677_AZIF0045P001C01CS-SA     I5 @S9S_MB_2U_LIB.S9S_MB_2U(SCH_1):PAGE46

NC_SPI_S3M_CPU1_OE_LVC1_R_N @S9S_MB_2U_LIB.S9S_MB_2U(SCH_1):NC_SPI_S3M_CPU1_OE_LVC1_R_N
    U1 BA68 RSVD34 SOCKET4677_AZIF0045P001C01CS-SA     I5 @S9S_MB_2U_LIB.S9S_MB_2U(SCH_1):PAGE46

NC_U104_NC1 @S9S_MB_2U_LIB.S9S_MB_2U(SCH_1):NC_U104_NC1
  U104    1    NC1 74LVC1G07GV-74LVC1G07GV,SMLF,IA    I63 @S9S_MB_2U_LIB.S9S_MB_2U(SCH_1):PAGE152

NC_U150_A1 @S9S_MB_2U_LIB.S9S_MB_2U(SCH_1):NC_U150_A1
  U150    3     A1 74LVC2G17GW-74LVC2G17GW,SMLF,IA     I2 @S9S_MB_2U_LIB.S9S_MB_2U(SCH_1):PAGE213

NC_U150_B1 @S9S_MB_2U_LIB.S9S_MB_2U(SCH_1):NC_U150_B1
  U150    4     B1 74LVC2G17GW-74LVC2G17GW,SMLF,IA     I2 @S9S_MB_2U_LIB.S9S_MB_2U(SCH_1):PAGE213

NC_U157_NC1 @S9S_MB_2U_LIB.S9S_MB_2U(SCH_1):NC_U157_NC1
  U157    1    NC1 74LVC1G07GV-74LVC1G07GV,SMLF,IA    I65 @S9S_MB_2U_LIB.S9S_MB_2U(SCH_1):PAGE152

NC_U205_INB- @S9S_MB_2U_LIB.S9S_MB_2U(SCH_1):NC_U205_INB-
  U205    4   INB- TPS3700DDCR-TPS3700DDCR,SMLF,EA     I5 @S9S_MB_2U_LIB.S9S_MB_2U(SCH_1):PAGE326

NC_U205_OUTB @S9S_MB_2U_LIB.S9S_MB_2U(SCH_1):NC_U205_OUTB
  U205    6   OUTB TPS3700DDCR-TPS3700DDCR,SMLF,EA     I5 @S9S_MB_2U_LIB.S9S_MB_2U(SCH_1):PAGE326

NC_U218_NC1 @S9S_MB_2U_LIB.S9S_MB_2U(SCH_1):NC_U218_NC1
  U218    1    NC1 74LVC1G07GV-74LVC1G07GV,SMLF,IA    I31 @S9S_MB_2U_LIB.S9S_MB_2U(SCH_1):PAGE156

NC_U219_NC1 @S9S_MB_2U_LIB.S9S_MB_2U(SCH_1):NC_U219_NC1
  U219    1    NC1 74LVC1G07GV-74LVC1G07GV,SMLF,IA    I61 @S9S_MB_2U_LIB.S9S_MB_2U(SCH_1):PAGE156

NC_U257_2Y @S9S_MB_2U_LIB.S9S_MB_2U(SCH_1):NC_U257_2Y
  U257    4     2Y 74LVC2G07DW7-74LVC2G07DW-7,SMLA    I50 @S9S_MB_2U_LIB.S9S_MB_2U(SCH_1):PAGE296

NC_U306_A0 @S9S_MB_2U_LIB.S9S_MB_2U(SCH_1):NC_U306_A0
  U306   13     A0 GTL2014PW-GTL2014PW,SMLF,IC,ALA    I80 @S9S_MB_2U_LIB.S9S_MB_2U(SCH_1):PAGE322

NC_U314_FBOUT @S9S_MB_2U_LIB.S9S_MB_2U(SCH_1):NC_U314_FBOUT
  U314    9 FBOUT_NC 9ZXL0451EKILFT-9ZXL0451EKILFT,A     I1 @S9S_MB_2U_LIB.S9S_MB_2U(SCH_1):PAGE200

NC_U314_FBOUT_N @S9S_MB_2U_LIB.S9S_MB_2U(SCH_1):NC_U314_FBOUT_N
  U314    8 FBOUT_NC# 9ZXL0451EKILFT-9ZXL0451EKILFT,A     I1 @S9S_MB_2U_LIB.S9S_MB_2U(SCH_1):PAGE200

NC_U314_NC0 @S9S_MB_2U_LIB.S9S_MB_2U(SCH_1):NC_U314_NC0
  U314   10    NC0 9ZXL0451EKILFT-9ZXL0451EKILFT,A     I1 @S9S_MB_2U_LIB.S9S_MB_2U(SCH_1):PAGE200

NC_U314_NC1 @S9S_MB_2U_LIB.S9S_MB_2U(SCH_1):NC_U314_NC1
  U314   11    NC1 9ZXL0451EKILFT-9ZXL0451EKILFT,A     I1 @S9S_MB_2U_LIB.S9S_MB_2U(SCH_1):PAGE200

NC_U314_NC2 @S9S_MB_2U_LIB.S9S_MB_2U(SCH_1):NC_U314_NC2
  U314   17    NC2 9ZXL0451EKILFT-9ZXL0451EKILFT,A     I1 @S9S_MB_2U_LIB.S9S_MB_2U(SCH_1):PAGE200

NC_U314_NC3 @S9S_MB_2U_LIB.S9S_MB_2U(SCH_1):NC_U314_NC3
  U314   30    NC3 9ZXL0451EKILFT-9ZXL0451EKILFT,A     I1 @S9S_MB_2U_LIB.S9S_MB_2U(SCH_1):PAGE200

NC_U316_2Y @S9S_MB_2U_LIB.S9S_MB_2U(SCH_1):NC_U316_2Y
  U316    4     B1 74LVC2G17GW-74LVC2G17GW,SMLF,IA    I86 @S9S_MB_2U_LIB.S9S_MB_2U(SCH_1):PAGE139

NC_UART_IBL_CPU0_CTS @S9S_MB_2U_LIB.S9S_MB_2U(SCH_1):NC_UART_IBL_CPU0_CTS
    U2 CV71 RSVD143 SOCKET4677_AZIF0045P001C01CS-SA     I1 @S9S_MB_2U_LIB.S9S_MB_2U(SCH_1):PAGE15

NC_UART_IBL_CPU0_RTS @S9S_MB_2U_LIB.S9S_MB_2U(SCH_1):NC_UART_IBL_CPU0_RTS
    U2 CY71 RSVD156 SOCKET4677_AZIF0045P001C01CS-SA     I1 @S9S_MB_2U_LIB.S9S_MB_2U(SCH_1):PAGE15

NC_UART_IBL_CPU0_RXD @S9S_MB_2U_LIB.S9S_MB_2U(SCH_1):NC_UART_IBL_CPU0_RXD
    U2 CY69 RSVD155 SOCKET4677_AZIF0045P001C01CS-SA     I1 @S9S_MB_2U_LIB.S9S_MB_2U(SCH_1):PAGE15

NC_UART_IBL_CPU0_TXD @S9S_MB_2U_LIB.S9S_MB_2U(SCH_1):NC_UART_IBL_CPU0_TXD
    U2 CV69 RSVD142 SOCKET4677_AZIF0045P001C01CS-SA     I1 @S9S_MB_2U_LIB.S9S_MB_2U(SCH_1):PAGE15

NC_UART_IBL_CPU1_CTS @S9S_MB_2U_LIB.S9S_MB_2U(SCH_1):NC_UART_IBL_CPU1_CTS
    U1 CV71 RSVD143 SOCKET4677_AZIF0045P001C01CS-SA     I5 @S9S_MB_2U_LIB.S9S_MB_2U(SCH_1):PAGE46

NC_UART_IBL_CPU1_RTS @S9S_MB_2U_LIB.S9S_MB_2U(SCH_1):NC_UART_IBL_CPU1_RTS
    U1 CY71 RSVD156 SOCKET4677_AZIF0045P001C01CS-SA     I5 @S9S_MB_2U_LIB.S9S_MB_2U(SCH_1):PAGE46

NC_UART_IBL_CPU1_RXD @S9S_MB_2U_LIB.S9S_MB_2U(SCH_1):NC_UART_IBL_CPU1_RXD
    U1 CY69 RSVD155 SOCKET4677_AZIF0045P001C01CS-SA     I5 @S9S_MB_2U_LIB.S9S_MB_2U(SCH_1):PAGE46

NC_UART_IBL_CPU1_TXD @S9S_MB_2U_LIB.S9S_MB_2U(SCH_1):NC_UART_IBL_CPU1_TXD
    U1 CV69 RSVD142 SOCKET4677_AZIF0045P001C01CS-SA     I5 @S9S_MB_2U_LIB.S9S_MB_2U(SCH_1):PAGE46

NC_USB_HUB_2_DM2 @S9S_MB_2U_LIB.S9S_MB_2U(SCH_1):NC_USB_HUB_2_DM2
  U313    6    DM2 GL852GOHY60-GL852G-OHY60,SMLF,B    I40 @S9S_MB_2U_LIB.S9S_MB_2U(SCH_1):PAGE194

NC_USB_HUB_2_DM3 @S9S_MB_2U_LIB.S9S_MB_2U(SCH_1):NC_USB_HUB_2_DM3
  U313   12    DM3 GL852GOHY60-GL852G-OHY60,SMLF,B    I40 @S9S_MB_2U_LIB.S9S_MB_2U(SCH_1):PAGE194

NC_USB_HUB_2_DM4 @S9S_MB_2U_LIB.S9S_MB_2U(SCH_1):NC_USB_HUB_2_DM4
  U313   15    DM4 GL852GOHY60-GL852G-OHY60,SMLF,B    I40 @S9S_MB_2U_LIB.S9S_MB_2U(SCH_1):PAGE194

NC_USB_HUB_2_DP2 @S9S_MB_2U_LIB.S9S_MB_2U(SCH_1):NC_USB_HUB_2_DP2
  U313    7    DP2 GL852GOHY60-GL852G-OHY60,SMLF,B    I40 @S9S_MB_2U_LIB.S9S_MB_2U(SCH_1):PAGE194

NC_USB_HUB_2_DP3 @S9S_MB_2U_LIB.S9S_MB_2U(SCH_1):NC_USB_HUB_2_DP3
  U313   13    DP3 GL852GOHY60-GL852G-OHY60,SMLF,B    I40 @S9S_MB_2U_LIB.S9S_MB_2U(SCH_1):PAGE194

NC_USB_HUB_2_DP4 @S9S_MB_2U_LIB.S9S_MB_2U(SCH_1):NC_USB_HUB_2_DP4
  U313   16    DP4 GL852GOHY60-GL852G-OHY60,SMLF,B    I40 @S9S_MB_2U_LIB.S9S_MB_2U(SCH_1):PAGE194

NC_USB_HUB_2_SDA @S9S_MB_2U_LIB.S9S_MB_2U(SCH_1):NC_USB_HUB_2_SDA
  U313   26    SDA GL852GOHY60-GL852G-OHY60,SMLF,B    I40 @S9S_MB_2U_LIB.S9S_MB_2U(SCH_1):PAGE194

NC_USB_HUB_DM2 @S9S_MB_2U_LIB.S9S_MB_2U(SCH_1):NC_USB_HUB_DM2
  U268    6    DM2 GL852GOHY60-GL852G-OHY60,SMLF,A   I100 @S9S_MB_2U_LIB.S9S_MB_2U(SCH_1):PAGE155

NC_USB_HUB_DM3 @S9S_MB_2U_LIB.S9S_MB_2U(SCH_1):NC_USB_HUB_DM3
  U268   12    DM3 GL852GOHY60-GL852G-OHY60,SMLF,A   I100 @S9S_MB_2U_LIB.S9S_MB_2U(SCH_1):PAGE155

NC_USB_HUB_DM4 @S9S_MB_2U_LIB.S9S_MB_2U(SCH_1):NC_USB_HUB_DM4
  U268   15    DM4 GL852GOHY60-GL852G-OHY60,SMLF,A   I100 @S9S_MB_2U_LIB.S9S_MB_2U(SCH_1):PAGE155

NC_USB_HUB_DP2 @S9S_MB_2U_LIB.S9S_MB_2U(SCH_1):NC_USB_HUB_DP2
  U268    7    DP2 GL852GOHY60-GL852G-OHY60,SMLF,A   I100 @S9S_MB_2U_LIB.S9S_MB_2U(SCH_1):PAGE155

NC_USB_HUB_DP3 @S9S_MB_2U_LIB.S9S_MB_2U(SCH_1):NC_USB_HUB_DP3
  U268   13    DP3 GL852GOHY60-GL852G-OHY60,SMLF,A   I100 @S9S_MB_2U_LIB.S9S_MB_2U(SCH_1):PAGE155

NC_USB_HUB_DP4 @S9S_MB_2U_LIB.S9S_MB_2U(SCH_1):NC_USB_HUB_DP4
  U268   16    DP4 GL852GOHY60-GL852G-OHY60,SMLF,A   I100 @S9S_MB_2U_LIB.S9S_MB_2U(SCH_1):PAGE155

NC_USB_HUB_SDA @S9S_MB_2U_LIB.S9S_MB_2U(SCH_1):NC_USB_HUB_SDA
  U268   26    SDA GL852GOHY60-GL852G-OHY60,SMLF,A   I100 @S9S_MB_2U_LIB.S9S_MB_2U(SCH_1):PAGE155

NC_UXX_2Y @S9S_MB_2U_LIB.S9S_MB_2U(SCH_1):NC_UXX_2Y
  U332    4     2Y 74LVC2G07DW7-74LVC2G07DW-7,SMLB    I37 @S9S_MB_2U_LIB.S9S_MB_2U(SCH_1):PAGE213

NC_XTAL_CPU0_25M_IN @S9S_MB_2U_LIB.S9S_MB_2U(SCH_1):NC_XTAL_CPU0_25M_IN
    U2   G5 RSVD161 SOCKET4677_AZIF0045P001C01CS-SA    I57 @S9S_MB_2U_LIB.S9S_MB_2U(SCH_1):PAGE13

NC_XTAL_CPU0_25M_OUT @S9S_MB_2U_LIB.S9S_MB_2U(SCH_1):NC_XTAL_CPU0_25M_OUT
    U2   D4 RSVD157 SOCKET4677_AZIF0045P001C01CS-SA    I57 @S9S_MB_2U_LIB.S9S_MB_2U(SCH_1):PAGE13

OCP_SFF_AUX_PWR_EN @S9S_MB_2U_LIB.S9S_MB_2U(SCH_1):OCP_SFF_AUX_PWR_EN
 R1929    2      B Q_RES_0402LF-10K,1%,1/16W,CHIPA    I37 @S9S_MB_2U_LIB.S9S_MB_2U(SCH_1):PAGE150
 R1671    1      A Q_RES_0402LF-0,5%,1/16W,CHIP,CA    I51 @S9S_MB_2U_LIB.S9S_MB_2U(SCH_1):PAGE150
 R3231    1      A Q_RES_0402LF-33.2,1%,1/16W,CHIA     I3 @S9S_MB_2U_LIB.S9S_MB_2U(SCH_1):PAGE151
 R1719    1      A Q_RES_0402LF-33.2,1%,1/16W,CHIA     I5 @S9S_MB_2U_LIB.S9S_MB_2U(SCH_1):PAGE151
 R4750    2      B Q_RES_0402LF-49.9,1%,1/16W,CHIA   I247 @S9S_MB_2U_LIB.S9S_MB_2U(SCH_1):PAGE154

OCP_SFF_AUX_PWR_EN_R @S9S_MB_2U_LIB.S9S_MB_2U(SCH_1):OCP_SFF_AUX_PWR_EN_R
 R1671    2      B Q_RES_0402LF-0,5%,1/16W,CHIP,CA    I51 @S9S_MB_2U_LIB.S9S_MB_2U(SCH_1):PAGE150
   J37  B12 AUX_PWR_EN SCONN168_ME1016810202011-SCONNA   I199 @S9S_MB_2U_LIB.S9S_MB_2U(SCH_1):PAGE150

OCP_SFF_AUX_PWR_EN_R1 @S9S_MB_2U_LIB.S9S_MB_2U(SCH_1):OCP_SFF_AUX_PWR_EN_R1
 R1719    2      B Q_RES_0402LF-33.2,1%,1/16W,CHIA     I5 @S9S_MB_2U_LIB.S9S_MB_2U(SCH_1):PAGE151
   U66    1     OE 74LVC1G126SE7-74LVC1G126SE-7,SA    I15 @S9S_MB_2U_LIB.S9S_MB_2U(SCH_1):PAGE151

OCP_SFF_AUX_PWR_EN_R2 @S9S_MB_2U_LIB.S9S_MB_2U(SCH_1):OCP_SFF_AUX_PWR_EN_R2
  U334    4      Y 74LVC1G08W57-74LVC1G08W5-7,SMLA   I243 @S9S_MB_2U_LIB.S9S_MB_2U(SCH_1):PAGE154
 R4750    1      A Q_RES_0402LF-49.9,1%,1/16W,CHIA   I247 @S9S_MB_2U_LIB.S9S_MB_2U(SCH_1):PAGE154
 R4748    2      B Q_RES_0402LF-0,5%,1/16W,EMPTY,A   I253 @S9S_MB_2U_LIB.S9S_MB_2U(SCH_1):PAGE154
 R4749    2      B Q_RES_0402LF-0,5%,1/16W,EMPTY,A   I254 @S9S_MB_2U_LIB.S9S_MB_2U(SCH_1):PAGE154

OCP_SFF_AUX_PWR_EN_R4 @S9S_MB_2U_LIB.S9S_MB_2U(SCH_1):OCP_SFF_AUX_PWR_EN_R4
 R3231    2      B Q_RES_0402LF-33.2,1%,1/16W,CHIA     I3 @S9S_MB_2U_LIB.S9S_MB_2U(SCH_1):PAGE151
  U224    1     OE 74LVC1G126SE7-74LVC1G126SE-7,SA     I7 @S9S_MB_2U_LIB.S9S_MB_2U(SCH_1):PAGE151

OCP_SFF_AUX_PWR_PLD_EN @S9S_MB_2U_LIB.S9S_MB_2U(SCH_1):OCP_SFF_AUX_PWR_PLD_EN
  U249   E7  PT13D LCMXO3LF9400C5BG484C-LCMXO3LF-A   I188 @S9S_MB_2U_LIB.S9S_MB_2U(SCH_1):PAGE314
 R4747    1      A Q_RES_0402LF-33.2,1%,1/16W,CHIA   I249 @S9S_MB_2U_LIB.S9S_MB_2U(SCH_1):PAGE154

OCP_SFF_AUX_PWR_PLD_EN_R @S9S_MB_2U_LIB.S9S_MB_2U(SCH_1):OCP_SFF_AUX_PWR_PLD_EN_R
  U334    2      B 74LVC1G08W57-74LVC1G08W5-7,SMLA   I243 @S9S_MB_2U_LIB.S9S_MB_2U(SCH_1):PAGE154
 R4747    2      B Q_RES_0402LF-33.2,1%,1/16W,CHIA   I249 @S9S_MB_2U_LIB.S9S_MB_2U(SCH_1):PAGE154
 R4749    1      A Q_RES_0402LF-0,5%,1/16W,EMPTY,A   I254 @S9S_MB_2U_LIB.S9S_MB_2U(SCH_1):PAGE154
 R4745    2      B Q_RES_0402LF-10K,1%,1/16W,CHIPA   I256 @S9S_MB_2U_LIB.S9S_MB_2U(SCH_1):PAGE154

OCP_SFF_BIF0_R_N @S9S_MB_2U_LIB.S9S_MB_2U(SCH_1):OCP_SFF_BIF0_R_N
  R416    2      B Q_RES_0402LF-0,5%,1/16W,CHIP,CA    I54 @S9S_MB_2U_LIB.S9S_MB_2U(SCH_1):PAGE150
   J37   B7  BIF0# SCONN168_ME1016810202011-SCONNA   I199 @S9S_MB_2U_LIB.S9S_MB_2U(SCH_1):PAGE150

OCP_SFF_BIF1_R_N @S9S_MB_2U_LIB.S9S_MB_2U(SCH_1):OCP_SFF_BIF1_R_N
  R417    2      B Q_RES_0402LF-0,5%,1/16W,CHIP,CA    I53 @S9S_MB_2U_LIB.S9S_MB_2U(SCH_1):PAGE150
   J37   B8  BIF1# SCONN168_ME1016810202011-SCONNA   I199 @S9S_MB_2U_LIB.S9S_MB_2U(SCH_1):PAGE150

OCP_SFF_BIF2_R_N @S9S_MB_2U_LIB.S9S_MB_2U(SCH_1):OCP_SFF_BIF2_R_N
  R418    2      B Q_RES_0402LF-0,5%,1/16W,CHIP,CA    I52 @S9S_MB_2U_LIB.S9S_MB_2U(SCH_1):PAGE150
   J37   B9  BIF2# SCONN168_ME1016810202011-SCONNA   I199 @S9S_MB_2U_LIB.S9S_MB_2U(SCH_1):PAGE150

OCP_SFF_CLK_OE_N @S9S_MB_2U_LIB.S9S_MB_2U(SCH_1):OCP_SFF_CLK_OE_N
 R1543    1      A Q_RES_0402LF-0,5%,1/16W,CHIP,CA   I534 @S9S_MB_2U_LIB.S9S_MB_2U(SCH_1):PAGE195
 R2562    1      A Q_RES_0402LF-0,5%,1/16W,CHIP,CA   I535 @S9S_MB_2U_LIB.S9S_MB_2U(SCH_1):PAGE195
 R3636    1      A Q_RES_0402LF-0,5%,1/16W,CHIP,CA   I536 @S9S_MB_2U_LIB.S9S_MB_2U(SCH_1):PAGE195
 R3637    1      A Q_RES_0402LF-0,5%,1/16W,CHIP,CA   I537 @S9S_MB_2U_LIB.S9S_MB_2U(SCH_1):PAGE195
 R4517    2      B Q_RES_0402LF-10K,1%,1/16W,CHIPA   I540 @S9S_MB_2U_LIB.S9S_MB_2U(SCH_1):PAGE195
 R4495    2      B Q_RES_0402LF-33.2,1%,1/16W,CHIA   I141 @S9S_MB_2U_LIB.S9S_MB_2U(SCH_1):PAGE314

OCP_SFF_CLK_OE_R_N @S9S_MB_2U_LIB.S9S_MB_2U(SCH_1):OCP_SFF_CLK_OE_R_N
 R4495    1      A Q_RES_0402LF-33.2,1%,1/16W,CHIA   I141 @S9S_MB_2U_LIB.S9S_MB_2U(SCH_1):PAGE314
  U249   C8  PT15A LCMXO3LF9400C5BG484C-LCMXO3LF-A   I188 @S9S_MB_2U_LIB.S9S_MB_2U(SCH_1):PAGE314

OCP_SFF_ID0 @S9S_MB_2U_LIB.S9S_MB_2U(SCH_1):OCP_SFF_ID0
  R410    1      A Q_RES_0402LF-4.7K,1%,1/16W,CHIA     I2 @S9S_MB_2U_LIB.S9S_MB_2U(SCH_1):PAGE150
  R409    2      B Q_RES_0402LF-4.7K,1%,1/16W,EMPA     I5 @S9S_MB_2U_LIB.S9S_MB_2U(SCH_1):PAGE150
   J37  OB7 SLOT_ID0 SCONN168_ME1016810202011-SCONNA   I199 @S9S_MB_2U_LIB.S9S_MB_2U(SCH_1):PAGE150

OCP_SFF_ID1 @S9S_MB_2U_LIB.S9S_MB_2U(SCH_1):OCP_SFF_ID1
  R415    1      A Q_RES_0402LF-4.7K,1%,1/16W,CHIA     I4 @S9S_MB_2U_LIB.S9S_MB_2U(SCH_1):PAGE150
  R414    2      B Q_RES_0402LF-4.7K,1%,1/16W,EMPA     I6 @S9S_MB_2U_LIB.S9S_MB_2U(SCH_1):PAGE150
   J37  OA6 SLOT_ID1 SCONN168_ME1016810202011-SCONNA   I199 @S9S_MB_2U_LIB.S9S_MB_2U(SCH_1):PAGE150

OCP_SFF_ISO1_RBT_ARB_IN @S9S_MB_2U_LIB.S9S_MB_2U(SCH_1):OCP_SFF_ISO1_RBT_ARB_IN
   J37  OA4 RBT_ARB_IN SCONN168_ME1016810202011-SCONNA   I199 @S9S_MB_2U_LIB.S9S_MB_2U(SCH_1):PAGE150
   U67   11     4B 74CBTLV3126PW-74CBTLV3126PW,SMA    I39 @S9S_MB_2U_LIB.S9S_MB_2U(SCH_1):PAGE151

OCP_SFF_ISO2_RBT_ARB_OUT @S9S_MB_2U_LIB.S9S_MB_2U(SCH_1):OCP_SFF_ISO2_RBT_ARB_OUT
   J37  OA5 RBT_ARB_OUT SCONN168_ME1016810202011-SCONNA   I199 @S9S_MB_2U_LIB.S9S_MB_2U(SCH_1):PAGE150
   U68   11     4B 74CBTLV3126PW-74CBTLV3126PW,SMA    I30 @S9S_MB_2U_LIB.S9S_MB_2U(SCH_1):PAGE151

OCP_SFF_ISO_BIF0_EN @S9S_MB_2U_LIB.S9S_MB_2U(SCH_1):OCP_SFF_ISO_BIF0_EN
  R416    1      A Q_RES_0402LF-0,5%,1/16W,CHIP,CA    I54 @S9S_MB_2U_LIB.S9S_MB_2U(SCH_1):PAGE150
 R1896    1      A Q_RES_0402LF-100,1%,1/16W,CHIPA    I43 @S9S_MB_2U_LIB.S9S_MB_2U(SCH_1):PAGE151

OCP_SFF_ISO_BIF1_EN @S9S_MB_2U_LIB.S9S_MB_2U(SCH_1):OCP_SFF_ISO_BIF1_EN
  R417    1      A Q_RES_0402LF-0,5%,1/16W,CHIP,CA    I53 @S9S_MB_2U_LIB.S9S_MB_2U(SCH_1):PAGE150
 R1897    1      A Q_RES_0402LF-100,1%,1/16W,CHIPA    I50 @S9S_MB_2U_LIB.S9S_MB_2U(SCH_1):PAGE151

OCP_SFF_ISO_BIF2_EN @S9S_MB_2U_LIB.S9S_MB_2U(SCH_1):OCP_SFF_ISO_BIF2_EN
  R418    1      A Q_RES_0402LF-0,5%,1/16W,CHIP,CA    I52 @S9S_MB_2U_LIB.S9S_MB_2U(SCH_1):PAGE150
 R1898    1      A Q_RES_0402LF-100,1%,1/16W,CHIPA    I52 @S9S_MB_2U_LIB.S9S_MB_2U(SCH_1):PAGE151

OCP_SFF_MAIN_PWR_EN @S9S_MB_2U_LIB.S9S_MB_2U(SCH_1):OCP_SFF_MAIN_PWR_EN
 R1930    2      B Q_RES_0402LF-10K,1%,1/16W,CHIPA    I36 @S9S_MB_2U_LIB.S9S_MB_2U(SCH_1):PAGE150
  R429    1      A Q_RES_0402LF-0,5%,1/16W,CHIP,CA    I58 @S9S_MB_2U_LIB.S9S_MB_2U(SCH_1):PAGE150
  U249  T18  PR27B LCMXO3LF9400C5BG484C-LCMXO3LF-A     I1 @S9S_MB_2U_LIB.S9S_MB_2U(SCH_1):PAGE313

OCP_SFF_MAIN_PWR_EN_R @S9S_MB_2U_LIB.S9S_MB_2U(SCH_1):OCP_SFF_MAIN_PWR_EN_R
  R429    2      B Q_RES_0402LF-0,5%,1/16W,CHIP,CA    I58 @S9S_MB_2U_LIB.S9S_MB_2U(SCH_1):PAGE150
   J37  OB2 MAIN_PWR_EN SCONN168_ME1016810202011-SCONNA   I199 @S9S_MB_2U_LIB.S9S_MB_2U(SCH_1):PAGE150

OCP_SFF_NOT_PRSNT_RBT_ARB_IN @S9S_MB_2U_LIB.S9S_MB_2U(SCH_1):OCP_SFF_NOT_PRSNT_RBT_ARB_IN
  U243    1     B1 NC7SB3157_SMLF-NC7SB3157P6X,NCB    I15 @S9S_MB_2U_LIB.S9S_MB_2U(SCH_1):PAGE170
  U244    1     B1 NC7SB3157_SMLF-NC7SB3157P6X,NCB    I16 @S9S_MB_2U_LIB.S9S_MB_2U(SCH_1):PAGE170

OCP_SFF_P3V3_ADC_ALERT @S9S_MB_2U_LIB.S9S_MB_2U(SCH_1):OCP_SFF_P3V3_ADC_ALERT
  U249  K20  PR12D LCMXO3LF9400C5BG484C-LCMXO3LF-A     I1 @S9S_MB_2U_LIB.S9S_MB_2U(SCH_1):PAGE313
 R3563    2      B Q_RES_0402LF-0,5%,1/16W,CHIP,CA    I35 @S9S_MB_2U_LIB.S9S_MB_2U(SCH_1):PAGE295

OCP_SFF_P3V3_ADC_ALERT_R @S9S_MB_2U_LIB.S9S_MB_2U(SCH_1):OCP_SFF_P3V3_ADC_ALERT_R
  U266    3  ALERT INA230AIRGTR-INA230AIRGTR,SMLFB    I30 @S9S_MB_2U_LIB.S9S_MB_2U(SCH_1):PAGE295
 R3563    1      A Q_RES_0402LF-0,5%,1/16W,CHIP,CA    I35 @S9S_MB_2U_LIB.S9S_MB_2U(SCH_1):PAGE295
 R4094    2      B Q_RES_0402LF-4.7K,1%,1/16W,CHIA   I151 @S9S_MB_2U_LIB.S9S_MB_2U(SCH_1):PAGE295

OCP_SFF_PRSNT01_R_N @S9S_MB_2U_LIB.S9S_MB_2U(SCH_1):OCP_SFF_PRSNT01_R_N
  U240    7     1Y 74LVC2G08DP-74LVC2G08DP,SMLF,IA    I11 @S9S_MB_2U_LIB.S9S_MB_2U(SCH_1):PAGE170
  U242    1     1A 74LVC2G08DP-74LVC2G08DP,SMLF,IA    I13 @S9S_MB_2U_LIB.S9S_MB_2U(SCH_1):PAGE170

OCP_SFF_PRSNT0_R_N @S9S_MB_2U_LIB.S9S_MB_2U(SCH_1):OCP_SFF_PRSNT0_R_N
  U240    1     1A 74LVC2G08DP-74LVC2G08DP,SMLF,IA    I11 @S9S_MB_2U_LIB.S9S_MB_2U(SCH_1):PAGE170
   J37  B42 PRSNTB0# SCONN168_ME1016810202011-SCONNA   I199 @S9S_MB_2U_LIB.S9S_MB_2U(SCH_1):PAGE150
  U211    1     1A 74LVC2G07DW7-74LVC2G07DW-7,SMLA    I26 @S9S_MB_2U_LIB.S9S_MB_2U(SCH_1):PAGE153
 R1905    2      B Q_RES_0402LF-1K,1%,1/16W,CHIP,A    I13 @S9S_MB_2U_LIB.S9S_MB_2U(SCH_1):PAGE153

OCP_SFF_PRSNT1_R_N @S9S_MB_2U_LIB.S9S_MB_2U(SCH_1):OCP_SFF_PRSNT1_R_N
  U240    2     1B 74LVC2G08DP-74LVC2G08DP,SMLF,IA    I11 @S9S_MB_2U_LIB.S9S_MB_2U(SCH_1):PAGE170
   J37  A42 PRSNTB1# SCONN168_ME1016810202011-SCONNA   I199 @S9S_MB_2U_LIB.S9S_MB_2U(SCH_1):PAGE150
  U211    3     2A 74LVC2G07DW7-74LVC2G07DW-7,SMLA    I26 @S9S_MB_2U_LIB.S9S_MB_2U(SCH_1):PAGE153
 R1907    2      B Q_RES_0402LF-1K,1%,1/16W,CHIP,A    I25 @S9S_MB_2U_LIB.S9S_MB_2U(SCH_1):PAGE153

OCP_SFF_PRSNT23_R_N @S9S_MB_2U_LIB.S9S_MB_2U(SCH_1):OCP_SFF_PRSNT23_R_N
  U240    3     2Y 74LVC2G08DP-74LVC2G08DP,SMLF,IA    I12 @S9S_MB_2U_LIB.S9S_MB_2U(SCH_1):PAGE170
  U242    2     1B 74LVC2G08DP-74LVC2G08DP,SMLF,IA    I13 @S9S_MB_2U_LIB.S9S_MB_2U(SCH_1):PAGE170

OCP_SFF_PRSNT2_R_N @S9S_MB_2U_LIB.S9S_MB_2U(SCH_1):OCP_SFF_PRSNT2_R_N
  U240    5     2A 74LVC2G08DP-74LVC2G08DP,SMLF,IA    I12 @S9S_MB_2U_LIB.S9S_MB_2U(SCH_1):PAGE170
   J37  A12 PRSNTB2# SCONN168_ME1016810202011-SCONNA   I199 @S9S_MB_2U_LIB.S9S_MB_2U(SCH_1):PAGE150
  U212    1     1A 74LVC2G07DW7-74LVC2G07DW-7,SMLA    I23 @S9S_MB_2U_LIB.S9S_MB_2U(SCH_1):PAGE153
 R1906    2      B Q_RES_0402LF-1K,1%,1/16W,CHIP,A     I7 @S9S_MB_2U_LIB.S9S_MB_2U(SCH_1):PAGE153

OCP_SFF_PRSNT3_R_N @S9S_MB_2U_LIB.S9S_MB_2U(SCH_1):OCP_SFF_PRSNT3_R_N
  U240    6     2B 74LVC2G08DP-74LVC2G08DP,SMLF,IA    I12 @S9S_MB_2U_LIB.S9S_MB_2U(SCH_1):PAGE170
   J37  B70 PRSNTB3# SCONN168_ME1016810202011-SCONNA   I199 @S9S_MB_2U_LIB.S9S_MB_2U(SCH_1):PAGE150
 R1908    2      B Q_RES_0402LF-1K,1%,1/16W,CHIP,A    I22 @S9S_MB_2U_LIB.S9S_MB_2U(SCH_1):PAGE153
  U212    3     2A 74LVC2G07DW7-74LVC2G07DW-7,SMLA    I23 @S9S_MB_2U_LIB.S9S_MB_2U(SCH_1):PAGE153

OCP_SFF_PRSNTA_R_N @S9S_MB_2U_LIB.S9S_MB_2U(SCH_1):OCP_SFF_PRSNTA_R_N
 R1895    1      A Q_RES_0402LF-100,1%,1/16W,CHIPA   I149 @S9S_MB_2U_LIB.S9S_MB_2U(SCH_1):PAGE150
   J37  A10 PRSNTA# SCONN168_ME1016810202011-SCONNA   I199 @S9S_MB_2U_LIB.S9S_MB_2U(SCH_1):PAGE150

OCP_SFF_PRSNT_ALL_R1_N @S9S_MB_2U_LIB.S9S_MB_2U(SCH_1):OCP_SFF_PRSNT_ALL_R1_N
  U243    6      S NC7SB3157_SMLF-NC7SB3157P6X,NCB    I15 @S9S_MB_2U_LIB.S9S_MB_2U(SCH_1):PAGE170
 R3303    2      B Q_RES_0402LF-0,5%,1/16W,CHIP,CA    I44 @S9S_MB_2U_LIB.S9S_MB_2U(SCH_1):PAGE170

OCP_SFF_PRSNT_ALL_R3_N @S9S_MB_2U_LIB.S9S_MB_2U(SCH_1):OCP_SFF_PRSNT_ALL_R3_N
  U244    6      S NC7SB3157_SMLF-NC7SB3157P6X,NCB    I16 @S9S_MB_2U_LIB.S9S_MB_2U(SCH_1):PAGE170
 R3304    2      B Q_RES_0402LF-0,5%,1/16W,CHIP,CA    I45 @S9S_MB_2U_LIB.S9S_MB_2U(SCH_1):PAGE170

OCP_SFF_PRSNT_ALL_R_N @S9S_MB_2U_LIB.S9S_MB_2U(SCH_1):OCP_SFF_PRSNT_ALL_R_N
  U242    7     1Y 74LVC2G08DP-74LVC2G08DP,SMLF,IA    I13 @S9S_MB_2U_LIB.S9S_MB_2U(SCH_1):PAGE170
 R3303    1      A Q_RES_0402LF-0,5%,1/16W,CHIP,CA    I44 @S9S_MB_2U_LIB.S9S_MB_2U(SCH_1):PAGE170
 R3304    1      A Q_RES_0402LF-0,5%,1/16W,CHIP,CA    I45 @S9S_MB_2U_LIB.S9S_MB_2U(SCH_1):PAGE170

OCP_SFF_PWRBRK_BUFF_N @S9S_MB_2U_LIB.S9S_MB_2U(SCH_1):OCP_SFF_PWRBRK_BUFF_N
 R1595    1      A Q_RES_0402LF-33.2,1%,1/16W,CHIA    I40 @S9S_MB_2U_LIB.S9S_MB_2U(SCH_1):PAGE152
 R1593    2      B Q_RES_0402LF-4.7K,1%,1/16W,CHIA    I42 @S9S_MB_2U_LIB.S9S_MB_2U(SCH_1):PAGE152
  U104    4      Y 74LVC1G07GV-74LVC1G07GV,SMLF,IA    I63 @S9S_MB_2U_LIB.S9S_MB_2U(SCH_1):PAGE152

OCP_SFF_PWRBRK_N @S9S_MB_2U_LIB.S9S_MB_2U(SCH_1):OCP_SFF_PWRBRK_N
 R1595    2      B Q_RES_0402LF-33.2,1%,1/16W,CHIA    I40 @S9S_MB_2U_LIB.S9S_MB_2U(SCH_1):PAGE152
   J37  A70 PWRBRK0# SCONN168_ME1016810202011-SCONNA   I199 @S9S_MB_2U_LIB.S9S_MB_2U(SCH_1):PAGE150

OCP_SFF_RBT_ARB_IN @S9S_MB_2U_LIB.S9S_MB_2U(SCH_1):OCP_SFF_RBT_ARB_IN
  U244    3     B0 NC7SB3157_SMLF-NC7SB3157P6X,NCB    I16 @S9S_MB_2U_LIB.S9S_MB_2U(SCH_1):PAGE170
 R1290    2      B Q_RES_0402LF-22,1%,1/16W,EMPTYA    I81 @S9S_MB_2U_LIB.S9S_MB_2U(SCH_1):PAGE151

OCP_SFF_RBT_ARB_IN_MUX1 @S9S_MB_2U_LIB.S9S_MB_2U(SCH_1):OCP_SFF_RBT_ARB_IN_MUX1
  U246    4      A NC7SB3157_SMLF-NC7SB3157P6X,NCB    I17 @S9S_MB_2U_LIB.S9S_MB_2U(SCH_1):PAGE170
 R3305    1      A Q_RES_0402LF-0,5%,1/16W,CHIP,CA    I50 @S9S_MB_2U_LIB.S9S_MB_2U(SCH_1):PAGE170

OCP_SFF_RBT_ARB_IN_MUX1_R @S9S_MB_2U_LIB.S9S_MB_2U(SCH_1):OCP_SFF_RBT_ARB_IN_MUX1_R
  U244    4      A NC7SB3157_SMLF-NC7SB3157P6X,NCB    I16 @S9S_MB_2U_LIB.S9S_MB_2U(SCH_1):PAGE170
 R3305    2      B Q_RES_0402LF-0,5%,1/16W,CHIP,CA    I50 @S9S_MB_2U_LIB.S9S_MB_2U(SCH_1):PAGE170

OCP_SFF_RBT_ARB_IN_MUX2 @S9S_MB_2U_LIB.S9S_MB_2U(SCH_1):OCP_SFF_RBT_ARB_IN_MUX2
  U243    4      A NC7SB3157_SMLF-NC7SB3157P6X,NCB    I15 @S9S_MB_2U_LIB.S9S_MB_2U(SCH_1):PAGE170
 R3307    1      A Q_RES_0402LF-0,5%,1/16W,CHIP,CA    I52 @S9S_MB_2U_LIB.S9S_MB_2U(SCH_1):PAGE170

OCP_SFF_RBT_ARB_IN_MUX2_R @S9S_MB_2U_LIB.S9S_MB_2U(SCH_1):OCP_SFF_RBT_ARB_IN_MUX2_R
  U245    4      A NC7SB3157_SMLF-NC7SB3157P6X,NCB    I18 @S9S_MB_2U_LIB.S9S_MB_2U(SCH_1):PAGE170
 R3307    2      B Q_RES_0402LF-0,5%,1/16W,CHIP,CA    I52 @S9S_MB_2U_LIB.S9S_MB_2U(SCH_1):PAGE170

OCP_SFF_RBT_ARB_IN_R @S9S_MB_2U_LIB.S9S_MB_2U(SCH_1):OCP_SFF_RBT_ARB_IN_R
   U67   12     4A 74CBTLV3126PW-74CBTLV3126PW,SMA    I39 @S9S_MB_2U_LIB.S9S_MB_2U(SCH_1):PAGE151
 R3237    2      B Q_RES_0402LF-0,5%,1/16W,CHIP,CA    I80 @S9S_MB_2U_LIB.S9S_MB_2U(SCH_1):PAGE151
 R1290    1      A Q_RES_0402LF-22,1%,1/16W,EMPTYA    I81 @S9S_MB_2U_LIB.S9S_MB_2U(SCH_1):PAGE151

OCP_SFF_RBT_ARB_OUT @S9S_MB_2U_LIB.S9S_MB_2U(SCH_1):OCP_SFF_RBT_ARB_OUT
  U243    3     B0 NC7SB3157_SMLF-NC7SB3157P6X,NCB    I15 @S9S_MB_2U_LIB.S9S_MB_2U(SCH_1):PAGE170
   U68   12     4A 74CBTLV3126PW-74CBTLV3126PW,SMA    I30 @S9S_MB_2U_LIB.S9S_MB_2U(SCH_1):PAGE151
 R3237    1      A Q_RES_0402LF-0,5%,1/16W,CHIP,CA    I80 @S9S_MB_2U_LIB.S9S_MB_2U(SCH_1):PAGE151

OCP_SFF_USB2_3_DN @S9S_MB_2U_LIB.S9S_MB_2U(SCH_1):OCP_SFF_USB2_3_DN
  R444    1      A Q_RES_0402LF-0,5%,1/16W,CHIP,CA   I118 @S9S_MB_2U_LIB.S9S_MB_2U(SCH_1):PAGE150
   J37  A68 USB_DATN SCONN168_ME1016810202011-SCONNA   I199 @S9S_MB_2U_LIB.S9S_MB_2U(SCH_1):PAGE150

OCP_SFF_USB2_3_DP @S9S_MB_2U_LIB.S9S_MB_2U(SCH_1):OCP_SFF_USB2_3_DP
  R445    1      A Q_RES_0402LF-0,5%,1/16W,CHIP,CA   I119 @S9S_MB_2U_LIB.S9S_MB_2U(SCH_1):PAGE150
   J37  A69 USB_DATP SCONN168_ME1016810202011-SCONNA   I199 @S9S_MB_2U_LIB.S9S_MB_2U(SCH_1):PAGE150

OCP_SFF_WAKE_BUFF_N @S9S_MB_2U_LIB.S9S_MB_2U(SCH_1):OCP_SFF_WAKE_BUFF_N
 R1594    1      A Q_RES_0402LF-33.2,1%,1/16W,CHIA    I26 @S9S_MB_2U_LIB.S9S_MB_2U(SCH_1):PAGE152
 R2488    2      B Q_RES_0402LF-4.7K,1%,1/16W,CHIA    I74 @S9S_MB_2U_LIB.S9S_MB_2U(SCH_1):PAGE152
   U82    4      Y 74LVC1G126SE7-74LVC1G126SE-7,SA    I79 @S9S_MB_2U_LIB.S9S_MB_2U(SCH_1):PAGE152

OCP_SFF_WAKE_BUFF_R_N @S9S_MB_2U_LIB.S9S_MB_2U(SCH_1):OCP_SFF_WAKE_BUFF_R_N
 R1594    2      B Q_RES_0402LF-33.2,1%,1/16W,CHIA    I26 @S9S_MB_2U_LIB.S9S_MB_2U(SCH_1):PAGE152
  U157    2      A 74LVC1G07GV-74LVC1G07GV,SMLF,IA    I65 @S9S_MB_2U_LIB.S9S_MB_2U(SCH_1):PAGE152

OCP_V3_1_P3V3_PWRGD @S9S_MB_2U_LIB.S9S_MB_2U(SCH_1):OCP_V3_1_P3V3_PWRGD
 R3794    2      B Q_RES_0402LF-0,5%,1/16W,CHIP,CA   I105 @S9S_MB_2U_LIB.S9S_MB_2U(SCH_1):PAGE153
 R4613    1      A Q_RES_0402LF-0,5%,1/16W,EMPTY,A   I232 @S9S_MB_2U_LIB.S9S_MB_2U(SCH_1):PAGE154
 R3783    2      B Q_RES_0402LF-100K,1%,1/16W,CHIA   I110 @S9S_MB_2U_LIB.S9S_MB_2U(SCH_1):PAGE153

OCP_V3_1_PRSNTA_R_N @S9S_MB_2U_LIB.S9S_MB_2U(SCH_1):OCP_V3_1_PRSNTA_R_N
 R3180    1      A Q_RES_0402LF-100,1%,1/16W,CHIPA   I152 @S9S_MB_2U_LIB.S9S_MB_2U(SCH_1):PAGE146
   J35  A10 PRSNTA# SCONN168_ME1016810202011-SCONNA   I303 @S9S_MB_2U_LIB.S9S_MB_2U(SCH_1):PAGE146

OCP_V3_2_AUX_PWR_EN @S9S_MB_2U_LIB.S9S_MB_2U(SCH_1):OCP_V3_2_AUX_PWR_EN
 R3172    1      A Q_RES_0402LF-0,5%,1/16W,CHIP,CA    I36 @S9S_MB_2U_LIB.S9S_MB_2U(SCH_1):PAGE146
 R3164    2      B Q_RES_0402LF-10K,1%,1/16W,CHIPA    I38 @S9S_MB_2U_LIB.S9S_MB_2U(SCH_1):PAGE146
 R3203    1      A Q_RES_0402LF-33.2,1%,1/16W,CHIA    I81 @S9S_MB_2U_LIB.S9S_MB_2U(SCH_1):PAGE307
 R3234    1      A Q_RES_0402LF-33.2,1%,1/16W,CHIA    I75 @S9S_MB_2U_LIB.S9S_MB_2U(SCH_1):PAGE156
 R4759    2      B Q_RES_0402LF-49.9,1%,1/16W,CHIA   I111 @S9S_MB_2U_LIB.S9S_MB_2U(SCH_1):PAGE132

OCP_V3_2_AUX_PWR_EN_R @S9S_MB_2U_LIB.S9S_MB_2U(SCH_1):OCP_V3_2_AUX_PWR_EN_R
 R3172    2      B Q_RES_0402LF-0,5%,1/16W,CHIP,CA    I36 @S9S_MB_2U_LIB.S9S_MB_2U(SCH_1):PAGE146
   J35  B12 AUX_PWR_EN SCONN168_ME1016810202011-SCONNA   I303 @S9S_MB_2U_LIB.S9S_MB_2U(SCH_1):PAGE146

OCP_V3_2_AUX_PWR_EN_R1 @S9S_MB_2U_LIB.S9S_MB_2U(SCH_1):OCP_V3_2_AUX_PWR_EN_R1
  U286    1     OE 74LVC1G126SE7-74LVC1G126SE-7,SA    I80 @S9S_MB_2U_LIB.S9S_MB_2U(SCH_1):PAGE307
 R3203    2      B Q_RES_0402LF-33.2,1%,1/16W,CHIA    I81 @S9S_MB_2U_LIB.S9S_MB_2U(SCH_1):PAGE307

OCP_V3_2_AUX_PWR_EN_R2 @S9S_MB_2U_LIB.S9S_MB_2U(SCH_1):OCP_V3_2_AUX_PWR_EN_R2
 R4758    2      B Q_RES_0402LF-0,5%,1/16W,EMPTY,A   I107 @S9S_MB_2U_LIB.S9S_MB_2U(SCH_1):PAGE132
  U335    4      Y 74LVC1G08W57-74LVC1G08W5-7,SMLA   I108 @S9S_MB_2U_LIB.S9S_MB_2U(SCH_1):PAGE132
 R4759    1      A Q_RES_0402LF-49.9,1%,1/16W,CHIA   I111 @S9S_MB_2U_LIB.S9S_MB_2U(SCH_1):PAGE132
 R4757    2      B Q_RES_0402LF-0,5%,1/16W,EMPTY,A   I112 @S9S_MB_2U_LIB.S9S_MB_2U(SCH_1):PAGE132

OCP_V3_2_AUX_PWR_EN_R3 @S9S_MB_2U_LIB.S9S_MB_2U(SCH_1):OCP_V3_2_AUX_PWR_EN_R3
  U225    1     OE 74LVC1G126SE7-74LVC1G126SE-7,SA    I74 @S9S_MB_2U_LIB.S9S_MB_2U(SCH_1):PAGE156
 R3234    2      B Q_RES_0402LF-33.2,1%,1/16W,CHIA    I75 @S9S_MB_2U_LIB.S9S_MB_2U(SCH_1):PAGE156

OCP_V3_2_AUX_PWR_PLD_EN @S9S_MB_2U_LIB.S9S_MB_2U(SCH_1):OCP_V3_2_AUX_PWR_PLD_EN
  U249   D6  PT13C LCMXO3LF9400C5BG484C-LCMXO3LF-A   I188 @S9S_MB_2U_LIB.S9S_MB_2U(SCH_1):PAGE314
 R4755    1      A Q_RES_0402LF-33.2,1%,1/16W,CHIA   I103 @S9S_MB_2U_LIB.S9S_MB_2U(SCH_1):PAGE132

OCP_V3_2_AUX_PWR_PLD_EN_R @S9S_MB_2U_LIB.S9S_MB_2U(SCH_1):OCP_V3_2_AUX_PWR_PLD_EN_R
 R4755    2      B Q_RES_0402LF-33.2,1%,1/16W,CHIA   I103 @S9S_MB_2U_LIB.S9S_MB_2U(SCH_1):PAGE132
 R4756    2      B Q_RES_0402LF-10K,1%,1/16W,CHIPA   I105 @S9S_MB_2U_LIB.S9S_MB_2U(SCH_1):PAGE132
 R4758    1      A Q_RES_0402LF-0,5%,1/16W,EMPTY,A   I107 @S9S_MB_2U_LIB.S9S_MB_2U(SCH_1):PAGE132
  U335    2      B 74LVC1G08W57-74LVC1G08W5-7,SMLA   I108 @S9S_MB_2U_LIB.S9S_MB_2U(SCH_1):PAGE132

OCP_V3_2_BIF0_R_N @S9S_MB_2U_LIB.S9S_MB_2U(SCH_1):OCP_V3_2_BIF0_R_N
 R3169    2      B Q_RES_0402LF-0,5%,1/16W,CHIP,CA    I33 @S9S_MB_2U_LIB.S9S_MB_2U(SCH_1):PAGE146
   J35   B7  BIF0# SCONN168_ME1016810202011-SCONNA   I303 @S9S_MB_2U_LIB.S9S_MB_2U(SCH_1):PAGE146

OCP_V3_2_BIF1_R_N @S9S_MB_2U_LIB.S9S_MB_2U(SCH_1):OCP_V3_2_BIF1_R_N
 R3170    2      B Q_RES_0402LF-0,5%,1/16W,CHIP,CA    I32 @S9S_MB_2U_LIB.S9S_MB_2U(SCH_1):PAGE146
   J35   B8  BIF1# SCONN168_ME1016810202011-SCONNA   I303 @S9S_MB_2U_LIB.S9S_MB_2U(SCH_1):PAGE146

OCP_V3_2_BIF2_R_N @S9S_MB_2U_LIB.S9S_MB_2U(SCH_1):OCP_V3_2_BIF2_R_N
 R3171    2      B Q_RES_0402LF-0,5%,1/16W,CHIP,CA    I31 @S9S_MB_2U_LIB.S9S_MB_2U(SCH_1):PAGE146
   J35   B9  BIF2# SCONN168_ME1016810202011-SCONNA   I303 @S9S_MB_2U_LIB.S9S_MB_2U(SCH_1):PAGE146

OCP_V3_2_ID0 @S9S_MB_2U_LIB.S9S_MB_2U(SCH_1):OCP_V3_2_ID0
 R3163    1      A Q_RES_0402LF-4.7K,1%,1/16W,EMPA    I25 @S9S_MB_2U_LIB.S9S_MB_2U(SCH_1):PAGE146
 R3162    2      B Q_RES_0402LF-4.7K,1%,1/16W,CHIA    I26 @S9S_MB_2U_LIB.S9S_MB_2U(SCH_1):PAGE146
   J35  OB7 SLOT_ID0 SCONN168_ME1016810202011-SCONNA   I303 @S9S_MB_2U_LIB.S9S_MB_2U(SCH_1):PAGE146

OCP_V3_2_ID1 @S9S_MB_2U_LIB.S9S_MB_2U(SCH_1):OCP_V3_2_ID1
 R3167    1      A Q_RES_0402LF-4.7K,1%,1/16W,CHIA    I20 @S9S_MB_2U_LIB.S9S_MB_2U(SCH_1):PAGE146
 R3166    2      B Q_RES_0402LF-4.7K,1%,1/16W,EMPA    I23 @S9S_MB_2U_LIB.S9S_MB_2U(SCH_1):PAGE146
   J35  OA6 SLOT_ID1 SCONN168_ME1016810202011-SCONNA   I303 @S9S_MB_2U_LIB.S9S_MB_2U(SCH_1):PAGE146

OCP_V3_2_ISO1_RBT_ARB_IN @S9S_MB_2U_LIB.S9S_MB_2U(SCH_1):OCP_V3_2_ISO1_RBT_ARB_IN
  U222   11     4B 74CBTLV3126PW-74CBTLV3126PW,SMA    I32 @S9S_MB_2U_LIB.S9S_MB_2U(SCH_1):PAGE307
   J35  OA4 RBT_ARB_IN SCONN168_ME1016810202011-SCONNA   I303 @S9S_MB_2U_LIB.S9S_MB_2U(SCH_1):PAGE146

OCP_V3_2_ISO2_RBT_ARB_OUT @S9S_MB_2U_LIB.S9S_MB_2U(SCH_1):OCP_V3_2_ISO2_RBT_ARB_OUT
  U223   11     4B 74CBTLV3126PW-74CBTLV3126PW,SMA    I78 @S9S_MB_2U_LIB.S9S_MB_2U(SCH_1):PAGE307
   J35  OA5 RBT_ARB_OUT SCONN168_ME1016810202011-SCONNA   I303 @S9S_MB_2U_LIB.S9S_MB_2U(SCH_1):PAGE146

OCP_V3_2_ISO_BIF0_EN @S9S_MB_2U_LIB.S9S_MB_2U(SCH_1):OCP_V3_2_ISO_BIF0_EN
 R3169    1      A Q_RES_0402LF-0,5%,1/16W,CHIP,CA    I33 @S9S_MB_2U_LIB.S9S_MB_2U(SCH_1):PAGE146
 R3208    1      A Q_RES_0402LF-100,1%,1/16W,CHIPA    I37 @S9S_MB_2U_LIB.S9S_MB_2U(SCH_1):PAGE307

OCP_V3_2_ISO_BIF1_EN @S9S_MB_2U_LIB.S9S_MB_2U(SCH_1):OCP_V3_2_ISO_BIF1_EN
 R3170    1      A Q_RES_0402LF-0,5%,1/16W,CHIP,CA    I32 @S9S_MB_2U_LIB.S9S_MB_2U(SCH_1):PAGE146
 R3216    1      A Q_RES_0402LF-100,1%,1/16W,CHIPA    I38 @S9S_MB_2U_LIB.S9S_MB_2U(SCH_1):PAGE307

OCP_V3_2_ISO_BIF2_EN @S9S_MB_2U_LIB.S9S_MB_2U(SCH_1):OCP_V3_2_ISO_BIF2_EN
 R3171    1      A Q_RES_0402LF-0,5%,1/16W,CHIP,CA    I31 @S9S_MB_2U_LIB.S9S_MB_2U(SCH_1):PAGE146
 R3217    1      A Q_RES_0402LF-100,1%,1/16W,CHIPA    I40 @S9S_MB_2U_LIB.S9S_MB_2U(SCH_1):PAGE307

OCP_V3_2_MAIN_PWR_EN @S9S_MB_2U_LIB.S9S_MB_2U(SCH_1):OCP_V3_2_MAIN_PWR_EN
 R3168    1      A Q_RES_0402LF-0,5%,1/16W,CHIP,CA     I5 @S9S_MB_2U_LIB.S9S_MB_2U(SCH_1):PAGE146
 R3165    2      B Q_RES_0402LF-10K,1%,1/16W,CHIPA    I37 @S9S_MB_2U_LIB.S9S_MB_2U(SCH_1):PAGE146
  U249  T17  PR27C LCMXO3LF9400C5BG484C-LCMXO3LF-A     I1 @S9S_MB_2U_LIB.S9S_MB_2U(SCH_1):PAGE313

OCP_V3_2_MAIN_PWR_EN_R @S9S_MB_2U_LIB.S9S_MB_2U(SCH_1):OCP_V3_2_MAIN_PWR_EN_R
 R3168    2      B Q_RES_0402LF-0,5%,1/16W,CHIP,CA     I5 @S9S_MB_2U_LIB.S9S_MB_2U(SCH_1):PAGE146
   J35  OB2 MAIN_PWR_EN SCONN168_ME1016810202011-SCONNA   I303 @S9S_MB_2U_LIB.S9S_MB_2U(SCH_1):PAGE146

OCP_V3_2_NOT_PRSNT_RBT_ARB_IN @S9S_MB_2U_LIB.S9S_MB_2U(SCH_1):OCP_V3_2_NOT_PRSNT_RBT_ARB_IN
  U246    1     B1 NC7SB3157_SMLF-NC7SB3157P6X,NCB    I17 @S9S_MB_2U_LIB.S9S_MB_2U(SCH_1):PAGE170
  U245    1     B1 NC7SB3157_SMLF-NC7SB3157P6X,NCB    I18 @S9S_MB_2U_LIB.S9S_MB_2U(SCH_1):PAGE170

OCP_V3_2_P3V3_ADC_ALERT @S9S_MB_2U_LIB.S9S_MB_2U(SCH_1):OCP_V3_2_P3V3_ADC_ALERT
  U249  K18  PR13B LCMXO3LF9400C5BG484C-LCMXO3LF-A     I1 @S9S_MB_2U_LIB.S9S_MB_2U(SCH_1):PAGE313
 R3559    2      B Q_RES_0402LF-0,5%,1/16W,CHIP,CA    I96 @S9S_MB_2U_LIB.S9S_MB_2U(SCH_1):PAGE163

OCP_V3_2_P3V3_ADC_ALERT_R @S9S_MB_2U_LIB.S9S_MB_2U(SCH_1):OCP_V3_2_P3V3_ADC_ALERT_R
  U263    3  ALERT INA230AIRGTR-INA230AIRGTR,SMLFB    I94 @S9S_MB_2U_LIB.S9S_MB_2U(SCH_1):PAGE163
 R3559    1      A Q_RES_0402LF-0,5%,1/16W,CHIP,CA    I96 @S9S_MB_2U_LIB.S9S_MB_2U(SCH_1):PAGE163
 R4092    2      B Q_RES_0402LF-4.7K,1%,1/16W,CHIA   I126 @S9S_MB_2U_LIB.S9S_MB_2U(SCH_1):PAGE163

OCP_V3_2_P3V3_PWRGD @S9S_MB_2U_LIB.S9S_MB_2U(SCH_1):OCP_V3_2_P3V3_PWRGD
 R3832    2      B Q_RES_0402LF-0,5%,1/16W,CHIP,CA    I97 @S9S_MB_2U_LIB.S9S_MB_2U(SCH_1):PAGE131
 R4615    1      A Q_RES_0402LF-0,5%,1/16W,EMPTY,A    I96 @S9S_MB_2U_LIB.S9S_MB_2U(SCH_1):PAGE132
 R3826    2      B Q_RES_0402LF-100K,1%,1/16W,CHIA   I110 @S9S_MB_2U_LIB.S9S_MB_2U(SCH_1):PAGE131

OCP_V3_2_PRSNT01_R_N @S9S_MB_2U_LIB.S9S_MB_2U(SCH_1):OCP_V3_2_PRSNT01_R_N
  U241    7     1Y 74LVC2G08DP-74LVC2G08DP,SMLF,IA     I1 @S9S_MB_2U_LIB.S9S_MB_2U(SCH_1):PAGE170
  U242    5     2A 74LVC2G08DP-74LVC2G08DP,SMLF,IA    I14 @S9S_MB_2U_LIB.S9S_MB_2U(SCH_1):PAGE170

OCP_V3_2_PRSNT0_R_N @S9S_MB_2U_LIB.S9S_MB_2U(SCH_1):OCP_V3_2_PRSNT0_R_N
  U241    1     1A 74LVC2G08DP-74LVC2G08DP,SMLF,IA     I1 @S9S_MB_2U_LIB.S9S_MB_2U(SCH_1):PAGE170
   J35  B42 PRSNTB0# SCONN168_ME1016810202011-SCONNA   I303 @S9S_MB_2U_LIB.S9S_MB_2U(SCH_1):PAGE146
 R3133    2      B Q_RES_0402LF-1K,1%,1/16W,CHIP,A    I11 @S9S_MB_2U_LIB.S9S_MB_2U(SCH_1):PAGE131
   U58    1     1A 74LVC2G07DW7-74LVC2G07DW-7,SMLA    I25 @S9S_MB_2U_LIB.S9S_MB_2U(SCH_1):PAGE131

OCP_V3_2_PRSNT1_R_N @S9S_MB_2U_LIB.S9S_MB_2U(SCH_1):OCP_V3_2_PRSNT1_R_N
  U241    2     1B 74LVC2G08DP-74LVC2G08DP,SMLF,IA     I1 @S9S_MB_2U_LIB.S9S_MB_2U(SCH_1):PAGE170
   J35  A42 PRSNTB1# SCONN168_ME1016810202011-SCONNA   I303 @S9S_MB_2U_LIB.S9S_MB_2U(SCH_1):PAGE146
 R3135    2      B Q_RES_0402LF-1K,1%,1/16W,CHIP,A    I13 @S9S_MB_2U_LIB.S9S_MB_2U(SCH_1):PAGE131
   U58    3     2A 74LVC2G07DW7-74LVC2G07DW-7,SMLA    I25 @S9S_MB_2U_LIB.S9S_MB_2U(SCH_1):PAGE131

OCP_V3_2_PRSNT23_R_N @S9S_MB_2U_LIB.S9S_MB_2U(SCH_1):OCP_V3_2_PRSNT23_R_N
  U241    3     2Y 74LVC2G08DP-74LVC2G08DP,SMLF,IA     I2 @S9S_MB_2U_LIB.S9S_MB_2U(SCH_1):PAGE170
  U242    6     2B 74LVC2G08DP-74LVC2G08DP,SMLF,IA    I14 @S9S_MB_2U_LIB.S9S_MB_2U(SCH_1):PAGE170

OCP_V3_2_PRSNT2_R_N @S9S_MB_2U_LIB.S9S_MB_2U(SCH_1):OCP_V3_2_PRSNT2_R_N
  U241    5     2A 74LVC2G08DP-74LVC2G08DP,SMLF,IA     I2 @S9S_MB_2U_LIB.S9S_MB_2U(SCH_1):PAGE170
   J35  A12 PRSNTB2# SCONN168_ME1016810202011-SCONNA   I303 @S9S_MB_2U_LIB.S9S_MB_2U(SCH_1):PAGE146
 R3134    2      B Q_RES_0402LF-1K,1%,1/16W,CHIP,A     I3 @S9S_MB_2U_LIB.S9S_MB_2U(SCH_1):PAGE131
   U59    1     1A 74LVC2G07DW7-74LVC2G07DW-7,SMLA    I19 @S9S_MB_2U_LIB.S9S_MB_2U(SCH_1):PAGE131

OCP_V3_2_PRSNT3_R_N @S9S_MB_2U_LIB.S9S_MB_2U(SCH_1):OCP_V3_2_PRSNT3_R_N
  U241    6     2B 74LVC2G08DP-74LVC2G08DP,SMLF,IA     I2 @S9S_MB_2U_LIB.S9S_MB_2U(SCH_1):PAGE170
   J35  B70 PRSNTB3# SCONN168_ME1016810202011-SCONNA   I303 @S9S_MB_2U_LIB.S9S_MB_2U(SCH_1):PAGE146
 R3136    2      B Q_RES_0402LF-1K,1%,1/16W,CHIP,A     I5 @S9S_MB_2U_LIB.S9S_MB_2U(SCH_1):PAGE131
   U59    3     2A 74LVC2G07DW7-74LVC2G07DW-7,SMLA    I19 @S9S_MB_2U_LIB.S9S_MB_2U(SCH_1):PAGE131

OCP_V3_2_PRSNT_ALL_R1_N @S9S_MB_2U_LIB.S9S_MB_2U(SCH_1):OCP_V3_2_PRSNT_ALL_R1_N
  U246    6      S NC7SB3157_SMLF-NC7SB3157P6X,NCB    I17 @S9S_MB_2U_LIB.S9S_MB_2U(SCH_1):PAGE170
 R3308    2      B Q_RES_0402LF-0,5%,1/16W,CHIP,CA    I46 @S9S_MB_2U_LIB.S9S_MB_2U(SCH_1):PAGE170

OCP_V3_2_PRSNT_ALL_R3_N @S9S_MB_2U_LIB.S9S_MB_2U(SCH_1):OCP_V3_2_PRSNT_ALL_R3_N
  U245    6      S NC7SB3157_SMLF-NC7SB3157P6X,NCB    I18 @S9S_MB_2U_LIB.S9S_MB_2U(SCH_1):PAGE170
 R3306    2      B Q_RES_0402LF-0,5%,1/16W,CHIP,CA    I47 @S9S_MB_2U_LIB.S9S_MB_2U(SCH_1):PAGE170

OCP_V3_2_PRSNT_ALL_R_N @S9S_MB_2U_LIB.S9S_MB_2U(SCH_1):OCP_V3_2_PRSNT_ALL_R_N
  U242    3     2Y 74LVC2G08DP-74LVC2G08DP,SMLF,IA    I14 @S9S_MB_2U_LIB.S9S_MB_2U(SCH_1):PAGE170
 R3308    1      A Q_RES_0402LF-0,5%,1/16W,CHIP,CA    I46 @S9S_MB_2U_LIB.S9S_MB_2U(SCH_1):PAGE170
 R3306    1      A Q_RES_0402LF-0,5%,1/16W,CHIP,CA    I47 @S9S_MB_2U_LIB.S9S_MB_2U(SCH_1):PAGE170

OCP_V3_2_PWRBRK_BUFF_N @S9S_MB_2U_LIB.S9S_MB_2U(SCH_1):OCP_V3_2_PWRBRK_BUFF_N
  U218    4      Y 74LVC1G07GV-74LVC1G07GV,SMLF,IA    I31 @S9S_MB_2U_LIB.S9S_MB_2U(SCH_1):PAGE156
 R3190    2      B Q_RES_0402LF-4.7K,1%,1/16W,CHIA    I42 @S9S_MB_2U_LIB.S9S_MB_2U(SCH_1):PAGE156
 R3191    1      A Q_RES_0402LF-33.2,1%,1/16W,CHIA    I44 @S9S_MB_2U_LIB.S9S_MB_2U(SCH_1):PAGE156

OCP_V3_2_PWRBRK_N @S9S_MB_2U_LIB.S9S_MB_2U(SCH_1):OCP_V3_2_PWRBRK_N
 R3191    2      B Q_RES_0402LF-33.2,1%,1/16W,CHIA    I44 @S9S_MB_2U_LIB.S9S_MB_2U(SCH_1):PAGE156
   J35  A70 PWRBRK0# SCONN168_ME1016810202011-SCONNA   I303 @S9S_MB_2U_LIB.S9S_MB_2U(SCH_1):PAGE146

OCP_V3_2_RBT_ARB_IN @S9S_MB_2U_LIB.S9S_MB_2U(SCH_1):OCP_V3_2_RBT_ARB_IN
 R3209    2      B Q_RES_0402LF-22,1%,1/16W,EMPTYA    I64 @S9S_MB_2U_LIB.S9S_MB_2U(SCH_1):PAGE307
  U245    3     B0 NC7SB3157_SMLF-NC7SB3157P6X,NCB    I18 @S9S_MB_2U_LIB.S9S_MB_2U(SCH_1):PAGE170

OCP_V3_2_RBT_ARB_IN_R @S9S_MB_2U_LIB.S9S_MB_2U(SCH_1):OCP_V3_2_RBT_ARB_IN_R
  U222   12     4A 74CBTLV3126PW-74CBTLV3126PW,SMA    I32 @S9S_MB_2U_LIB.S9S_MB_2U(SCH_1):PAGE307
 R3209    1      A Q_RES_0402LF-22,1%,1/16W,EMPTYA    I64 @S9S_MB_2U_LIB.S9S_MB_2U(SCH_1):PAGE307
 R3244    2      B Q_RES_0402LF-0,5%,1/16W,CHIP,CA    I79 @S9S_MB_2U_LIB.S9S_MB_2U(SCH_1):PAGE307

OCP_V3_2_RBT_ARB_OUT @S9S_MB_2U_LIB.S9S_MB_2U(SCH_1):OCP_V3_2_RBT_ARB_OUT
  U223   12     4A 74CBTLV3126PW-74CBTLV3126PW,SMA    I78 @S9S_MB_2U_LIB.S9S_MB_2U(SCH_1):PAGE307
 R3244    1      A Q_RES_0402LF-0,5%,1/16W,CHIP,CA    I79 @S9S_MB_2U_LIB.S9S_MB_2U(SCH_1):PAGE307
  U246    3     B0 NC7SB3157_SMLF-NC7SB3157P6X,NCB    I17 @S9S_MB_2U_LIB.S9S_MB_2U(SCH_1):PAGE170

OCP_V3_2_WAKE_BUFF_N @S9S_MB_2U_LIB.S9S_MB_2U(SCH_1):OCP_V3_2_WAKE_BUFF_N
 R3185    1      A Q_RES_0402LF-33.2,1%,1/16W,CHIA    I24 @S9S_MB_2U_LIB.S9S_MB_2U(SCH_1):PAGE156
 R3184    2      B Q_RES_0402LF-4.7K,1%,1/16W,CHIA    I28 @S9S_MB_2U_LIB.S9S_MB_2U(SCH_1):PAGE156
  U217    4      Y 74LVC1G126SE7-74LVC1G126SE-7,SA    I79 @S9S_MB_2U_LIB.S9S_MB_2U(SCH_1):PAGE156

OCP_V3_2_WAKE_BUFF_R_N @S9S_MB_2U_LIB.S9S_MB_2U(SCH_1):OCP_V3_2_WAKE_BUFF_R_N
 R3185    2      B Q_RES_0402LF-33.2,1%,1/16W,CHIA    I24 @S9S_MB_2U_LIB.S9S_MB_2U(SCH_1):PAGE156
  U219    2      A 74LVC1G07GV-74LVC1G07GV,SMLF,IA    I61 @S9S_MB_2U_LIB.S9S_MB_2U(SCH_1):PAGE156

OC_P2V5_COMP @S9S_MB_2U_LIB.S9S_MB_2U(SCH_1):OC_P2V5_COMP
  U343    1     1+ LM4040AIM3X25NOPB-LM4040AIM3X-A    I56 @S9S_MB_2U_LIB.S9S_MB_2U(SCH_1):PAGE326
 R4792    2      B Q_RES_0402LF-10K,1%,1/16W,EMPTA    I57 @S9S_MB_2U_LIB.S9S_MB_2U(SCH_1):PAGE326
 C2388    1      A Q_CAP_C0402-100NF,50V,10%,EMPTA    I64 @S9S_MB_2U_LIB.S9S_MB_2U(SCH_1):PAGE326
  U344    1    IN- AP331AWG7-AP331AWG-7,SMLF,EMPTA    I66 @S9S_MB_2U_LIB.S9S_MB_2U(SCH_1):PAGE326

P0V62_CPU0_ERRS_U306_VREF @S9S_MB_2U_LIB.S9S_MB_2U(SCH_1):P0V62_CPU0_ERRS_U306_VREF
  U306    4   VREF GTL2014PW-GTL2014PW,SMLF,IC,ALA    I80 @S9S_MB_2U_LIB.S9S_MB_2U(SCH_1):PAGE322
 C2254    1      A Q_CAP_0402-0.1UF,25V,10%,X7R,CA   I111 @S9S_MB_2U_LIB.S9S_MB_2U(SCH_1):PAGE322
 R4041    1      A Q_RES_0402LF-1K,1%,1/16W,CHIP,A   I181 @S9S_MB_2U_LIB.S9S_MB_2U(SCH_1):PAGE322
 R4038    2      B Q_RES_0402LF-4.32K,1%,1/16W,CHA   I182 @S9S_MB_2U_LIB.S9S_MB_2U(SCH_1):PAGE322

P0V62_CPU0_ERRS_VREF @S9S_MB_2U_LIB.S9S_MB_2U(SCH_1):P0V62_CPU0_ERRS_VREF
 C2249    1      A Q_CAP_0402-0.1UF,25V,10%,X7R,CA    I83 @S9S_MB_2U_LIB.S9S_MB_2U(SCH_1):PAGE321
  U301    4   VREF GTL2014PW-GTL2014PW,SMLF,IC,ALA    I91 @S9S_MB_2U_LIB.S9S_MB_2U(SCH_1):PAGE321
 R4016    2      B Q_RES_0402LF-4.32K,1%,1/16W,CHA    I97 @S9S_MB_2U_LIB.S9S_MB_2U(SCH_1):PAGE321
 R4019    1      A Q_RES_0402LF-1K,1%,1/16W,CHIP,A    I98 @S9S_MB_2U_LIB.S9S_MB_2U(SCH_1):PAGE321

P0V62_CPU0_RST_DDR_VREF @S9S_MB_2U_LIB.S9S_MB_2U(SCH_1):P0V62_CPU0_RST_DDR_VREF
  U304    4   VREF GTL2014PW-GTL2014PW,SMLF,IC,ALA    I27 @S9S_MB_2U_LIB.S9S_MB_2U(SCH_1):PAGE322
 C2252    1      A Q_CAP_0402-0.1UF,25V,10%,X7R,CA   I101 @S9S_MB_2U_LIB.S9S_MB_2U(SCH_1):PAGE322
 R4036    2      B Q_RES_0402LF-4.32K,1%,1/16W,CHA   I128 @S9S_MB_2U_LIB.S9S_MB_2U(SCH_1):PAGE322
 R4039    1      A Q_RES_0402LF-1K,1%,1/16W,CHIP,A   I129 @S9S_MB_2U_LIB.S9S_MB_2U(SCH_1):PAGE322

P0V62_CPU1_RST_DDR_VREF @S9S_MB_2U_LIB.S9S_MB_2U(SCH_1):P0V62_CPU1_RST_DDR_VREF
  U305    4   VREF GTL2014PW-GTL2014PW,SMLF,IC,ALA    I44 @S9S_MB_2U_LIB.S9S_MB_2U(SCH_1):PAGE322
 C2253    1      A Q_CAP_0402-0.1UF,25V,10%,X7R,CA   I106 @S9S_MB_2U_LIB.S9S_MB_2U(SCH_1):PAGE322
 R4037    2      B Q_RES_0402LF-4.32K,1%,1/16W,CHA   I130 @S9S_MB_2U_LIB.S9S_MB_2U(SCH_1):PAGE322
 R4040    1      A Q_RES_0402LF-1K,1%,1/16W,CHIP,A   I131 @S9S_MB_2U_LIB.S9S_MB_2U(SCH_1):PAGE322

P0V7_JTAG_VREF_2 @S9S_MB_2U_LIB.S9S_MB_2U(SCH_1):P0V7_JTAG_VREF_2
 R1346    1      A Q_RES_0402LF-100,1%,1/16W,CHIPA    I34 @S9S_MB_2U_LIB.S9S_MB_2U(SCH_1):PAGE226
   U83    4   VREF GTL2014PW-GTL2014PW,SMLF,IC,ALA    I45 @S9S_MB_2U_LIB.S9S_MB_2U(SCH_1):PAGE226
 R2512    2      B Q_RES_0402LF-49.9,1%,1/16W,CHIA    I91 @S9S_MB_2U_LIB.S9S_MB_2U(SCH_1):PAGE226
 C1664    1      A Q_CAP_0402-0.1UF,25V,10%,X7R,CA    I93 @S9S_MB_2U_LIB.S9S_MB_2U(SCH_1):PAGE226

P12V_AUX @S9S_MB_2U_LIB.S9S_MB_2U(SCH_1):P12V_AUX
PC1656    1      A Q_CAP_C0402-100NF,50V,10%,X7R,A    I79 @S9S_MB_2U_LIB.S9S_MB_2U(SCH_1):PAGE271
  PL32    1      1 Q_INDUCTOR_SMLF-50NH/148A,IND,A    I83 @S9S_MB_2U_LIB.S9S_MB_2U(SCH_1):PAGE271
 PR260    1      A Q_RES_0402LF-0,5%,1/16W,EMPTY,A    I22 @S9S_MB_2U_LIB.S9S_MB_2U(SCH_1):PAGE278
PC1659    1      A Q_CAP_C0402-100NF,50V,10%,X7R,A    I68 @S9S_MB_2U_LIB.S9S_MB_2U(SCH_1):PAGE279
 R2528    1      A Q_RES_0402LF-100K,1%,1/16W,CHIA     I8 @S9S_MB_2U_LIB.S9S_MB_2U(SCH_1):PAGE234
 R2530    1      A Q_RES_0402LF-4.7K,5%,1/16W,CHIA    I10 @S9S_MB_2U_LIB.S9S_MB_2U(SCH_1):PAGE234
 R1799    1      A Q_RES_0402LF-7.87K,1%,1/16W,CHA   I173 @S9S_MB_2U_LIB.S9S_MB_2U(SCH_1):PAGE239
PR3830    1      A Q_RES_0402LF-10,1%,1/16W,EMPTYA    I85 @S9S_MB_2U_LIB.S9S_MB_2U(SCH_1):PAGE131
PR3966    1      A Q_RES_0402LF-10,1%,1/16W,EMPTYA    I61 @S9S_MB_2U_LIB.S9S_MB_2U(SCH_1):PAGE324
 PU294   A3  IN_A3 MAX15090BEWIT-MAX15090BEWI+T,SA    I62 @S9S_MB_2U_LIB.S9S_MB_2U(SCH_1):PAGE324
 PU294   A5  IN_A5 MAX15090BEWIT-MAX15090BEWI+T,SA    I62 @S9S_MB_2U_LIB.S9S_MB_2U(SCH_1):PAGE324
 PU294   B3  IN_B3 MAX15090BEWIT-MAX15090BEWI+T,SA    I62 @S9S_MB_2U_LIB.S9S_MB_2U(SCH_1):PAGE324
 PU294   B5  IN_B5 MAX15090BEWIT-MAX15090BEWI+T,SA    I62 @S9S_MB_2U_LIB.S9S_MB_2U(SCH_1):PAGE324
 PU294   C3  IN_C3 MAX15090BEWIT-MAX15090BEWI+T,SA    I62 @S9S_MB_2U_LIB.S9S_MB_2U(SCH_1):PAGE324
 PU294   C5  IN_C5 MAX15090BEWIT-MAX15090BEWI+T,SA    I62 @S9S_MB_2U_LIB.S9S_MB_2U(SCH_1):PAGE324
 PU294   D5  IN_D5 MAX15090BEWIT-MAX15090BEWI+T,SA    I62 @S9S_MB_2U_LIB.S9S_MB_2U(SCH_1):PAGE324
PR4000    1      A Q_RES_0402LF-160K,1%,1/16W,EMPA    I67 @S9S_MB_2U_LIB.S9S_MB_2U(SCH_1):PAGE229
PR3805    1      A Q_RES_0402LF-160K,1%,1/16W,EMPA    I33 @S9S_MB_2U_LIB.S9S_MB_2U(SCH_1):PAGE131
 R4067    1      A Q_RES_0402LF-10K,1%,1/16W,CHIPA    I40 @S9S_MB_2U_LIB.S9S_MB_2U(SCH_1):PAGE131
 R4072    1      A Q_RES_0402LF-10K,1%,1/16W,CHIPA     I6 @S9S_MB_2U_LIB.S9S_MB_2U(SCH_1):PAGE324
PC2231    1      A Q_CAP_C0402-1UF,25V,10%,X6S,CHA    I37 @S9S_MB_2U_LIB.S9S_MB_2U(SCH_1):PAGE229
 R1655    1      A Q_RES_0402LF-10K,1%,1/16W,CHIPA     I6 @S9S_MB_2U_LIB.S9S_MB_2U(SCH_1):PAGE246
 R1643    1      A Q_RES_0402LF-100K,1%,1/16W,CHIA    I17 @S9S_MB_2U_LIB.S9S_MB_2U(SCH_1):PAGE246
 R1642    1      A Q_RES_0402LF-10K,1%,1/16W,CHIPA    I22 @S9S_MB_2U_LIB.S9S_MB_2U(SCH_1):PAGE246
PC1651    1      A Q_CAP_C0402-100NF,50V,10%,X7R,A    I14 @S9S_MB_2U_LIB.S9S_MB_2U(SCH_1):PAGE249
PR2556    1      A Q_RES_2512LF-0.03,0.1%,1W,EMPTA    I82 @S9S_MB_2U_LIB.S9S_MB_2U(SCH_1):PAGE271
  PL14    1      1 Q_INDUCTOR_SMLF-100NH/16A,IND,A    I64 @S9S_MB_2U_LIB.S9S_MB_2U(SCH_1):PAGE276
 PU297    1  VOUT1 MP5991GLUZ-MP5991GLU-Z,SMLF,ICA    I17 @S9S_MB_2U_LIB.S9S_MB_2U(SCH_1):PAGE325
 PU297    2  VOUT2 MP5991GLUZ-MP5991GLU-Z,SMLF,ICA    I17 @S9S_MB_2U_LIB.S9S_MB_2U(SCH_1):PAGE325
 PU297   25  VOUT3 MP5991GLUZ-MP5991GLU-Z,SMLF,ICA    I17 @S9S_MB_2U_LIB.S9S_MB_2U(SCH_1):PAGE325
 PU297   26  VOUT4 MP5991GLUZ-MP5991GLU-Z,SMLF,ICA    I17 @S9S_MB_2U_LIB.S9S_MB_2U(SCH_1):PAGE325
 PU297   27  VOUT5 MP5991GLUZ-MP5991GLU-Z,SMLF,ICA    I17 @S9S_MB_2U_LIB.S9S_MB_2U(SCH_1):PAGE325
 PU297   28  VOUT6 MP5991GLUZ-MP5991GLU-Z,SMLF,ICA    I17 @S9S_MB_2U_LIB.S9S_MB_2U(SCH_1):PAGE325
 PU297   29  VOUT7 MP5991GLUZ-MP5991GLU-Z,SMLF,ICA    I17 @S9S_MB_2U_LIB.S9S_MB_2U(SCH_1):PAGE325
 PU297   30  VOUT8 MP5991GLUZ-MP5991GLU-Z,SMLF,ICA    I17 @S9S_MB_2U_LIB.S9S_MB_2U(SCH_1):PAGE325
 PU297   31  VOUT9 MP5991GLUZ-MP5991GLU-Z,SMLF,ICA    I17 @S9S_MB_2U_LIB.S9S_MB_2U(SCH_1):PAGE325
 PU297   32 VOUT10 MP5991GLUZ-MP5991GLU-Z,SMLF,ICA    I17 @S9S_MB_2U_LIB.S9S_MB_2U(SCH_1):PAGE325
PR2554    1      A Q_RES_2512LF-0.03,0.1%,1W,EMPTA    I81 @S9S_MB_2U_LIB.S9S_MB_2U(SCH_1):PAGE253
PC1655    1      A Q_CAP_C0402-100NF,50V,10%,X7R,A    I60 @S9S_MB_2U_LIB.S9S_MB_2U(SCH_1):PAGE261
   PL6    1      1 Q_INDUCTOR_SMLF-100NH/16A,IND,A    I62 @S9S_MB_2U_LIB.S9S_MB_2U(SCH_1):PAGE261
 PU289   27  VOUT1 MP5990GMA1111Z-MP5990GMA-1111-A    I56 @S9S_MB_2U_LIB.S9S_MB_2U(SCH_1):PAGE303
 PU289   28  VOUT2 MP5990GMA1111Z-MP5990GMA-1111-A    I56 @S9S_MB_2U_LIB.S9S_MB_2U(SCH_1):PAGE303
 PU289   29  VOUT3 MP5990GMA1111Z-MP5990GMA-1111-A    I56 @S9S_MB_2U_LIB.S9S_MB_2U(SCH_1):PAGE303
 PU289   30  VOUT4 MP5990GMA1111Z-MP5990GMA-1111-A    I56 @S9S_MB_2U_LIB.S9S_MB_2U(SCH_1):PAGE303
 PU289   31  VOUT5 MP5990GMA1111Z-MP5990GMA-1111-A    I56 @S9S_MB_2U_LIB.S9S_MB_2U(SCH_1):PAGE303
 PU289   32  VOUT6 MP5990GMA1111Z-MP5990GMA-1111-A    I56 @S9S_MB_2U_LIB.S9S_MB_2U(SCH_1):PAGE303
 PU289   33  VOUT7 MP5990GMA1111Z-MP5990GMA-1111-A    I56 @S9S_MB_2U_LIB.S9S_MB_2U(SCH_1):PAGE303
 PU289   34  VOUT8 MP5990GMA1111Z-MP5990GMA-1111-A    I56 @S9S_MB_2U_LIB.S9S_MB_2U(SCH_1):PAGE303
 PU289   35  VOUT9 MP5990GMA1111Z-MP5990GMA-1111-A    I56 @S9S_MB_2U_LIB.S9S_MB_2U(SCH_1):PAGE303
 PU289   36 VOUT10 MP5990GMA1111Z-MP5990GMA-1111-A    I56 @S9S_MB_2U_LIB.S9S_MB_2U(SCH_1):PAGE303
PR3931    1      A Q_RES_0402LF-75K,0.1%,1/16W,CHA    I86 @S9S_MB_2U_LIB.S9S_MB_2U(SCH_1):PAGE303
 PU296    1  VOUT1 MP5991GLUZ-MP5991GLU-Z,SMLF,ICA    I35 @S9S_MB_2U_LIB.S9S_MB_2U(SCH_1):PAGE325
 PU296    2  VOUT2 MP5991GLUZ-MP5991GLU-Z,SMLF,ICA    I35 @S9S_MB_2U_LIB.S9S_MB_2U(SCH_1):PAGE325
 PU296   25  VOUT3 MP5991GLUZ-MP5991GLU-Z,SMLF,ICA    I35 @S9S_MB_2U_LIB.S9S_MB_2U(SCH_1):PAGE325
 PU296   26  VOUT4 MP5991GLUZ-MP5991GLU-Z,SMLF,ICA    I35 @S9S_MB_2U_LIB.S9S_MB_2U(SCH_1):PAGE325
 PU296   27  VOUT5 MP5991GLUZ-MP5991GLU-Z,SMLF,ICA    I35 @S9S_MB_2U_LIB.S9S_MB_2U(SCH_1):PAGE325
 PU296   28  VOUT6 MP5991GLUZ-MP5991GLU-Z,SMLF,ICA    I35 @S9S_MB_2U_LIB.S9S_MB_2U(SCH_1):PAGE325
 PU296   29  VOUT7 MP5991GLUZ-MP5991GLU-Z,SMLF,ICA    I35 @S9S_MB_2U_LIB.S9S_MB_2U(SCH_1):PAGE325
 PU296   30  VOUT8 MP5991GLUZ-MP5991GLU-Z,SMLF,ICA    I35 @S9S_MB_2U_LIB.S9S_MB_2U(SCH_1):PAGE325
 PU296   31  VOUT9 MP5991GLUZ-MP5991GLU-Z,SMLF,ICA    I35 @S9S_MB_2U_LIB.S9S_MB_2U(SCH_1):PAGE325
 PU296   32 VOUT10 MP5991GLUZ-MP5991GLU-Z,SMLF,ICA    I35 @S9S_MB_2U_LIB.S9S_MB_2U(SCH_1):PAGE325
PC1654    1      A Q_CAP_C0402-100NF,50V,10%,X7R,A    I57 @S9S_MB_2U_LIB.S9S_MB_2U(SCH_1):PAGE258
 PR303    1      A Q_RES_0402LF-0,5%,1/16W,CHIP,CA     I7 @S9S_MB_2U_LIB.S9S_MB_2U(SCH_1):PAGE270
 PR156    1      A Q_RES_0402LF-0,5%,1/16W,CHIP,CA    I10 @S9S_MB_2U_LIB.S9S_MB_2U(SCH_1):PAGE252
 PR157    1      A Q_RES_0402LF-0,5%,1/16W,EMPTY,A    I11 @S9S_MB_2U_LIB.S9S_MB_2U(SCH_1):PAGE252
 PR261    1      A Q_RES_0402LF-0,5%,1/16W,CHIP,CA    I21 @S9S_MB_2U_LIB.S9S_MB_2U(SCH_1):PAGE278
 PU287    1  VOUT1 MP5991GLUZ-MP5991GLU-Z,SMLF,ICA    I35 @S9S_MB_2U_LIB.S9S_MB_2U(SCH_1):PAGE301
 PU287    2  VOUT2 MP5991GLUZ-MP5991GLU-Z,SMLF,ICA    I35 @S9S_MB_2U_LIB.S9S_MB_2U(SCH_1):PAGE301
 PU287   25  VOUT3 MP5991GLUZ-MP5991GLU-Z,SMLF,ICA    I35 @S9S_MB_2U_LIB.S9S_MB_2U(SCH_1):PAGE301
 PU287   26  VOUT4 MP5991GLUZ-MP5991GLU-Z,SMLF,ICA    I35 @S9S_MB_2U_LIB.S9S_MB_2U(SCH_1):PAGE301
 PU287   27  VOUT5 MP5991GLUZ-MP5991GLU-Z,SMLF,ICA    I35 @S9S_MB_2U_LIB.S9S_MB_2U(SCH_1):PAGE301
 PU287   28  VOUT6 MP5991GLUZ-MP5991GLU-Z,SMLF,ICA    I35 @S9S_MB_2U_LIB.S9S_MB_2U(SCH_1):PAGE301
 PU287   29  VOUT7 MP5991GLUZ-MP5991GLU-Z,SMLF,ICA    I35 @S9S_MB_2U_LIB.S9S_MB_2U(SCH_1):PAGE301
 PU287   30  VOUT8 MP5991GLUZ-MP5991GLU-Z,SMLF,ICA    I35 @S9S_MB_2U_LIB.S9S_MB_2U(SCH_1):PAGE301
 PU287   31  VOUT9 MP5991GLUZ-MP5991GLU-Z,SMLF,ICA    I35 @S9S_MB_2U_LIB.S9S_MB_2U(SCH_1):PAGE301
 PU287   32 VOUT10 MP5991GLUZ-MP5991GLU-Z,SMLF,ICA    I35 @S9S_MB_2U_LIB.S9S_MB_2U(SCH_1):PAGE301
 PD101    C      C DIODE_TVS-SMF14A,SMLF,IC,BCSMFA    I38 @S9S_MB_2U_LIB.S9S_MB_2U(SCH_1):PAGE153
 R4070    1      A Q_RES_0402LF-10K,1%,1/16W,CHIPA    I62 @S9S_MB_2U_LIB.S9S_MB_2U(SCH_1):PAGE153
 R4065    1      A Q_RES_0402LF-10K,1%,1/16W,EMPTA    I14 @S9S_MB_2U_LIB.S9S_MB_2U(SCH_1):PAGE131
 PU201   A3  IN_A3 MAX15090BEWIT-MAX15090BEWI+T,SA    I63 @S9S_MB_2U_LIB.S9S_MB_2U(SCH_1):PAGE131
 PU201   A5  IN_A5 MAX15090BEWIT-MAX15090BEWI+T,SA    I63 @S9S_MB_2U_LIB.S9S_MB_2U(SCH_1):PAGE131
 PU201   B3  IN_B3 MAX15090BEWIT-MAX15090BEWI+T,SA    I63 @S9S_MB_2U_LIB.S9S_MB_2U(SCH_1):PAGE131
 PU201   B5  IN_B5 MAX15090BEWIT-MAX15090BEWI+T,SA    I63 @S9S_MB_2U_LIB.S9S_MB_2U(SCH_1):PAGE131
 PU201   C3  IN_C3 MAX15090BEWIT-MAX15090BEWI+T,SA    I63 @S9S_MB_2U_LIB.S9S_MB_2U(SCH_1):PAGE131
 PU201   C5  IN_C5 MAX15090BEWIT-MAX15090BEWI+T,SA    I63 @S9S_MB_2U_LIB.S9S_MB_2U(SCH_1):PAGE131
 PU201   D5  IN_D5 MAX15090BEWIT-MAX15090BEWI+T,SA    I63 @S9S_MB_2U_LIB.S9S_MB_2U(SCH_1):PAGE131
 R4074    1      A Q_RES_0402LF-10K,1%,1/16W,EMPTA    I22 @S9S_MB_2U_LIB.S9S_MB_2U(SCH_1):PAGE324
PC2207    1      A Q_CAP_C0402-1UF,25V,10%,X6S,CHA    I31 @S9S_MB_2U_LIB.S9S_MB_2U(SCH_1):PAGE324
 PU292 21_22 VIN_21_22 RS31312R-RS31312R,SMLF,IC,AL03A    I49 @S9S_MB_2U_LIB.S9S_MB_2U(SCH_1):PAGE323
 PU292   23 VIN_23 RS31312R-RS31312R,SMLF,IC,AL03A    I49 @S9S_MB_2U_LIB.S9S_MB_2U(SCH_1):PAGE323
 PU292   24 VIN_24 RS31312R-RS31312R,SMLF,IC,AL03A    I49 @S9S_MB_2U_LIB.S9S_MB_2U(SCH_1):PAGE323
 PU292   25 VIN_25 RS31312R-RS31312R,SMLF,IC,AL03A    I49 @S9S_MB_2U_LIB.S9S_MB_2U(SCH_1):PAGE323
 PU292   26 VIN_26 RS31312R-RS31312R,SMLF,IC,AL03A    I49 @S9S_MB_2U_LIB.S9S_MB_2U(SCH_1):PAGE323
PC2198    1      A Q_CAP_C0402-1UF,25V,10%,X6S,CHA    I51 @S9S_MB_2U_LIB.S9S_MB_2U(SCH_1):PAGE323
 PD115    C      C DIODE_TVS-SMF14A,SMLF,IC,BCSMFA    I29 @S9S_MB_2U_LIB.S9S_MB_2U(SCH_1):PAGE229
PC2230    1      A Q_CAP_C0402-1UF,25V,10%,X6S,CHA    I31 @S9S_MB_2U_LIB.S9S_MB_2U(SCH_1):PAGE229
PR4010    1      A Q_RES_0402LF-120K,1%,1/16W,CHIA    I52 @S9S_MB_2U_LIB.S9S_MB_2U(SCH_1):PAGE229
PR4003    1      A Q_RES_0402LF-10,1%,1/16W,EMPTYA    I70 @S9S_MB_2U_LIB.S9S_MB_2U(SCH_1):PAGE229
PC1657    1      A Q_CAP_C0402-100NF,50V,10%,X7R,A    I77 @S9S_MB_2U_LIB.S9S_MB_2U(SCH_1):PAGE275
  PL43    1      1 Q_INDUCTOR_SMLF-100NH/16A,IND,A    I79 @S9S_MB_2U_LIB.S9S_MB_2U(SCH_1):PAGE275
  PL44    1      1 Q_INDUCTOR_SMLF-100NH/16A,IND,A    I80 @S9S_MB_2U_LIB.S9S_MB_2U(SCH_1):PAGE257
PC1652    1      A Q_CAP_C0402-100NF,50V,10%,X7R,A    I80 @S9S_MB_2U_LIB.S9S_MB_2U(SCH_1):PAGE253
  PL15    1      1 Q_INDUCTOR_SMLF-50NH/148A,IND,A    I82 @S9S_MB_2U_LIB.S9S_MB_2U(SCH_1):PAGE253
PC1653    1      A Q_CAP_C0402-100NF,50V,10%,X7R,A    I78 @S9S_MB_2U_LIB.S9S_MB_2U(SCH_1):PAGE257
 PL101    1      1 Q_INDUCTOR_SMLF-100NH/16A,IND,A    I59 @S9S_MB_2U_LIB.S9S_MB_2U(SCH_1):PAGE258
PC1658    1      A Q_CAP_C0402-100NF,50V,10%,X7R,A    I62 @S9S_MB_2U_LIB.S9S_MB_2U(SCH_1):PAGE276
  PL23    1      1 Q_INDUCTOR_SMLF-100NH/16A,IND,A    I78 @S9S_MB_2U_LIB.S9S_MB_2U(SCH_1):PAGE279
 PR304    1      A Q_RES_0402LF-0,5%,1/16W,EMPTY,A     I9 @S9S_MB_2U_LIB.S9S_MB_2U(SCH_1):PAGE270
 PR108    1      A Q_RES_0402LF-0,5%,1/16W,CHIP,CA     I9 @S9S_MB_2U_LIB.S9S_MB_2U(SCH_1):PAGE260
 PR107    1      A Q_RES_0402LF-0,5%,1/16W,EMPTY,A    I10 @S9S_MB_2U_LIB.S9S_MB_2U(SCH_1):PAGE260
PC1650    1      A Q_CAP_C0402-100NF,50V,10%,X7R,A    I18 @S9S_MB_2U_LIB.S9S_MB_2U(SCH_1):PAGE248
 R1837    1      1 Q_RES_4P_12-0.001,1%,3W,SMLF,CA     I3 @S9S_MB_2U_LIB.S9S_MB_2U(SCH_1):PAGE240
 R1838    1      1 Q_RES_4P_12-0.001,1%,3W,SMLF,CA    I11 @S9S_MB_2U_LIB.S9S_MB_2U(SCH_1):PAGE240
 PU288    1  VOUT1 MP5991GLUZ-MP5991GLU-Z,SMLF,ICA    I14 @S9S_MB_2U_LIB.S9S_MB_2U(SCH_1):PAGE301
 PU288    2  VOUT2 MP5991GLUZ-MP5991GLU-Z,SMLF,ICA    I14 @S9S_MB_2U_LIB.S9S_MB_2U(SCH_1):PAGE301
 PU288   25  VOUT3 MP5991GLUZ-MP5991GLU-Z,SMLF,ICA    I14 @S9S_MB_2U_LIB.S9S_MB_2U(SCH_1):PAGE301
 PU288   26  VOUT4 MP5991GLUZ-MP5991GLU-Z,SMLF,ICA    I14 @S9S_MB_2U_LIB.S9S_MB_2U(SCH_1):PAGE301
 PU288   27  VOUT5 MP5991GLUZ-MP5991GLU-Z,SMLF,ICA    I14 @S9S_MB_2U_LIB.S9S_MB_2U(SCH_1):PAGE301
 PU288   28  VOUT6 MP5991GLUZ-MP5991GLU-Z,SMLF,ICA    I14 @S9S_MB_2U_LIB.S9S_MB_2U(SCH_1):PAGE301
 PU288   29  VOUT7 MP5991GLUZ-MP5991GLU-Z,SMLF,ICA    I14 @S9S_MB_2U_LIB.S9S_MB_2U(SCH_1):PAGE301
 PU288   30  VOUT8 MP5991GLUZ-MP5991GLU-Z,SMLF,ICA    I14 @S9S_MB_2U_LIB.S9S_MB_2U(SCH_1):PAGE301
 PU288   31  VOUT9 MP5991GLUZ-MP5991GLU-Z,SMLF,ICA    I14 @S9S_MB_2U_LIB.S9S_MB_2U(SCH_1):PAGE301
 PU288   32 VOUT10 MP5991GLUZ-MP5991GLU-Z,SMLF,ICA    I14 @S9S_MB_2U_LIB.S9S_MB_2U(SCH_1):PAGE301
  PPQ5    1      1 MOSFET_NCH_1D3S-PSMNR58-30YLH,B    I35 @S9S_MB_2U_LIB.S9S_MB_2U(SCH_1):PAGE328
  PPQ5    2      2 MOSFET_NCH_1D3S-PSMNR58-30YLH,B    I35 @S9S_MB_2U_LIB.S9S_MB_2U(SCH_1):PAGE328
  PPQ5    3      3 MOSFET_NCH_1D3S-PSMNR58-30YLH,B    I35 @S9S_MB_2U_LIB.S9S_MB_2U(SCH_1):PAGE328
  PPQ6    1      1 MOSFET_NCH_1D3S-PSMNR58-30YLH,B    I40 @S9S_MB_2U_LIB.S9S_MB_2U(SCH_1):PAGE328
  PPQ6    2      2 MOSFET_NCH_1D3S-PSMNR58-30YLH,B    I40 @S9S_MB_2U_LIB.S9S_MB_2U(SCH_1):PAGE328
  PPQ6    3      3 MOSFET_NCH_1D3S-PSMNR58-30YLH,B    I40 @S9S_MB_2U_LIB.S9S_MB_2U(SCH_1):PAGE328
  PPQ7    1      1 MOSFET_NCH_1D3S-PSMNR58-30YLH,B    I41 @S9S_MB_2U_LIB.S9S_MB_2U(SCH_1):PAGE328
  PPQ7    2      2 MOSFET_NCH_1D3S-PSMNR58-30YLH,B    I41 @S9S_MB_2U_LIB.S9S_MB_2U(SCH_1):PAGE328
  PPQ7    3      3 MOSFET_NCH_1D3S-PSMNR58-30YLH,B    I41 @S9S_MB_2U_LIB.S9S_MB_2U(SCH_1):PAGE328
  PPQ8    1      1 MOSFET_NCH_1D3S-PSMNR58-30YLH,B    I62 @S9S_MB_2U_LIB.S9S_MB_2U(SCH_1):PAGE328
  PPQ8    2      2 MOSFET_NCH_1D3S-PSMNR58-30YLH,B    I62 @S9S_MB_2U_LIB.S9S_MB_2U(SCH_1):PAGE328
  PPQ8    3      3 MOSFET_NCH_1D3S-PSMNR58-30YLH,B    I62 @S9S_MB_2U_LIB.S9S_MB_2U(SCH_1):PAGE328
  PPQ1    1      1 MOSFET_NCH_1D3S-PSMNR58-30YLH,B    I65 @S9S_MB_2U_LIB.S9S_MB_2U(SCH_1):PAGE328
  PPQ1    2      2 MOSFET_NCH_1D3S-PSMNR58-30YLH,B    I65 @S9S_MB_2U_LIB.S9S_MB_2U(SCH_1):PAGE328
  PPQ1    3      3 MOSFET_NCH_1D3S-PSMNR58-30YLH,B    I65 @S9S_MB_2U_LIB.S9S_MB_2U(SCH_1):PAGE328
PC1750    1      A Q_CAP_C0402-33NF,25V,10%,EMPTYA    I68 @S9S_MB_2U_LIB.S9S_MB_2U(SCH_1):PAGE328
PR2537    1      A Q_RES_0402LF-10,1%,1/16W,EMPTYA    I70 @S9S_MB_2U_LIB.S9S_MB_2U(SCH_1):PAGE328
  PD17    K CATHODE SS15P3SM386A-SS15P3S-M3/86A,SMA    I72 @S9S_MB_2U_LIB.S9S_MB_2U(SCH_1):PAGE328
  PPQ2    1      1 MOSFET_NCH_1D3S-PSMNR58-30YLH,B    I73 @S9S_MB_2U_LIB.S9S_MB_2U(SCH_1):PAGE328
  PPQ2    2      2 MOSFET_NCH_1D3S-PSMNR58-30YLH,B    I73 @S9S_MB_2U_LIB.S9S_MB_2U(SCH_1):PAGE328
  PPQ2    3      3 MOSFET_NCH_1D3S-PSMNR58-30YLH,B    I73 @S9S_MB_2U_LIB.S9S_MB_2U(SCH_1):PAGE328
  PPQ9    1      1 MOSFET_NCH_1D3S-PSMNR58-30YLH,B    I77 @S9S_MB_2U_LIB.S9S_MB_2U(SCH_1):PAGE328
  PPQ9    2      2 MOSFET_NCH_1D3S-PSMNR58-30YLH,B    I77 @S9S_MB_2U_LIB.S9S_MB_2U(SCH_1):PAGE328
  PPQ9    3      3 MOSFET_NCH_1D3S-PSMNR58-30YLH,B    I77 @S9S_MB_2U_LIB.S9S_MB_2U(SCH_1):PAGE328
  PJ42   10     10 SCONN21_9193031121LF-SCONN21_9A    I34 @S9S_MB_2U_LIB.S9S_MB_2U(SCH_1):PAGE327
PC1789    1      A Q_CAP_0402-0.1UF,25V,10%,EMPTYA    I38 @S9S_MB_2U_LIB.S9S_MB_2U(SCH_1):PAGE327
 R2236    1      A Q_RES_0402LF-100K,1%,1/16W,EMPA     I7 @S9S_MB_2U_LIB.S9S_MB_2U(SCH_1):PAGE326
 R2221    1      A Q_RES_0402LF-26.7K,1%,1/16W,CHA    I20 @S9S_MB_2U_LIB.S9S_MB_2U(SCH_1):PAGE326
 R3933    1      A Q_RES_0402LF-16.9K,1%,1/16W,CHA    I62 @S9S_MB_2U_LIB.S9S_MB_2U(SCH_1):PAGE303
 R4680    1      A Q_RES_0402LF-100K,1%,1/16W,CHIA   I102 @S9S_MB_2U_LIB.S9S_MB_2U(SCH_1):PAGE246
 R4706    2      B Q_RES_0402LF-560,1%,1/16W,CHIPA    I66 @S9S_MB_2U_LIB.S9S_MB_2U(SCH_1):PAGE241
 C2383    1      A Q_CAP_C0402-100NF,50V,10%,EMPTA    I11 @S9S_MB_2U_LIB.S9S_MB_2U(SCH_1):PAGE329
  U339    5    VCC AP331AWG7-AP331AWG-7,SMLF,EMPTA    I12 @S9S_MB_2U_LIB.S9S_MB_2U(SCH_1):PAGE329
 R4774    1      A Q_RES_0402LF-17.8K,1%,1/16W,EMA    I17 @S9S_MB_2U_LIB.S9S_MB_2U(SCH_1):PAGE329
  U340    5    VCC AP331AWG7-AP331AWG-7,SMLF,EMPTA    I23 @S9S_MB_2U_LIB.S9S_MB_2U(SCH_1):PAGE329
 C2384    1      A Q_CAP_C0402-100NF,50V,10%,EMPTA    I29 @S9S_MB_2U_LIB.S9S_MB_2U(SCH_1):PAGE329
 R4776    1      A Q_RES_0402LF-17.8K,1%,1/16W,EMA    I38 @S9S_MB_2U_LIB.S9S_MB_2U(SCH_1):PAGE329
  U342    5    VCC AP331AWG7-AP331AWG-7,SMLF,EMPTA    I45 @S9S_MB_2U_LIB.S9S_MB_2U(SCH_1):PAGE329
 C2387    1      A Q_CAP_C0402-100NF,50V,10%,EMPTA    I51 @S9S_MB_2U_LIB.S9S_MB_2U(SCH_1):PAGE329
 R4790    1      A Q_RES_0402LF-4.75K,1%,1/16W,EMA    I67 @S9S_MB_2U_LIB.S9S_MB_2U(SCH_1):PAGE329
  U344    5    VCC AP331AWG7-AP331AWG-7,SMLF,EMPTA    I66 @S9S_MB_2U_LIB.S9S_MB_2U(SCH_1):PAGE326
 C2390    1      A Q_CAP_C0402-100NF,50V,10%,EMPTA    I71 @S9S_MB_2U_LIB.S9S_MB_2U(SCH_1):PAGE326
 R4806    1      A Q_RES_0402LF-1K,1%,1/16W,CHIP,A    I98 @S9S_MB_2U_LIB.S9S_MB_2U(SCH_1):PAGE326
 R2219    1      A Q_RES_0402LF-26.7K,1%,1/16W,CHA   I100 @S9S_MB_2U_LIB.S9S_MB_2U(SCH_1):PAGE326
 R4068    1      A Q_RES_0402LF-10K,1%,1/16W,EMPTA    I15 @S9S_MB_2U_LIB.S9S_MB_2U(SCH_1):PAGE153
PR3786    1      A Q_RES_0402LF-160K,1%,1/16W,EMPA    I42 @S9S_MB_2U_LIB.S9S_MB_2U(SCH_1):PAGE153
PC2079    1      A Q_CAP_C0402-1UF,25V,10%,X6S,CHA    I44 @S9S_MB_2U_LIB.S9S_MB_2U(SCH_1):PAGE153
 PU203   A3  IN_A3 MAX15090BEWIT-MAX15090BEWI+T,SA    I51 @S9S_MB_2U_LIB.S9S_MB_2U(SCH_1):PAGE153
 PU203   A5  IN_A5 MAX15090BEWIT-MAX15090BEWI+T,SA    I51 @S9S_MB_2U_LIB.S9S_MB_2U(SCH_1):PAGE153
 PU203   B3  IN_B3 MAX15090BEWIT-MAX15090BEWI+T,SA    I51 @S9S_MB_2U_LIB.S9S_MB_2U(SCH_1):PAGE153
 PU203   B5  IN_B5 MAX15090BEWIT-MAX15090BEWI+T,SA    I51 @S9S_MB_2U_LIB.S9S_MB_2U(SCH_1):PAGE153
 PU203   C3  IN_C3 MAX15090BEWIT-MAX15090BEWI+T,SA    I51 @S9S_MB_2U_LIB.S9S_MB_2U(SCH_1):PAGE153
 PU203   C5  IN_C5 MAX15090BEWIT-MAX15090BEWI+T,SA    I51 @S9S_MB_2U_LIB.S9S_MB_2U(SCH_1):PAGE153
 PU203   D5  IN_D5 MAX15090BEWIT-MAX15090BEWI+T,SA    I51 @S9S_MB_2U_LIB.S9S_MB_2U(SCH_1):PAGE153
PR3792    1      A Q_RES_0402LF-10,1%,1/16W,EMPTYA    I56 @S9S_MB_2U_LIB.S9S_MB_2U(SCH_1):PAGE153
PC2154    1      A Q_CAP_C0402-1UF,25V,10%,X6S,CHA    I68 @S9S_MB_2U_LIB.S9S_MB_2U(SCH_1):PAGE236
 PU204 21_22 VIN_21_22 RS31312R-RS31312R,SMLF,IC,AL03A    I70 @S9S_MB_2U_LIB.S9S_MB_2U(SCH_1):PAGE236
 PU204   23 VIN_23 RS31312R-RS31312R,SMLF,IC,AL03A    I70 @S9S_MB_2U_LIB.S9S_MB_2U(SCH_1):PAGE236
 PU204   24 VIN_24 RS31312R-RS31312R,SMLF,IC,AL03A    I70 @S9S_MB_2U_LIB.S9S_MB_2U(SCH_1):PAGE236
 PU204   25 VIN_25 RS31312R-RS31312R,SMLF,IC,AL03A    I70 @S9S_MB_2U_LIB.S9S_MB_2U(SCH_1):PAGE236
 PU204   26 VIN_26 RS31312R-RS31312R,SMLF,IC,AL03A    I70 @S9S_MB_2U_LIB.S9S_MB_2U(SCH_1):PAGE236
PR3841    1      A Q_RES_0402LF-120K,1%,1/16W,CHIA    I86 @S9S_MB_2U_LIB.S9S_MB_2U(SCH_1):PAGE236
PR3843    1      A Q_RES_0603LF-49.9,1%,1/10W,CHIA    I89 @S9S_MB_2U_LIB.S9S_MB_2U(SCH_1):PAGE236
 PD107    C      C DIODE_TVS-SMF14A,SMLF,IC,BCSMFA    I44 @S9S_MB_2U_LIB.S9S_MB_2U(SCH_1):PAGE131
PC2139    1      A Q_CAP_C0402-1UF,25V,10%,X6S,CHA    I46 @S9S_MB_2U_LIB.S9S_MB_2U(SCH_1):PAGE131
PC2165    1      A Q_CAP_C0402-1UF,25V,10%,X6S,CHA    I68 @S9S_MB_2U_LIB.S9S_MB_2U(SCH_1):PAGE237
 PU206 21_22 VIN_21_22 RS31312R-RS31312R,SMLF,IC,AL03A    I70 @S9S_MB_2U_LIB.S9S_MB_2U(SCH_1):PAGE237
 PU206   23 VIN_23 RS31312R-RS31312R,SMLF,IC,AL03A    I70 @S9S_MB_2U_LIB.S9S_MB_2U(SCH_1):PAGE237
 PU206   24 VIN_24 RS31312R-RS31312R,SMLF,IC,AL03A    I70 @S9S_MB_2U_LIB.S9S_MB_2U(SCH_1):PAGE237
 PU206   25 VIN_25 RS31312R-RS31312R,SMLF,IC,AL03A    I70 @S9S_MB_2U_LIB.S9S_MB_2U(SCH_1):PAGE237
 PU206   26 VIN_26 RS31312R-RS31312R,SMLF,IC,AL03A    I70 @S9S_MB_2U_LIB.S9S_MB_2U(SCH_1):PAGE237
PR3853    1      A Q_RES_0402LF-120K,1%,1/16W,CHIA    I84 @S9S_MB_2U_LIB.S9S_MB_2U(SCH_1):PAGE237
PR3857    1      A Q_RES_0603LF-49.9,1%,1/10W,CHIA    I87 @S9S_MB_2U_LIB.S9S_MB_2U(SCH_1):PAGE237
PR3953    1      A Q_RES_0402LF-120K,1%,1/16W,CHIA    I63 @S9S_MB_2U_LIB.S9S_MB_2U(SCH_1):PAGE323
PR3957    1      A Q_RES_0603LF-49.9,1%,1/10W,CHIA    I70 @S9S_MB_2U_LIB.S9S_MB_2U(SCH_1):PAGE323
PR3960    1      A Q_RES_0402LF-160K,1%,1/16W,EMPA    I32 @S9S_MB_2U_LIB.S9S_MB_2U(SCH_1):PAGE324
 PD114    C      C DIODE_TVS-SMF14A,SMLF,IC,BCSMFA    I84 @S9S_MB_2U_LIB.S9S_MB_2U(SCH_1):PAGE324
 R3117    1      A Q_RES_0402LF-510K,5%,1/16W,EMPA    I78 @S9S_MB_2U_LIB.S9S_MB_2U(SCH_1):PAGE245
   PU9    3    VIN IR3889MTRPBF-IR3889MTRPBF,SMLFA    I95 @S9S_MB_2U_LIB.S9S_MB_2U(SCH_1):PAGE245
PC1649    1      A Q_CAP_C0402-100NF,50V,10%,X7R,A    I97 @S9S_MB_2U_LIB.S9S_MB_2U(SCH_1):PAGE245
  PL45    1      1 Q_INDUCTOR_SMLF-100NH/16A,IND,A    I98 @S9S_MB_2U_LIB.S9S_MB_2U(SCH_1):PAGE245
   PC8    1      A Q_CAP_C0603-4.7UF,16V,10%,X6S,A   I118 @S9S_MB_2U_LIB.S9S_MB_2U(SCH_1):PAGE245
 R4071    1      A Q_RES_0402LF-10K,1%,1/16W,EMPTA    I24 @S9S_MB_2U_LIB.S9S_MB_2U(SCH_1):PAGE229
PR4014    1      A Q_RES_0603LF-49.9,1%,1/10W,CHIA    I54 @S9S_MB_2U_LIB.S9S_MB_2U(SCH_1):PAGE229
 PU300   A3  IN_A3 MAX15090BEWIT-MAX15090BEWI+T,SA    I69 @S9S_MB_2U_LIB.S9S_MB_2U(SCH_1):PAGE229
 PU300   A5  IN_A5 MAX15090BEWIT-MAX15090BEWI+T,SA    I69 @S9S_MB_2U_LIB.S9S_MB_2U(SCH_1):PAGE229
 PU300   B3  IN_B3 MAX15090BEWIT-MAX15090BEWI+T,SA    I69 @S9S_MB_2U_LIB.S9S_MB_2U(SCH_1):PAGE229
 PU300   B5  IN_B5 MAX15090BEWIT-MAX15090BEWI+T,SA    I69 @S9S_MB_2U_LIB.S9S_MB_2U(SCH_1):PAGE229
 PU300   C3  IN_C3 MAX15090BEWIT-MAX15090BEWI+T,SA    I69 @S9S_MB_2U_LIB.S9S_MB_2U(SCH_1):PAGE229
 PU300   C5  IN_C5 MAX15090BEWIT-MAX15090BEWI+T,SA    I69 @S9S_MB_2U_LIB.S9S_MB_2U(SCH_1):PAGE229
 PU300   D5  IN_D5 MAX15090BEWIT-MAX15090BEWI+T,SA    I69 @S9S_MB_2U_LIB.S9S_MB_2U(SCH_1):PAGE229
 PU299 21_22 VIN_21_22 RS31312R-RS31312R,SMLF,IC,AL03A    I90 @S9S_MB_2U_LIB.S9S_MB_2U(SCH_1):PAGE229
 PU299   23 VIN_23 RS31312R-RS31312R,SMLF,IC,AL03A    I90 @S9S_MB_2U_LIB.S9S_MB_2U(SCH_1):PAGE229
 PU299   24 VIN_24 RS31312R-RS31312R,SMLF,IC,AL03A    I90 @S9S_MB_2U_LIB.S9S_MB_2U(SCH_1):PAGE229
 PU299   25 VIN_25 RS31312R-RS31312R,SMLF,IC,AL03A    I90 @S9S_MB_2U_LIB.S9S_MB_2U(SCH_1):PAGE229
 PU299   26 VIN_26 RS31312R-RS31312R,SMLF,IC,AL03A    I90 @S9S_MB_2U_LIB.S9S_MB_2U(SCH_1):PAGE229
PC1648    1      A Q_CAP_C0402-100NF,50V,10%,X7R,A     I2 @S9S_MB_2U_LIB.S9S_MB_2U(SCH_1):PAGE244
  PL64    1      1 Q_INDUCTOR_SMLF-BLM18SN220TN1DA     I5 @S9S_MB_2U_LIB.S9S_MB_2U(SCH_1):PAGE244
  PL16    1      1 Q_INDUCTOR_SMLF-BLM18SN220TN1DA    I16 @S9S_MB_2U_LIB.S9S_MB_2U(SCH_1):PAGE249
 PL110    1      1 Q_INDUCTOR_SMLF-100NH/16A,IND,A    I19 @S9S_MB_2U_LIB.S9S_MB_2U(SCH_1):PAGE248
 R1688    1      A Q_RES_0402LF-100K,1%,1/16W,CHIA    I18 @S9S_MB_2U_LIB.S9S_MB_2U(SCH_1):PAGE232

P12V_AUX_ADC @S9S_MB_2U_LIB.S9S_MB_2U(SCH_1):P12V_AUX_ADC
 R1799    2      B Q_RES_0402LF-7.87K,1%,1/16W,CHA   I173 @S9S_MB_2U_LIB.S9S_MB_2U(SCH_1):PAGE239
 R1800    1      A Q_RES_0402LF-1.21K,1%,1/16W,CHA   I174 @S9S_MB_2U_LIB.S9S_MB_2U(SCH_1):PAGE239
 R3679    1      A Q_RES_0402LF-0,5%,1/16W,EMPTY,A   I209 @S9S_MB_2U_LIB.S9S_MB_2U(SCH_1):PAGE239
 R3680    1      A Q_RES_0402LF-0,5%,1/16W,CHIP,CA   I210 @S9S_MB_2U_LIB.S9S_MB_2U(SCH_1):PAGE239

P12V_AUX_ADC_MAM @S9S_MB_2U_LIB.S9S_MB_2U(SCH_1):P12V_AUX_ADC_MAM
  U193    5   AIN0 MAX11617EEET-MAX11617EEE+T,SMLA    I57 @S9S_MB_2U_LIB.S9S_MB_2U(SCH_1):PAGE239
 C1344    1      A Q_CAP_0402-100PF,50V,5%,EMPTY,A   I205 @S9S_MB_2U_LIB.S9S_MB_2U(SCH_1):PAGE239
 R3679    2      B Q_RES_0402LF-0,5%,1/16W,EMPTY,A   I209 @S9S_MB_2U_LIB.S9S_MB_2U(SCH_1):PAGE239

P12V_AUX_ADC_TIC @S9S_MB_2U_LIB.S9S_MB_2U(SCH_1):P12V_AUX_ADC_TIC
  U269   16    IN0 ADC128D818CIMTXNOPB-ADC128D818A   I103 @S9S_MB_2U_LIB.S9S_MB_2U(SCH_1):PAGE239
 C2046    1      A Q_CAP_0402-0.1UF,25V,10%,X7R,CA   I207 @S9S_MB_2U_LIB.S9S_MB_2U(SCH_1):PAGE239
 R3680    2      B Q_RES_0402LF-0,5%,1/16W,CHIP,CA   I210 @S9S_MB_2U_LIB.S9S_MB_2U(SCH_1):PAGE239

P12V_AUX_BLEEDING @S9S_MB_2U_LIB.S9S_MB_2U(SCH_1):P12V_AUX_BLEEDING
 R2530    2      B Q_RES_0402LF-4.7K,5%,1/16W,CHIA    I10 @S9S_MB_2U_LIB.S9S_MB_2U(SCH_1):PAGE234
   Q54    D      D MOSFET_NCH_GDS_ESD_PROTECTED-2A    I14 @S9S_MB_2U_LIB.S9S_MB_2U(SCH_1):PAGE234

P12V_AUX_CPU0_DIMM_ISEN_N @S9S_MB_2U_LIB.S9S_MB_2U(SCH_1):P12V_AUX_CPU0_DIMM_ISEN_N
PR1390    1      A Q_RES_0402LF-49.9,1%,1/16W,CHIA    I10 @S9S_MB_2U_LIB.S9S_MB_2U(SCH_1):PAGE264
 R1838    4      4 Q_RES_4P_12-0.001,1%,3W,SMLF,CA    I11 @S9S_MB_2U_LIB.S9S_MB_2U(SCH_1):PAGE240
  U102    4    IN- INA183A1IDBVR-INA183A1IDBVR,SMA    I29 @S9S_MB_2U_LIB.S9S_MB_2U(SCH_1):PAGE240

P12V_AUX_CPU0_DIMM_ISEN_P @S9S_MB_2U_LIB.S9S_MB_2U(SCH_1):P12V_AUX_CPU0_DIMM_ISEN_P
PR1380    1      A Q_RES_0402LF-49.9,1%,1/16W,CHIA    I11 @S9S_MB_2U_LIB.S9S_MB_2U(SCH_1):PAGE264
 R1838    3      3 Q_RES_4P_12-0.001,1%,3W,SMLF,CA    I11 @S9S_MB_2U_LIB.S9S_MB_2U(SCH_1):PAGE240
  U102    5    IN+ INA183A1IDBVR-INA183A1IDBVR,SMA    I29 @S9S_MB_2U_LIB.S9S_MB_2U(SCH_1):PAGE240

P12V_AUX_CPU1_DIMM_ISEN_N @S9S_MB_2U_LIB.S9S_MB_2U(SCH_1):P12V_AUX_CPU1_DIMM_ISEN_N
  U103    4    IN- INA183A1IDBVR-INA183A1IDBVR,SMA    I22 @S9S_MB_2U_LIB.S9S_MB_2U(SCH_1):PAGE240
PR1410    1      A Q_RES_0402LF-49.9,1%,1/16W,CHIA    I10 @S9S_MB_2U_LIB.S9S_MB_2U(SCH_1):PAGE282
 R1837    4      4 Q_RES_4P_12-0.001,1%,3W,SMLF,CA     I3 @S9S_MB_2U_LIB.S9S_MB_2U(SCH_1):PAGE240

P12V_AUX_CPU1_DIMM_ISEN_P @S9S_MB_2U_LIB.S9S_MB_2U(SCH_1):P12V_AUX_CPU1_DIMM_ISEN_P
  U103    5    IN+ INA183A1IDBVR-INA183A1IDBVR,SMA    I22 @S9S_MB_2U_LIB.S9S_MB_2U(SCH_1):PAGE240
PR1400    1      A Q_RES_0402LF-49.9,1%,1/16W,CHIA     I9 @S9S_MB_2U_LIB.S9S_MB_2U(SCH_1):PAGE282
 R1837    3      3 Q_RES_4P_12-0.001,1%,3W,SMLF,CA     I3 @S9S_MB_2U_LIB.S9S_MB_2U(SCH_1):PAGE240

P12V_AUX_UV_ADR_TRIGGER @S9S_MB_2U_LIB.S9S_MB_2U(SCH_1):P12V_AUX_UV_ADR_TRIGGER
 R4775    1      A Q_RES_0402LF-5.11K,1%,1/16W,EMA     I2 @S9S_MB_2U_LIB.S9S_MB_2U(SCH_1):PAGE329
 R4778    1      A Q_RES_0402LF-1M,1%,1/16W,CHIP,A     I9 @S9S_MB_2U_LIB.S9S_MB_2U(SCH_1):PAGE329
  U339    3    IN+ AP331AWG7-AP331AWG-7,SMLF,EMPTA    I12 @S9S_MB_2U_LIB.S9S_MB_2U(SCH_1):PAGE329
 C2381    1      A Q_CAP_C0402-100NF,50V,10%,EMPTA    I14 @S9S_MB_2U_LIB.S9S_MB_2U(SCH_1):PAGE329
 R4774    2      B Q_RES_0402LF-17.8K,1%,1/16W,EMA    I17 @S9S_MB_2U_LIB.S9S_MB_2U(SCH_1):PAGE329

P12V_AUX_UV_TRIGGER @S9S_MB_2U_LIB.S9S_MB_2U(SCH_1):P12V_AUX_UV_TRIGGER
  U340    3    IN+ AP331AWG7-AP331AWG-7,SMLF,EMPTA    I23 @S9S_MB_2U_LIB.S9S_MB_2U(SCH_1):PAGE329
 R4779    1      A Q_RES_0402LF-1M,1%,1/16W,CHIP,A    I31 @S9S_MB_2U_LIB.S9S_MB_2U(SCH_1):PAGE329
 C2382    1      A Q_CAP_C0402-100NF,50V,10%,EMPTA    I33 @S9S_MB_2U_LIB.S9S_MB_2U(SCH_1):PAGE329
 R4776    2      B Q_RES_0402LF-17.8K,1%,1/16W,EMA    I38 @S9S_MB_2U_LIB.S9S_MB_2U(SCH_1):PAGE329
 R4777    1      A Q_RES_0402LF-5.11K,1%,1/16W,EMA    I39 @S9S_MB_2U_LIB.S9S_MB_2U(SCH_1):PAGE329

P12V_E1S_0 @S9S_MB_2U_LIB.S9S_MB_2U(SCH_1):P12V_E1S_0
 C1277    1      A Q_CAP_C0805-22UF,16V,20%,X6S,CA   I237 @S9S_MB_2U_LIB.S9S_MB_2U(SCH_1):PAGE297
 C1279    1      A Q_CAP_0402-0.1UF,25V,10%,X7R,CA   I252 @S9S_MB_2U_LIB.S9S_MB_2U(SCH_1):PAGE297
 C1278    1      A Q_CAP_0402-0.1UF,25V,10%,X7R,CA   I258 @S9S_MB_2U_LIB.S9S_MB_2U(SCH_1):PAGE297
 C1276    1      A Q_CAP_C0805-22UF,16V,20%,X6S,CA   I260 @S9S_MB_2U_LIB.S9S_MB_2U(SCH_1):PAGE297
 PU294   A4 OUT_A4 MAX15090BEWIT-MAX15090BEWI+T,SA    I62 @S9S_MB_2U_LIB.S9S_MB_2U(SCH_1):PAGE324
 PU294   B4 OUT_B4 MAX15090BEWIT-MAX15090BEWI+T,SA    I62 @S9S_MB_2U_LIB.S9S_MB_2U(SCH_1):PAGE324
 PU294   B6 OUT_B6 MAX15090BEWIT-MAX15090BEWI+T,SA    I62 @S9S_MB_2U_LIB.S9S_MB_2U(SCH_1):PAGE324
 PU294   C4 OUT_C4 MAX15090BEWIT-MAX15090BEWI+T,SA    I62 @S9S_MB_2U_LIB.S9S_MB_2U(SCH_1):PAGE324
 PU294   C6 OUT_C6 MAX15090BEWIT-MAX15090BEWI+T,SA    I62 @S9S_MB_2U_LIB.S9S_MB_2U(SCH_1):PAGE324
 PU294   D4 OUT_D4 MAX15090BEWIT-MAX15090BEWI+T,SA    I62 @S9S_MB_2U_LIB.S9S_MB_2U(SCH_1):PAGE324
 PU294   D6 OUT_D6 MAX15090BEWIT-MAX15090BEWI+T,SA    I62 @S9S_MB_2U_LIB.S9S_MB_2U(SCH_1):PAGE324
PR4528    1      A Q_RES_0402LF-10M,1%,1/16W,EMPTA    I70 @S9S_MB_2U_LIB.S9S_MB_2U(SCH_1):PAGE324
 PD112    C      C SCHOTTKY_AC-B340A-13-F,SMLF,ICA    I71 @S9S_MB_2U_LIB.S9S_MB_2U(SCH_1):PAGE324
   J90   B1 P12V_B1 SCONN56_123276793-SCONN56_1-23A   I318 @S9S_MB_2U_LIB.S9S_MB_2U(SCH_1):PAGE297
   J90   B2 P12V_B2 SCONN56_123276793-SCONN56_1-23A   I318 @S9S_MB_2U_LIB.S9S_MB_2U(SCH_1):PAGE297
   J90   B3 P12V_B3 SCONN56_123276793-SCONN56_1-23A   I318 @S9S_MB_2U_LIB.S9S_MB_2U(SCH_1):PAGE297
   J90   B4 P12V_B4 SCONN56_123276793-SCONN56_1-23A   I318 @S9S_MB_2U_LIB.S9S_MB_2U(SCH_1):PAGE297
   J90   B5 P12V_B5 SCONN56_123276793-SCONN56_1-23A   I318 @S9S_MB_2U_LIB.S9S_MB_2U(SCH_1):PAGE297
   J90   B6 P12V_B6 SCONN56_123276793-SCONN56_1-23A   I318 @S9S_MB_2U_LIB.S9S_MB_2U(SCH_1):PAGE297
PC2214    1      A Q_CAP_C0402-0.01UF,50V,10%,EMPA    I69 @S9S_MB_2U_LIB.S9S_MB_2U(SCH_1):PAGE324
PC2217    1      A Q_CAP_0402-0.1UF,25V,10%,X7R,CA    I75 @S9S_MB_2U_LIB.S9S_MB_2U(SCH_1):PAGE324
PC2219    1      A Q_CAP_C0805-10UF,16V,10%,X6S,CC    I78 @S9S_MB_2U_LIB.S9S_MB_2U(SCH_1):PAGE324
 PU292   13 VOUT_13 RS31312R-RS31312R,SMLF,IC,AL03A    I49 @S9S_MB_2U_LIB.S9S_MB_2U(SCH_1):PAGE323
 PU292   14 VOUT_14 RS31312R-RS31312R,SMLF,IC,AL03A    I49 @S9S_MB_2U_LIB.S9S_MB_2U(SCH_1):PAGE323
 PU292   15 VOUT_15 RS31312R-RS31312R,SMLF,IC,AL03A    I49 @S9S_MB_2U_LIB.S9S_MB_2U(SCH_1):PAGE323
 PU292   16 VOUT_16 RS31312R-RS31312R,SMLF,IC,AL03A    I49 @S9S_MB_2U_LIB.S9S_MB_2U(SCH_1):PAGE323
 PU292   17 VOUT_17 RS31312R-RS31312R,SMLF,IC,AL03A    I49 @S9S_MB_2U_LIB.S9S_MB_2U(SCH_1):PAGE323
 PU292   18 VOUT_18 RS31312R-RS31312R,SMLF,IC,AL03A    I49 @S9S_MB_2U_LIB.S9S_MB_2U(SCH_1):PAGE323
 PU292   19 VOUT_19 RS31312R-RS31312R,SMLF,IC,AL03A    I49 @S9S_MB_2U_LIB.S9S_MB_2U(SCH_1):PAGE323
 PU292   20 VOUT_20 RS31312R-RS31312R,SMLF,IC,AL03A    I49 @S9S_MB_2U_LIB.S9S_MB_2U(SCH_1):PAGE323
PR3950    1      A Q_RES_0402LF-100,1%,1/16W,EMPTA    I55 @S9S_MB_2U_LIB.S9S_MB_2U(SCH_1):PAGE323
PR3952    1      A Q_RES_0402LF-71.5K,1%,1/16W,EMA    I62 @S9S_MB_2U_LIB.S9S_MB_2U(SCH_1):PAGE323
PC2206    1      A Q_CAP_0402-0.1UF,25V,10%,X7R,CA    I73 @S9S_MB_2U_LIB.S9S_MB_2U(SCH_1):PAGE323
PC2280    1      A Q_CAP_C0805-10UF,16V,10%,X6S,CC    I79 @S9S_MB_2U_LIB.S9S_MB_2U(SCH_1):PAGE324

P12V_E1S_0_EN_G @S9S_MB_2U_LIB.S9S_MB_2U(SCH_1):P12V_E1S_0_EN_G
 R4074    2      B Q_RES_0402LF-10K,1%,1/16W,EMPTA    I22 @S9S_MB_2U_LIB.S9S_MB_2U(SCH_1):PAGE324
  Q127    6     D1 MOSFET_NCH_DUAL-PJT138K,SMLF,EA    I10 @S9S_MB_2U_LIB.S9S_MB_2U(SCH_1):PAGE324
  Q127    5     G2 MOSFET_NCH_DUAL-PJT138K,SMLF,EA    I24 @S9S_MB_2U_LIB.S9S_MB_2U(SCH_1):PAGE324

P12V_E1S_0_ISENSE_MAM @S9S_MB_2U_LIB.S9S_MB_2U(SCH_1):P12V_E1S_0_ISENSE_MAM
  U193   12   AIN7 MAX11617EEET-MAX11617EEE+T,SMLA    I57 @S9S_MB_2U_LIB.S9S_MB_2U(SCH_1):PAGE239
 R3939    2      B Q_RES_0402LF-0,5%,1/16W,EMPTY,A   I330 @S9S_MB_2U_LIB.S9S_MB_2U(SCH_1):PAGE239
 C2195    1      A Q_CAP_0402-100PF,50V,5%,EMPTY,A   I333 @S9S_MB_2U_LIB.S9S_MB_2U(SCH_1):PAGE239
 R3940    2      B Q_RES_0402LF-0,5%,1/16W,EMPTY,A   I337 @S9S_MB_2U_LIB.S9S_MB_2U(SCH_1):PAGE239

P12V_E1S_0_ISENSE_MAM_MAM @S9S_MB_2U_LIB.S9S_MB_2U(SCH_1):P12V_E1S_0_ISENSE_MAM_MAM
 R3974    2      B Q_RES_0402LF-0,5%,1/16W,EMPTY,A    I67 @S9S_MB_2U_LIB.S9S_MB_2U(SCH_1):PAGE324
 R3939    1      A Q_RES_0402LF-0,5%,1/16W,EMPTY,A   I330 @S9S_MB_2U_LIB.S9S_MB_2U(SCH_1):PAGE239

P12V_E1S_0_ISENSE_MAM_TIC @S9S_MB_2U_LIB.S9S_MB_2U(SCH_1):P12V_E1S_0_ISENSE_MAM_TIC
 R3941    1      A Q_RES_0402LF-0,5%,1/16W,EMPTY,A   I338 @S9S_MB_2U_LIB.S9S_MB_2U(SCH_1):PAGE239
 R3975    2      B Q_RES_0402LF-0,5%,1/16W,EMPTY,A    I65 @S9S_MB_2U_LIB.S9S_MB_2U(SCH_1):PAGE324

P12V_E1S_0_ISENSE_MPS_MAM @S9S_MB_2U_LIB.S9S_MB_2U(SCH_1):P12V_E1S_0_ISENSE_MPS_MAM
 R3940    1      A Q_RES_0402LF-0,5%,1/16W,EMPTY,A   I337 @S9S_MB_2U_LIB.S9S_MB_2U(SCH_1):PAGE239
 R3955    2      B Q_RES_0402LF-0,5%,1/16W,EMPTY,A    I67 @S9S_MB_2U_LIB.S9S_MB_2U(SCH_1):PAGE323

P12V_E1S_0_ISENSE_MPS_TIC @S9S_MB_2U_LIB.S9S_MB_2U(SCH_1):P12V_E1S_0_ISENSE_MPS_TIC
 R3942    1      A Q_RES_0402LF-0,5%,1/16W,CHIP,CA   I339 @S9S_MB_2U_LIB.S9S_MB_2U(SCH_1):PAGE239
 R3956    2      B Q_RES_0402LF-0,5%,1/16W,CHIP,CA    I66 @S9S_MB_2U_LIB.S9S_MB_2U(SCH_1):PAGE323

P12V_E1S_0_ISENSE_TIC @S9S_MB_2U_LIB.S9S_MB_2U(SCH_1):P12V_E1S_0_ISENSE_TIC
  U269    9    IN7 ADC128D818CIMTXNOPB-ADC128D818A   I103 @S9S_MB_2U_LIB.S9S_MB_2U(SCH_1):PAGE239
 C2194    1      A Q_CAP_0402-0.1UF,25V,10%,X7R,CA   I336 @S9S_MB_2U_LIB.S9S_MB_2U(SCH_1):PAGE239
 R3941    2      B Q_RES_0402LF-0,5%,1/16W,EMPTY,A   I338 @S9S_MB_2U_LIB.S9S_MB_2U(SCH_1):PAGE239
 R3942    2      B Q_RES_0402LF-0,5%,1/16W,CHIP,CA   I339 @S9S_MB_2U_LIB.S9S_MB_2U(SCH_1):PAGE239

P12V_E1S_AVIN_PD_0 @S9S_MB_2U_LIB.S9S_MB_2U(SCH_1):P12V_E1S_AVIN_PD_0
 PU292   12   AVIN RS31312R-RS31312R,SMLF,IC,AL03A    I49 @S9S_MB_2U_LIB.S9S_MB_2U(SCH_1):PAGE323
PR3950    2      B Q_RES_0402LF-100,1%,1/16W,EMPTA    I55 @S9S_MB_2U_LIB.S9S_MB_2U(SCH_1):PAGE323
PC2205    1      A Q_CAP_C0603-2.2UF,16V,20%,X7R,A    I69 @S9S_MB_2U_LIB.S9S_MB_2U(SCH_1):PAGE323
PR3957    2      B Q_RES_0603LF-49.9,1%,1/10W,CHIA    I70 @S9S_MB_2U_LIB.S9S_MB_2U(SCH_1):PAGE323

P12V_E1S_CB_0 @S9S_MB_2U_LIB.S9S_MB_2U(SCH_1):P12V_E1S_CB_0
 PU294   B1     CB MAX15090BEWIT-MAX15090BEWI+T,SA    I62 @S9S_MB_2U_LIB.S9S_MB_2U(SCH_1):PAGE324
PR3968    1      A Q_RES_0402LF-9.31K,1%,1/16W,EMA    I59 @S9S_MB_2U_LIB.S9S_MB_2U(SCH_1):PAGE324

P12V_E1S_EN_0_R @S9S_MB_2U_LIB.S9S_MB_2U(SCH_1):P12V_E1S_EN_0_R
 R4064    2      B Q_RES_0402LF-0,5%,1/16W,CHIP,CA    I21 @S9S_MB_2U_LIB.S9S_MB_2U(SCH_1):PAGE324
 R4073    1      A Q_RES_0402LF-4.7K,5%,1/16W,CHIA     I9 @S9S_MB_2U_LIB.S9S_MB_2U(SCH_1):PAGE324
  Q127    2     G1 MOSFET_NCH_DUAL-PJT138K,SMLF,EA    I10 @S9S_MB_2U_LIB.S9S_MB_2U(SCH_1):PAGE324

P12V_E1S_EN_0_R2 @S9S_MB_2U_LIB.S9S_MB_2U(SCH_1):P12V_E1S_EN_0_R2
 R3943    2      B Q_RES_0402LF-0,5%,1/16W,CHIP,CA    I45 @S9S_MB_2U_LIB.S9S_MB_2U(SCH_1):PAGE323
 PU292    1     EN RS31312R-RS31312R,SMLF,IC,AL03A    I49 @S9S_MB_2U_LIB.S9S_MB_2U(SCH_1):PAGE323

P12V_E1S_FAULT_0 @S9S_MB_2U_LIB.S9S_MB_2U(SCH_1):P12V_E1S_FAULT_0
 PU294   C7 FAULT# MAX15090BEWIT-MAX15090BEWI+T,SA    I62 @S9S_MB_2U_LIB.S9S_MB_2U(SCH_1):PAGE324
 R3976    2      B Q_RES_0402LF-100K,1%,1/16W,EMPA    I73 @S9S_MB_2U_LIB.S9S_MB_2U(SCH_1):PAGE324

P12V_E1S_FLTB_0 @S9S_MB_2U_LIB.S9S_MB_2U(SCH_1):P12V_E1S_FLTB_0
 PU292    9   FLTB RS31312R-RS31312R,SMLF,IC,AL03A    I49 @S9S_MB_2U_LIB.S9S_MB_2U(SCH_1):PAGE323
PR3951    1      A Q_RES_0402LF-10K,1%,1/16W,CHIPA    I54 @S9S_MB_2U_LIB.S9S_MB_2U(SCH_1):PAGE323

P12V_E1S_GATE_0 @S9S_MB_2U_LIB.S9S_MB_2U(SCH_1):P12V_E1S_GATE_0
 PU294   A6   GATE MAX15090BEWIT-MAX15090BEWI+T,SA    I62 @S9S_MB_2U_LIB.S9S_MB_2U(SCH_1):PAGE324
PR4528    2      B Q_RES_0402LF-10M,1%,1/16W,EMPTA    I70 @S9S_MB_2U_LIB.S9S_MB_2U(SCH_1):PAGE324
PC2215    1      A Q_CAP_C0402-3900PF,50V,10%,EMPA    I66 @S9S_MB_2U_LIB.S9S_MB_2U(SCH_1):PAGE324
PC2214    2      B Q_CAP_C0402-0.01UF,50V,10%,EMPA    I69 @S9S_MB_2U_LIB.S9S_MB_2U(SCH_1):PAGE324

P12V_E1S_IMON_0 @S9S_MB_2U_LIB.S9S_MB_2U(SCH_1):P12V_E1S_IMON_0
 PU292    8   IMON RS31312R-RS31312R,SMLF,IC,AL03A    I49 @S9S_MB_2U_LIB.S9S_MB_2U(SCH_1):PAGE323
PC2202    1      A Q_CAP_C0402-100NF,50V,10%,X7R,A    I56 @S9S_MB_2U_LIB.S9S_MB_2U(SCH_1):PAGE323
PR3949    1      A Q_RES_0402LF-56K,1%,1/16W,CHIPA    I53 @S9S_MB_2U_LIB.S9S_MB_2U(SCH_1):PAGE323
 R3956    1      A Q_RES_0402LF-0,5%,1/16W,CHIP,CA    I66 @S9S_MB_2U_LIB.S9S_MB_2U(SCH_1):PAGE323
 R3955    1      A Q_RES_0402LF-0,5%,1/16W,EMPTY,A    I67 @S9S_MB_2U_LIB.S9S_MB_2U(SCH_1):PAGE323

P12V_E1S_ISET_0 @S9S_MB_2U_LIB.S9S_MB_2U(SCH_1):P12V_E1S_ISET_0
PR3944    1      A Q_RES_0402LF-46.4K,1%,1/16W,CHA    I40 @S9S_MB_2U_LIB.S9S_MB_2U(SCH_1):PAGE323
 PU292    5   ISET RS31312R-RS31312R,SMLF,IC,AL03A    I49 @S9S_MB_2U_LIB.S9S_MB_2U(SCH_1):PAGE323
PR4541    1      A Q_RES_0402LF-20K,1%,1/16W,CHIPA    I43 @S9S_MB_2U_LIB.S9S_MB_2U(SCH_1):PAGE323

P12V_E1S_ISET_0_R @S9S_MB_2U_LIB.S9S_MB_2U(SCH_1):P12V_E1S_ISET_0_R
PC2341    1      A Q_CAP_C0402-560PF,50V,10%,X7R,A    I42 @S9S_MB_2U_LIB.S9S_MB_2U(SCH_1):PAGE323
PR4541    2      B Q_RES_0402LF-20K,1%,1/16W,CHIPA    I43 @S9S_MB_2U_LIB.S9S_MB_2U(SCH_1):PAGE323

P12V_E1S_OV_0 @S9S_MB_2U_LIB.S9S_MB_2U(SCH_1):P12V_E1S_OV_0
 PU294   D3     OV MAX15090BEWIT-MAX15090BEWI+T,SA    I62 @S9S_MB_2U_LIB.S9S_MB_2U(SCH_1):PAGE324
PR3962    1      A Q_RES_0402LF-15K,1%,1/16W,EMPTA    I28 @S9S_MB_2U_LIB.S9S_MB_2U(SCH_1):PAGE324
PR3961    2      B Q_RES_0402LF-6.8K,1%,1/16W,EMPA    I85 @S9S_MB_2U_LIB.S9S_MB_2U(SCH_1):PAGE324

P12V_E1S_OV_FB_0 @S9S_MB_2U_LIB.S9S_MB_2U(SCH_1):P12V_E1S_OV_FB_0
 PU292   11     OV RS31312R-RS31312R,SMLF,IC,AL03A    I49 @S9S_MB_2U_LIB.S9S_MB_2U(SCH_1):PAGE323
PR3954    1      A Q_RES_0402LF-10K,1%,1/16W,CHIPA    I58 @S9S_MB_2U_LIB.S9S_MB_2U(SCH_1):PAGE323
PR3952    2      B Q_RES_0402LF-71.5K,1%,1/16W,EMA    I62 @S9S_MB_2U_LIB.S9S_MB_2U(SCH_1):PAGE323
PR3953    2      B Q_RES_0402LF-120K,1%,1/16W,CHIA    I63 @S9S_MB_2U_LIB.S9S_MB_2U(SCH_1):PAGE323

P12V_E1S_PWRGD_0 @S9S_MB_2U_LIB.S9S_MB_2U(SCH_1):P12V_E1S_PWRGD_0
 PU294   D7     PG MAX15090BEWIT-MAX15090BEWI+T,SA    I62 @S9S_MB_2U_LIB.S9S_MB_2U(SCH_1):PAGE324
 R3972    1      A Q_RES_0402LF-0,5%,1/16W,EMPTY,A    I68 @S9S_MB_2U_LIB.S9S_MB_2U(SCH_1):PAGE324

P12V_E1S_REG_0 @S9S_MB_2U_LIB.S9S_MB_2U(SCH_1):P12V_E1S_REG_0
 PU294   D1    REG MAX15090BEWIT-MAX15090BEWI+T,SA    I62 @S9S_MB_2U_LIB.S9S_MB_2U(SCH_1):PAGE324
PC2211    2      B Q_CAP_C0402-1UF,25V,10%,EMPTY,A    I57 @S9S_MB_2U_LIB.S9S_MB_2U(SCH_1):PAGE324

P12V_E1S_SENSE_0 @S9S_MB_2U_LIB.S9S_MB_2U(SCH_1):P12V_E1S_SENSE_0
 PU294   A1 ISENSE MAX15090BEWIT-MAX15090BEWI+T,SA    I62 @S9S_MB_2U_LIB.S9S_MB_2U(SCH_1):PAGE324
 R3974    1      A Q_RES_0402LF-0,5%,1/16W,EMPTY,A    I67 @S9S_MB_2U_LIB.S9S_MB_2U(SCH_1):PAGE324
 R3975    1      A Q_RES_0402LF-0,5%,1/16W,EMPTY,A    I65 @S9S_MB_2U_LIB.S9S_MB_2U(SCH_1):PAGE324
PR3970    1      A Q_RES_0402LF-2.67K,1%,1/16W,EMA    I64 @S9S_MB_2U_LIB.S9S_MB_2U(SCH_1):PAGE324

P12V_E1S_SS_0 @S9S_MB_2U_LIB.S9S_MB_2U(SCH_1):P12V_E1S_SS_0
PC2281    1      A Q_CAP_C0402-0.047UF,25V,10%,X7A    I47 @S9S_MB_2U_LIB.S9S_MB_2U(SCH_1):PAGE323
 PU292    6     SS RS31312R-RS31312R,SMLF,IC,AL03A    I49 @S9S_MB_2U_LIB.S9S_MB_2U(SCH_1):PAGE323

P12V_E1S_TIMER_0 @S9S_MB_2U_LIB.S9S_MB_2U(SCH_1):P12V_E1S_TIMER_0
PC2196    1      A Q_CAP_0402-0.22UF,16V,10%,X7R,A    I37 @S9S_MB_2U_LIB.S9S_MB_2U(SCH_1):PAGE323
 PU292    4  TIMER RS31312R-RS31312R,SMLF,IC,AL03A    I49 @S9S_MB_2U_LIB.S9S_MB_2U(SCH_1):PAGE323

P12V_E1S_UV_0 @S9S_MB_2U_LIB.S9S_MB_2U(SCH_1):P12V_E1S_UV_0
 PU294   D2     UV MAX15090BEWIT-MAX15090BEWI+T,SA    I62 @S9S_MB_2U_LIB.S9S_MB_2U(SCH_1):PAGE324
 R3958    2      B Q_RES_0402LF-0,5%,1/16W,EMPTY,A    I26 @S9S_MB_2U_LIB.S9S_MB_2U(SCH_1):PAGE324
PR3960    2      B Q_RES_0402LF-160K,1%,1/16W,EMPA    I32 @S9S_MB_2U_LIB.S9S_MB_2U(SCH_1):PAGE324
PR3961    1      A Q_RES_0402LF-6.8K,1%,1/16W,EMPA    I85 @S9S_MB_2U_LIB.S9S_MB_2U(SCH_1):PAGE324

P12V_E1S_UV_0_R @S9S_MB_2U_LIB.S9S_MB_2U(SCH_1):P12V_E1S_UV_0_R
  Q127    3     D2 MOSFET_NCH_DUAL-PJT138K,SMLF,EA    I24 @S9S_MB_2U_LIB.S9S_MB_2U(SCH_1):PAGE324
 R3958    1      A Q_RES_0402LF-0,5%,1/16W,EMPTY,A    I26 @S9S_MB_2U_LIB.S9S_MB_2U(SCH_1):PAGE324

P12V_E1S_VCC_0 @S9S_MB_2U_LIB.S9S_MB_2U(SCH_1):P12V_E1S_VCC_0
PR3966    2      B Q_RES_0402LF-10,1%,1/16W,EMPTYA    I61 @S9S_MB_2U_LIB.S9S_MB_2U(SCH_1):PAGE324
 PU294   A2    VCC MAX15090BEWIT-MAX15090BEWI+T,SA    I62 @S9S_MB_2U_LIB.S9S_MB_2U(SCH_1):PAGE324
PC2209    1      A Q_CAP_C0402-1UF,25V,10%,EMPTY,A    I60 @S9S_MB_2U_LIB.S9S_MB_2U(SCH_1):PAGE324

P12V_HSC_ADC_N @S9S_MB_2U_LIB.S9S_MB_2U(SCH_1):P12V_HSC_ADC_N
  PJ42    6      6 SCONN21_9193031121LF-SCONN21_9A    I34 @S9S_MB_2U_LIB.S9S_MB_2U(SCH_1):PAGE327
PR2517    1      A Q_RES_0402LF-10,1%,1/16W,EMPTYA    I90 @S9S_MB_2U_LIB.S9S_MB_2U(SCH_1):PAGE328
PR2518    1      A Q_RES_0402LF-10,1%,1/16W,EMPTYA    I91 @S9S_MB_2U_LIB.S9S_MB_2U(SCH_1):PAGE328
PR2519    1      A Q_RES_0402LF-100,1%,1/16W,EMPTA    I92 @S9S_MB_2U_LIB.S9S_MB_2U(SCH_1):PAGE328
PR2515    1      A Q_RES_0402LF-10,1%,1/16W,EMPTYA    I93 @S9S_MB_2U_LIB.S9S_MB_2U(SCH_1):PAGE328
PR2516    1      A Q_RES_0402LF-10,1%,1/16W,EMPTYA    I94 @S9S_MB_2U_LIB.S9S_MB_2U(SCH_1):PAGE328

P12V_HSC_ADC_P @S9S_MB_2U_LIB.S9S_MB_2U(SCH_1):P12V_HSC_ADC_P
  PJ42    7      7 SCONN21_9193031121LF-SCONN21_9A    I34 @S9S_MB_2U_LIB.S9S_MB_2U(SCH_1):PAGE327
PR2513    1      A Q_RES_0402LF-1,1%,1/16W,EMPTY,A    I95 @S9S_MB_2U_LIB.S9S_MB_2U(SCH_1):PAGE328
PR2512    1      A Q_RES_0402LF-1,1%,1/16W,EMPTY,A    I96 @S9S_MB_2U_LIB.S9S_MB_2U(SCH_1):PAGE328
PR2514    1      A Q_RES_0402LF-10,1%,1/16W,EMPTYA    I97 @S9S_MB_2U_LIB.S9S_MB_2U(SCH_1):PAGE328
PR2510    1      A Q_RES_0402LF-1,1%,1/16W,EMPTY,A    I98 @S9S_MB_2U_LIB.S9S_MB_2U(SCH_1):PAGE328
PR2511    1      A Q_RES_0402LF-1,1%,1/16W,EMPTY,A    I99 @S9S_MB_2U_LIB.S9S_MB_2U(SCH_1):PAGE328

P12V_HSC_GATE1 @S9S_MB_2U_LIB.S9S_MB_2U(SCH_1):P12V_HSC_GATE1
PR2538    2      B Q_RES_0402LF-10,1%,1/16W,EMPTYA    I76 @S9S_MB_2U_LIB.S9S_MB_2U(SCH_1):PAGE328
  PJ42    8      8 SCONN21_9193031121LF-SCONN21_9A    I34 @S9S_MB_2U_LIB.S9S_MB_2U(SCH_1):PAGE327

P12V_HSC_GATE2 @S9S_MB_2U_LIB.S9S_MB_2U(SCH_1):P12V_HSC_GATE2
PR2528    2      B Q_RES_0402LF-10,1%,1/16W,EMPTYA    I16 @S9S_MB_2U_LIB.S9S_MB_2U(SCH_1):PAGE328
PR2529    2      B Q_RES_0402LF-10,1%,1/16W,EMPTYA    I38 @S9S_MB_2U_LIB.S9S_MB_2U(SCH_1):PAGE328
PR2530    2      B Q_RES_0402LF-10,1%,1/16W,EMPTYA    I39 @S9S_MB_2U_LIB.S9S_MB_2U(SCH_1):PAGE328
PR2531    2      B Q_RES_0402LF-10,1%,1/16W,EMPTYA    I59 @S9S_MB_2U_LIB.S9S_MB_2U(SCH_1):PAGE328
PR2535    2      B Q_RES_0402LF-10,1%,1/16W,EMPTYA    I60 @S9S_MB_2U_LIB.S9S_MB_2U(SCH_1):PAGE328
PR2536    2      B Q_RES_0402LF-10,1%,1/16W,EMPTYA    I61 @S9S_MB_2U_LIB.S9S_MB_2U(SCH_1):PAGE328
PC1750    2      B Q_CAP_C0402-33NF,25V,10%,EMPTYA    I68 @S9S_MB_2U_LIB.S9S_MB_2U(SCH_1):PAGE328
PC1751    2      B Q_CAP_0402-1NF,50V,10%,EMPTY,CA    I69 @S9S_MB_2U_LIB.S9S_MB_2U(SCH_1):PAGE328
  PJ42    9      9 SCONN21_9193031121LF-SCONN21_9A    I34 @S9S_MB_2U_LIB.S9S_MB_2U(SCH_1):PAGE327

P12V_HSC_GATE_G1 @S9S_MB_2U_LIB.S9S_MB_2U(SCH_1):P12V_HSC_GATE_G1
PR2528    1      A Q_RES_0402LF-10,1%,1/16W,EMPTYA    I16 @S9S_MB_2U_LIB.S9S_MB_2U(SCH_1):PAGE328
  PPQ5    4      4 MOSFET_NCH_1D3S-PSMNR58-30YLH,B    I35 @S9S_MB_2U_LIB.S9S_MB_2U(SCH_1):PAGE328

P12V_HSC_GATE_G2 @S9S_MB_2U_LIB.S9S_MB_2U(SCH_1):P12V_HSC_GATE_G2
PR2529    1      A Q_RES_0402LF-10,1%,1/16W,EMPTYA    I38 @S9S_MB_2U_LIB.S9S_MB_2U(SCH_1):PAGE328
  PPQ6    4      4 MOSFET_NCH_1D3S-PSMNR58-30YLH,B    I40 @S9S_MB_2U_LIB.S9S_MB_2U(SCH_1):PAGE328

P12V_HSC_GATE_G3 @S9S_MB_2U_LIB.S9S_MB_2U(SCH_1):P12V_HSC_GATE_G3
PR2530    1      A Q_RES_0402LF-10,1%,1/16W,EMPTYA    I39 @S9S_MB_2U_LIB.S9S_MB_2U(SCH_1):PAGE328
  PPQ7    4      4 MOSFET_NCH_1D3S-PSMNR58-30YLH,B    I41 @S9S_MB_2U_LIB.S9S_MB_2U(SCH_1):PAGE328

P12V_HSC_GATE_G4 @S9S_MB_2U_LIB.S9S_MB_2U(SCH_1):P12V_HSC_GATE_G4
PR2531    1      A Q_RES_0402LF-10,1%,1/16W,EMPTYA    I59 @S9S_MB_2U_LIB.S9S_MB_2U(SCH_1):PAGE328
  PPQ8    4      4 MOSFET_NCH_1D3S-PSMNR58-30YLH,B    I62 @S9S_MB_2U_LIB.S9S_MB_2U(SCH_1):PAGE328

P12V_HSC_GATE_G5 @S9S_MB_2U_LIB.S9S_MB_2U(SCH_1):P12V_HSC_GATE_G5
PR2535    1      A Q_RES_0402LF-10,1%,1/16W,EMPTYA    I60 @S9S_MB_2U_LIB.S9S_MB_2U(SCH_1):PAGE328
  PPQ1    4      4 MOSFET_NCH_1D3S-PSMNR58-30YLH,B    I65 @S9S_MB_2U_LIB.S9S_MB_2U(SCH_1):PAGE328

P12V_HSC_GATE_G6 @S9S_MB_2U_LIB.S9S_MB_2U(SCH_1):P12V_HSC_GATE_G6
PR2536    1      A Q_RES_0402LF-10,1%,1/16W,EMPTYA    I61 @S9S_MB_2U_LIB.S9S_MB_2U(SCH_1):PAGE328
  PPQ2    4      4 MOSFET_NCH_1D3S-PSMNR58-30YLH,B    I73 @S9S_MB_2U_LIB.S9S_MB_2U(SCH_1):PAGE328

P12V_HSC_GATE_RC @S9S_MB_2U_LIB.S9S_MB_2U(SCH_1):P12V_HSC_GATE_RC
PC1751    1      A Q_CAP_0402-1NF,50V,10%,EMPTY,CA    I69 @S9S_MB_2U_LIB.S9S_MB_2U(SCH_1):PAGE328
PR2537    2      B Q_RES_0402LF-10,1%,1/16W,EMPTYA    I70 @S9S_MB_2U_LIB.S9S_MB_2U(SCH_1):PAGE328

P12V_HSC_SENSE1_N @S9S_MB_2U_LIB.S9S_MB_2U(SCH_1):P12V_HSC_SENSE1_N
  PJ42    3      3 SCONN21_9193031121LF-SCONN21_9A    I34 @S9S_MB_2U_LIB.S9S_MB_2U(SCH_1):PAGE327
PR2519    2      B Q_RES_0402LF-100,1%,1/16W,EMPTA    I92 @S9S_MB_2U_LIB.S9S_MB_2U(SCH_1):PAGE328
   PR3    4      4 Q_RES_4P_12-0.003,1%,3W,SMLF,EA   I126 @S9S_MB_2U_LIB.S9S_MB_2U(SCH_1):PAGE328

P12V_HSC_SENSE1_P @S9S_MB_2U_LIB.S9S_MB_2U(SCH_1):P12V_HSC_SENSE1_P
  PJ42    2      2 SCONN21_9193031121LF-SCONN21_9A    I34 @S9S_MB_2U_LIB.S9S_MB_2U(SCH_1):PAGE327
PR2514    2      B Q_RES_0402LF-10,1%,1/16W,EMPTYA    I97 @S9S_MB_2U_LIB.S9S_MB_2U(SCH_1):PAGE328
   PR3    3      3 Q_RES_4P_12-0.003,1%,3W,SMLF,EA   I126 @S9S_MB_2U_LIB.S9S_MB_2U(SCH_1):PAGE328

P12V_HSC_SENSE2_N @S9S_MB_2U_LIB.S9S_MB_2U(SCH_1):P12V_HSC_SENSE2_N
  PJ42    5      5 SCONN21_9193031121LF-SCONN21_9A    I34 @S9S_MB_2U_LIB.S9S_MB_2U(SCH_1):PAGE327
PR2527    1      A Q_RES_0402LF-10,1%,1/16W,EMPTYA   I117 @S9S_MB_2U_LIB.S9S_MB_2U(SCH_1):PAGE328
PR2526    1      A Q_RES_0402LF-10,1%,1/16W,EMPTYA   I118 @S9S_MB_2U_LIB.S9S_MB_2U(SCH_1):PAGE328
PR2524    1      A Q_RES_0402LF-10,1%,1/16W,EMPTYA   I119 @S9S_MB_2U_LIB.S9S_MB_2U(SCH_1):PAGE328
PR2525    1      A Q_RES_0402LF-10,1%,1/16W,EMPTYA   I120 @S9S_MB_2U_LIB.S9S_MB_2U(SCH_1):PAGE328

P12V_HSC_SENSE2_P @S9S_MB_2U_LIB.S9S_MB_2U(SCH_1):P12V_HSC_SENSE2_P
  PJ42    4      4 SCONN21_9193031121LF-SCONN21_9A    I34 @S9S_MB_2U_LIB.S9S_MB_2U(SCH_1):PAGE327
PR2522    1      A Q_RES_0402LF-1,1%,1/16W,EMPTY,A    I86 @S9S_MB_2U_LIB.S9S_MB_2U(SCH_1):PAGE328
PR2523    1      A Q_RES_0402LF-1,1%,1/16W,EMPTY,A    I87 @S9S_MB_2U_LIB.S9S_MB_2U(SCH_1):PAGE328
PR2521    1      A Q_RES_0402LF-1,1%,1/16W,EMPTY,A    I88 @S9S_MB_2U_LIB.S9S_MB_2U(SCH_1):PAGE328
PR2520    1      A Q_RES_0402LF-1,1%,1/16W,EMPTY,A    I89 @S9S_MB_2U_LIB.S9S_MB_2U(SCH_1):PAGE328

P12V_HSC_SENSE2_R1_N @S9S_MB_2U_LIB.S9S_MB_2U(SCH_1):P12V_HSC_SENSE2_R1_N
   PR4   2B     2B Q_SP_RES4P-0.0003,1%,4W,SMLF,EA    I79 @S9S_MB_2U_LIB.S9S_MB_2U(SCH_1):PAGE328
PR2515    2      B Q_RES_0402LF-10,1%,1/16W,EMPTYA    I93 @S9S_MB_2U_LIB.S9S_MB_2U(SCH_1):PAGE328
PR2524    2      B Q_RES_0402LF-10,1%,1/16W,EMPTYA   I119 @S9S_MB_2U_LIB.S9S_MB_2U(SCH_1):PAGE328

P12V_HSC_SENSE2_R1_P @S9S_MB_2U_LIB.S9S_MB_2U(SCH_1):P12V_HSC_SENSE2_R1_P
   PR4   1B     1B Q_SP_RES4P-0.0003,1%,4W,SMLF,EA    I79 @S9S_MB_2U_LIB.S9S_MB_2U(SCH_1):PAGE328
PR2520    2      B Q_RES_0402LF-1,1%,1/16W,EMPTY,A    I89 @S9S_MB_2U_LIB.S9S_MB_2U(SCH_1):PAGE328
PR2510    2      B Q_RES_0402LF-1,1%,1/16W,EMPTY,A    I98 @S9S_MB_2U_LIB.S9S_MB_2U(SCH_1):PAGE328

P12V_HSC_SENSE2_R2_N @S9S_MB_2U_LIB.S9S_MB_2U(SCH_1):P12V_HSC_SENSE2_R2_N
PR2532   2B     2B Q_SP_RES4P-0.0003,1%,4W,SMLF,EA    I78 @S9S_MB_2U_LIB.S9S_MB_2U(SCH_1):PAGE328
PR2516    2      B Q_RES_0402LF-10,1%,1/16W,EMPTYA    I94 @S9S_MB_2U_LIB.S9S_MB_2U(SCH_1):PAGE328
PR2525    2      B Q_RES_0402LF-10,1%,1/16W,EMPTYA   I120 @S9S_MB_2U_LIB.S9S_MB_2U(SCH_1):PAGE328

P12V_HSC_SENSE2_R2_P @S9S_MB_2U_LIB.S9S_MB_2U(SCH_1):P12V_HSC_SENSE2_R2_P
PR2532   1B     1B Q_SP_RES4P-0.0003,1%,4W,SMLF,EA    I78 @S9S_MB_2U_LIB.S9S_MB_2U(SCH_1):PAGE328
PR2521    2      B Q_RES_0402LF-1,1%,1/16W,EMPTY,A    I88 @S9S_MB_2U_LIB.S9S_MB_2U(SCH_1):PAGE328
PR2511    2      B Q_RES_0402LF-1,1%,1/16W,EMPTY,A    I99 @S9S_MB_2U_LIB.S9S_MB_2U(SCH_1):PAGE328

P12V_HSC_SENSE2_R3_N @S9S_MB_2U_LIB.S9S_MB_2U(SCH_1):P12V_HSC_SENSE2_R3_N
PR2533   2B     2B Q_SP_RES4P-0.0003,1%,4W,SMLF,EA    I64 @S9S_MB_2U_LIB.S9S_MB_2U(SCH_1):PAGE328
PR2517    2      B Q_RES_0402LF-10,1%,1/16W,EMPTYA    I90 @S9S_MB_2U_LIB.S9S_MB_2U(SCH_1):PAGE328
PR2526    2      B Q_RES_0402LF-10,1%,1/16W,EMPTYA   I118 @S9S_MB_2U_LIB.S9S_MB_2U(SCH_1):PAGE328

P12V_HSC_SENSE2_R3_P @S9S_MB_2U_LIB.S9S_MB_2U(SCH_1):P12V_HSC_SENSE2_R3_P
PR2533   1B     1B Q_SP_RES4P-0.0003,1%,4W,SMLF,EA    I64 @S9S_MB_2U_LIB.S9S_MB_2U(SCH_1):PAGE328
PR2522    2      B Q_RES_0402LF-1,1%,1/16W,EMPTY,A    I86 @S9S_MB_2U_LIB.S9S_MB_2U(SCH_1):PAGE328
PR2512    2      B Q_RES_0402LF-1,1%,1/16W,EMPTY,A    I96 @S9S_MB_2U_LIB.S9S_MB_2U(SCH_1):PAGE328

P12V_HSC_SENSE2_R4_N @S9S_MB_2U_LIB.S9S_MB_2U(SCH_1):P12V_HSC_SENSE2_R4_N
PR2534   2B     2B Q_SP_RES4P-0.0003,1%,4W,SMLF,EA    I63 @S9S_MB_2U_LIB.S9S_MB_2U(SCH_1):PAGE328
PR2518    2      B Q_RES_0402LF-10,1%,1/16W,EMPTYA    I91 @S9S_MB_2U_LIB.S9S_MB_2U(SCH_1):PAGE328
PR2527    2      B Q_RES_0402LF-10,1%,1/16W,EMPTYA   I117 @S9S_MB_2U_LIB.S9S_MB_2U(SCH_1):PAGE328

P12V_HSC_SENSE2_R4_P @S9S_MB_2U_LIB.S9S_MB_2U(SCH_1):P12V_HSC_SENSE2_R4_P
PR2534   1B     1B Q_SP_RES4P-0.0003,1%,4W,SMLF,EA    I63 @S9S_MB_2U_LIB.S9S_MB_2U(SCH_1):PAGE328
PR2523    2      B Q_RES_0402LF-1,1%,1/16W,EMPTY,A    I87 @S9S_MB_2U_LIB.S9S_MB_2U(SCH_1):PAGE328
PR2513    2      B Q_RES_0402LF-1,1%,1/16W,EMPTY,A    I95 @S9S_MB_2U_LIB.S9S_MB_2U(SCH_1):PAGE328

P12V_HSC_TEMP_ALERT_N @S9S_MB_2U_LIB.S9S_MB_2U(SCH_1):P12V_HSC_TEMP_ALERT_N
  U345    6 ALERT# NCT7718W-NCT7718W,SMLF,EMPTY,AA    I10 @S9S_MB_2U_LIB.S9S_MB_2U(SCH_1):PAGE327
 R4684    1      A Q_RES_0402LF-0,5%,1/16W,EMPTY,A    I14 @S9S_MB_2U_LIB.S9S_MB_2U(SCH_1):PAGE327

P12V_HSC_TEMP_ALERT_R_N @S9S_MB_2U_LIB.S9S_MB_2U(SCH_1):P12V_HSC_TEMP_ALERT_R_N
 R4684    2      B Q_RES_0402LF-0,5%,1/16W,EMPTY,A    I14 @S9S_MB_2U_LIB.S9S_MB_2U(SCH_1):PAGE327
 R4685    2      B Q_RES_0402LF-10.5K,1%,1/16W,EMA    I23 @S9S_MB_2U_LIB.S9S_MB_2U(SCH_1):PAGE327
  U249  A19  PT42A LCMXO3LF9400C5BG484C-LCMXO3LF-A   I188 @S9S_MB_2U_LIB.S9S_MB_2U(SCH_1):PAGE314

P12V_HSC_TEMP_D+ @S9S_MB_2U_LIB.S9S_MB_2U(SCH_1):P12V_HSC_TEMP_D+
 R4892    2      B Q_RES_0402LF-49.9,1%,1/16W,EMPA     I5 @S9S_MB_2U_LIB.S9S_MB_2U(SCH_1):PAGE327
 C2459    1      A Q_CAP_0603-1000PF,50V,10%,EMPTA     I6 @S9S_MB_2U_LIB.S9S_MB_2U(SCH_1):PAGE327
  U345    2     D+ NCT7718W-NCT7718W,SMLF,EMPTY,AA    I10 @S9S_MB_2U_LIB.S9S_MB_2U(SCH_1):PAGE327

P12V_HSC_TEMP_D- @S9S_MB_2U_LIB.S9S_MB_2U(SCH_1):P12V_HSC_TEMP_D-
 R4893    2      B Q_RES_0402LF-49.9,1%,1/16W,EMPA     I4 @S9S_MB_2U_LIB.S9S_MB_2U(SCH_1):PAGE327
 C2459    2      B Q_CAP_0603-1000PF,50V,10%,EMPTA     I6 @S9S_MB_2U_LIB.S9S_MB_2U(SCH_1):PAGE327
  U345    3     D- NCT7718W-NCT7718W,SMLF,EMPTY,AA    I10 @S9S_MB_2U_LIB.S9S_MB_2U(SCH_1):PAGE327

P12V_HSC_TEMP_E @S9S_MB_2U_LIB.S9S_MB_2U(SCH_1):P12V_HSC_TEMP_E
 R4893    1      A Q_RES_0402LF-49.9,1%,1/16W,EMPA     I4 @S9S_MB_2U_LIB.S9S_MB_2U(SCH_1):PAGE327
  U365    E      2 MMBT3904_SMLF-MMBT3904    ,EMPA    I49 @S9S_MB_2U_LIB.S9S_MB_2U(SCH_1):PAGE327

P12V_HSC_TEMP_R @S9S_MB_2U_LIB.S9S_MB_2U(SCH_1):P12V_HSC_TEMP_R
 R4892    1      A Q_RES_0402LF-49.9,1%,1/16W,EMPA     I5 @S9S_MB_2U_LIB.S9S_MB_2U(SCH_1):PAGE327
  U365    B      1 MMBT3904_SMLF-MMBT3904    ,EMPA    I49 @S9S_MB_2U_LIB.S9S_MB_2U(SCH_1):PAGE327
  U365    C      3 MMBT3904_SMLF-MMBT3904    ,EMPA    I49 @S9S_MB_2U_LIB.S9S_MB_2U(SCH_1):PAGE327

P12V_HSC_TEMP_SCL @S9S_MB_2U_LIB.S9S_MB_2U(SCH_1):P12V_HSC_TEMP_SCL
  U345    8    SCL NCT7718W-NCT7718W,SMLF,EMPTY,AA    I10 @S9S_MB_2U_LIB.S9S_MB_2U(SCH_1):PAGE327
 R4894    1      A Q_RES_0402LF-0,5%,1/16W,EMPTY,A    I15 @S9S_MB_2U_LIB.S9S_MB_2U(SCH_1):PAGE327

P12V_HSC_TEMP_SDA @S9S_MB_2U_LIB.S9S_MB_2U(SCH_1):P12V_HSC_TEMP_SDA
  U345    7    SDA NCT7718W-NCT7718W,SMLF,EMPTY,AA    I10 @S9S_MB_2U_LIB.S9S_MB_2U(SCH_1):PAGE327
 R4895    1      A Q_RES_0402LF-0,5%,1/16W,EMPTY,A    I16 @S9S_MB_2U_LIB.S9S_MB_2U(SCH_1):PAGE327

P12V_HSC_T_CRIT_N @S9S_MB_2U_LIB.S9S_MB_2U(SCH_1):P12V_HSC_T_CRIT_N
  U345    4 T_CRIT# NCT7718W-NCT7718W,SMLF,EMPTY,AA    I10 @S9S_MB_2U_LIB.S9S_MB_2U(SCH_1):PAGE327
 R4896    1      A Q_RES_0402LF-0,5%,1/16W,EMPTY,A    I11 @S9S_MB_2U_LIB.S9S_MB_2U(SCH_1):PAGE327

P12V_HSC_T_CRIT_R_N @S9S_MB_2U_LIB.S9S_MB_2U(SCH_1):P12V_HSC_T_CRIT_R_N
 R4896    2      B Q_RES_0402LF-0,5%,1/16W,EMPTY,A    I11 @S9S_MB_2U_LIB.S9S_MB_2U(SCH_1):PAGE327
 R4686    2      B Q_RES_0402LF-10.5K,1%,1/16W,EMA    I17 @S9S_MB_2U_LIB.S9S_MB_2U(SCH_1):PAGE327
  U249  B20  PT42B LCMXO3LF9400C5BG484C-LCMXO3LF-A   I188 @S9S_MB_2U_LIB.S9S_MB_2U(SCH_1):PAGE314

P12V_MAIN_R @S9S_MB_2U_LIB.S9S_MB_2U(SCH_1):P12V_MAIN_R
  PPQ5    5      5 MOSFET_NCH_1D3S-PSMNR58-30YLH,B    I35 @S9S_MB_2U_LIB.S9S_MB_2U(SCH_1):PAGE328
  PPQ6    5      5 MOSFET_NCH_1D3S-PSMNR58-30YLH,B    I40 @S9S_MB_2U_LIB.S9S_MB_2U(SCH_1):PAGE328
  PPQ7    5      5 MOSFET_NCH_1D3S-PSMNR58-30YLH,B    I41 @S9S_MB_2U_LIB.S9S_MB_2U(SCH_1):PAGE328
  PPQ8    5      5 MOSFET_NCH_1D3S-PSMNR58-30YLH,B    I62 @S9S_MB_2U_LIB.S9S_MB_2U(SCH_1):PAGE328
PR2534   2A     2A Q_SP_RES4P-0.0003,1%,4W,SMLF,EA    I63 @S9S_MB_2U_LIB.S9S_MB_2U(SCH_1):PAGE328
PR2533   2A     2A Q_SP_RES4P-0.0003,1%,4W,SMLF,EA    I64 @S9S_MB_2U_LIB.S9S_MB_2U(SCH_1):PAGE328
  PPQ1    5      5 MOSFET_NCH_1D3S-PSMNR58-30YLH,B    I65 @S9S_MB_2U_LIB.S9S_MB_2U(SCH_1):PAGE328
  PPQ2    5      5 MOSFET_NCH_1D3S-PSMNR58-30YLH,B    I73 @S9S_MB_2U_LIB.S9S_MB_2U(SCH_1):PAGE328
PR2532   2A     2A Q_SP_RES4P-0.0003,1%,4W,SMLF,EA    I78 @S9S_MB_2U_LIB.S9S_MB_2U(SCH_1):PAGE328
   PR4   2A     2A Q_SP_RES4P-0.0003,1%,4W,SMLF,EA    I79 @S9S_MB_2U_LIB.S9S_MB_2U(SCH_1):PAGE328

P12V_MAIN_R_0 @S9S_MB_2U_LIB.S9S_MB_2U(SCH_1):P12V_MAIN_R_0
  PPQ9    5      5 MOSFET_NCH_1D3S-PSMNR58-30YLH,B    I77 @S9S_MB_2U_LIB.S9S_MB_2U(SCH_1):PAGE328
   PR3    2      2 Q_RES_4P_12-0.003,1%,3W,SMLF,EA   I126 @S9S_MB_2U_LIB.S9S_MB_2U(SCH_1):PAGE328

P12V_OCP_1_EN_G @S9S_MB_2U_LIB.S9S_MB_2U(SCH_1):P12V_OCP_1_EN_G
  Q123    5     G2 MOSFET_NCH_DUAL-PJT138K,SMLF,EA    I17 @S9S_MB_2U_LIB.S9S_MB_2U(SCH_1):PAGE153
  Q123    6     D1 MOSFET_NCH_DUAL-PJT138K,SMLF,EA     I9 @S9S_MB_2U_LIB.S9S_MB_2U(SCH_1):PAGE153
 R4068    2      B Q_RES_0402LF-10K,1%,1/16W,EMPTA    I15 @S9S_MB_2U_LIB.S9S_MB_2U(SCH_1):PAGE153

P12V_OCP_2_EN_G @S9S_MB_2U_LIB.S9S_MB_2U(SCH_1):P12V_OCP_2_EN_G
 R4065    2      B Q_RES_0402LF-10K,1%,1/16W,EMPTA    I14 @S9S_MB_2U_LIB.S9S_MB_2U(SCH_1):PAGE131
  Q118    5     G2 MOSFET_NCH_DUAL-PJT138K,SMLF,EA    I16 @S9S_MB_2U_LIB.S9S_MB_2U(SCH_1):PAGE131
  Q118    6     D1 MOSFET_NCH_DUAL-PJT138K,SMLF,EA     I7 @S9S_MB_2U_LIB.S9S_MB_2U(SCH_1):PAGE131

P12V_OCP_AVIN_PD_1 @S9S_MB_2U_LIB.S9S_MB_2U(SCH_1):P12V_OCP_AVIN_PD_1
 PU204   12   AVIN RS31312R-RS31312R,SMLF,IC,AL03A    I70 @S9S_MB_2U_LIB.S9S_MB_2U(SCH_1):PAGE236
PR3838    2      B Q_RES_0402LF-100,1%,1/16W,EMPTA    I77 @S9S_MB_2U_LIB.S9S_MB_2U(SCH_1):PAGE236
PC2158    1      A Q_CAP_C0603-2.2UF,16V,20%,X7R,A    I88 @S9S_MB_2U_LIB.S9S_MB_2U(SCH_1):PAGE236
PR3843    2      B Q_RES_0603LF-49.9,1%,1/10W,CHIA    I89 @S9S_MB_2U_LIB.S9S_MB_2U(SCH_1):PAGE236

P12V_OCP_AVIN_PD_2 @S9S_MB_2U_LIB.S9S_MB_2U(SCH_1):P12V_OCP_AVIN_PD_2
 PU206   12   AVIN RS31312R-RS31312R,SMLF,IC,AL03A    I70 @S9S_MB_2U_LIB.S9S_MB_2U(SCH_1):PAGE237
PR3850    2      B Q_RES_0402LF-100,1%,1/16W,EMPTA    I77 @S9S_MB_2U_LIB.S9S_MB_2U(SCH_1):PAGE237
PR3857    2      B Q_RES_0603LF-49.9,1%,1/10W,CHIA    I87 @S9S_MB_2U_LIB.S9S_MB_2U(SCH_1):PAGE237
PC1320    1      A Q_CAP_C0603-2.2UF,16V,20%,X7R,A    I95 @S9S_MB_2U_LIB.S9S_MB_2U(SCH_1):PAGE237

P12V_OCP_CB_1 @S9S_MB_2U_LIB.S9S_MB_2U(SCH_1):P12V_OCP_CB_1
PR5484    1      A Q_RES_0402LF-30.1K,1%,1/16W,EMA    I49 @S9S_MB_2U_LIB.S9S_MB_2U(SCH_1):PAGE153
 PU203   B1     CB MAX15090BEWIT-MAX15090BEWI+T,SA    I51 @S9S_MB_2U_LIB.S9S_MB_2U(SCH_1):PAGE153

P12V_OCP_CB_2 @S9S_MB_2U_LIB.S9S_MB_2U(SCH_1):P12V_OCP_CB_2
PR3821    1      A Q_RES_0402LF-30.1K,1%,1/16W,EMA    I59 @S9S_MB_2U_LIB.S9S_MB_2U(SCH_1):PAGE131
 PU201   B1     CB MAX15090BEWIT-MAX15090BEWI+T,SA    I63 @S9S_MB_2U_LIB.S9S_MB_2U(SCH_1):PAGE131

P12V_OCP_EN_1_R @S9S_MB_2U_LIB.S9S_MB_2U(SCH_1):P12V_OCP_EN_1_R
 R4061    2      B Q_RES_0402LF-0,5%,1/16W,EMPTY,A     I4 @S9S_MB_2U_LIB.S9S_MB_2U(SCH_1):PAGE153
  Q123    2     G1 MOSFET_NCH_DUAL-PJT138K,SMLF,EA     I9 @S9S_MB_2U_LIB.S9S_MB_2U(SCH_1):PAGE153

P12V_OCP_EN_1_R2 @S9S_MB_2U_LIB.S9S_MB_2U(SCH_1):P12V_OCP_EN_1_R2
 R3834    2      B Q_RES_0402LF-0,5%,1/16W,CHIP,CA    I65 @S9S_MB_2U_LIB.S9S_MB_2U(SCH_1):PAGE236
 PU204    1     EN RS31312R-RS31312R,SMLF,IC,AL03A    I70 @S9S_MB_2U_LIB.S9S_MB_2U(SCH_1):PAGE236

P12V_OCP_EN_2_R @S9S_MB_2U_LIB.S9S_MB_2U(SCH_1):P12V_OCP_EN_2_R
 R4059    2      B Q_RES_0402LF-0,5%,1/16W,EMPTY,A     I6 @S9S_MB_2U_LIB.S9S_MB_2U(SCH_1):PAGE131
  Q118    2     G1 MOSFET_NCH_DUAL-PJT138K,SMLF,EA     I7 @S9S_MB_2U_LIB.S9S_MB_2U(SCH_1):PAGE131

P12V_OCP_FAULT_1 @S9S_MB_2U_LIB.S9S_MB_2U(SCH_1):P12V_OCP_FAULT_1
 R3799    2      B Q_RES_0402LF-100K,1%,1/16W,EMPA    I90 @S9S_MB_2U_LIB.S9S_MB_2U(SCH_1):PAGE153
 PU203   C7 FAULT# MAX15090BEWIT-MAX15090BEWI+T,SA    I51 @S9S_MB_2U_LIB.S9S_MB_2U(SCH_1):PAGE153

P12V_OCP_FAULT_2 @S9S_MB_2U_LIB.S9S_MB_2U(SCH_1):P12V_OCP_FAULT_2
 R3816    2      B Q_RES_0402LF-100K,1%,1/16W,EMPA    I80 @S9S_MB_2U_LIB.S9S_MB_2U(SCH_1):PAGE131
 PU201   C7 FAULT# MAX15090BEWIT-MAX15090BEWI+T,SA    I63 @S9S_MB_2U_LIB.S9S_MB_2U(SCH_1):PAGE131

P12V_OCP_FLTB_1 @S9S_MB_2U_LIB.S9S_MB_2U(SCH_1):P12V_OCP_FLTB_1
 PU204    9   FLTB RS31312R-RS31312R,SMLF,IC,AL03A    I70 @S9S_MB_2U_LIB.S9S_MB_2U(SCH_1):PAGE236
PR3839    1      A Q_RES_0402LF-10K,1%,1/16W,CHIPA    I75 @S9S_MB_2U_LIB.S9S_MB_2U(SCH_1):PAGE236

P12V_OCP_FLTB_2 @S9S_MB_2U_LIB.S9S_MB_2U(SCH_1):P12V_OCP_FLTB_2
 PU206    9   FLTB RS31312R-RS31312R,SMLF,IC,AL03A    I70 @S9S_MB_2U_LIB.S9S_MB_2U(SCH_1):PAGE237
PR3851    1      A Q_RES_0402LF-10K,1%,1/16W,CHIPA    I74 @S9S_MB_2U_LIB.S9S_MB_2U(SCH_1):PAGE237

P12V_OCP_GATE_1 @S9S_MB_2U_LIB.S9S_MB_2U(SCH_1):P12V_OCP_GATE_1
PC2088    2      B Q_CAP_C0402-0.01UF,50V,10%,EMPA    I81 @S9S_MB_2U_LIB.S9S_MB_2U(SCH_1):PAGE153
 PU203   A6   GATE MAX15090BEWIT-MAX15090BEWI+T,SA    I51 @S9S_MB_2U_LIB.S9S_MB_2U(SCH_1):PAGE153
PC4056    1      A Q_CAP_C0402-3900PF,50V,10%,EMPA    I83 @S9S_MB_2U_LIB.S9S_MB_2U(SCH_1):PAGE153
PR4524    2      B Q_RES_0402LF-10M,1%,1/16W,EMPTA    I84 @S9S_MB_2U_LIB.S9S_MB_2U(SCH_1):PAGE153

P12V_OCP_GATE_2 @S9S_MB_2U_LIB.S9S_MB_2U(SCH_1):P12V_OCP_GATE_2
 PU201   A6   GATE MAX15090BEWIT-MAX15090BEWI+T,SA    I63 @S9S_MB_2U_LIB.S9S_MB_2U(SCH_1):PAGE131
 C2148    2      B Q_CAP_C0402-0.01UF,50V,10%,EMPA    I73 @S9S_MB_2U_LIB.S9S_MB_2U(SCH_1):PAGE131
PC2150    1      A Q_CAP_C0402-3900PF,50V,10%,EMPA    I76 @S9S_MB_2U_LIB.S9S_MB_2U(SCH_1):PAGE131
PR4522    2      B Q_RES_0402LF-10M,1%,1/16W,EMPTA    I77 @S9S_MB_2U_LIB.S9S_MB_2U(SCH_1):PAGE131

P12V_OCP_IMON_1 @S9S_MB_2U_LIB.S9S_MB_2U(SCH_1):P12V_OCP_IMON_1
 PU204    8   IMON RS31312R-RS31312R,SMLF,IC,AL03A    I70 @S9S_MB_2U_LIB.S9S_MB_2U(SCH_1):PAGE236
PR3837    1      A Q_RES_0402LF-17.4K,1%,1/16W,CHA    I72 @S9S_MB_2U_LIB.S9S_MB_2U(SCH_1):PAGE236
PC2156    1      A Q_CAP_C0402-100NF,50V,10%,X7R,A    I74 @S9S_MB_2U_LIB.S9S_MB_2U(SCH_1):PAGE236
 R3872    1      A Q_RES_0402LF-0,5%,1/16W,CHIP,CA    I81 @S9S_MB_2U_LIB.S9S_MB_2U(SCH_1):PAGE236
 R3871    1      A Q_RES_0402LF-0,5%,1/16W,EMPTY,A    I82 @S9S_MB_2U_LIB.S9S_MB_2U(SCH_1):PAGE236

P12V_OCP_IMON_2 @S9S_MB_2U_LIB.S9S_MB_2U(SCH_1):P12V_OCP_IMON_2
 PU206    8   IMON RS31312R-RS31312R,SMLF,IC,AL03A    I70 @S9S_MB_2U_LIB.S9S_MB_2U(SCH_1):PAGE237
PR3849    1      A Q_RES_0402LF-17.4K,1%,1/16W,CHA    I72 @S9S_MB_2U_LIB.S9S_MB_2U(SCH_1):PAGE237
PC2167    1      A Q_CAP_0402-100PF,50V,5%,X7R,CHA    I73 @S9S_MB_2U_LIB.S9S_MB_2U(SCH_1):PAGE237
 R3874    1      A Q_RES_0402LF-0,5%,1/16W,CHIP,CA    I80 @S9S_MB_2U_LIB.S9S_MB_2U(SCH_1):PAGE237
 R3873    1      A Q_RES_0402LF-0,5%,1/16W,EMPTY,A    I81 @S9S_MB_2U_LIB.S9S_MB_2U(SCH_1):PAGE237

P12V_OCP_ISET_1 @S9S_MB_2U_LIB.S9S_MB_2U(SCH_1):P12V_OCP_ISET_1
PR3835    1      A Q_RES_0402LF-14.3K,1%,1/16W,CHA    I62 @S9S_MB_2U_LIB.S9S_MB_2U(SCH_1):PAGE236
 PU204    5   ISET RS31312R-RS31312R,SMLF,IC,AL03A    I70 @S9S_MB_2U_LIB.S9S_MB_2U(SCH_1):PAGE236

P12V_OCP_ISET_2 @S9S_MB_2U_LIB.S9S_MB_2U(SCH_1):P12V_OCP_ISET_2
PR3847    1      A Q_RES_0402LF-14.3K,1%,1/16W,CHA    I61 @S9S_MB_2U_LIB.S9S_MB_2U(SCH_1):PAGE237
 PU206    5   ISET RS31312R-RS31312R,SMLF,IC,AL03A    I70 @S9S_MB_2U_LIB.S9S_MB_2U(SCH_1):PAGE237

P12V_OCP_OV_1 @S9S_MB_2U_LIB.S9S_MB_2U(SCH_1):P12V_OCP_OV_1
PR3787    2      B Q_RES_0402LF-6.8K,1%,1/16W,EMPA    I41 @S9S_MB_2U_LIB.S9S_MB_2U(SCH_1):PAGE153
PR3788    1      A Q_RES_0402LF-15K,1%,1/16W,EMPTA    I33 @S9S_MB_2U_LIB.S9S_MB_2U(SCH_1):PAGE153
 PU203   D3     OV MAX15090BEWIT-MAX15090BEWI+T,SA    I51 @S9S_MB_2U_LIB.S9S_MB_2U(SCH_1):PAGE153

P12V_OCP_OV_2 @S9S_MB_2U_LIB.S9S_MB_2U(SCH_1):P12V_OCP_OV_2
PR3806    2      B Q_RES_0402LF-6.8K,1%,1/16W,EMPA    I32 @S9S_MB_2U_LIB.S9S_MB_2U(SCH_1):PAGE131
 PU201   D3     OV MAX15090BEWIT-MAX15090BEWI+T,SA    I63 @S9S_MB_2U_LIB.S9S_MB_2U(SCH_1):PAGE131
PR3828    1      A Q_RES_0402LF-15K,1%,1/16W,EMPTA    I29 @S9S_MB_2U_LIB.S9S_MB_2U(SCH_1):PAGE131

P12V_OCP_OV_FB_1 @S9S_MB_2U_LIB.S9S_MB_2U(SCH_1):P12V_OCP_OV_FB_1
 PU204   11     OV RS31312R-RS31312R,SMLF,IC,AL03A    I70 @S9S_MB_2U_LIB.S9S_MB_2U(SCH_1):PAGE236
PR3842    1      A Q_RES_0402LF-10K,1%,1/16W,CHIPA    I83 @S9S_MB_2U_LIB.S9S_MB_2U(SCH_1):PAGE236
PR3840    2      B Q_RES_0402LF-71.5K,1%,1/16W,EMA    I85 @S9S_MB_2U_LIB.S9S_MB_2U(SCH_1):PAGE236
PR3841    2      B Q_RES_0402LF-120K,1%,1/16W,CHIA    I86 @S9S_MB_2U_LIB.S9S_MB_2U(SCH_1):PAGE236

P12V_OCP_OV_FB_2 @S9S_MB_2U_LIB.S9S_MB_2U(SCH_1):P12V_OCP_OV_FB_2
 PU206   11     OV RS31312R-RS31312R,SMLF,IC,AL03A    I70 @S9S_MB_2U_LIB.S9S_MB_2U(SCH_1):PAGE237
PR3854    1      A Q_RES_0402LF-10K,1%,1/16W,CHIPA    I83 @S9S_MB_2U_LIB.S9S_MB_2U(SCH_1):PAGE237
PR3853    2      B Q_RES_0402LF-120K,1%,1/16W,CHIA    I84 @S9S_MB_2U_LIB.S9S_MB_2U(SCH_1):PAGE237
PR3852    2      B Q_RES_0402LF-71.5K,1%,1/16W,EMA    I85 @S9S_MB_2U_LIB.S9S_MB_2U(SCH_1):PAGE237

P12V_OCP_PWRGD_1 @S9S_MB_2U_LIB.S9S_MB_2U(SCH_1):P12V_OCP_PWRGD_1
 R3144    1      A Q_RES_0402LF-0,5%,1/16W,EMPTY,A    I82 @S9S_MB_2U_LIB.S9S_MB_2U(SCH_1):PAGE153
 PU203   D7     PG MAX15090BEWIT-MAX15090BEWI+T,SA    I51 @S9S_MB_2U_LIB.S9S_MB_2U(SCH_1):PAGE153

P12V_OCP_PWRGD_2 @S9S_MB_2U_LIB.S9S_MB_2U(SCH_1):P12V_OCP_PWRGD_2
 R3831    1      A Q_RES_0402LF-0,5%,1/16W,EMPTY,A    I78 @S9S_MB_2U_LIB.S9S_MB_2U(SCH_1):PAGE131
 PU201   D7     PG MAX15090BEWIT-MAX15090BEWI+T,SA    I63 @S9S_MB_2U_LIB.S9S_MB_2U(SCH_1):PAGE131

P12V_OCP_REG_1 @S9S_MB_2U_LIB.S9S_MB_2U(SCH_1):P12V_OCP_REG_1
PC2087    2      B Q_CAP_C0402-1UF,25V,10%,EMPTY,A    I54 @S9S_MB_2U_LIB.S9S_MB_2U(SCH_1):PAGE153
 PU203   D1    REG MAX15090BEWIT-MAX15090BEWI+T,SA    I51 @S9S_MB_2U_LIB.S9S_MB_2U(SCH_1):PAGE153

P12V_OCP_REG_2 @S9S_MB_2U_LIB.S9S_MB_2U(SCH_1):P12V_OCP_REG_2
 PU201   D1    REG MAX15090BEWIT-MAX15090BEWI+T,SA    I63 @S9S_MB_2U_LIB.S9S_MB_2U(SCH_1):PAGE131
PC2146    2      B Q_CAP_C0402-1UF,25V,10%,EMPTY,A    I62 @S9S_MB_2U_LIB.S9S_MB_2U(SCH_1):PAGE131

P12V_OCP_SENSE_1 @S9S_MB_2U_LIB.S9S_MB_2U(SCH_1):P12V_OCP_SENSE_1
PR3781    1      A Q_RES_0402LF-845,1%,1/16W,EMPTA    I80 @S9S_MB_2U_LIB.S9S_MB_2U(SCH_1):PAGE153
 R3869    1      A Q_RES_0402LF-0,5%,1/16W,EMPTY,A    I87 @S9S_MB_2U_LIB.S9S_MB_2U(SCH_1):PAGE153
 R3870    1      A Q_RES_0402LF-0,5%,1/16W,EMPTY,A    I88 @S9S_MB_2U_LIB.S9S_MB_2U(SCH_1):PAGE153
 PU203   A1 ISENSE MAX15090BEWIT-MAX15090BEWI+T,SA    I51 @S9S_MB_2U_LIB.S9S_MB_2U(SCH_1):PAGE153

P12V_OCP_SENSE_2 @S9S_MB_2U_LIB.S9S_MB_2U(SCH_1):P12V_OCP_SENSE_2
 R3868    1      A Q_RES_0402LF-0,5%,1/16W,EMPTY,A    I74 @S9S_MB_2U_LIB.S9S_MB_2U(SCH_1):PAGE131
 PU201   A1 ISENSE MAX15090BEWIT-MAX15090BEWI+T,SA    I63 @S9S_MB_2U_LIB.S9S_MB_2U(SCH_1):PAGE131
PR3823    1      A Q_RES_0402LF-845,1%,1/16W,EMPTA    I72 @S9S_MB_2U_LIB.S9S_MB_2U(SCH_1):PAGE131
 R3867    1      A Q_RES_0402LF-0,5%,1/16W,EMPTY,A    I75 @S9S_MB_2U_LIB.S9S_MB_2U(SCH_1):PAGE131

P12V_OCP_SFF @S9S_MB_2U_LIB.S9S_MB_2U(SCH_1):P12V_OCP_SFF
 C1213    1      A Q_CAP_C0805-22UF,16V,20%,X6S,CB    I89 @S9S_MB_2U_LIB.S9S_MB_2U(SCH_1):PAGE150
 C1232    1      A Q_CAP_C0805-22UF,16V,20%,X6S,CB    I90 @S9S_MB_2U_LIB.S9S_MB_2U(SCH_1):PAGE150
 C1233    1      A Q_CAP_0402-0.1UF,25V,10%,X7R,CA    I91 @S9S_MB_2U_LIB.S9S_MB_2U(SCH_1):PAGE150
 C1234    1      A Q_CAP_0402-0.1UF,25V,10%,X7R,CA   I110 @S9S_MB_2U_LIB.S9S_MB_2U(SCH_1):PAGE150
 C1235    1      A Q_CAP_0402-0.1UF,25V,10%,X7R,CA   I111 @S9S_MB_2U_LIB.S9S_MB_2U(SCH_1):PAGE150
 C1236    1      A Q_CAP_0402-0.1UF,25V,10%,X7R,CA   I113 @S9S_MB_2U_LIB.S9S_MB_2U(SCH_1):PAGE150
   J37   B1 +12V_EDGE_B1 SCONN168_ME1016810202011-SCONNA   I199 @S9S_MB_2U_LIB.S9S_MB_2U(SCH_1):PAGE150
   J37   B2 +12V_EDGE_B2 SCONN168_ME1016810202011-SCONNA   I199 @S9S_MB_2U_LIB.S9S_MB_2U(SCH_1):PAGE150
   J37   B3 +12V_EDGE_B3 SCONN168_ME1016810202011-SCONNA   I199 @S9S_MB_2U_LIB.S9S_MB_2U(SCH_1):PAGE150
   J37   B4 +12V_EDGE_B4 SCONN168_ME1016810202011-SCONNA   I199 @S9S_MB_2U_LIB.S9S_MB_2U(SCH_1):PAGE150
   J37   B5 +12V_EDGE_B5 SCONN168_ME1016810202011-SCONNA   I199 @S9S_MB_2U_LIB.S9S_MB_2U(SCH_1):PAGE150
   J37   B6 +12V_EDGE_B6 SCONN168_ME1016810202011-SCONNA   I199 @S9S_MB_2U_LIB.S9S_MB_2U(SCH_1):PAGE150
PC2088    1      A Q_CAP_C0402-0.01UF,50V,10%,EMPA    I81 @S9S_MB_2U_LIB.S9S_MB_2U(SCH_1):PAGE153
PC2092    1      A Q_CAP_0402-0.1UF,25V,10%,X7R,CA    I93 @S9S_MB_2U_LIB.S9S_MB_2U(SCH_1):PAGE153
PC2082    1      A Q_CAP_C0805-10UF,16V,10%,X6S,CC    I96 @S9S_MB_2U_LIB.S9S_MB_2U(SCH_1):PAGE153
 PU203   A4 OUT_A4 MAX15090BEWIT-MAX15090BEWI+T,SA    I51 @S9S_MB_2U_LIB.S9S_MB_2U(SCH_1):PAGE153
 PU203   B4 OUT_B4 MAX15090BEWIT-MAX15090BEWI+T,SA    I51 @S9S_MB_2U_LIB.S9S_MB_2U(SCH_1):PAGE153
 PU203   B6 OUT_B6 MAX15090BEWIT-MAX15090BEWI+T,SA    I51 @S9S_MB_2U_LIB.S9S_MB_2U(SCH_1):PAGE153
 PU203   C4 OUT_C4 MAX15090BEWIT-MAX15090BEWI+T,SA    I51 @S9S_MB_2U_LIB.S9S_MB_2U(SCH_1):PAGE153
 PU203   C6 OUT_C6 MAX15090BEWIT-MAX15090BEWI+T,SA    I51 @S9S_MB_2U_LIB.S9S_MB_2U(SCH_1):PAGE153
 PU203   D4 OUT_D4 MAX15090BEWIT-MAX15090BEWI+T,SA    I51 @S9S_MB_2U_LIB.S9S_MB_2U(SCH_1):PAGE153
 PU203   D6 OUT_D6 MAX15090BEWIT-MAX15090BEWI+T,SA    I51 @S9S_MB_2U_LIB.S9S_MB_2U(SCH_1):PAGE153
PR4524    1      A Q_RES_0402LF-10M,1%,1/16W,EMPTA    I84 @S9S_MB_2U_LIB.S9S_MB_2U(SCH_1):PAGE153
 PD102    C      C SCHOTTKY_AC-B340A-13-F,SMLF,ICA    I86 @S9S_MB_2U_LIB.S9S_MB_2U(SCH_1):PAGE153
PC2080    1      A Q_CAP_C0805-22UF,16V,20%,X6S,CC    I94 @S9S_MB_2U_LIB.S9S_MB_2U(SCH_1):PAGE153
 PU204   13 VOUT_13 RS31312R-RS31312R,SMLF,IC,AL03A    I70 @S9S_MB_2U_LIB.S9S_MB_2U(SCH_1):PAGE236
 PU204   14 VOUT_14 RS31312R-RS31312R,SMLF,IC,AL03A    I70 @S9S_MB_2U_LIB.S9S_MB_2U(SCH_1):PAGE236
 PU204   15 VOUT_15 RS31312R-RS31312R,SMLF,IC,AL03A    I70 @S9S_MB_2U_LIB.S9S_MB_2U(SCH_1):PAGE236
 PU204   16 VOUT_16 RS31312R-RS31312R,SMLF,IC,AL03A    I70 @S9S_MB_2U_LIB.S9S_MB_2U(SCH_1):PAGE236
 PU204   17 VOUT_17 RS31312R-RS31312R,SMLF,IC,AL03A    I70 @S9S_MB_2U_LIB.S9S_MB_2U(SCH_1):PAGE236
 PU204   18 VOUT_18 RS31312R-RS31312R,SMLF,IC,AL03A    I70 @S9S_MB_2U_LIB.S9S_MB_2U(SCH_1):PAGE236
 PU204   19 VOUT_19 RS31312R-RS31312R,SMLF,IC,AL03A    I70 @S9S_MB_2U_LIB.S9S_MB_2U(SCH_1):PAGE236
 PU204   20 VOUT_20 RS31312R-RS31312R,SMLF,IC,AL03A    I70 @S9S_MB_2U_LIB.S9S_MB_2U(SCH_1):PAGE236
PR3838    1      A Q_RES_0402LF-100,1%,1/16W,EMPTA    I77 @S9S_MB_2U_LIB.S9S_MB_2U(SCH_1):PAGE236
PR3840    1      A Q_RES_0402LF-71.5K,1%,1/16W,EMA    I85 @S9S_MB_2U_LIB.S9S_MB_2U(SCH_1):PAGE236
PC2160    1      A Q_CAP_0402-0.1UF,25V,10%,X7R,CA    I91 @S9S_MB_2U_LIB.S9S_MB_2U(SCH_1):PAGE236

P12V_OCP_SFF_ISENSE_MAM @S9S_MB_2U_LIB.S9S_MB_2U(SCH_1):P12V_OCP_SFF_ISENSE_MAM
  U193    6   AIN1 MAX11617EEET-MAX11617EEE+T,SMLA    I57 @S9S_MB_2U_LIB.S9S_MB_2U(SCH_1):PAGE239
 C2176    1      A Q_CAP_0402-100PF,50V,5%,EMPTY,A   I304 @S9S_MB_2U_LIB.S9S_MB_2U(SCH_1):PAGE239
 R3863    2      B Q_RES_0402LF-0,5%,1/16W,EMPTY,A   I313 @S9S_MB_2U_LIB.S9S_MB_2U(SCH_1):PAGE239
 R3864    2      B Q_RES_0402LF-0,5%,1/16W,EMPTY,A   I314 @S9S_MB_2U_LIB.S9S_MB_2U(SCH_1):PAGE239

P12V_OCP_SFF_ISENSE_MAM_MAM @S9S_MB_2U_LIB.S9S_MB_2U(SCH_1):P12V_OCP_SFF_ISENSE_MAM_MAM
 R3863    1      A Q_RES_0402LF-0,5%,1/16W,EMPTY,A   I313 @S9S_MB_2U_LIB.S9S_MB_2U(SCH_1):PAGE239
 R3869    2      B Q_RES_0402LF-0,5%,1/16W,EMPTY,A    I87 @S9S_MB_2U_LIB.S9S_MB_2U(SCH_1):PAGE153

P12V_OCP_SFF_ISENSE_MAM_TIC @S9S_MB_2U_LIB.S9S_MB_2U(SCH_1):P12V_OCP_SFF_ISENSE_MAM_TIC
 R3865    1      A Q_RES_0402LF-0,5%,1/16W,EMPTY,A   I315 @S9S_MB_2U_LIB.S9S_MB_2U(SCH_1):PAGE239
 R3870    2      B Q_RES_0402LF-0,5%,1/16W,EMPTY,A    I88 @S9S_MB_2U_LIB.S9S_MB_2U(SCH_1):PAGE153

P12V_OCP_SFF_ISENSE_MPS_MAM @S9S_MB_2U_LIB.S9S_MB_2U(SCH_1):P12V_OCP_SFF_ISENSE_MPS_MAM
 R3864    1      A Q_RES_0402LF-0,5%,1/16W,EMPTY,A   I314 @S9S_MB_2U_LIB.S9S_MB_2U(SCH_1):PAGE239
 R3871    2      B Q_RES_0402LF-0,5%,1/16W,EMPTY,A    I82 @S9S_MB_2U_LIB.S9S_MB_2U(SCH_1):PAGE236

P12V_OCP_SFF_ISENSE_MPS_TIC @S9S_MB_2U_LIB.S9S_MB_2U(SCH_1):P12V_OCP_SFF_ISENSE_MPS_TIC
 R3866    1      A Q_RES_0402LF-0,5%,1/16W,CHIP,CA   I316 @S9S_MB_2U_LIB.S9S_MB_2U(SCH_1):PAGE239
 R3872    2      B Q_RES_0402LF-0,5%,1/16W,CHIP,CA    I81 @S9S_MB_2U_LIB.S9S_MB_2U(SCH_1):PAGE236

P12V_OCP_SFF_ISENSE_TIC @S9S_MB_2U_LIB.S9S_MB_2U(SCH_1):P12V_OCP_SFF_ISENSE_TIC
  U269   15    IN1 ADC128D818CIMTXNOPB-ADC128D818A   I103 @S9S_MB_2U_LIB.S9S_MB_2U(SCH_1):PAGE239
 C2178    1      A Q_CAP_0402-0.1UF,25V,10%,X7R,CA   I305 @S9S_MB_2U_LIB.S9S_MB_2U(SCH_1):PAGE239
 R3865    2      B Q_RES_0402LF-0,5%,1/16W,EMPTY,A   I315 @S9S_MB_2U_LIB.S9S_MB_2U(SCH_1):PAGE239
 R3866    2      B Q_RES_0402LF-0,5%,1/16W,CHIP,CA   I316 @S9S_MB_2U_LIB.S9S_MB_2U(SCH_1):PAGE239

P12V_OCP_SS_1 @S9S_MB_2U_LIB.S9S_MB_2U(SCH_1):P12V_OCP_SS_1
PC2155    1      A Q_CAP_C0402-0.047UF,25V,10%,X7A    I63 @S9S_MB_2U_LIB.S9S_MB_2U(SCH_1):PAGE236
 PU204    6     SS RS31312R-RS31312R,SMLF,IC,AL03A    I70 @S9S_MB_2U_LIB.S9S_MB_2U(SCH_1):PAGE236

P12V_OCP_SS_2 @S9S_MB_2U_LIB.S9S_MB_2U(SCH_1):P12V_OCP_SS_2
PC2166    1      A Q_CAP_C0402-0.047UF,25V,10%,X7A    I65 @S9S_MB_2U_LIB.S9S_MB_2U(SCH_1):PAGE237
 PU206    6     SS RS31312R-RS31312R,SMLF,IC,AL03A    I70 @S9S_MB_2U_LIB.S9S_MB_2U(SCH_1):PAGE237

P12V_OCP_TIMER_1 @S9S_MB_2U_LIB.S9S_MB_2U(SCH_1):P12V_OCP_TIMER_1
PC2153    1      A Q_CAP_0402-0.22UF,16V,10%,X7R,A    I60 @S9S_MB_2U_LIB.S9S_MB_2U(SCH_1):PAGE236
 PU204    4  TIMER RS31312R-RS31312R,SMLF,IC,AL03A    I70 @S9S_MB_2U_LIB.S9S_MB_2U(SCH_1):PAGE236

P12V_OCP_TIMER_2 @S9S_MB_2U_LIB.S9S_MB_2U(SCH_1):P12V_OCP_TIMER_2
PC2164    1      A Q_CAP_0402-0.22UF,16V,10%,X7R,A    I62 @S9S_MB_2U_LIB.S9S_MB_2U(SCH_1):PAGE237
 PU206    4  TIMER RS31312R-RS31312R,SMLF,IC,AL03A    I70 @S9S_MB_2U_LIB.S9S_MB_2U(SCH_1):PAGE237

P12V_OCP_UV_1 @S9S_MB_2U_LIB.S9S_MB_2U(SCH_1):P12V_OCP_UV_1
PR3787    1      A Q_RES_0402LF-6.8K,1%,1/16W,EMPA    I41 @S9S_MB_2U_LIB.S9S_MB_2U(SCH_1):PAGE153
 R3784    2      B Q_RES_0402LF-0,5%,1/16W,EMPTY,A    I39 @S9S_MB_2U_LIB.S9S_MB_2U(SCH_1):PAGE153
PR3786    2      B Q_RES_0402LF-160K,1%,1/16W,EMPA    I42 @S9S_MB_2U_LIB.S9S_MB_2U(SCH_1):PAGE153
 PU203   D2     UV MAX15090BEWIT-MAX15090BEWI+T,SA    I51 @S9S_MB_2U_LIB.S9S_MB_2U(SCH_1):PAGE153

P12V_OCP_UV_1_R @S9S_MB_2U_LIB.S9S_MB_2U(SCH_1):P12V_OCP_UV_1_R
  Q123    3     D2 MOSFET_NCH_DUAL-PJT138K,SMLF,EA    I17 @S9S_MB_2U_LIB.S9S_MB_2U(SCH_1):PAGE153
 R3784    1      A Q_RES_0402LF-0,5%,1/16W,EMPTY,A    I39 @S9S_MB_2U_LIB.S9S_MB_2U(SCH_1):PAGE153

P12V_OCP_UV_2 @S9S_MB_2U_LIB.S9S_MB_2U(SCH_1):P12V_OCP_UV_2
PR3805    2      B Q_RES_0402LF-160K,1%,1/16W,EMPA    I33 @S9S_MB_2U_LIB.S9S_MB_2U(SCH_1):PAGE131
PR3806    1      A Q_RES_0402LF-6.8K,1%,1/16W,EMPA    I32 @S9S_MB_2U_LIB.S9S_MB_2U(SCH_1):PAGE131
 PU201   D2     UV MAX15090BEWIT-MAX15090BEWI+T,SA    I63 @S9S_MB_2U_LIB.S9S_MB_2U(SCH_1):PAGE131
 R3827    2      B Q_RES_0402LF-0,5%,1/16W,EMPTY,A    I30 @S9S_MB_2U_LIB.S9S_MB_2U(SCH_1):PAGE131

P12V_OCP_UV_2_R @S9S_MB_2U_LIB.S9S_MB_2U(SCH_1):P12V_OCP_UV_2_R
  Q118    3     D2 MOSFET_NCH_DUAL-PJT138K,SMLF,EA    I16 @S9S_MB_2U_LIB.S9S_MB_2U(SCH_1):PAGE131
 R3827    1      A Q_RES_0402LF-0,5%,1/16W,EMPTY,A    I30 @S9S_MB_2U_LIB.S9S_MB_2U(SCH_1):PAGE131

P12V_OCP_V3_2 @S9S_MB_2U_LIB.S9S_MB_2U(SCH_1):P12V_OCP_V3_2
 C1829    1      A Q_CAP_C0805-22UF,16V,20%,X6S,CB   I166 @S9S_MB_2U_LIB.S9S_MB_2U(SCH_1):PAGE146
 C1830    1      A Q_CAP_C0805-22UF,16V,20%,X6S,CB   I167 @S9S_MB_2U_LIB.S9S_MB_2U(SCH_1):PAGE146
 C1831    1      A Q_CAP_0402-0.1UF,25V,10%,X7R,CA   I168 @S9S_MB_2U_LIB.S9S_MB_2U(SCH_1):PAGE146
 C1833    1      A Q_CAP_0402-0.1UF,25V,10%,X7R,CA   I169 @S9S_MB_2U_LIB.S9S_MB_2U(SCH_1):PAGE146
 C1834    1      A Q_CAP_0402-0.1UF,25V,10%,X7R,CA   I171 @S9S_MB_2U_LIB.S9S_MB_2U(SCH_1):PAGE146
 C1832    1      A Q_CAP_0402-0.1UF,25V,10%,X7R,CA   I179 @S9S_MB_2U_LIB.S9S_MB_2U(SCH_1):PAGE146
 C1839    1      A Q_CAP_0402-0.1UF,25V,10%,X7R,CA   I180 @S9S_MB_2U_LIB.S9S_MB_2U(SCH_1):PAGE146
   J35   B1 +12V_EDGE_B1 SCONN168_ME1016810202011-SCONNA   I303 @S9S_MB_2U_LIB.S9S_MB_2U(SCH_1):PAGE146
   J35   B2 +12V_EDGE_B2 SCONN168_ME1016810202011-SCONNA   I303 @S9S_MB_2U_LIB.S9S_MB_2U(SCH_1):PAGE146
   J35   B3 +12V_EDGE_B3 SCONN168_ME1016810202011-SCONNA   I303 @S9S_MB_2U_LIB.S9S_MB_2U(SCH_1):PAGE146
   J35   B4 +12V_EDGE_B4 SCONN168_ME1016810202011-SCONNA   I303 @S9S_MB_2U_LIB.S9S_MB_2U(SCH_1):PAGE146
   J35   B5 +12V_EDGE_B5 SCONN168_ME1016810202011-SCONNA   I303 @S9S_MB_2U_LIB.S9S_MB_2U(SCH_1):PAGE146
   J35   B6 +12V_EDGE_B6 SCONN168_ME1016810202011-SCONNA   I303 @S9S_MB_2U_LIB.S9S_MB_2U(SCH_1):PAGE146
 PU201   A4 OUT_A4 MAX15090BEWIT-MAX15090BEWI+T,SA    I63 @S9S_MB_2U_LIB.S9S_MB_2U(SCH_1):PAGE131
 PU201   B4 OUT_B4 MAX15090BEWIT-MAX15090BEWI+T,SA    I63 @S9S_MB_2U_LIB.S9S_MB_2U(SCH_1):PAGE131
 PU201   B6 OUT_B6 MAX15090BEWIT-MAX15090BEWI+T,SA    I63 @S9S_MB_2U_LIB.S9S_MB_2U(SCH_1):PAGE131
 PU201   C4 OUT_C4 MAX15090BEWIT-MAX15090BEWI+T,SA    I63 @S9S_MB_2U_LIB.S9S_MB_2U(SCH_1):PAGE131
 PU201   C6 OUT_C6 MAX15090BEWIT-MAX15090BEWI+T,SA    I63 @S9S_MB_2U_LIB.S9S_MB_2U(SCH_1):PAGE131
 PU201   D4 OUT_D4 MAX15090BEWIT-MAX15090BEWI+T,SA    I63 @S9S_MB_2U_LIB.S9S_MB_2U(SCH_1):PAGE131
 PU201   D6 OUT_D6 MAX15090BEWIT-MAX15090BEWI+T,SA    I63 @S9S_MB_2U_LIB.S9S_MB_2U(SCH_1):PAGE131
 C2148    1      A Q_CAP_C0402-0.01UF,50V,10%,EMPA    I73 @S9S_MB_2U_LIB.S9S_MB_2U(SCH_1):PAGE131
 PD108    C      C SCHOTTKY_AC-B340A-13-F,SMLF,ICA    I93 @S9S_MB_2U_LIB.S9S_MB_2U(SCH_1):PAGE131
PC2141    1      A Q_CAP_C0805-22UF,16V,20%,X6S,CC   I100 @S9S_MB_2U_LIB.S9S_MB_2U(SCH_1):PAGE131
PC2143    1      A Q_CAP_C0805-10UF,16V,10%,X6S,CC   I102 @S9S_MB_2U_LIB.S9S_MB_2U(SCH_1):PAGE131
PR4522    1      A Q_RES_0402LF-10M,1%,1/16W,EMPTA    I77 @S9S_MB_2U_LIB.S9S_MB_2U(SCH_1):PAGE131
PC2152    1      A Q_CAP_0402-0.1UF,25V,10%,X7R,CA    I98 @S9S_MB_2U_LIB.S9S_MB_2U(SCH_1):PAGE131
 PU206   13 VOUT_13 RS31312R-RS31312R,SMLF,IC,AL03A    I70 @S9S_MB_2U_LIB.S9S_MB_2U(SCH_1):PAGE237
 PU206   14 VOUT_14 RS31312R-RS31312R,SMLF,IC,AL03A    I70 @S9S_MB_2U_LIB.S9S_MB_2U(SCH_1):PAGE237
 PU206   15 VOUT_15 RS31312R-RS31312R,SMLF,IC,AL03A    I70 @S9S_MB_2U_LIB.S9S_MB_2U(SCH_1):PAGE237
 PU206   16 VOUT_16 RS31312R-RS31312R,SMLF,IC,AL03A    I70 @S9S_MB_2U_LIB.S9S_MB_2U(SCH_1):PAGE237
 PU206   17 VOUT_17 RS31312R-RS31312R,SMLF,IC,AL03A    I70 @S9S_MB_2U_LIB.S9S_MB_2U(SCH_1):PAGE237
 PU206   18 VOUT_18 RS31312R-RS31312R,SMLF,IC,AL03A    I70 @S9S_MB_2U_LIB.S9S_MB_2U(SCH_1):PAGE237
 PU206   19 VOUT_19 RS31312R-RS31312R,SMLF,IC,AL03A    I70 @S9S_MB_2U_LIB.S9S_MB_2U(SCH_1):PAGE237
 PU206   20 VOUT_20 RS31312R-RS31312R,SMLF,IC,AL03A    I70 @S9S_MB_2U_LIB.S9S_MB_2U(SCH_1):PAGE237
PR3850    1      A Q_RES_0402LF-100,1%,1/16W,EMPTA    I77 @S9S_MB_2U_LIB.S9S_MB_2U(SCH_1):PAGE237
PR3852    1      A Q_RES_0402LF-71.5K,1%,1/16W,EMA    I85 @S9S_MB_2U_LIB.S9S_MB_2U(SCH_1):PAGE237
PC2174    1      A Q_CAP_0402-0.1UF,25V,10%,X7R,CA    I91 @S9S_MB_2U_LIB.S9S_MB_2U(SCH_1):PAGE237

P12V_OCP_V3_2_EN_2_R3 @S9S_MB_2U_LIB.S9S_MB_2U(SCH_1):P12V_OCP_V3_2_EN_2_R3
 R3630    2      B Q_RES_0402LF-0,5%,1/16W,CHIP,CA    I66 @S9S_MB_2U_LIB.S9S_MB_2U(SCH_1):PAGE237
 PU206    1     EN RS31312R-RS31312R,SMLF,IC,AL03A    I70 @S9S_MB_2U_LIB.S9S_MB_2U(SCH_1):PAGE237

P12V_OCP_V3_2_ISENSE_MAM @S9S_MB_2U_LIB.S9S_MB_2U(SCH_1):P12V_OCP_V3_2_ISENSE_MAM
  U193    7   AIN2 MAX11617EEET-MAX11617EEE+T,SMLA    I57 @S9S_MB_2U_LIB.S9S_MB_2U(SCH_1):PAGE239
 C2175    1      A Q_CAP_0402-100PF,50V,5%,EMPTY,A   I309 @S9S_MB_2U_LIB.S9S_MB_2U(SCH_1):PAGE239
 R3859    2      B Q_RES_0402LF-0,5%,1/16W,EMPTY,A   I321 @S9S_MB_2U_LIB.S9S_MB_2U(SCH_1):PAGE239
 R3860    2      B Q_RES_0402LF-0,5%,1/16W,EMPTY,A   I322 @S9S_MB_2U_LIB.S9S_MB_2U(SCH_1):PAGE239

P12V_OCP_V3_2_ISENSE_MAM_MAM @S9S_MB_2U_LIB.S9S_MB_2U(SCH_1):P12V_OCP_V3_2_ISENSE_MAM_MAM
 R3859    1      A Q_RES_0402LF-0,5%,1/16W,EMPTY,A   I321 @S9S_MB_2U_LIB.S9S_MB_2U(SCH_1):PAGE239
 R3867    2      B Q_RES_0402LF-0,5%,1/16W,EMPTY,A    I75 @S9S_MB_2U_LIB.S9S_MB_2U(SCH_1):PAGE131

P12V_OCP_V3_2_ISENSE_MAM_TIC @S9S_MB_2U_LIB.S9S_MB_2U(SCH_1):P12V_OCP_V3_2_ISENSE_MAM_TIC
 R3861    1      A Q_RES_0402LF-0,5%,1/16W,EMPTY,A   I323 @S9S_MB_2U_LIB.S9S_MB_2U(SCH_1):PAGE239
 R3868    2      B Q_RES_0402LF-0,5%,1/16W,EMPTY,A    I74 @S9S_MB_2U_LIB.S9S_MB_2U(SCH_1):PAGE131

P12V_OCP_V3_2_ISENSE_MPS_MAM @S9S_MB_2U_LIB.S9S_MB_2U(SCH_1):P12V_OCP_V3_2_ISENSE_MPS_MAM
 R3860    1      A Q_RES_0402LF-0,5%,1/16W,EMPTY,A   I322 @S9S_MB_2U_LIB.S9S_MB_2U(SCH_1):PAGE239
 R3873    2      B Q_RES_0402LF-0,5%,1/16W,EMPTY,A    I81 @S9S_MB_2U_LIB.S9S_MB_2U(SCH_1):PAGE237

P12V_OCP_V3_2_ISENSE_MPS_TIC @S9S_MB_2U_LIB.S9S_MB_2U(SCH_1):P12V_OCP_V3_2_ISENSE_MPS_TIC
 R3862    1      A Q_RES_0402LF-0,5%,1/16W,CHIP,CA   I324 @S9S_MB_2U_LIB.S9S_MB_2U(SCH_1):PAGE239
 R3874    2      B Q_RES_0402LF-0,5%,1/16W,CHIP,CA    I80 @S9S_MB_2U_LIB.S9S_MB_2U(SCH_1):PAGE237

P12V_OCP_V3_2_ISENSE_TIC @S9S_MB_2U_LIB.S9S_MB_2U(SCH_1):P12V_OCP_V3_2_ISENSE_TIC
  U269   14    IN2 ADC128D818CIMTXNOPB-ADC128D818A   I103 @S9S_MB_2U_LIB.S9S_MB_2U(SCH_1):PAGE239
 C2177    1      A Q_CAP_0402-0.1UF,25V,10%,X7R,CA   I311 @S9S_MB_2U_LIB.S9S_MB_2U(SCH_1):PAGE239
 R3861    2      B Q_RES_0402LF-0,5%,1/16W,EMPTY,A   I323 @S9S_MB_2U_LIB.S9S_MB_2U(SCH_1):PAGE239
 R3862    2      B Q_RES_0402LF-0,5%,1/16W,CHIP,CA   I324 @S9S_MB_2U_LIB.S9S_MB_2U(SCH_1):PAGE239

P12V_OCP_VCC_1 @S9S_MB_2U_LIB.S9S_MB_2U(SCH_1):P12V_OCP_VCC_1
PC2085    1      A Q_CAP_C0402-1UF,25V,10%,EMPTY,A    I55 @S9S_MB_2U_LIB.S9S_MB_2U(SCH_1):PAGE153
 PU203   A2    VCC MAX15090BEWIT-MAX15090BEWI+T,SA    I51 @S9S_MB_2U_LIB.S9S_MB_2U(SCH_1):PAGE153
PR3792    2      B Q_RES_0402LF-10,1%,1/16W,EMPTYA    I56 @S9S_MB_2U_LIB.S9S_MB_2U(SCH_1):PAGE153

P12V_OCP_VCC_2 @S9S_MB_2U_LIB.S9S_MB_2U(SCH_1):P12V_OCP_VCC_2
PR3830    2      B Q_RES_0402LF-10,1%,1/16W,EMPTYA    I85 @S9S_MB_2U_LIB.S9S_MB_2U(SCH_1):PAGE131
 PU201   A2    VCC MAX15090BEWIT-MAX15090BEWI+T,SA    I63 @S9S_MB_2U_LIB.S9S_MB_2U(SCH_1):PAGE131
PC2098    1      A Q_CAP_C0402-1UF,25V,10%,EMPTY,A    I61 @S9S_MB_2U_LIB.S9S_MB_2U(SCH_1):PAGE131

P12V_PSU @S9S_MB_2U_LIB.S9S_MB_2U(SCH_1):P12V_PSU
 PU297    9   VIN1 MP5991GLUZ-MP5991GLU-Z,SMLF,ICA    I17 @S9S_MB_2U_LIB.S9S_MB_2U(SCH_1):PAGE325
 PU297   10   VIN2 MP5991GLUZ-MP5991GLU-Z,SMLF,ICA    I17 @S9S_MB_2U_LIB.S9S_MB_2U(SCH_1):PAGE325
 PU297   11   VIN3 MP5991GLUZ-MP5991GLU-Z,SMLF,ICA    I17 @S9S_MB_2U_LIB.S9S_MB_2U(SCH_1):PAGE325
 PU297   12   VIN4 MP5991GLUZ-MP5991GLU-Z,SMLF,ICA    I17 @S9S_MB_2U_LIB.S9S_MB_2U(SCH_1):PAGE325
 PU297   13   VIN5 MP5991GLUZ-MP5991GLU-Z,SMLF,ICA    I17 @S9S_MB_2U_LIB.S9S_MB_2U(SCH_1):PAGE325
 PU297   14   VIN6 MP5991GLUZ-MP5991GLU-Z,SMLF,ICA    I17 @S9S_MB_2U_LIB.S9S_MB_2U(SCH_1):PAGE325
 PU297   15   VIN7 MP5991GLUZ-MP5991GLU-Z,SMLF,ICA    I17 @S9S_MB_2U_LIB.S9S_MB_2U(SCH_1):PAGE325
 PU297   16   VIN8 MP5991GLUZ-MP5991GLU-Z,SMLF,ICA    I17 @S9S_MB_2U_LIB.S9S_MB_2U(SCH_1):PAGE325
 PU297   33   VIN9 MP5991GLUZ-MP5991GLU-Z,SMLF,ICA    I17 @S9S_MB_2U_LIB.S9S_MB_2U(SCH_1):PAGE325
PR3926    1      A Q_RES_0402LF-75K,0.1%,1/16W,CHA    I52 @S9S_MB_2U_LIB.S9S_MB_2U(SCH_1):PAGE303
 PU289    1   VIN1 MP5990GMA1111Z-MP5990GMA-1111-A    I56 @S9S_MB_2U_LIB.S9S_MB_2U(SCH_1):PAGE303
 PU289    2   VIN2 MP5990GMA1111Z-MP5990GMA-1111-A    I56 @S9S_MB_2U_LIB.S9S_MB_2U(SCH_1):PAGE303
 PU289    3   VIN3 MP5990GMA1111Z-MP5990GMA-1111-A    I56 @S9S_MB_2U_LIB.S9S_MB_2U(SCH_1):PAGE303
 PU289    4   VIN4 MP5990GMA1111Z-MP5990GMA-1111-A    I56 @S9S_MB_2U_LIB.S9S_MB_2U(SCH_1):PAGE303
 PU289    5   VIN5 MP5990GMA1111Z-MP5990GMA-1111-A    I56 @S9S_MB_2U_LIB.S9S_MB_2U(SCH_1):PAGE303
 PU289    6   VIN6 MP5990GMA1111Z-MP5990GMA-1111-A    I56 @S9S_MB_2U_LIB.S9S_MB_2U(SCH_1):PAGE303
 PU289    7   VIN7 MP5990GMA1111Z-MP5990GMA-1111-A    I56 @S9S_MB_2U_LIB.S9S_MB_2U(SCH_1):PAGE303
 PU289    8   VIN8 MP5990GMA1111Z-MP5990GMA-1111-A    I56 @S9S_MB_2U_LIB.S9S_MB_2U(SCH_1):PAGE303
 PU289   42   VIN9 MP5990GMA1111Z-MP5990GMA-1111-A    I56 @S9S_MB_2U_LIB.S9S_MB_2U(SCH_1):PAGE303
 PU289   43  VIN10 MP5990GMA1111Z-MP5990GMA-1111-A    I56 @S9S_MB_2U_LIB.S9S_MB_2U(SCH_1):PAGE303
 PU296    9   VIN1 MP5991GLUZ-MP5991GLU-Z,SMLF,ICA    I35 @S9S_MB_2U_LIB.S9S_MB_2U(SCH_1):PAGE325
 PU296   10   VIN2 MP5991GLUZ-MP5991GLU-Z,SMLF,ICA    I35 @S9S_MB_2U_LIB.S9S_MB_2U(SCH_1):PAGE325
 PU296   11   VIN3 MP5991GLUZ-MP5991GLU-Z,SMLF,ICA    I35 @S9S_MB_2U_LIB.S9S_MB_2U(SCH_1):PAGE325
 PU296   12   VIN4 MP5991GLUZ-MP5991GLU-Z,SMLF,ICA    I35 @S9S_MB_2U_LIB.S9S_MB_2U(SCH_1):PAGE325
 PU296   13   VIN5 MP5991GLUZ-MP5991GLU-Z,SMLF,ICA    I35 @S9S_MB_2U_LIB.S9S_MB_2U(SCH_1):PAGE325
 PU296   14   VIN6 MP5991GLUZ-MP5991GLU-Z,SMLF,ICA    I35 @S9S_MB_2U_LIB.S9S_MB_2U(SCH_1):PAGE325
 PU296   15   VIN7 MP5991GLUZ-MP5991GLU-Z,SMLF,ICA    I35 @S9S_MB_2U_LIB.S9S_MB_2U(SCH_1):PAGE325
 PU296   16   VIN8 MP5991GLUZ-MP5991GLU-Z,SMLF,ICA    I35 @S9S_MB_2U_LIB.S9S_MB_2U(SCH_1):PAGE325
 PU296   33   VIN9 MP5991GLUZ-MP5991GLU-Z,SMLF,ICA    I35 @S9S_MB_2U_LIB.S9S_MB_2U(SCH_1):PAGE325
PC2188    1      A Q_CAP_C0402-1UF,25V,10%,X6S,CHA    I51 @S9S_MB_2U_LIB.S9S_MB_2U(SCH_1):PAGE303
 PU287    9   VIN1 MP5991GLUZ-MP5991GLU-Z,SMLF,ICA    I35 @S9S_MB_2U_LIB.S9S_MB_2U(SCH_1):PAGE301
 PU287   10   VIN2 MP5991GLUZ-MP5991GLU-Z,SMLF,ICA    I35 @S9S_MB_2U_LIB.S9S_MB_2U(SCH_1):PAGE301
 PU287   11   VIN3 MP5991GLUZ-MP5991GLU-Z,SMLF,ICA    I35 @S9S_MB_2U_LIB.S9S_MB_2U(SCH_1):PAGE301
 PU287   12   VIN4 MP5991GLUZ-MP5991GLU-Z,SMLF,ICA    I35 @S9S_MB_2U_LIB.S9S_MB_2U(SCH_1):PAGE301
 PU287   13   VIN5 MP5991GLUZ-MP5991GLU-Z,SMLF,ICA    I35 @S9S_MB_2U_LIB.S9S_MB_2U(SCH_1):PAGE301
 PU287   14   VIN6 MP5991GLUZ-MP5991GLU-Z,SMLF,ICA    I35 @S9S_MB_2U_LIB.S9S_MB_2U(SCH_1):PAGE301
 PU287   15   VIN7 MP5991GLUZ-MP5991GLU-Z,SMLF,ICA    I35 @S9S_MB_2U_LIB.S9S_MB_2U(SCH_1):PAGE301
 PU287   16   VIN8 MP5991GLUZ-MP5991GLU-Z,SMLF,ICA    I35 @S9S_MB_2U_LIB.S9S_MB_2U(SCH_1):PAGE301
 PU287   33   VIN9 MP5991GLUZ-MP5991GLU-Z,SMLF,ICA    I35 @S9S_MB_2U_LIB.S9S_MB_2U(SCH_1):PAGE301
 PU288    9   VIN1 MP5991GLUZ-MP5991GLU-Z,SMLF,ICA    I14 @S9S_MB_2U_LIB.S9S_MB_2U(SCH_1):PAGE301
 PU288   10   VIN2 MP5991GLUZ-MP5991GLU-Z,SMLF,ICA    I14 @S9S_MB_2U_LIB.S9S_MB_2U(SCH_1):PAGE301
 PU288   11   VIN3 MP5991GLUZ-MP5991GLU-Z,SMLF,ICA    I14 @S9S_MB_2U_LIB.S9S_MB_2U(SCH_1):PAGE301
 PU288   12   VIN4 MP5991GLUZ-MP5991GLU-Z,SMLF,ICA    I14 @S9S_MB_2U_LIB.S9S_MB_2U(SCH_1):PAGE301
 PU288   13   VIN5 MP5991GLUZ-MP5991GLU-Z,SMLF,ICA    I14 @S9S_MB_2U_LIB.S9S_MB_2U(SCH_1):PAGE301
 PU288   14   VIN6 MP5991GLUZ-MP5991GLU-Z,SMLF,ICA    I14 @S9S_MB_2U_LIB.S9S_MB_2U(SCH_1):PAGE301
 PU288   15   VIN7 MP5991GLUZ-MP5991GLU-Z,SMLF,ICA    I14 @S9S_MB_2U_LIB.S9S_MB_2U(SCH_1):PAGE301
 PU288   16   VIN8 MP5991GLUZ-MP5991GLU-Z,SMLF,ICA    I14 @S9S_MB_2U_LIB.S9S_MB_2U(SCH_1):PAGE301
 PU288   33   VIN9 MP5991GLUZ-MP5991GLU-Z,SMLF,ICA    I14 @S9S_MB_2U_LIB.S9S_MB_2U(SCH_1):PAGE301
   FS1    1      1 Q_FUSE_SMLF-20A/125V,IC,DKK00XA    I54 @S9S_MB_2U_LIB.S9S_MB_2U(SCH_1):PAGE328
PR2534   1A     1A Q_SP_RES4P-0.0003,1%,4W,SMLF,EA    I63 @S9S_MB_2U_LIB.S9S_MB_2U(SCH_1):PAGE328
PR2533   1A     1A Q_SP_RES4P-0.0003,1%,4W,SMLF,EA    I64 @S9S_MB_2U_LIB.S9S_MB_2U(SCH_1):PAGE328
PR2532   1A     1A Q_SP_RES4P-0.0003,1%,4W,SMLF,EA    I78 @S9S_MB_2U_LIB.S9S_MB_2U(SCH_1):PAGE328
   PR4   1A     1A Q_SP_RES4P-0.0003,1%,4W,SMLF,EA    I79 @S9S_MB_2U_LIB.S9S_MB_2U(SCH_1):PAGE328
  PJ42    1      1 SCONN21_9193031121LF-SCONN21_9A    I34 @S9S_MB_2U_LIB.S9S_MB_2U(SCH_1):PAGE327
   PR3    1      1 Q_RES_4P_12-0.003,1%,3W,SMLF,EA   I126 @S9S_MB_2U_LIB.S9S_MB_2U(SCH_1):PAGE328
 R4707    2      B Q_RES_0402LF-560,1%,1/16W,CHIPA    I63 @S9S_MB_2U_LIB.S9S_MB_2U(SCH_1):PAGE241
   J45 P4_1   P4_1 CONN60_101062636003K02LF-CONN6A    I12 @S9S_MB_2U_LIB.S9S_MB_2U(SCH_1):PAGE233
   J45 P4_2   P4_2 CONN60_101062636003K02LF-CONN6A    I12 @S9S_MB_2U_LIB.S9S_MB_2U(SCH_1):PAGE233
   J45 P4_3   P4_3 CONN60_101062636003K02LF-CONN6A    I12 @S9S_MB_2U_LIB.S9S_MB_2U(SCH_1):PAGE233
   J45 P4_4   P4_4 CONN60_101062636003K02LF-CONN6A    I12 @S9S_MB_2U_LIB.S9S_MB_2U(SCH_1):PAGE233
   J45 P4_5   P4_5 CONN60_101062636003K02LF-CONN6A    I12 @S9S_MB_2U_LIB.S9S_MB_2U(SCH_1):PAGE233
   J45 P4_6   P4_6 CONN60_101062636003K02LF-CONN6A    I12 @S9S_MB_2U_LIB.S9S_MB_2U(SCH_1):PAGE233
   J45 P4_7   P4_7 CONN60_101062636003K02LF-CONN6A    I12 @S9S_MB_2U_LIB.S9S_MB_2U(SCH_1):PAGE233
   J45 P4_8   P4_8 CONN60_101062636003K02LF-CONN6A    I12 @S9S_MB_2U_LIB.S9S_MB_2U(SCH_1):PAGE233
   J45 P5_1   P5_1 CONN60_101062636003K02LF-CONN6A    I12 @S9S_MB_2U_LIB.S9S_MB_2U(SCH_1):PAGE233
   J45 P5_2   P5_2 CONN60_101062636003K02LF-CONN6A    I12 @S9S_MB_2U_LIB.S9S_MB_2U(SCH_1):PAGE233
   J45 P5_3   P5_3 CONN60_101062636003K02LF-CONN6A    I12 @S9S_MB_2U_LIB.S9S_MB_2U(SCH_1):PAGE233
   J45 P5_4   P5_4 CONN60_101062636003K02LF-CONN6A    I12 @S9S_MB_2U_LIB.S9S_MB_2U(SCH_1):PAGE233
   J45 P5_5   P5_5 CONN60_101062636003K02LF-CONN6A    I12 @S9S_MB_2U_LIB.S9S_MB_2U(SCH_1):PAGE233
   J45 P5_6   P5_6 CONN60_101062636003K02LF-CONN6A    I12 @S9S_MB_2U_LIB.S9S_MB_2U(SCH_1):PAGE233
   J45 P5_7   P5_7 CONN60_101062636003K02LF-CONN6A    I12 @S9S_MB_2U_LIB.S9S_MB_2U(SCH_1):PAGE233
   J45 P5_8   P5_8 CONN60_101062636003K02LF-CONN6A    I12 @S9S_MB_2U_LIB.S9S_MB_2U(SCH_1):PAGE233
   J45 P6_1   P6_1 CONN60_101062636003K02LF-CONN6A    I12 @S9S_MB_2U_LIB.S9S_MB_2U(SCH_1):PAGE233
   J45 P6_2   P6_2 CONN60_101062636003K02LF-CONN6A    I12 @S9S_MB_2U_LIB.S9S_MB_2U(SCH_1):PAGE233
   J45 P6_3   P6_3 CONN60_101062636003K02LF-CONN6A    I12 @S9S_MB_2U_LIB.S9S_MB_2U(SCH_1):PAGE233
   J45 P6_4   P6_4 CONN60_101062636003K02LF-CONN6A    I12 @S9S_MB_2U_LIB.S9S_MB_2U(SCH_1):PAGE233
   J45 P6_5   P6_5 CONN60_101062636003K02LF-CONN6A    I12 @S9S_MB_2U_LIB.S9S_MB_2U(SCH_1):PAGE233
   J45 P6_6   P6_6 CONN60_101062636003K02LF-CONN6A    I12 @S9S_MB_2U_LIB.S9S_MB_2U(SCH_1):PAGE233
   J45 P6_7   P6_7 CONN60_101062636003K02LF-CONN6A    I12 @S9S_MB_2U_LIB.S9S_MB_2U(SCH_1):PAGE233
   J45 P6_8   P6_8 CONN60_101062636003K02LF-CONN6A    I12 @S9S_MB_2U_LIB.S9S_MB_2U(SCH_1):PAGE233

P12V_PSU_FUSE @S9S_MB_2U_LIB.S9S_MB_2U(SCH_1):P12V_PSU_FUSE
 R3923    1      A Q_RES_0402LF-63.4K,1%,1/16W,CHA    I10 @S9S_MB_2U_LIB.S9S_MB_2U(SCH_1):PAGE303
  PD15    C      C ZENER_AC-5.0SMDJ14A,SMLF,IC,BCA    I51 @S9S_MB_2U_LIB.S9S_MB_2U(SCH_1):PAGE328
  PD16    C      C ZENER_AC-5.0SMDJ14A,SMLF,IC,BCA    I53 @S9S_MB_2U_LIB.S9S_MB_2U(SCH_1):PAGE328
   FS1    2      2 Q_FUSE_SMLF-20A/125V,IC,DKK00XA    I54 @S9S_MB_2U_LIB.S9S_MB_2U(SCH_1):PAGE328
 R4901    1      A Q_RES_0402LF-82K,1%,1/16W,CHIPA    I26 @S9S_MB_2U_LIB.S9S_MB_2U(SCH_1):PAGE303

P12V_S3_AUX_CPU0_NVDIMM @S9S_MB_2U_LIB.S9S_MB_2U(SCH_1):P12V_S3_AUX_CPU0_NVDIMM
    C3    1      A Q_CAP_C0805-10UF,16V,10%,X6S,CA   I188 @S9S_MB_2U_LIB.S9S_MB_2U(SCH_1):PAGE82
    C4    1      A Q_CAP_C0805-10UF,16V,10%,X6S,CA   I190 @S9S_MB_2U_LIB.S9S_MB_2U(SCH_1):PAGE82
    C6    1      A Q_CAP_C0805-10UF,16V,10%,X6S,CA   I122 @S9S_MB_2U_LIB.S9S_MB_2U(SCH_1):PAGE83
    C7    1      A Q_CAP_C0805-10UF,16V,10%,X6S,CA   I144 @S9S_MB_2U_LIB.S9S_MB_2U(SCH_1):PAGE83
    J2    1 VIN_BULK0 SCONN288_ADR50017P087CC-SCONN2A   I179 @S9S_MB_2U_LIB.S9S_MB_2U(SCH_1):PAGE83
    J2  145 VIN_BULK1 SCONN288_ADR50017P087CC-SCONN2A   I179 @S9S_MB_2U_LIB.S9S_MB_2U(SCH_1):PAGE83
    J2  146 VIN_BULK2 SCONN288_ADR50017P087CC-SCONN2A   I179 @S9S_MB_2U_LIB.S9S_MB_2U(SCH_1):PAGE83
    C9    1      A Q_CAP_C0805-10UF,16V,10%,X6S,CA   I122 @S9S_MB_2U_LIB.S9S_MB_2U(SCH_1):PAGE84
   C10    1      A Q_CAP_C0805-10UF,16V,10%,X6S,CA   I144 @S9S_MB_2U_LIB.S9S_MB_2U(SCH_1):PAGE84
    J3    1 VIN_BULK0 SCONN288_ADR50017P130CC-SCONN2A   I178 @S9S_MB_2U_LIB.S9S_MB_2U(SCH_1):PAGE84
    J3  145 VIN_BULK1 SCONN288_ADR50017P130CC-SCONN2A   I178 @S9S_MB_2U_LIB.S9S_MB_2U(SCH_1):PAGE84
    J3  146 VIN_BULK2 SCONN288_ADR50017P130CC-SCONN2A   I178 @S9S_MB_2U_LIB.S9S_MB_2U(SCH_1):PAGE84
   C12    1      A Q_CAP_C0805-10UF,16V,10%,X6S,CA   I125 @S9S_MB_2U_LIB.S9S_MB_2U(SCH_1):PAGE85
   C13    1      A Q_CAP_C0805-10UF,16V,10%,X6S,CA   I127 @S9S_MB_2U_LIB.S9S_MB_2U(SCH_1):PAGE85
    J4    1 VIN_BULK0 SCONN288_ADR50017P087CC-SCONN2A   I174 @S9S_MB_2U_LIB.S9S_MB_2U(SCH_1):PAGE85
    J4  145 VIN_BULK1 SCONN288_ADR50017P087CC-SCONN2A   I174 @S9S_MB_2U_LIB.S9S_MB_2U(SCH_1):PAGE85
    J4  146 VIN_BULK2 SCONN288_ADR50017P087CC-SCONN2A   I174 @S9S_MB_2U_LIB.S9S_MB_2U(SCH_1):PAGE85
   C15    1      A Q_CAP_C0805-10UF,16V,10%,X6S,CA   I121 @S9S_MB_2U_LIB.S9S_MB_2U(SCH_1):PAGE86
   C16    1      A Q_CAP_C0805-10UF,16V,10%,X6S,CA   I123 @S9S_MB_2U_LIB.S9S_MB_2U(SCH_1):PAGE86
    J5    1 VIN_BULK0 SCONN288_ADR50017P130CC-SCONN2A   I174 @S9S_MB_2U_LIB.S9S_MB_2U(SCH_1):PAGE86
    J5  145 VIN_BULK1 SCONN288_ADR50017P130CC-SCONN2A   I174 @S9S_MB_2U_LIB.S9S_MB_2U(SCH_1):PAGE86
    J5  146 VIN_BULK2 SCONN288_ADR50017P130CC-SCONN2A   I174 @S9S_MB_2U_LIB.S9S_MB_2U(SCH_1):PAGE86
   C18    1      A Q_CAP_C0805-10UF,16V,10%,X6S,CA   I124 @S9S_MB_2U_LIB.S9S_MB_2U(SCH_1):PAGE87
   C19    1      A Q_CAP_C0805-10UF,16V,10%,X6S,CA   I127 @S9S_MB_2U_LIB.S9S_MB_2U(SCH_1):PAGE87
    J6    1 VIN_BULK0 SCONN288_ADR50017P087CC-SCONN2A   I175 @S9S_MB_2U_LIB.S9S_MB_2U(SCH_1):PAGE87
    J6  145 VIN_BULK1 SCONN288_ADR50017P087CC-SCONN2A   I175 @S9S_MB_2U_LIB.S9S_MB_2U(SCH_1):PAGE87
    J6  146 VIN_BULK2 SCONN288_ADR50017P087CC-SCONN2A   I175 @S9S_MB_2U_LIB.S9S_MB_2U(SCH_1):PAGE87
   C21    1      A Q_CAP_C0805-10UF,16V,10%,X6S,CA   I126 @S9S_MB_2U_LIB.S9S_MB_2U(SCH_1):PAGE88
   C22    1      A Q_CAP_C0805-10UF,16V,10%,X6S,CA   I166 @S9S_MB_2U_LIB.S9S_MB_2U(SCH_1):PAGE88
    J7    1 VIN_BULK0 SCONN288_ADR50017P130CC-SCONN2A   I168 @S9S_MB_2U_LIB.S9S_MB_2U(SCH_1):PAGE88
    J7  145 VIN_BULK1 SCONN288_ADR50017P130CC-SCONN2A   I168 @S9S_MB_2U_LIB.S9S_MB_2U(SCH_1):PAGE88
    J7  146 VIN_BULK2 SCONN288_ADR50017P130CC-SCONN2A   I168 @S9S_MB_2U_LIB.S9S_MB_2U(SCH_1):PAGE88
   C24    1      A Q_CAP_C0805-10UF,16V,10%,X6S,CA   I125 @S9S_MB_2U_LIB.S9S_MB_2U(SCH_1):PAGE89
   C25    1      A Q_CAP_C0805-10UF,16V,10%,X6S,CA   I127 @S9S_MB_2U_LIB.S9S_MB_2U(SCH_1):PAGE89
    J8    1 VIN_BULK0 SCONN288_ADR50017P087CC-SCONN2A   I175 @S9S_MB_2U_LIB.S9S_MB_2U(SCH_1):PAGE89
    J8  145 VIN_BULK1 SCONN288_ADR50017P087CC-SCONN2A   I175 @S9S_MB_2U_LIB.S9S_MB_2U(SCH_1):PAGE89
    J8  146 VIN_BULK2 SCONN288_ADR50017P087CC-SCONN2A   I175 @S9S_MB_2U_LIB.S9S_MB_2U(SCH_1):PAGE89
   C27    1      A Q_CAP_C0805-10UF,16V,10%,X6S,CA   I123 @S9S_MB_2U_LIB.S9S_MB_2U(SCH_1):PAGE90
   C28    1      A Q_CAP_C0805-10UF,16V,10%,X6S,CA   I145 @S9S_MB_2U_LIB.S9S_MB_2U(SCH_1):PAGE90
    J9    1 VIN_BULK0 SCONN288_ADR50017P130CC-SCONN2A   I147 @S9S_MB_2U_LIB.S9S_MB_2U(SCH_1):PAGE90
    J9  145 VIN_BULK1 SCONN288_ADR50017P130CC-SCONN2A   I147 @S9S_MB_2U_LIB.S9S_MB_2U(SCH_1):PAGE90
    J9  146 VIN_BULK2 SCONN288_ADR50017P130CC-SCONN2A   I147 @S9S_MB_2U_LIB.S9S_MB_2U(SCH_1):PAGE90
   C30    1      A Q_CAP_C0805-10UF,16V,10%,X6S,CA   I124 @S9S_MB_2U_LIB.S9S_MB_2U(SCH_1):PAGE91
   C31    1      A Q_CAP_C0805-10UF,16V,10%,X6S,CA   I146 @S9S_MB_2U_LIB.S9S_MB_2U(SCH_1):PAGE91
   J10    1 VIN_BULK0 SCONN288_ADR50017P087CC-SCONN2A   I148 @S9S_MB_2U_LIB.S9S_MB_2U(SCH_1):PAGE91
   J10  145 VIN_BULK1 SCONN288_ADR50017P087CC-SCONN2A   I148 @S9S_MB_2U_LIB.S9S_MB_2U(SCH_1):PAGE91
   J10  146 VIN_BULK2 SCONN288_ADR50017P087CC-SCONN2A   I148 @S9S_MB_2U_LIB.S9S_MB_2U(SCH_1):PAGE91
   C33    1      A Q_CAP_C0805-10UF,16V,10%,X6S,CA   I127 @S9S_MB_2U_LIB.S9S_MB_2U(SCH_1):PAGE92
   C34    1      A Q_CAP_C0805-10UF,16V,10%,X6S,CA   I130 @S9S_MB_2U_LIB.S9S_MB_2U(SCH_1):PAGE92
   J11    1 VIN_BULK0 SCONN288_ADR50017P130CC-SCONN2A   I175 @S9S_MB_2U_LIB.S9S_MB_2U(SCH_1):PAGE92
   J11  145 VIN_BULK1 SCONN288_ADR50017P130CC-SCONN2A   I175 @S9S_MB_2U_LIB.S9S_MB_2U(SCH_1):PAGE92
   J11  146 VIN_BULK2 SCONN288_ADR50017P130CC-SCONN2A   I175 @S9S_MB_2U_LIB.S9S_MB_2U(SCH_1):PAGE92
   C36    1      A Q_CAP_C0805-10UF,16V,10%,X6S,CA   I126 @S9S_MB_2U_LIB.S9S_MB_2U(SCH_1):PAGE93
   C37    1      A Q_CAP_C0805-10UF,16V,10%,X6S,CA   I128 @S9S_MB_2U_LIB.S9S_MB_2U(SCH_1):PAGE93
   J12    1 VIN_BULK0 SCONN288_ADR50017P087CC-SCONN2A   I175 @S9S_MB_2U_LIB.S9S_MB_2U(SCH_1):PAGE93
   J12  145 VIN_BULK1 SCONN288_ADR50017P087CC-SCONN2A   I175 @S9S_MB_2U_LIB.S9S_MB_2U(SCH_1):PAGE93
   J12  146 VIN_BULK2 SCONN288_ADR50017P087CC-SCONN2A   I175 @S9S_MB_2U_LIB.S9S_MB_2U(SCH_1):PAGE93
   C39    1      A Q_CAP_C0805-10UF,16V,10%,X6S,CA   I125 @S9S_MB_2U_LIB.S9S_MB_2U(SCH_1):PAGE94
   C40    1      A Q_CAP_C0805-10UF,16V,10%,X6S,CA   I162 @S9S_MB_2U_LIB.S9S_MB_2U(SCH_1):PAGE94
   J13    1 VIN_BULK0 SCONN288_ADR50017P130CC-SCONN2A   I164 @S9S_MB_2U_LIB.S9S_MB_2U(SCH_1):PAGE94
   J13  145 VIN_BULK1 SCONN288_ADR50017P130CC-SCONN2A   I164 @S9S_MB_2U_LIB.S9S_MB_2U(SCH_1):PAGE94
   J13  146 VIN_BULK2 SCONN288_ADR50017P130CC-SCONN2A   I164 @S9S_MB_2U_LIB.S9S_MB_2U(SCH_1):PAGE94
   C42    1      A Q_CAP_C0805-10UF,16V,10%,X6S,CA   I125 @S9S_MB_2U_LIB.S9S_MB_2U(SCH_1):PAGE95
   C43    1      A Q_CAP_C0805-10UF,16V,10%,X6S,CA   I128 @S9S_MB_2U_LIB.S9S_MB_2U(SCH_1):PAGE95
   J14    1 VIN_BULK0 SCONN288_ADR50017P087CC-SCONN2A   I176 @S9S_MB_2U_LIB.S9S_MB_2U(SCH_1):PAGE95
   J14  145 VIN_BULK1 SCONN288_ADR50017P087CC-SCONN2A   I176 @S9S_MB_2U_LIB.S9S_MB_2U(SCH_1):PAGE95
   J14  146 VIN_BULK2 SCONN288_ADR50017P087CC-SCONN2A   I176 @S9S_MB_2U_LIB.S9S_MB_2U(SCH_1):PAGE95
   C45    1      A Q_CAP_C0805-10UF,16V,10%,X6S,CA   I125 @S9S_MB_2U_LIB.S9S_MB_2U(SCH_1):PAGE96
   C46    1      A Q_CAP_C0805-10UF,16V,10%,X6S,CA   I127 @S9S_MB_2U_LIB.S9S_MB_2U(SCH_1):PAGE96
   J15    1 VIN_BULK0 SCONN288_ADR50017P130CC-SCONN2A   I176 @S9S_MB_2U_LIB.S9S_MB_2U(SCH_1):PAGE96
   J15  145 VIN_BULK1 SCONN288_ADR50017P130CC-SCONN2A   I176 @S9S_MB_2U_LIB.S9S_MB_2U(SCH_1):PAGE96
   J15  146 VIN_BULK2 SCONN288_ADR50017P130CC-SCONN2A   I176 @S9S_MB_2U_LIB.S9S_MB_2U(SCH_1):PAGE96
   C48    1      A Q_CAP_C0805-10UF,16V,10%,X6S,CA    I59 @S9S_MB_2U_LIB.S9S_MB_2U(SCH_1):PAGE97
   C49    1      A Q_CAP_C0805-10UF,16V,10%,X6S,CA    I62 @S9S_MB_2U_LIB.S9S_MB_2U(SCH_1):PAGE97
   J16    1 VIN_BULK0 SCONN288_ADR50017P087CC-SCONN2A    I64 @S9S_MB_2U_LIB.S9S_MB_2U(SCH_1):PAGE97
   J16  145 VIN_BULK1 SCONN288_ADR50017P087CC-SCONN2A    I64 @S9S_MB_2U_LIB.S9S_MB_2U(SCH_1):PAGE97
   J16  146 VIN_BULK2 SCONN288_ADR50017P087CC-SCONN2A    I64 @S9S_MB_2U_LIB.S9S_MB_2U(SCH_1):PAGE97
    J1    1 VIN_BULK0 SCONN288_ADR50017P130CC-SCONN2A   I203 @S9S_MB_2U_LIB.S9S_MB_2U(SCH_1):PAGE82
    J1  145 VIN_BULK1 SCONN288_ADR50017P130CC-SCONN2A   I203 @S9S_MB_2U_LIB.S9S_MB_2U(SCH_1):PAGE82
    J1  146 VIN_BULK2 SCONN288_ADR50017P130CC-SCONN2A   I203 @S9S_MB_2U_LIB.S9S_MB_2U(SCH_1):PAGE82
 R1838    2      2 Q_RES_4P_12-0.001,1%,3W,SMLF,CA    I11 @S9S_MB_2U_LIB.S9S_MB_2U(SCH_1):PAGE240

P12V_S3_AUX_CPU1_NVDIMM @S9S_MB_2U_LIB.S9S_MB_2U(SCH_1):P12V_S3_AUX_CPU1_NVDIMM
   C51    1      A Q_CAP_C0805-10UF,16V,10%,X6S,CA   I123 @S9S_MB_2U_LIB.S9S_MB_2U(SCH_1):PAGE98
   C52    1      A Q_CAP_C0805-10UF,16V,10%,X6S,CA   I145 @S9S_MB_2U_LIB.S9S_MB_2U(SCH_1):PAGE98
   J17    1 VIN_BULK0 SCONN288_ADR50017P130CC-SCONN2A   I147 @S9S_MB_2U_LIB.S9S_MB_2U(SCH_1):PAGE98
   J17  145 VIN_BULK1 SCONN288_ADR50017P130CC-SCONN2A   I147 @S9S_MB_2U_LIB.S9S_MB_2U(SCH_1):PAGE98
   J17  146 VIN_BULK2 SCONN288_ADR50017P130CC-SCONN2A   I147 @S9S_MB_2U_LIB.S9S_MB_2U(SCH_1):PAGE98
   C54    1      A Q_CAP_C0805-10UF,16V,10%,X6S,CA   I126 @S9S_MB_2U_LIB.S9S_MB_2U(SCH_1):PAGE99
   C55    1      A Q_CAP_C0805-10UF,16V,10%,X6S,CA   I128 @S9S_MB_2U_LIB.S9S_MB_2U(SCH_1):PAGE99
   J18    1 VIN_BULK0 SCONN288_ADR50017P087CC-SCONN2A   I175 @S9S_MB_2U_LIB.S9S_MB_2U(SCH_1):PAGE99
   J18  145 VIN_BULK1 SCONN288_ADR50017P087CC-SCONN2A   I175 @S9S_MB_2U_LIB.S9S_MB_2U(SCH_1):PAGE99
   J18  146 VIN_BULK2 SCONN288_ADR50017P087CC-SCONN2A   I175 @S9S_MB_2U_LIB.S9S_MB_2U(SCH_1):PAGE99
   C57    1      A Q_CAP_C0805-10UF,16V,10%,X6S,CA   I122 @S9S_MB_2U_LIB.S9S_MB_2U(SCH_1):PAGE100
   C58    1      A Q_CAP_C0805-10UF,16V,10%,X6S,CA   I124 @S9S_MB_2U_LIB.S9S_MB_2U(SCH_1):PAGE100
   J19    1 VIN_BULK0 SCONN288_ADR50017P130CC-SCONN2A   I175 @S9S_MB_2U_LIB.S9S_MB_2U(SCH_1):PAGE100
   J19  145 VIN_BULK1 SCONN288_ADR50017P130CC-SCONN2A   I175 @S9S_MB_2U_LIB.S9S_MB_2U(SCH_1):PAGE100
   J19  146 VIN_BULK2 SCONN288_ADR50017P130CC-SCONN2A   I175 @S9S_MB_2U_LIB.S9S_MB_2U(SCH_1):PAGE100
   C60    1      A Q_CAP_C0805-10UF,16V,10%,X6S,CA   I125 @S9S_MB_2U_LIB.S9S_MB_2U(SCH_1):PAGE101
   C61    1      A Q_CAP_C0805-10UF,16V,10%,X6S,CA   I127 @S9S_MB_2U_LIB.S9S_MB_2U(SCH_1):PAGE101
   J20    1 VIN_BULK0 SCONN288_ADR50017P087CC-SCONN2A   I176 @S9S_MB_2U_LIB.S9S_MB_2U(SCH_1):PAGE101
   J20  145 VIN_BULK1 SCONN288_ADR50017P087CC-SCONN2A   I176 @S9S_MB_2U_LIB.S9S_MB_2U(SCH_1):PAGE101
   J20  146 VIN_BULK2 SCONN288_ADR50017P087CC-SCONN2A   I176 @S9S_MB_2U_LIB.S9S_MB_2U(SCH_1):PAGE101
   C63    1      A Q_CAP_C0805-10UF,16V,10%,X6S,CA   I127 @S9S_MB_2U_LIB.S9S_MB_2U(SCH_1):PAGE102
   C64    1      A Q_CAP_C0805-10UF,16V,10%,X6S,CA   I167 @S9S_MB_2U_LIB.S9S_MB_2U(SCH_1):PAGE102
   J21    1 VIN_BULK0 SCONN288_ADR50017P130CC-SCONN2A   I169 @S9S_MB_2U_LIB.S9S_MB_2U(SCH_1):PAGE102
   J21  145 VIN_BULK1 SCONN288_ADR50017P130CC-SCONN2A   I169 @S9S_MB_2U_LIB.S9S_MB_2U(SCH_1):PAGE102
   J21  146 VIN_BULK2 SCONN288_ADR50017P130CC-SCONN2A   I169 @S9S_MB_2U_LIB.S9S_MB_2U(SCH_1):PAGE102
   C66    1      A Q_CAP_C0805-10UF,16V,10%,X6S,CA   I126 @S9S_MB_2U_LIB.S9S_MB_2U(SCH_1):PAGE103
   C67    1      A Q_CAP_C0805-10UF,16V,10%,X6S,CA   I128 @S9S_MB_2U_LIB.S9S_MB_2U(SCH_1):PAGE103
   J22    1 VIN_BULK0 SCONN288_ADR50017P087CC-SCONN2A   I176 @S9S_MB_2U_LIB.S9S_MB_2U(SCH_1):PAGE103
   J22  145 VIN_BULK1 SCONN288_ADR50017P087CC-SCONN2A   I176 @S9S_MB_2U_LIB.S9S_MB_2U(SCH_1):PAGE103
   J22  146 VIN_BULK2 SCONN288_ADR50017P087CC-SCONN2A   I176 @S9S_MB_2U_LIB.S9S_MB_2U(SCH_1):PAGE103
   C69    1      A Q_CAP_C0805-10UF,16V,10%,X6S,CA   I127 @S9S_MB_2U_LIB.S9S_MB_2U(SCH_1):PAGE104
   C70    1      A Q_CAP_C0805-10UF,16V,10%,X6S,CA   I129 @S9S_MB_2U_LIB.S9S_MB_2U(SCH_1):PAGE104
   J23    1 VIN_BULK0 SCONN288_ADR50017P130CC-SCONN2A   I175 @S9S_MB_2U_LIB.S9S_MB_2U(SCH_1):PAGE104
   J23  145 VIN_BULK1 SCONN288_ADR50017P130CC-SCONN2A   I175 @S9S_MB_2U_LIB.S9S_MB_2U(SCH_1):PAGE104
   J23  146 VIN_BULK2 SCONN288_ADR50017P130CC-SCONN2A   I175 @S9S_MB_2U_LIB.S9S_MB_2U(SCH_1):PAGE104
   C97    1      A Q_CAP_C0805-10UF,16V,10%,X6S,CA   I124 @S9S_MB_2U_LIB.S9S_MB_2U(SCH_1):PAGE105
   C98    1      A Q_CAP_C0805-10UF,16V,10%,X6S,CA   I146 @S9S_MB_2U_LIB.S9S_MB_2U(SCH_1):PAGE105
   J24    1 VIN_BULK0 SCONN288_ADR50017P087CC-SCONN2A   I180 @S9S_MB_2U_LIB.S9S_MB_2U(SCH_1):PAGE105
   J24  145 VIN_BULK1 SCONN288_ADR50017P087CC-SCONN2A   I180 @S9S_MB_2U_LIB.S9S_MB_2U(SCH_1):PAGE105
   J24  146 VIN_BULK2 SCONN288_ADR50017P087CC-SCONN2A   I180 @S9S_MB_2U_LIB.S9S_MB_2U(SCH_1):PAGE105
   C94    1      A Q_CAP_C0805-10UF,16V,10%,X6S,CA   I127 @S9S_MB_2U_LIB.S9S_MB_2U(SCH_1):PAGE106
   C95    1      A Q_CAP_C0805-10UF,16V,10%,X6S,CA   I130 @S9S_MB_2U_LIB.S9S_MB_2U(SCH_1):PAGE106
   J25    1 VIN_BULK0 SCONN288_ADR50017P130CC-SCONN2A   I178 @S9S_MB_2U_LIB.S9S_MB_2U(SCH_1):PAGE106
   J25  145 VIN_BULK1 SCONN288_ADR50017P130CC-SCONN2A   I178 @S9S_MB_2U_LIB.S9S_MB_2U(SCH_1):PAGE106
   J25  146 VIN_BULK2 SCONN288_ADR50017P130CC-SCONN2A   I178 @S9S_MB_2U_LIB.S9S_MB_2U(SCH_1):PAGE106
   C91    1      A Q_CAP_C0805-10UF,16V,10%,X6S,CA   I126 @S9S_MB_2U_LIB.S9S_MB_2U(SCH_1):PAGE107
   C92    1      A Q_CAP_C0805-10UF,16V,10%,X6S,CA   I128 @S9S_MB_2U_LIB.S9S_MB_2U(SCH_1):PAGE107
   J26    1 VIN_BULK0 SCONN288_ADR50017P087CC-SCONN2A   I179 @S9S_MB_2U_LIB.S9S_MB_2U(SCH_1):PAGE107
   J26  145 VIN_BULK1 SCONN288_ADR50017P087CC-SCONN2A   I179 @S9S_MB_2U_LIB.S9S_MB_2U(SCH_1):PAGE107
   J26  146 VIN_BULK2 SCONN288_ADR50017P087CC-SCONN2A   I179 @S9S_MB_2U_LIB.S9S_MB_2U(SCH_1):PAGE107
   C88    1      A Q_CAP_C0805-10UF,16V,10%,X6S,CA   I123 @S9S_MB_2U_LIB.S9S_MB_2U(SCH_1):PAGE108
   C89    1      A Q_CAP_C0805-10UF,16V,10%,X6S,CA   I160 @S9S_MB_2U_LIB.S9S_MB_2U(SCH_1):PAGE108
   J27    1 VIN_BULK0 SCONN288_ADR50017P130CC-SCONN2A   I178 @S9S_MB_2U_LIB.S9S_MB_2U(SCH_1):PAGE108
   J27  145 VIN_BULK1 SCONN288_ADR50017P130CC-SCONN2A   I178 @S9S_MB_2U_LIB.S9S_MB_2U(SCH_1):PAGE108
   J27  146 VIN_BULK2 SCONN288_ADR50017P130CC-SCONN2A   I178 @S9S_MB_2U_LIB.S9S_MB_2U(SCH_1):PAGE108
   C85    1      A Q_CAP_C0805-10UF,16V,10%,X6S,CA   I125 @S9S_MB_2U_LIB.S9S_MB_2U(SCH_1):PAGE109
   C86    1      A Q_CAP_C0805-10UF,16V,10%,X6S,CA   I128 @S9S_MB_2U_LIB.S9S_MB_2U(SCH_1):PAGE109
   J28    1 VIN_BULK0 SCONN288_ADR50017P087CC-SCONN2A   I176 @S9S_MB_2U_LIB.S9S_MB_2U(SCH_1):PAGE109
   J28  145 VIN_BULK1 SCONN288_ADR50017P087CC-SCONN2A   I176 @S9S_MB_2U_LIB.S9S_MB_2U(SCH_1):PAGE109
   J28  146 VIN_BULK2 SCONN288_ADR50017P087CC-SCONN2A   I176 @S9S_MB_2U_LIB.S9S_MB_2U(SCH_1):PAGE109
   C82    1      A Q_CAP_C0805-10UF,16V,10%,X6S,CA   I124 @S9S_MB_2U_LIB.S9S_MB_2U(SCH_1):PAGE110
   C83    1      A Q_CAP_C0805-10UF,16V,10%,X6S,CA   I126 @S9S_MB_2U_LIB.S9S_MB_2U(SCH_1):PAGE110
   J29    1 VIN_BULK0 SCONN288_ADR50017P130CC-SCONN2A   I178 @S9S_MB_2U_LIB.S9S_MB_2U(SCH_1):PAGE110
   J29  145 VIN_BULK1 SCONN288_ADR50017P130CC-SCONN2A   I178 @S9S_MB_2U_LIB.S9S_MB_2U(SCH_1):PAGE110
   J29  146 VIN_BULK2 SCONN288_ADR50017P130CC-SCONN2A   I178 @S9S_MB_2U_LIB.S9S_MB_2U(SCH_1):PAGE110
   C79    1      A Q_CAP_C0805-10UF,16V,10%,X6S,CA    I56 @S9S_MB_2U_LIB.S9S_MB_2U(SCH_1):PAGE111
   C80    1      A Q_CAP_C0805-10UF,16V,10%,X6S,CA    I59 @S9S_MB_2U_LIB.S9S_MB_2U(SCH_1):PAGE111
   J30    1 VIN_BULK0 SCONN288_ADR50017P087CC-SCONN2A   I178 @S9S_MB_2U_LIB.S9S_MB_2U(SCH_1):PAGE111
   J30  145 VIN_BULK1 SCONN288_ADR50017P087CC-SCONN2A   I178 @S9S_MB_2U_LIB.S9S_MB_2U(SCH_1):PAGE111
   J30  146 VIN_BULK2 SCONN288_ADR50017P087CC-SCONN2A   I178 @S9S_MB_2U_LIB.S9S_MB_2U(SCH_1):PAGE111
   C76    1      A Q_CAP_C0805-10UF,16V,10%,X6S,CA   I125 @S9S_MB_2U_LIB.S9S_MB_2U(SCH_1):PAGE112
   C77    1      A Q_CAP_C0805-10UF,16V,10%,X6S,CA   I126 @S9S_MB_2U_LIB.S9S_MB_2U(SCH_1):PAGE112
   J31    1 VIN_BULK0 SCONN288_ADR50017P130CC-SCONN2A   I178 @S9S_MB_2U_LIB.S9S_MB_2U(SCH_1):PAGE112
   J31  145 VIN_BULK1 SCONN288_ADR50017P130CC-SCONN2A   I178 @S9S_MB_2U_LIB.S9S_MB_2U(SCH_1):PAGE112
   J31  146 VIN_BULK2 SCONN288_ADR50017P130CC-SCONN2A   I178 @S9S_MB_2U_LIB.S9S_MB_2U(SCH_1):PAGE112
   C73    1      A Q_CAP_C0805-10UF,16V,10%,X6S,CA   I120 @S9S_MB_2U_LIB.S9S_MB_2U(SCH_1):PAGE113
   C74    1      A Q_CAP_C0805-10UF,16V,10%,X6S,CA   I122 @S9S_MB_2U_LIB.S9S_MB_2U(SCH_1):PAGE113
   J32    1 VIN_BULK0 SCONN288_ADR50017P087CC-SCONN2A   I177 @S9S_MB_2U_LIB.S9S_MB_2U(SCH_1):PAGE113
   J32  145 VIN_BULK1 SCONN288_ADR50017P087CC-SCONN2A   I177 @S9S_MB_2U_LIB.S9S_MB_2U(SCH_1):PAGE113
   J32  146 VIN_BULK2 SCONN288_ADR50017P087CC-SCONN2A   I177 @S9S_MB_2U_LIB.S9S_MB_2U(SCH_1):PAGE113
 R1837    2      2 Q_RES_4P_12-0.001,1%,3W,SMLF,CA     I3 @S9S_MB_2U_LIB.S9S_MB_2U(SCH_1):PAGE240

P12V_SCM @S9S_MB_2U_LIB.S9S_MB_2U(SCH_1):P12V_SCM
 R3579    1      A Q_RES_0402LF-10,1%,1/16W,CHIP,A    I56 @S9S_MB_2U_LIB.S9S_MB_2U(SCH_1):PAGE163
 R3635    1      A Q_RES_2512LF-0.01,1%,1W,CHIP,CA   I129 @S9S_MB_2U_LIB.S9S_MB_2U(SCH_1):PAGE163
   J41  OB2 MAIN_PWR_EN SCONN168_ME1016810202011-SCONNA   I173 @S9S_MB_2U_LIB.S9S_MB_2U(SCH_1):PAGE227
   J41  OB1 NIC_PWR_GOOD SCONN168_ME1016810202011-SCONNA   I173 @S9S_MB_2U_LIB.S9S_MB_2U(SCH_1):PAGE227
   J41  OA1 PERST2# SCONN168_ME1016810202011-SCONNA   I173 @S9S_MB_2U_LIB.S9S_MB_2U(SCH_1):PAGE227
   J41  OA2 PERST3# SCONN168_ME1016810202011-SCONNA   I173 @S9S_MB_2U_LIB.S9S_MB_2U(SCH_1):PAGE227

P12V_SCM_ADC_ALERT @S9S_MB_2U_LIB.S9S_MB_2U(SCH_1):P12V_SCM_ADC_ALERT
  U249  K16  PR13D LCMXO3LF9400C5BG484C-LCMXO3LF-A     I1 @S9S_MB_2U_LIB.S9S_MB_2U(SCH_1):PAGE313
 R3561    2      B Q_RES_0402LF-0,5%,1/16W,CHIP,CA    I64 @S9S_MB_2U_LIB.S9S_MB_2U(SCH_1):PAGE163

P12V_SCM_ADC_ALERT_R @S9S_MB_2U_LIB.S9S_MB_2U(SCH_1):P12V_SCM_ADC_ALERT_R
 R3561    1      A Q_RES_0402LF-0,5%,1/16W,CHIP,CA    I64 @S9S_MB_2U_LIB.S9S_MB_2U(SCH_1):PAGE163
  U265    3  ALERT INA230AIRGTR-INA230AIRGTR,SMLFB    I69 @S9S_MB_2U_LIB.S9S_MB_2U(SCH_1):PAGE163
 R4091    2      B Q_RES_0402LF-4.7K,1%,1/16W,CHIA   I122 @S9S_MB_2U_LIB.S9S_MB_2U(SCH_1):PAGE163

P12V_SCM_AVIN_PD @S9S_MB_2U_LIB.S9S_MB_2U(SCH_1):P12V_SCM_AVIN_PD
PC2239    1      A Q_CAP_C0603-2.2UF,16V,20%,X7R,A    I53 @S9S_MB_2U_LIB.S9S_MB_2U(SCH_1):PAGE229
PR4006    2      B Q_RES_0402LF-100,1%,1/16W,EMPTA    I39 @S9S_MB_2U_LIB.S9S_MB_2U(SCH_1):PAGE229
PR4014    2      B Q_RES_0603LF-49.9,1%,1/10W,CHIA    I54 @S9S_MB_2U_LIB.S9S_MB_2U(SCH_1):PAGE229
 PU299   12   AVIN RS31312R-RS31312R,SMLF,IC,AL03A    I90 @S9S_MB_2U_LIB.S9S_MB_2U(SCH_1):PAGE229

P12V_SCM_CB @S9S_MB_2U_LIB.S9S_MB_2U(SCH_1):P12V_SCM_CB
PR4004    1      A Q_RES_0402LF-17.8K,1%,1/16W,EMA    I63 @S9S_MB_2U_LIB.S9S_MB_2U(SCH_1):PAGE229
 PU300   B1     CB MAX15090BEWIT-MAX15090BEWI+T,SA    I69 @S9S_MB_2U_LIB.S9S_MB_2U(SCH_1):PAGE229

P12V_SCM_EN @S9S_MB_2U_LIB.S9S_MB_2U(SCH_1):P12V_SCM_EN
 R3998    1      A Q_RES_0402LF-0,5%,1/16W,CHIP,CA    I14 @S9S_MB_2U_LIB.S9S_MB_2U(SCH_1):PAGE229
 R3996    2      B Q_RES_0402LF-0,5%,1/16W,CHIP,CA    I17 @S9S_MB_2U_LIB.S9S_MB_2U(SCH_1):PAGE229
 R1857    2      B Q_RES_0402LF-10K,1%,1/16W,CHIPA    I18 @S9S_MB_2U_LIB.S9S_MB_2U(SCH_1):PAGE229
 R4062    1      A Q_RES_0402LF-0,5%,1/16W,EMPTY,A    I20 @S9S_MB_2U_LIB.S9S_MB_2U(SCH_1):PAGE229
   Q39    D      D MOSFET_NCH_GDS_ESD_PROTECTED-2A     I9 @S9S_MB_2U_LIB.S9S_MB_2U(SCH_1):PAGE229

P12V_SCM_EN_G @S9S_MB_2U_LIB.S9S_MB_2U(SCH_1):P12V_SCM_EN_G
  Q125    6     D1 MOSFET_NCH_DUAL-PJT138K,SMLF,EA    I21 @S9S_MB_2U_LIB.S9S_MB_2U(SCH_1):PAGE229
 R4071    2      B Q_RES_0402LF-10K,1%,1/16W,EMPTA    I24 @S9S_MB_2U_LIB.S9S_MB_2U(SCH_1):PAGE229
  Q125    5     G2 MOSFET_NCH_DUAL-PJT138K,SMLF,EA    I26 @S9S_MB_2U_LIB.S9S_MB_2U(SCH_1):PAGE229

P12V_SCM_EN_R @S9S_MB_2U_LIB.S9S_MB_2U(SCH_1):P12V_SCM_EN_R
  Q125    2     G1 MOSFET_NCH_DUAL-PJT138K,SMLF,EA    I21 @S9S_MB_2U_LIB.S9S_MB_2U(SCH_1):PAGE229
 R4062    2      B Q_RES_0402LF-0,5%,1/16W,EMPTY,A    I20 @S9S_MB_2U_LIB.S9S_MB_2U(SCH_1):PAGE229

P12V_SCM_EN_R2 @S9S_MB_2U_LIB.S9S_MB_2U(SCH_1):P12V_SCM_EN_R2
 R3998    2      B Q_RES_0402LF-0,5%,1/16W,CHIP,CA    I14 @S9S_MB_2U_LIB.S9S_MB_2U(SCH_1):PAGE229
 PU299    1     EN RS31312R-RS31312R,SMLF,IC,AL03A    I90 @S9S_MB_2U_LIB.S9S_MB_2U(SCH_1):PAGE229

P12V_SCM_FAULT_N @S9S_MB_2U_LIB.S9S_MB_2U(SCH_1):P12V_SCM_FAULT_N
 PU300   C7 FAULT# MAX15090BEWIT-MAX15090BEWI+T,SA    I69 @S9S_MB_2U_LIB.S9S_MB_2U(SCH_1):PAGE229
 R4708    1      A Q_RES_0402LF-0,5%,1/16W,EMPTY,A    I77 @S9S_MB_2U_LIB.S9S_MB_2U(SCH_1):PAGE229

P12V_SCM_FAULT_R_N @S9S_MB_2U_LIB.S9S_MB_2U(SCH_1):P12V_SCM_FAULT_R_N
 R4013    2      B Q_RES_0402LF-100K,1%,1/16W,EMPA    I79 @S9S_MB_2U_LIB.S9S_MB_2U(SCH_1):PAGE229
  Q150    2     G1 MOSFET_NCH_DUAL-PJT138K,SMLF,IA    I69 @S9S_MB_2U_LIB.S9S_MB_2U(SCH_1):PAGE241
 R4709    2      B Q_RES_0402LF-0,5%,1/16W,CHIP,CA    I44 @S9S_MB_2U_LIB.S9S_MB_2U(SCH_1):PAGE229
 R4708    2      B Q_RES_0402LF-0,5%,1/16W,EMPTY,A    I77 @S9S_MB_2U_LIB.S9S_MB_2U(SCH_1):PAGE229

P12V_SCM_FLTB_N @S9S_MB_2U_LIB.S9S_MB_2U(SCH_1):P12V_SCM_FLTB_N
PR4007    1      A Q_RES_0402LF-10K,1%,1/16W,CHIPA    I48 @S9S_MB_2U_LIB.S9S_MB_2U(SCH_1):PAGE229
 R4709    1      A Q_RES_0402LF-0,5%,1/16W,CHIP,CA    I44 @S9S_MB_2U_LIB.S9S_MB_2U(SCH_1):PAGE229
 PU299    9   FLTB RS31312R-RS31312R,SMLF,IC,AL03A    I90 @S9S_MB_2U_LIB.S9S_MB_2U(SCH_1):PAGE229

P12V_SCM_GATE @S9S_MB_2U_LIB.S9S_MB_2U(SCH_1):P12V_SCM_GATE
PC2236    2      B Q_CAP_C0402-0.01UF,50V,10%,EMPA    I73 @S9S_MB_2U_LIB.S9S_MB_2U(SCH_1):PAGE229
PR4526    2      B Q_RES_0402LF-10M,1%,1/16W,EMPTA    I76 @S9S_MB_2U_LIB.S9S_MB_2U(SCH_1):PAGE229
 PU300   A6   GATE MAX15090BEWIT-MAX15090BEWI+T,SA    I69 @S9S_MB_2U_LIB.S9S_MB_2U(SCH_1):PAGE229
PC2237    1      A Q_CAP_C0402-3900PF,50V,10%,EMPA    I75 @S9S_MB_2U_LIB.S9S_MB_2U(SCH_1):PAGE229

P12V_SCM_IMON @S9S_MB_2U_LIB.S9S_MB_2U(SCH_1):P12V_SCM_IMON
PR4005    1      A Q_RES_0402LF-30.1K,1%,1/16W,CHA    I34 @S9S_MB_2U_LIB.S9S_MB_2U(SCH_1):PAGE229
PC2235    1      A Q_CAP_C0402-100NF,50V,10%,X7R,A    I42 @S9S_MB_2U_LIB.S9S_MB_2U(SCH_1):PAGE229
 PU299    8   IMON RS31312R-RS31312R,SMLF,IC,AL03A    I90 @S9S_MB_2U_LIB.S9S_MB_2U(SCH_1):PAGE229

P12V_SCM_ISET @S9S_MB_2U_LIB.S9S_MB_2U(SCH_1):P12V_SCM_ISET
PR4540    1      A Q_RES_0402LF-20K,1%,1/16W,CHIPA    I12 @S9S_MB_2U_LIB.S9S_MB_2U(SCH_1):PAGE229
PR3999    1      A Q_RES_0402LF-24.3K,1%,1/16W,CHA    I11 @S9S_MB_2U_LIB.S9S_MB_2U(SCH_1):PAGE229
 PU299    5   ISET RS31312R-RS31312R,SMLF,IC,AL03A    I90 @S9S_MB_2U_LIB.S9S_MB_2U(SCH_1):PAGE229

P12V_SCM_ISET_R @S9S_MB_2U_LIB.S9S_MB_2U(SCH_1):P12V_SCM_ISET_R
PR4540    2      B Q_RES_0402LF-20K,1%,1/16W,CHIPA    I12 @S9S_MB_2U_LIB.S9S_MB_2U(SCH_1):PAGE229
PC2340    1      A Q_CAP_C0402-560PF,50V,10%,X7R,A     I7 @S9S_MB_2U_LIB.S9S_MB_2U(SCH_1):PAGE229

P12V_SCM_OV @S9S_MB_2U_LIB.S9S_MB_2U(SCH_1):P12V_SCM_OV
PR4002    1      A Q_RES_0402LF-15K,1%,1/16W,EMPTA    I61 @S9S_MB_2U_LIB.S9S_MB_2U(SCH_1):PAGE229
PR4001    2      B Q_RES_0402LF-6.8K,1%,1/16W,EMPA    I64 @S9S_MB_2U_LIB.S9S_MB_2U(SCH_1):PAGE229
 PU300   D3     OV MAX15090BEWIT-MAX15090BEWI+T,SA    I69 @S9S_MB_2U_LIB.S9S_MB_2U(SCH_1):PAGE229

P12V_SCM_OV_FB @S9S_MB_2U_LIB.S9S_MB_2U(SCH_1):P12V_SCM_OV_FB
PR4011    1      A Q_RES_0402LF-10K,1%,1/16W,CHIPA    I50 @S9S_MB_2U_LIB.S9S_MB_2U(SCH_1):PAGE229
PR4009    2      B Q_RES_0402LF-71.5K,1%,1/16W,EMA    I51 @S9S_MB_2U_LIB.S9S_MB_2U(SCH_1):PAGE229
PR4010    2      B Q_RES_0402LF-120K,1%,1/16W,CHIA    I52 @S9S_MB_2U_LIB.S9S_MB_2U(SCH_1):PAGE229
 PU299   11     OV RS31312R-RS31312R,SMLF,IC,AL03A    I90 @S9S_MB_2U_LIB.S9S_MB_2U(SCH_1):PAGE229

P12V_SCM_PWRGD @S9S_MB_2U_LIB.S9S_MB_2U(SCH_1):P12V_SCM_PWRGD
PR4012    1      A Q_RES_0402LF-0,5%,1/16W,EMPTY,A    I74 @S9S_MB_2U_LIB.S9S_MB_2U(SCH_1):PAGE229
 PU300   D7     PG MAX15090BEWIT-MAX15090BEWI+T,SA    I69 @S9S_MB_2U_LIB.S9S_MB_2U(SCH_1):PAGE229

P12V_SCM_R @S9S_MB_2U_LIB.S9S_MB_2U(SCH_1):P12V_SCM_R
 C2019    1      A Q_CAP_0402-0.1UF,25V,10%,X7R,CA    I49 @S9S_MB_2U_LIB.S9S_MB_2U(SCH_1):PAGE163
 R3578    1      A Q_RES_0402LF-10,1%,1/16W,CHIP,A    I58 @S9S_MB_2U_LIB.S9S_MB_2U(SCH_1):PAGE163
  U265   11    BUS INA230AIRGTR-INA230AIRGTR,SMLFB    I69 @S9S_MB_2U_LIB.S9S_MB_2U(SCH_1):PAGE163
PR4009    1      A Q_RES_0402LF-71.5K,1%,1/16W,EMA    I51 @S9S_MB_2U_LIB.S9S_MB_2U(SCH_1):PAGE229
PC2236    1      A Q_CAP_C0402-0.01UF,50V,10%,EMPA    I73 @S9S_MB_2U_LIB.S9S_MB_2U(SCH_1):PAGE229
PR4526    1      A Q_RES_0402LF-10M,1%,1/16W,EMPTA    I76 @S9S_MB_2U_LIB.S9S_MB_2U(SCH_1):PAGE229
PC2238    1      A Q_CAP_0402-0.1UF,25V,10%,X7R,CA    I83 @S9S_MB_2U_LIB.S9S_MB_2U(SCH_1):PAGE229
 R3635    2      B Q_RES_2512LF-0.01,1%,1W,CHIP,CA   I129 @S9S_MB_2U_LIB.S9S_MB_2U(SCH_1):PAGE163
PR4006    1      A Q_RES_0402LF-100,1%,1/16W,EMPTA    I39 @S9S_MB_2U_LIB.S9S_MB_2U(SCH_1):PAGE229
PC2241    1      A Q_CAP_0402-0.1UF,25V,10%,X7R,CA    I57 @S9S_MB_2U_LIB.S9S_MB_2U(SCH_1):PAGE229
 PU300   A4 OUT_A4 MAX15090BEWIT-MAX15090BEWI+T,SA    I69 @S9S_MB_2U_LIB.S9S_MB_2U(SCH_1):PAGE229
 PU300   B4 OUT_B4 MAX15090BEWIT-MAX15090BEWI+T,SA    I69 @S9S_MB_2U_LIB.S9S_MB_2U(SCH_1):PAGE229
 PU300   B6 OUT_B6 MAX15090BEWIT-MAX15090BEWI+T,SA    I69 @S9S_MB_2U_LIB.S9S_MB_2U(SCH_1):PAGE229
 PU300   C4 OUT_C4 MAX15090BEWIT-MAX15090BEWI+T,SA    I69 @S9S_MB_2U_LIB.S9S_MB_2U(SCH_1):PAGE229
 PU300   C6 OUT_C6 MAX15090BEWIT-MAX15090BEWI+T,SA    I69 @S9S_MB_2U_LIB.S9S_MB_2U(SCH_1):PAGE229
 PU300   D4 OUT_D4 MAX15090BEWIT-MAX15090BEWI+T,SA    I69 @S9S_MB_2U_LIB.S9S_MB_2U(SCH_1):PAGE229
 PU300   D6 OUT_D6 MAX15090BEWIT-MAX15090BEWI+T,SA    I69 @S9S_MB_2U_LIB.S9S_MB_2U(SCH_1):PAGE229
 PD116    C      C SCHOTTKY_AC-B340A-13-F,SMLF,ICA    I82 @S9S_MB_2U_LIB.S9S_MB_2U(SCH_1):PAGE229
PC2240    1      A Q_CAP_C0805-10UF,16V,10%,X6S,CC    I84 @S9S_MB_2U_LIB.S9S_MB_2U(SCH_1):PAGE229
PC2242    1      A Q_CAP_C0805-22UF,16V,20%,X6S,CC    I88 @S9S_MB_2U_LIB.S9S_MB_2U(SCH_1):PAGE229
 PU299   13 VOUT_13 RS31312R-RS31312R,SMLF,IC,AL03A    I90 @S9S_MB_2U_LIB.S9S_MB_2U(SCH_1):PAGE229
 PU299   14 VOUT_14 RS31312R-RS31312R,SMLF,IC,AL03A    I90 @S9S_MB_2U_LIB.S9S_MB_2U(SCH_1):PAGE229
 PU299   15 VOUT_15 RS31312R-RS31312R,SMLF,IC,AL03A    I90 @S9S_MB_2U_LIB.S9S_MB_2U(SCH_1):PAGE229
 PU299   16 VOUT_16 RS31312R-RS31312R,SMLF,IC,AL03A    I90 @S9S_MB_2U_LIB.S9S_MB_2U(SCH_1):PAGE229
 PU299   17 VOUT_17 RS31312R-RS31312R,SMLF,IC,AL03A    I90 @S9S_MB_2U_LIB.S9S_MB_2U(SCH_1):PAGE229
 PU299   18 VOUT_18 RS31312R-RS31312R,SMLF,IC,AL03A    I90 @S9S_MB_2U_LIB.S9S_MB_2U(SCH_1):PAGE229
 PU299   19 VOUT_19 RS31312R-RS31312R,SMLF,IC,AL03A    I90 @S9S_MB_2U_LIB.S9S_MB_2U(SCH_1):PAGE229
 PU299   20 VOUT_20 RS31312R-RS31312R,SMLF,IC,AL03A    I90 @S9S_MB_2U_LIB.S9S_MB_2U(SCH_1):PAGE229

P12V_SCM_REG @S9S_MB_2U_LIB.S9S_MB_2U(SCH_1):P12V_SCM_REG
PC2234    2      B Q_CAP_C0402-1UF,25V,10%,EMPTY,A    I66 @S9S_MB_2U_LIB.S9S_MB_2U(SCH_1):PAGE229
 PU300   D1    REG MAX15090BEWIT-MAX15090BEWI+T,SA    I69 @S9S_MB_2U_LIB.S9S_MB_2U(SCH_1):PAGE229

P12V_SCM_SENSE @S9S_MB_2U_LIB.S9S_MB_2U(SCH_1):P12V_SCM_SENSE
PR4008    1      A Q_RES_0402LF-1.33K,1%,1/16W,EMA    I72 @S9S_MB_2U_LIB.S9S_MB_2U(SCH_1):PAGE229
 PU300   A1 ISENSE MAX15090BEWIT-MAX15090BEWI+T,SA    I69 @S9S_MB_2U_LIB.S9S_MB_2U(SCH_1):PAGE229

P12V_SCM_SS @S9S_MB_2U_LIB.S9S_MB_2U(SCH_1):P12V_SCM_SS
PC2232    1      A Q_CAP_C0402-0.047UF,25V,10%,X7A    I33 @S9S_MB_2U_LIB.S9S_MB_2U(SCH_1):PAGE229
 PU299    6     SS RS31312R-RS31312R,SMLF,IC,AL03A    I90 @S9S_MB_2U_LIB.S9S_MB_2U(SCH_1):PAGE229

P12V_SCM_TIMER @S9S_MB_2U_LIB.S9S_MB_2U(SCH_1):P12V_SCM_TIMER
PC2229    1      A Q_CAP_0402-0.22UF,16V,10%,X7R,A     I8 @S9S_MB_2U_LIB.S9S_MB_2U(SCH_1):PAGE229
 PU299    4  TIMER RS31312R-RS31312R,SMLF,IC,AL03A    I90 @S9S_MB_2U_LIB.S9S_MB_2U(SCH_1):PAGE229

P12V_SCM_UV @S9S_MB_2U_LIB.S9S_MB_2U(SCH_1):P12V_SCM_UV
PR4000    2      B Q_RES_0402LF-160K,1%,1/16W,EMPA    I67 @S9S_MB_2U_LIB.S9S_MB_2U(SCH_1):PAGE229
 R3997    2      B Q_RES_0402LF-0,5%,1/16W,EMPTY,A    I27 @S9S_MB_2U_LIB.S9S_MB_2U(SCH_1):PAGE229
PR4001    1      A Q_RES_0402LF-6.8K,1%,1/16W,EMPA    I64 @S9S_MB_2U_LIB.S9S_MB_2U(SCH_1):PAGE229
 PU300   D2     UV MAX15090BEWIT-MAX15090BEWI+T,SA    I69 @S9S_MB_2U_LIB.S9S_MB_2U(SCH_1):PAGE229

P12V_SCM_UV_R @S9S_MB_2U_LIB.S9S_MB_2U(SCH_1):P12V_SCM_UV_R
 R3997    1      A Q_RES_0402LF-0,5%,1/16W,EMPTY,A    I27 @S9S_MB_2U_LIB.S9S_MB_2U(SCH_1):PAGE229
  Q125    3     D2 MOSFET_NCH_DUAL-PJT138K,SMLF,EA    I26 @S9S_MB_2U_LIB.S9S_MB_2U(SCH_1):PAGE229

P12V_SCM_VCC @S9S_MB_2U_LIB.S9S_MB_2U(SCH_1):P12V_SCM_VCC
PC2233    1      A Q_CAP_C0402-1UF,25V,10%,EMPTY,A    I68 @S9S_MB_2U_LIB.S9S_MB_2U(SCH_1):PAGE229
PR4003    2      B Q_RES_0402LF-10,1%,1/16W,EMPTYA    I70 @S9S_MB_2U_LIB.S9S_MB_2U(SCH_1):PAGE229
 PU300   A2    VCC MAX15090BEWIT-MAX15090BEWI+T,SA    I69 @S9S_MB_2U_LIB.S9S_MB_2U(SCH_1):PAGE229

P1V05_PCH_AUX @S9S_MB_2U_LIB.S9S_MB_2U(SCH_1):P1V05_PCH_AUX
   J42    1      1 SCONN60_ASP21410801-SCONN60_ASA    I44 @S9S_MB_2U_LIB.S9S_MB_2U(SCH_1):PAGE133
  C547    1      A Q_CAP_C0402-1UF,25V,10%,X6S,CHA   I100 @S9S_MB_2U_LIB.S9S_MB_2U(SCH_1):PAGE133
  R747    1      A Q_RES_0402LF-150,1%,1/16W,CHIPA   I176 @S9S_MB_2U_LIB.S9S_MB_2U(SCH_1):PAGE134
  R751    1      A Q_RES_0402LF-150,1%,1/16W,CHIPA   I177 @S9S_MB_2U_LIB.S9S_MB_2U(SCH_1):PAGE134
  R750    1      A Q_RES_0402LF-150,1%,1/16W,CHIPA   I178 @S9S_MB_2U_LIB.S9S_MB_2U(SCH_1):PAGE134
  R749    1      A Q_RES_0402LF-75,1%,1/16W,CHIP,A   I179 @S9S_MB_2U_LIB.S9S_MB_2U(SCH_1):PAGE134
  R748    1      A Q_RES_0402LF-75,1%,1/16W,CHIP,A   I180 @S9S_MB_2U_LIB.S9S_MB_2U(SCH_1):PAGE134
   U87    D  DRAIN MOSFET_N_SMLF-BSS138K,BSS138K,A    I96 @S9S_MB_2U_LIB.S9S_MB_2U(SCH_1):PAGE137
 R1026    2      B Q_RES_0402LF-1K,1%,1/16W,CHIP,A    I37 @S9S_MB_2U_LIB.S9S_MB_2U(SCH_1):PAGE174
    U4 AB19 VCCP_1P05_AB19 EMMITSBURG_REV0P9-GFNOCPU04302A    I11 @S9S_MB_2U_LIB.S9S_MB_2U(SCH_1):PAGE178
    U4 AB20 VCCP_1P05_AB20 EMMITSBURG_REV0P9-GFNOCPU04302A    I11 @S9S_MB_2U_LIB.S9S_MB_2U(SCH_1):PAGE178
    U4 AB22 VCCP_1P05_AB22 EMMITSBURG_REV0P9-GFNOCPU04302A    I11 @S9S_MB_2U_LIB.S9S_MB_2U(SCH_1):PAGE178
    U4 AB24 VCCP_1P05_AB24 EMMITSBURG_REV0P9-GFNOCPU04302A    I11 @S9S_MB_2U_LIB.S9S_MB_2U(SCH_1):PAGE178
    U4 AD25 VCCP_1P05_AD25 EMMITSBURG_REV0P9-GFNOCPU04302A    I11 @S9S_MB_2U_LIB.S9S_MB_2U(SCH_1):PAGE178
    U4 AD27 VCCP_1P05_AD27 EMMITSBURG_REV0P9-GFNOCPU04302A    I11 @S9S_MB_2U_LIB.S9S_MB_2U(SCH_1):PAGE178
    U4 AF25 VCCP_1P05_AF25 EMMITSBURG_REV0P9-GFNOCPU04302A    I11 @S9S_MB_2U_LIB.S9S_MB_2U(SCH_1):PAGE178
    U4 AF27 VCCP_1P05_AF27 EMMITSBURG_REV0P9-GFNOCPU04302A    I11 @S9S_MB_2U_LIB.S9S_MB_2U(SCH_1):PAGE178
    U4 AG25 VCCP_1P05_AG25 EMMITSBURG_REV0P9-GFNOCPU04302A    I11 @S9S_MB_2U_LIB.S9S_MB_2U(SCH_1):PAGE178
    U4 AG27 VCCP_1P05_AG27 EMMITSBURG_REV0P9-GFNOCPU04302A    I11 @S9S_MB_2U_LIB.S9S_MB_2U(SCH_1):PAGE178
    U4 AJ25 VCCP_1P05_AJ25 EMMITSBURG_REV0P9-GFNOCPU04302A    I11 @S9S_MB_2U_LIB.S9S_MB_2U(SCH_1):PAGE178
    U4 AJ27 VCCP_1P05_AJ27 EMMITSBURG_REV0P9-GFNOCPU04302A    I11 @S9S_MB_2U_LIB.S9S_MB_2U(SCH_1):PAGE178
    U4 AR26 VCCP_1P05_AR26 EMMITSBURG_REV0P9-GFNOCPU04302A    I11 @S9S_MB_2U_LIB.S9S_MB_2U(SCH_1):PAGE178
    U4  M24 VCCP_1P05_M24 EMMITSBURG_REV0P9-GFNOCPU04302A    I11 @S9S_MB_2U_LIB.S9S_MB_2U(SCH_1):PAGE178
    U4  N23 VCCP_1P05_N23 EMMITSBURG_REV0P9-GFNOCPU04302A    I11 @S9S_MB_2U_LIB.S9S_MB_2U(SCH_1):PAGE178
    U4  N26 VCCP_1P05_N26 EMMITSBURG_REV0P9-GFNOCPU04302A    I11 @S9S_MB_2U_LIB.S9S_MB_2U(SCH_1):PAGE178
    U4  P15 VCCP_1P05_P15 EMMITSBURG_REV0P9-GFNOCPU04302A    I11 @S9S_MB_2U_LIB.S9S_MB_2U(SCH_1):PAGE178
    U4  W17 VCCP_1P05_W17 EMMITSBURG_REV0P9-GFNOCPU04302A    I11 @S9S_MB_2U_LIB.S9S_MB_2U(SCH_1):PAGE178
    U4  W19 VCCP_1P05_W19 EMMITSBURG_REV0P9-GFNOCPU04302A    I11 @S9S_MB_2U_LIB.S9S_MB_2U(SCH_1):PAGE178
    U4  W20 VCCP_1P05_W20 EMMITSBURG_REV0P9-GFNOCPU04302A    I11 @S9S_MB_2U_LIB.S9S_MB_2U(SCH_1):PAGE178
    U4  W22 VCCP_1P05_W22 EMMITSBURG_REV0P9-GFNOCPU04302A    I11 @S9S_MB_2U_LIB.S9S_MB_2U(SCH_1):PAGE178
    U4  W24 VCCP_1P05_W24 EMMITSBURG_REV0P9-GFNOCPU04302A    I11 @S9S_MB_2U_LIB.S9S_MB_2U(SCH_1):PAGE178
    U4 AF20 VCCP_VNN_AF20 EMMITSBURG_REV0P9-GFNOCPU04302A    I11 @S9S_MB_2U_LIB.S9S_MB_2U(SCH_1):PAGE178
    U4 AF22 VCCP_VNN_AF22 EMMITSBURG_REV0P9-GFNOCPU04302A    I11 @S9S_MB_2U_LIB.S9S_MB_2U(SCH_1):PAGE178
    U4 AG20 VCCP_VNN_AG20 EMMITSBURG_REV0P9-GFNOCPU04302A    I11 @S9S_MB_2U_LIB.S9S_MB_2U(SCH_1):PAGE178
    U4 AG22 VCCP_VNN_AG22 EMMITSBURG_REV0P9-GFNOCPU04302A    I11 @S9S_MB_2U_LIB.S9S_MB_2U(SCH_1):PAGE178
    U4 AJ20 VCCP_VNN_AJ20 EMMITSBURG_REV0P9-GFNOCPU04302A    I11 @S9S_MB_2U_LIB.S9S_MB_2U(SCH_1):PAGE178
    U4 AJ22 VCCP_VNN_AJ22 EMMITSBURG_REV0P9-GFNOCPU04302A    I11 @S9S_MB_2U_LIB.S9S_MB_2U(SCH_1):PAGE178
    U4 AL20 VCCP_VNN_AL20 EMMITSBURG_REV0P9-GFNOCPU04302A    I11 @S9S_MB_2U_LIB.S9S_MB_2U(SCH_1):PAGE178
    U4 AL22 VCCP_VNN_AL22 EMMITSBURG_REV0P9-GFNOCPU04302A    I11 @S9S_MB_2U_LIB.S9S_MB_2U(SCH_1):PAGE178
    U4 AN23 VCCP_VNN_AN23 EMMITSBURG_REV0P9-GFNOCPU04302A    I11 @S9S_MB_2U_LIB.S9S_MB_2U(SCH_1):PAGE178
    U4 AP21 VCCP_VNN_AP21 EMMITSBURG_REV0P9-GFNOCPU04302A    I11 @S9S_MB_2U_LIB.S9S_MB_2U(SCH_1):PAGE178
    U4 AR23 VCCP_VNN_AR23 EMMITSBURG_REV0P9-GFNOCPU04302A    I11 @S9S_MB_2U_LIB.S9S_MB_2U(SCH_1):PAGE178
 C1178    1      A Q_CAP_C0603-22UF,4V,20%,X6S,CHA     I6 @S9S_MB_2U_LIB.S9S_MB_2U(SCH_1):PAGE181
 C1185    1      A Q_CAP_C0603-22UF,4V,20%,X6S,CHA     I7 @S9S_MB_2U_LIB.S9S_MB_2U(SCH_1):PAGE181
 C1192    1      A Q_CAP_C0603-22UF,4V,20%,X6S,CHA     I8 @S9S_MB_2U_LIB.S9S_MB_2U(SCH_1):PAGE181
 C1205    1      A Q_CAP_C0402-10UF,6.3V,20%,X6S,A    I12 @S9S_MB_2U_LIB.S9S_MB_2U(SCH_1):PAGE181
 C1228    1      A Q_CAP_C0402-10UF,6.3V,20%,X6S,A    I13 @S9S_MB_2U_LIB.S9S_MB_2U(SCH_1):PAGE181
 C1187    1      A Q_CAP_C0603-22UF,4V,20%,X6S,CHA    I40 @S9S_MB_2U_LIB.S9S_MB_2U(SCH_1):PAGE181
 C1182    1      A Q_CAP_C0603-22UF,4V,20%,X6S,CHA    I42 @S9S_MB_2U_LIB.S9S_MB_2U(SCH_1):PAGE181
 C1198    1      A Q_CAP_C0603-22UF,4V,20%,X6S,CHA    I43 @S9S_MB_2U_LIB.S9S_MB_2U(SCH_1):PAGE181
 C1210    1      A Q_CAP_C0402-10UF,6.3V,20%,X6S,A    I45 @S9S_MB_2U_LIB.S9S_MB_2U(SCH_1):PAGE181
 C1203    1      A Q_CAP_C0402-10UF,6.3V,20%,X6S,A    I48 @S9S_MB_2U_LIB.S9S_MB_2U(SCH_1):PAGE181
 C1231    1      A Q_CAP_C0402-10UF,6.3V,20%,X6S,A    I49 @S9S_MB_2U_LIB.S9S_MB_2U(SCH_1):PAGE181
 C1183    1      A Q_CAP_C0402-2.2UF,10V,10%,X6S,A    I51 @S9S_MB_2U_LIB.S9S_MB_2U(SCH_1):PAGE181
 C1189    1      A Q_CAP_C0402-2.2UF,10V,10%,X6S,A    I58 @S9S_MB_2U_LIB.S9S_MB_2U(SCH_1):PAGE181
 C1200    1      A Q_CAP_C0402-2.2UF,10V,10%,X6S,A    I59 @S9S_MB_2U_LIB.S9S_MB_2U(SCH_1):PAGE181
 C1204    1      A Q_CAP_C0402-2.2UF,10V,10%,X6S,A    I60 @S9S_MB_2U_LIB.S9S_MB_2U(SCH_1):PAGE181
 C1214    1      A Q_CAP_C0402-2.2UF,10V,10%,X6S,A    I61 @S9S_MB_2U_LIB.S9S_MB_2U(SCH_1):PAGE181
 C1242    1      A Q_CAP_C0402-2.2UF,10V,10%,X6S,A    I63 @S9S_MB_2U_LIB.S9S_MB_2U(SCH_1):PAGE181
 R1463    1      A Q_RES_0402LF-0,5%,1/16W,CHIP,CA   I129 @S9S_MB_2U_LIB.S9S_MB_2U(SCH_1):PAGE181
 C1250    1      A Q_CAP_0402-1UF,6.3V,10%,EMPTY,A   I137 @S9S_MB_2U_LIB.S9S_MB_2U(SCH_1):PAGE181
 R1298    1      A Q_RES_0402LF-1K,1%,1/16W,EMPTYA    I22 @S9S_MB_2U_LIB.S9S_MB_2U(SCH_1):PAGE188
 R1498    1      A Q_RES_0402LF-1K,1%,1/16W,EMPTYA    I76 @S9S_MB_2U_LIB.S9S_MB_2U(SCH_1):PAGE188
 R1262    1      A Q_RES_0402LF-10K,1%,1/16W,EMPTA    I11 @S9S_MB_2U_LIB.S9S_MB_2U(SCH_1):PAGE192
 R1260    1      A Q_RES_0402LF-10K,1%,1/16W,EMPTA    I17 @S9S_MB_2U_LIB.S9S_MB_2U(SCH_1):PAGE192
 R3042    1      A Q_RES_0402LF-10K,1%,1/16W,EMPTA    I18 @S9S_MB_2U_LIB.S9S_MB_2U(SCH_1):PAGE192
PC1227    1      A Q_CAPP_THLF-560UF,2.5V,20%,OSCA    I41 @S9S_MB_2U_LIB.S9S_MB_2U(SCH_1):PAGE248
  PJ62    2      2 Q_SHORT_SM-EMPTY,SHORT6    I43 @S9S_MB_2U_LIB.S9S_MB_2U(SCH_1):PAGE248
 R2512    1      A Q_RES_0402LF-49.9,1%,1/16W,CHIA    I91 @S9S_MB_2U_LIB.S9S_MB_2U(SCH_1):PAGE226
 R1317    1      A Q_RES_0402LF-1K,1%,1/16W,CHIP,A    I88 @S9S_MB_2U_LIB.S9S_MB_2U(SCH_1):PAGE189
 R1343    1      A Q_RES_0402LF-10K,1%,1/16W,CHIPA   I113 @S9S_MB_2U_LIB.S9S_MB_2U(SCH_1):PAGE189
 R1342    1      A Q_RES_0402LF-10K,1%,1/16W,CHIPA   I114 @S9S_MB_2U_LIB.S9S_MB_2U(SCH_1):PAGE189
PC1225    1      A Q_CAP_C0805-47UF,4V,20%,X6S,CHA    I44 @S9S_MB_2U_LIB.S9S_MB_2U(SCH_1):PAGE248
 C1244    1      A Q_CAP_C0805-47UF,4V,20%,X6S,CHA   I152 @S9S_MB_2U_LIB.S9S_MB_2U(SCH_1):PAGE181
 C1246    1      A Q_CAP_C0805-47UF,4V,20%,X6S,CHA   I153 @S9S_MB_2U_LIB.S9S_MB_2U(SCH_1):PAGE181
 C1247    1      A Q_CAP_C0805-47UF,4V,20%,X6S,CHA   I154 @S9S_MB_2U_LIB.S9S_MB_2U(SCH_1):PAGE181
 C1248    1      A Q_CAP_C0805-47UF,4V,20%,X6S,CHA   I155 @S9S_MB_2U_LIB.S9S_MB_2U(SCH_1):PAGE181
 C1249    1      A Q_CAP_C0805-47UF,4V,20%,X6S,CHA   I156 @S9S_MB_2U_LIB.S9S_MB_2U(SCH_1):PAGE181
 R1266    1      A Q_RES_0402LF-75,1%,1/16W,CHIP,A    I38 @S9S_MB_2U_LIB.S9S_MB_2U(SCH_1):PAGE191
 PL150    2      2 Q_INDUCTOR_SMLF-300NH/33A,IND,A    I53 @S9S_MB_2U_LIB.S9S_MB_2U(SCH_1):PAGE248
PC1226    1      A Q_CAP_C0805-47UF,4V,20%,X6S,CHA    I45 @S9S_MB_2U_LIB.S9S_MB_2U(SCH_1):PAGE248
 R2242    1      A Q_RES_0402LF-10K,1%,1/16W,EMPTA    I50 @S9S_MB_2U_LIB.S9S_MB_2U(SCH_1):PAGE184
PC1229    1      A Q_CAPP_SMLF-330UF,2V,35%,SPCAPA    I47 @S9S_MB_2U_LIB.S9S_MB_2U(SCH_1):PAGE248
    L2    1      1 Q_INDUCTOR_SMLF-BLM15PX121SN1DA   I164 @S9S_MB_2U_LIB.S9S_MB_2U(SCH_1):PAGE181
 R4803    1      A Q_RES_0402LF-0,5%,1/16W,CHIP,CA   I165 @S9S_MB_2U_LIB.S9S_MB_2U(SCH_1):PAGE181
PC1224    1      A Q_CAP_0402-0.1UF,25V,10%,X7R,CA    I38 @S9S_MB_2U_LIB.S9S_MB_2U(SCH_1):PAGE248
 PC117    1      A Q_CAPP_SMLF-330UF,2V,35%,SPCAPA    I40 @S9S_MB_2U_LIB.S9S_MB_2U(SCH_1):PAGE248
PC1230    1      A Q_CAPP_THLF-560UF,2.5V,20%,OSCA    I48 @S9S_MB_2U_LIB.S9S_MB_2U(SCH_1):PAGE248
 R2234    1      A Q_RES_0402LF-10K,1%,1/16W,EMPTA    I12 @S9S_MB_2U_LIB.S9S_MB_2U(SCH_1):PAGE184
 R2976    1      A Q_RES_0402LF-10K,1%,1/16W,EMPTA    I13 @S9S_MB_2U_LIB.S9S_MB_2U(SCH_1):PAGE184
 R2979    1      A Q_RES_0402LF-10K,1%,1/16W,EMPTA    I48 @S9S_MB_2U_LIB.S9S_MB_2U(SCH_1):PAGE184
 R2240    1      A Q_RES_0402LF-10K,1%,1/16W,EMPTA    I49 @S9S_MB_2U_LIB.S9S_MB_2U(SCH_1):PAGE184
 R2972    1      A Q_RES_0402LF-10K,1%,1/16W,CHIPA    I71 @S9S_MB_2U_LIB.S9S_MB_2U(SCH_1):PAGE184
 R2974    1      A Q_RES_0402LF-10K,1%,1/16W,CHIPA    I72 @S9S_MB_2U_LIB.S9S_MB_2U(SCH_1):PAGE184
 R2232    1      A Q_RES_0402LF-10K,1%,1/16W,CHIPA    I75 @S9S_MB_2U_LIB.S9S_MB_2U(SCH_1):PAGE184

P1V05_PCH_AUX_CS @S9S_MB_2U_LIB.S9S_MB_2U(SCH_1):P1V05_PCH_AUX_CS
PR1327    1      A Q_RES_0402LF-8.45K,1%,1/16W,CHA     I6 @S9S_MB_2U_LIB.S9S_MB_2U(SCH_1):PAGE248
  PU73    3     CS RS53319LR-RS53319LR,SMLF,IC,ALA    I11 @S9S_MB_2U_LIB.S9S_MB_2U(SCH_1):PAGE248

P1V05_PCH_AUX_FB @S9S_MB_2U_LIB.S9S_MB_2U(SCH_1):P1V05_PCH_AUX_FB
 PR187    1      A Q_RES_0402LF-10K,0.1%,1/16W,CHA    I34 @S9S_MB_2U_LIB.S9S_MB_2U(SCH_1):PAGE248
PC1223    1      A Q_CAP_0402-680PF,50V,10%,X7R,TA    I35 @S9S_MB_2U_LIB.S9S_MB_2U(SCH_1):PAGE248
PR1328    1      A Q_RES_0402LF-7.32K,0.1%,1/16W,A    I36 @S9S_MB_2U_LIB.S9S_MB_2U(SCH_1):PAGE248
  PU73    7     FB RS53319LR-RS53319LR,SMLF,IC,ALA    I11 @S9S_MB_2U_LIB.S9S_MB_2U(SCH_1):PAGE248

P1V05_PCH_AUX_MODE @S9S_MB_2U_LIB.S9S_MB_2U(SCH_1):P1V05_PCH_AUX_MODE
  PU73    4   MODE RS53319LR-RS53319LR,SMLF,IC,ALA    I11 @S9S_MB_2U_LIB.S9S_MB_2U(SCH_1):PAGE248
 PR338    1      A Q_RES_0402LF-0,5%,1/16W,CHIP,CA    I10 @S9S_MB_2U_LIB.S9S_MB_2U(SCH_1):PAGE248

P1V05_PCH_AUX_REF @S9S_MB_2U_LIB.S9S_MB_2U(SCH_1):P1V05_PCH_AUX_REF
  PU73    5    REF RS53319LR-RS53319LR,SMLF,IC,ALA    I11 @S9S_MB_2U_LIB.S9S_MB_2U(SCH_1):PAGE248
PC2000    1      A Q_CAP_0402-0.022UF,16V,10%,X7RA    I14 @S9S_MB_2U_LIB.S9S_MB_2U(SCH_1):PAGE248
PC1221    1      A Q_CAP_0402-0.1UF,25V,10%,X7R,CA    I16 @S9S_MB_2U_LIB.S9S_MB_2U(SCH_1):PAGE248

P1V05_PCH_AUX_VCC @S9S_MB_2U_LIB.S9S_MB_2U(SCH_1):P1V05_PCH_AUX_VCC
PR1326    2      B Q_RES_0402LF-0,5%,1/16W,CHIP,CA     I3 @S9S_MB_2U_LIB.S9S_MB_2U(SCH_1):PAGE248
  PU73   19    VCC RS53319LR-RS53319LR,SMLF,IC,ALA    I11 @S9S_MB_2U_LIB.S9S_MB_2U(SCH_1):PAGE248
 PC113    1      A Q_CAP_C0402-1UF,25V,10%,X6S,CHA     I2 @S9S_MB_2U_LIB.S9S_MB_2U(SCH_1):PAGE248

P1V05_PCH_PLL_AUX @S9S_MB_2U_LIB.S9S_MB_2U(SCH_1):P1V05_PCH_PLL_AUX
    U4 AA29 VCCP_1P05_FILTERED_AA29 EMMITSBURG_REV0P9-GFNOCPU04302A    I11 @S9S_MB_2U_LIB.S9S_MB_2U(SCH_1):PAGE178
    U4 AB27 VCCP_1P05_FILTERED_AB27 EMMITSBURG_REV0P9-GFNOCPU04302A    I11 @S9S_MB_2U_LIB.S9S_MB_2U(SCH_1):PAGE178
    U4 AE29 VCCP_1P05_FILTERED_AE29 EMMITSBURG_REV0P9-GFNOCPU04302A    I11 @S9S_MB_2U_LIB.S9S_MB_2U(SCH_1):PAGE178
    U4 AG29 VCCP_1P05_FILTERED_AG29 EMMITSBURG_REV0P9-GFNOCPU04302A    I11 @S9S_MB_2U_LIB.S9S_MB_2U(SCH_1):PAGE178
    U4 AL25 VCCP_1P05_FILTERED_AL25 EMMITSBURG_REV0P9-GFNOCPU04302A    I11 @S9S_MB_2U_LIB.S9S_MB_2U(SCH_1):PAGE178
    U4  R23 VCCP_1P05_FILTERED_R23 EMMITSBURG_REV0P9-GFNOCPU04302A    I11 @S9S_MB_2U_LIB.S9S_MB_2U(SCH_1):PAGE178
    U4  R26 VCCP_1P05_FILTERED_R26 EMMITSBURG_REV0P9-GFNOCPU04302A    I11 @S9S_MB_2U_LIB.S9S_MB_2U(SCH_1):PAGE178
    U4  R29 VCCP_1P05_FILTERED_R29 EMMITSBURG_REV0P9-GFNOCPU04302A    I11 @S9S_MB_2U_LIB.S9S_MB_2U(SCH_1):PAGE178
    U4  U27 VCCP_1P05_FILTERED_U27 EMMITSBURG_REV0P9-GFNOCPU04302A    I11 @S9S_MB_2U_LIB.S9S_MB_2U(SCH_1):PAGE178
 C1262    1      A Q_CAP_C0402-10UF,6.3V,20%,X6S,A   I104 @S9S_MB_2U_LIB.S9S_MB_2U(SCH_1):PAGE181
 C1251    1      A Q_CAP_C0603-10UF,6.3V,20%,X6S,A   I110 @S9S_MB_2U_LIB.S9S_MB_2U(SCH_1):PAGE181
 C1254    1      A Q_CAP_C0603-10UF,6.3V,20%,X6S,A   I111 @S9S_MB_2U_LIB.S9S_MB_2U(SCH_1):PAGE181
 R1463    2      B Q_RES_0402LF-0,5%,1/16W,CHIP,CA   I129 @S9S_MB_2U_LIB.S9S_MB_2U(SCH_1):PAGE181
 C1260    1      A Q_CAP_C0603-10UF,6.3V,20%,X6S,A   I131 @S9S_MB_2U_LIB.S9S_MB_2U(SCH_1):PAGE181
 C1264    1      A Q_CAP_0402-1UF,6.3V,10%,EMPTY,A   I133 @S9S_MB_2U_LIB.S9S_MB_2U(SCH_1):PAGE181
 C1256    1      A Q_CAP_0402-1UF,6.3V,10%,EMPTY,A   I136 @S9S_MB_2U_LIB.S9S_MB_2U(SCH_1):PAGE181
 C1258    1      A Q_CAP_C0805-47UF,4V,20%,X6S,CHA   I157 @S9S_MB_2U_LIB.S9S_MB_2U(SCH_1):PAGE181
 C1272    1      A Q_CAP_C0805-47UF,4V,20%,X6S,CHA   I159 @S9S_MB_2U_LIB.S9S_MB_2U(SCH_1):PAGE181
    L2    2      2 Q_INDUCTOR_SMLF-BLM15PX121SN1DA   I164 @S9S_MB_2U_LIB.S9S_MB_2U(SCH_1):PAGE181
 R4803    2      B Q_RES_0402LF-0,5%,1/16W,CHIP,CA   I165 @S9S_MB_2U_LIB.S9S_MB_2U(SCH_1):PAGE181

P1V581_PDB_ADC @S9S_MB_2U_LIB.S9S_MB_2U(SCH_1):P1V581_PDB_ADC
 R3687    1      A Q_RES_0402LF-0,5%,1/16W,EMPTY,A   I240 @S9S_MB_2U_LIB.S9S_MB_2U(SCH_1):PAGE239
 R3688    1      A Q_RES_0402LF-0,5%,1/16W,CHIP,CA   I241 @S9S_MB_2U_LIB.S9S_MB_2U(SCH_1):PAGE239
 R4568    1      A Q_RES_0402LF-4.7K,1%,1/16W,CHIA   I346 @S9S_MB_2U_LIB.S9S_MB_2U(SCH_1):PAGE239
 R4567    2      B Q_RES_0402LF-5.11K,1%,1/16W,CHA   I348 @S9S_MB_2U_LIB.S9S_MB_2U(SCH_1):PAGE239

P1V8_PCH_AUX @S9S_MB_2U_LIB.S9S_MB_2U(SCH_1):P1V8_PCH_AUX
   J42   12     12 SCONN60_ASP21410801-SCONN60_ASA    I44 @S9S_MB_2U_LIB.S9S_MB_2U(SCH_1):PAGE133
  C550    1      A Q_CAP_C0402-1UF,25V,10%,X6S,CHA    I99 @S9S_MB_2U_LIB.S9S_MB_2U(SCH_1):PAGE133
    U4  N20 VCCP_1P8_N20 EMMITSBURG_REV0P9-GFNOCPU04302A    I11 @S9S_MB_2U_LIB.S9S_MB_2U(SCH_1):PAGE178
    U4  U17 VCCP_1P8_U17 EMMITSBURG_REV0P9-GFNOCPU04302A    I11 @S9S_MB_2U_LIB.S9S_MB_2U(SCH_1):PAGE178
    U4  U19 VCCP_1P8_U19 EMMITSBURG_REV0P9-GFNOCPU04302A    I11 @S9S_MB_2U_LIB.S9S_MB_2U(SCH_1):PAGE178
    U4  U20 VCCP_1P8_U20 EMMITSBURG_REV0P9-GFNOCPU04302A    I11 @S9S_MB_2U_LIB.S9S_MB_2U(SCH_1):PAGE178
    U4  U22 VCCP_1P8_U22 EMMITSBURG_REV0P9-GFNOCPU04302A    I11 @S9S_MB_2U_LIB.S9S_MB_2U(SCH_1):PAGE178
    U4  U24 VCCP_1P8_U24 EMMITSBURG_REV0P9-GFNOCPU04302A    I11 @S9S_MB_2U_LIB.S9S_MB_2U(SCH_1):PAGE178
 C1186    1      A Q_CAP_C0603-22UF,4V,20%,X6S,CHA    I25 @S9S_MB_2U_LIB.S9S_MB_2U(SCH_1):PAGE181
 C1181    1      A Q_CAP_C0603-22UF,4V,20%,X6S,CHA    I27 @S9S_MB_2U_LIB.S9S_MB_2U(SCH_1):PAGE181
 C1202    1      A Q_CAP_C0603-22UF,4V,20%,X6S,CHA    I29 @S9S_MB_2U_LIB.S9S_MB_2U(SCH_1):PAGE181
 C1197    1      A Q_CAP_C0603-22UF,4V,20%,X6S,CHA    I30 @S9S_MB_2U_LIB.S9S_MB_2U(SCH_1):PAGE181
 C1207    1      A Q_CAP_C0402-10UF,6.3V,20%,X6S,A    I32 @S9S_MB_2U_LIB.S9S_MB_2U(SCH_1):PAGE181
 R1464    1      A Q_RES_0402LF-0,5%,1/16W,CHIP,CA   I144 @S9S_MB_2U_LIB.S9S_MB_2U(SCH_1):PAGE181
   L10    1      1 Q_INDUCTOR_SMLF-BLM18PG121SN1DA   I145 @S9S_MB_2U_LIB.S9S_MB_2U(SCH_1):PAGE181
 C1253    1      A Q_CAP_0402-1UF,6.3V,10%,EMPTY,A   I147 @S9S_MB_2U_LIB.S9S_MB_2U(SCH_1):PAGE181
   U98    2  VREF1 PCA9306DP1-PCA9306DP1,SMLF,IC,A    I27 @S9S_MB_2U_LIB.S9S_MB_2U(SCH_1):PAGE183
 C1323    1      A Q_CAP_0402-0.1UF,25V,10%,X7R,CA    I28 @S9S_MB_2U_LIB.S9S_MB_2U(SCH_1):PAGE183
 R1702    1      A Q_RES_0402LF-4.7K,5%,1/16W,CHIA    I43 @S9S_MB_2U_LIB.S9S_MB_2U(SCH_1):PAGE183
 R1703    1      A Q_RES_0402LF-4.7K,5%,1/16W,CHIA    I45 @S9S_MB_2U_LIB.S9S_MB_2U(SCH_1):PAGE183
 R1747    1      A Q_RES_0805LF-0,5%,1/8W,CHIP,CSA     I2 @S9S_MB_2U_LIB.S9S_MB_2U(SCH_1):PAGE243
  PU74   12   VOUT NB682GDZ-NB682GD-Z,SMLF,IC,AL0A    I26 @S9S_MB_2U_LIB.S9S_MB_2U(SCH_1):PAGE249
PC1236    1      A Q_CAP_C0402-100NF,50V,10%,X7R,A    I28 @S9S_MB_2U_LIB.S9S_MB_2U(SCH_1):PAGE249
PC1240    1      A Q_CAP_C0805-22UF,4V,20%,X6S,CHA    I39 @S9S_MB_2U_LIB.S9S_MB_2U(SCH_1):PAGE249
PC1237    1      A Q_CAP_C0805-22UF,4V,20%,X6S,CHA    I29 @S9S_MB_2U_LIB.S9S_MB_2U(SCH_1):PAGE249
PC1238    1      A Q_CAP_C0805-22UF,4V,20%,X6S,CHA    I37 @S9S_MB_2U_LIB.S9S_MB_2U(SCH_1):PAGE249
PC1239    1      A Q_CAP_C0805-22UF,4V,20%,X6S,CHA    I38 @S9S_MB_2U_LIB.S9S_MB_2U(SCH_1):PAGE249
PC1241    1      A Q_CAP_C0805-22UF,4V,20%,X6S,CHA    I41 @S9S_MB_2U_LIB.S9S_MB_2U(SCH_1):PAGE249
PR1653    1      A Q_RES_0402LF-470,1%,1/16W,CHIPA    I42 @S9S_MB_2U_LIB.S9S_MB_2U(SCH_1):PAGE249
 PL170    2      2 Q_INDUCTOR_SMLF-2.2UH,IND,CV-2A    I45 @S9S_MB_2U_LIB.S9S_MB_2U(SCH_1):PAGE249

P1V8_PCH_AUX_MODE @S9S_MB_2U_LIB.S9S_MB_2U(SCH_1):P1V8_PCH_AUX_MODE
  PU74    7   MODE NB682GDZ-NB682GD-Z,SMLF,IC,AL0A    I26 @S9S_MB_2U_LIB.S9S_MB_2U(SCH_1):PAGE249
PR1330    1      A Q_RES_0402LF-150K,1%,1/16W,CHIA    I24 @S9S_MB_2U_LIB.S9S_MB_2U(SCH_1):PAGE249

P1V8_PCH_AUX_VCC @S9S_MB_2U_LIB.S9S_MB_2U(SCH_1):P1V8_PCH_AUX_VCC
  PU74   10    3V3 NB682GDZ-NB682GD-Z,SMLF,IC,AL0A    I26 @S9S_MB_2U_LIB.S9S_MB_2U(SCH_1):PAGE249
  PU74    3     C1 NB682GDZ-NB682GD-Z,SMLF,IC,AL0A    I26 @S9S_MB_2U_LIB.S9S_MB_2U(SCH_1):PAGE249
  PU74    6    LP# NB682GDZ-NB682GD-Z,SMLF,IC,AL0A    I26 @S9S_MB_2U_LIB.S9S_MB_2U(SCH_1):PAGE249
PC1642    1      A Q_CAP_C0402-1UF,25V,10%,X6S,CHA     I4 @S9S_MB_2U_LIB.S9S_MB_2U(SCH_1):PAGE249
PR1329    2      B Q_RES_0402LF-5.1,5%,1/16W,CHIPA     I5 @S9S_MB_2U_LIB.S9S_MB_2U(SCH_1):PAGE249

P1V8_PCH_PLL_AUX @S9S_MB_2U_LIB.S9S_MB_2U(SCH_1):P1V8_PCH_PLL_AUX
    U4 AB31 VCCP_1P8_FILTERED_AB31 EMMITSBURG_REV0P9-GFNOCPU04302A    I11 @S9S_MB_2U_LIB.S9S_MB_2U(SCH_1):PAGE178
    U4 AB34 VCCP_1P8_FILTERED_AB34 EMMITSBURG_REV0P9-GFNOCPU04302A    I11 @S9S_MB_2U_LIB.S9S_MB_2U(SCH_1):PAGE178
    U4  U29 VCCP_1P8_FILTERED_U29 EMMITSBURG_REV0P9-GFNOCPU04302A    I11 @S9S_MB_2U_LIB.S9S_MB_2U(SCH_1):PAGE178
    U4  W27 VCCP_1P8_FILTERED_W27 EMMITSBURG_REV0P9-GFNOCPU04302A    I11 @S9S_MB_2U_LIB.S9S_MB_2U(SCH_1):PAGE178
    U4  W29 VCCP_1P8_FILTERED_W29 EMMITSBURG_REV0P9-GFNOCPU04302A    I11 @S9S_MB_2U_LIB.S9S_MB_2U(SCH_1):PAGE178
 C1263    1      A Q_CAP_C0402-10UF,6.3V,20%,X6S,A   I119 @S9S_MB_2U_LIB.S9S_MB_2U(SCH_1):PAGE181
 C1255    1      A Q_CAP_C0603-10UF,6.3V,20%,X6S,A   I123 @S9S_MB_2U_LIB.S9S_MB_2U(SCH_1):PAGE181
 C1252    1      A Q_CAP_C0603-10UF,6.3V,20%,X6S,A   I125 @S9S_MB_2U_LIB.S9S_MB_2U(SCH_1):PAGE181
 C1266    1      A Q_CAP_C0402-10UF,6.3V,20%,X6S,A   I127 @S9S_MB_2U_LIB.S9S_MB_2U(SCH_1):PAGE181
 C1265    1      A Q_CAP_0402-1UF,6.3V,10%,EMPTY,A   I140 @S9S_MB_2U_LIB.S9S_MB_2U(SCH_1):PAGE181
 C1261    1      A Q_CAP_C0603-10UF,6.3V,20%,X6S,A   I142 @S9S_MB_2U_LIB.S9S_MB_2U(SCH_1):PAGE181
 R1464    2      B Q_RES_0402LF-0,5%,1/16W,CHIP,CA   I144 @S9S_MB_2U_LIB.S9S_MB_2U(SCH_1):PAGE181
   L10    2      2 Q_INDUCTOR_SMLF-BLM18PG121SN1DA   I145 @S9S_MB_2U_LIB.S9S_MB_2U(SCH_1):PAGE181
 C1257    1      A Q_CAP_0402-1UF,6.3V,10%,EMPTY,A   I146 @S9S_MB_2U_LIB.S9S_MB_2U(SCH_1):PAGE181
 C1273    1      A Q_CAP_C0805-47UF,4V,20%,X6S,CHA   I151 @S9S_MB_2U_LIB.S9S_MB_2U(SCH_1):PAGE181
 C1259    1      A Q_CAP_C0805-47UF,4V,20%,X6S,CHA   I158 @S9S_MB_2U_LIB.S9S_MB_2U(SCH_1):PAGE181

P2E_BUF2_VDD @S9S_MB_2U_LIB.S9S_MB_2U(SCH_1):P2E_BUF2_VDD
  U328   21 VDD_21 DS125BR111RTWR-DS125BR111RTWR,A    I95 @S9S_MB_2U_LIB.S9S_MB_2U(SCH_1):PAGE159
  U328   22 VDD_22 DS125BR111RTWR-DS125BR111RTWR,A    I95 @S9S_MB_2U_LIB.S9S_MB_2U(SCH_1):PAGE159
 C2358    1      A Q_CAP_0402-0.1UF,25V,10%,X7R,CA   I100 @S9S_MB_2U_LIB.S9S_MB_2U(SCH_1):PAGE159
 C2357    1      A Q_CAP_0402-0.1UF,25V,10%,X7R,CA    I99 @S9S_MB_2U_LIB.S9S_MB_2U(SCH_1):PAGE159

P2E_MB_BMC_RX_BUF2_C_DN<0> @S9S_MB_2U_LIB.S9S_MB_2U(SCH_1):P2E_MB_BMC_RX_BUF2_C_DN(0)
  U328   19  OUTB- DS125BR111RTWR-DS125BR111RTWR,A    I95 @S9S_MB_2U_LIB.S9S_MB_2U(SCH_1):PAGE159
 C2354    1      A Q_CAP_0402-0.1UF,25V,10%,EMPTYA    I28 @S9S_MB_2U_LIB.S9S_MB_2U(SCH_1):PAGE159

P2E_MB_BMC_RX_BUF2_C_DP<0> @S9S_MB_2U_LIB.S9S_MB_2U(SCH_1):P2E_MB_BMC_RX_BUF2_C_DP(0)
 C2353    1      A Q_CAP_0402-0.1UF,25V,10%,EMPTYA    I27 @S9S_MB_2U_LIB.S9S_MB_2U(SCH_1):PAGE159
  U328   20  OUTB+ DS125BR111RTWR-DS125BR111RTWR,A    I95 @S9S_MB_2U_LIB.S9S_MB_2U(SCH_1):PAGE159

P2E_MB_BMC_RX_BUF_C_DN<0> @S9S_MB_2U_LIB.S9S_MB_2U(SCH_1):P2E_MB_BMC_RX_BUF_C_DN(0)
  U237    8    BON PI3EQX12902AZLEX-PI3EQX12902AZA    I50 @S9S_MB_2U_LIB.S9S_MB_2U(SCH_1):PAGE136
 C1869    1      A Q_CAP_0402-0.1UF,25V,10%,X7R,CA    I30 @S9S_MB_2U_LIB.S9S_MB_2U(SCH_1):PAGE159

P2E_MB_BMC_RX_BUF_C_DP<0> @S9S_MB_2U_LIB.S9S_MB_2U(SCH_1):P2E_MB_BMC_RX_BUF_C_DP(0)
  U237    9    BOP PI3EQX12902AZLEX-PI3EQX12902AZA    I50 @S9S_MB_2U_LIB.S9S_MB_2U(SCH_1):PAGE136
 C1868    1      A Q_CAP_0402-0.1UF,25V,10%,X7R,CA    I29 @S9S_MB_2U_LIB.S9S_MB_2U(SCH_1):PAGE159

P2E_MB_BMC_RX_BUF_DN<0> @S9S_MB_2U_LIB.S9S_MB_2U(SCH_1):P2E_MB_BMC_RX_BUF_DN(0)
 C2354    2      B Q_CAP_0402-0.1UF,25V,10%,EMPTYA    I28 @S9S_MB_2U_LIB.S9S_MB_2U(SCH_1):PAGE159
 C1869    2      B Q_CAP_0402-0.1UF,25V,10%,X7R,CA    I30 @S9S_MB_2U_LIB.S9S_MB_2U(SCH_1):PAGE159
   J41  A66 PERP15 SCONN168_ME1016810202011-SCONNA   I173 @S9S_MB_2U_LIB.S9S_MB_2U(SCH_1):PAGE227

P2E_MB_BMC_RX_BUF_DP<0> @S9S_MB_2U_LIB.S9S_MB_2U(SCH_1):P2E_MB_BMC_RX_BUF_DP(0)
 C2353    2      B Q_CAP_0402-0.1UF,25V,10%,EMPTYA    I27 @S9S_MB_2U_LIB.S9S_MB_2U(SCH_1):PAGE159
 C1868    2      B Q_CAP_0402-0.1UF,25V,10%,X7R,CA    I29 @S9S_MB_2U_LIB.S9S_MB_2U(SCH_1):PAGE159
   J41  A65 PERN15 SCONN168_ME1016810202011-SCONNA   I173 @S9S_MB_2U_LIB.S9S_MB_2U(SCH_1):PAGE227

P2E_MB_BMC_RX_DN<0> @S9S_MB_2U_LIB.S9S_MB_2U(SCH_1):P2E_MB_BMC_RX_DN(0)
  J112   N6     N6 CONN160_10131762101LF-CONN160_A    I75 @S9S_MB_2U_LIB.S9S_MB_2U(SCH_1):PAGE149
 R4666    1      A Q_RES_0402LF-0,5%,1/16W,EMPTY,A    I35 @S9S_MB_2U_LIB.S9S_MB_2U(SCH_1):PAGE159
 R4664    1      A Q_RES_0402LF-0,5%,1/16W,CHIP,CA    I42 @S9S_MB_2U_LIB.S9S_MB_2U(SCH_1):PAGE159

P2E_MB_BMC_RX_DP<0> @S9S_MB_2U_LIB.S9S_MB_2U(SCH_1):P2E_MB_BMC_RX_DP(0)
  J112   O6     O6 CONN160_10131762101LF-CONN160_A    I75 @S9S_MB_2U_LIB.S9S_MB_2U(SCH_1):PAGE149
 R4665    1      A Q_RES_0402LF-0,5%,1/16W,EMPTY,A    I36 @S9S_MB_2U_LIB.S9S_MB_2U(SCH_1):PAGE159
 R4663    1      A Q_RES_0402LF-0,5%,1/16W,CHIP,CA    I41 @S9S_MB_2U_LIB.S9S_MB_2U(SCH_1):PAGE159

P2E_MB_BMC_RX_R1_DN<0> @S9S_MB_2U_LIB.S9S_MB_2U(SCH_1):P2E_MB_BMC_RX_R1_DN(0)
  U237   18    BIN PI3EQX12902AZLEX-PI3EQX12902AZA    I50 @S9S_MB_2U_LIB.S9S_MB_2U(SCH_1):PAGE136
 R4664    2      B Q_RES_0402LF-0,5%,1/16W,CHIP,CA    I42 @S9S_MB_2U_LIB.S9S_MB_2U(SCH_1):PAGE159

P2E_MB_BMC_RX_R1_DP<0> @S9S_MB_2U_LIB.S9S_MB_2U(SCH_1):P2E_MB_BMC_RX_R1_DP(0)
  U237   17    BIP PI3EQX12902AZLEX-PI3EQX12902AZA    I50 @S9S_MB_2U_LIB.S9S_MB_2U(SCH_1):PAGE136
 R4663    2      B Q_RES_0402LF-0,5%,1/16W,CHIP,CA    I41 @S9S_MB_2U_LIB.S9S_MB_2U(SCH_1):PAGE159

P2E_MB_BMC_RX_R2_DN<0> @S9S_MB_2U_LIB.S9S_MB_2U(SCH_1):P2E_MB_BMC_RX_R2_DN(0)
  U328   12   INB- DS125BR111RTWR-DS125BR111RTWR,A    I95 @S9S_MB_2U_LIB.S9S_MB_2U(SCH_1):PAGE159
 R4666    2      B Q_RES_0402LF-0,5%,1/16W,EMPTY,A    I35 @S9S_MB_2U_LIB.S9S_MB_2U(SCH_1):PAGE159

P2E_MB_BMC_RX_R2_DP<0> @S9S_MB_2U_LIB.S9S_MB_2U(SCH_1):P2E_MB_BMC_RX_R2_DP(0)
  U328   11   INB+ DS125BR111RTWR-DS125BR111RTWR,A    I95 @S9S_MB_2U_LIB.S9S_MB_2U(SCH_1):PAGE159
 R4665    2      B Q_RES_0402LF-0,5%,1/16W,EMPTY,A    I36 @S9S_MB_2U_LIB.S9S_MB_2U(SCH_1):PAGE159

P2E_MB_BMC_TX_BUF2_DN<0> @S9S_MB_2U_LIB.S9S_MB_2U(SCH_1):P2E_MB_BMC_TX_BUF2_DN(0)
 C2352    1      A Q_CAP_0402-0.1UF,25V,10%,EMPTYA    I32 @S9S_MB_2U_LIB.S9S_MB_2U(SCH_1):PAGE159
  U328    8  OUTA- DS125BR111RTWR-DS125BR111RTWR,A    I95 @S9S_MB_2U_LIB.S9S_MB_2U(SCH_1):PAGE159

P2E_MB_BMC_TX_BUF2_DP<0> @S9S_MB_2U_LIB.S9S_MB_2U(SCH_1):P2E_MB_BMC_TX_BUF2_DP(0)
  U328    7  OUTA+ DS125BR111RTWR-DS125BR111RTWR,A    I95 @S9S_MB_2U_LIB.S9S_MB_2U(SCH_1):PAGE159
 C2351    1      A Q_CAP_0402-0.1UF,25V,10%,EMPTYA    I31 @S9S_MB_2U_LIB.S9S_MB_2U(SCH_1):PAGE159

P2E_MB_BMC_TX_BUF_C_DN<0> @S9S_MB_2U_LIB.S9S_MB_2U(SCH_1):P2E_MB_BMC_TX_BUF_C_DN(0)
  J112   Q6     Q6 CONN160_10131762101LF-CONN160_A    I75 @S9S_MB_2U_LIB.S9S_MB_2U(SCH_1):PAGE149
 C2352    2      B Q_CAP_0402-0.1UF,25V,10%,EMPTYA    I32 @S9S_MB_2U_LIB.S9S_MB_2U(SCH_1):PAGE159
 C1871    2      B Q_CAP_0402-0.1UF,25V,10%,X7R,CA    I34 @S9S_MB_2U_LIB.S9S_MB_2U(SCH_1):PAGE159

P2E_MB_BMC_TX_BUF_C_DP<0> @S9S_MB_2U_LIB.S9S_MB_2U(SCH_1):P2E_MB_BMC_TX_BUF_C_DP(0)
  J112   R6     R6 CONN160_10131762101LF-CONN160_A    I75 @S9S_MB_2U_LIB.S9S_MB_2U(SCH_1):PAGE149
 C2351    2      B Q_CAP_0402-0.1UF,25V,10%,EMPTYA    I31 @S9S_MB_2U_LIB.S9S_MB_2U(SCH_1):PAGE159
 C1870    2      B Q_CAP_0402-0.1UF,25V,10%,X7R,CA    I33 @S9S_MB_2U_LIB.S9S_MB_2U(SCH_1):PAGE159

P2E_MB_BMC_TX_BUF_DN<0> @S9S_MB_2U_LIB.S9S_MB_2U(SCH_1):P2E_MB_BMC_TX_BUF_DN(0)
  U237   23    AON PI3EQX12902AZLEX-PI3EQX12902AZA    I50 @S9S_MB_2U_LIB.S9S_MB_2U(SCH_1):PAGE136
 C1871    1      A Q_CAP_0402-0.1UF,25V,10%,X7R,CA    I34 @S9S_MB_2U_LIB.S9S_MB_2U(SCH_1):PAGE159

P2E_MB_BMC_TX_BUF_DP<0> @S9S_MB_2U_LIB.S9S_MB_2U(SCH_1):P2E_MB_BMC_TX_BUF_DP(0)
  U237   24    AOP PI3EQX12902AZLEX-PI3EQX12902AZA    I50 @S9S_MB_2U_LIB.S9S_MB_2U(SCH_1):PAGE136
 C1870    1      A Q_CAP_0402-0.1UF,25V,10%,X7R,CA    I33 @S9S_MB_2U_LIB.S9S_MB_2U(SCH_1):PAGE159

P2E_MB_BMC_TX_C_DN<0> @S9S_MB_2U_LIB.S9S_MB_2U(SCH_1):P2E_MB_BMC_TX_C_DN(0)
 R4662    1      A Q_RES_0402LF-0,5%,1/16W,EMPTY,A    I43 @S9S_MB_2U_LIB.S9S_MB_2U(SCH_1):PAGE159
 R4660    1      A Q_RES_0402LF-0,5%,1/16W,CHIP,CA    I45 @S9S_MB_2U_LIB.S9S_MB_2U(SCH_1):PAGE159
   J41  B66 PETP15 SCONN168_ME1016810202011-SCONNA   I173 @S9S_MB_2U_LIB.S9S_MB_2U(SCH_1):PAGE227

P2E_MB_BMC_TX_C_DP<0> @S9S_MB_2U_LIB.S9S_MB_2U(SCH_1):P2E_MB_BMC_TX_C_DP(0)
 R4661    1      A Q_RES_0402LF-0,5%,1/16W,EMPTY,A    I44 @S9S_MB_2U_LIB.S9S_MB_2U(SCH_1):PAGE159
 R4659    1      A Q_RES_0402LF-0,5%,1/16W,CHIP,CA    I46 @S9S_MB_2U_LIB.S9S_MB_2U(SCH_1):PAGE159
   J41  B65 PETN15 SCONN168_ME1016810202011-SCONNA   I173 @S9S_MB_2U_LIB.S9S_MB_2U(SCH_1):PAGE227

P2E_MB_BMC_TX_C_R1_DN<0> @S9S_MB_2U_LIB.S9S_MB_2U(SCH_1):P2E_MB_BMC_TX_C_R1_DN(0)
  U237    3    AIN PI3EQX12902AZLEX-PI3EQX12902AZA    I50 @S9S_MB_2U_LIB.S9S_MB_2U(SCH_1):PAGE136
 R4660    2      B Q_RES_0402LF-0,5%,1/16W,CHIP,CA    I45 @S9S_MB_2U_LIB.S9S_MB_2U(SCH_1):PAGE159

P2E_MB_BMC_TX_C_R1_DP<0> @S9S_MB_2U_LIB.S9S_MB_2U(SCH_1):P2E_MB_BMC_TX_C_R1_DP(0)
  U237    2    AIP PI3EQX12902AZLEX-PI3EQX12902AZA    I50 @S9S_MB_2U_LIB.S9S_MB_2U(SCH_1):PAGE136
 R4659    2      B Q_RES_0402LF-0,5%,1/16W,CHIP,CA    I46 @S9S_MB_2U_LIB.S9S_MB_2U(SCH_1):PAGE159

P2E_MB_BMC_TX_C_R2_DN<0> @S9S_MB_2U_LIB.S9S_MB_2U(SCH_1):P2E_MB_BMC_TX_C_R2_DN(0)
  U328   23   INA- DS125BR111RTWR-DS125BR111RTWR,A    I95 @S9S_MB_2U_LIB.S9S_MB_2U(SCH_1):PAGE159
 R4662    2      B Q_RES_0402LF-0,5%,1/16W,EMPTY,A    I43 @S9S_MB_2U_LIB.S9S_MB_2U(SCH_1):PAGE159

P2E_MB_BMC_TX_C_R2_DP<0> @S9S_MB_2U_LIB.S9S_MB_2U(SCH_1):P2E_MB_BMC_TX_C_R2_DP(0)
  U328   24   INA+ DS125BR111RTWR-DS125BR111RTWR,A    I95 @S9S_MB_2U_LIB.S9S_MB_2U(SCH_1):PAGE159
 R4661    2      B Q_RES_0402LF-0,5%,1/16W,EMPTY,A    I44 @S9S_MB_2U_LIB.S9S_MB_2U(SCH_1):PAGE159

P3E_PCH_BMC_RX_DN @S9S_MB_2U_LIB.S9S_MB_2U(SCH_1):P3E_PCH_BMC_RX_DN
    U4  U41 SATA_8_PCIE3_8_USB3_8_RXN EMMITSBURG_REV0P9-GFNOCPU04302A   I110 @S9S_MB_2U_LIB.S9S_MB_2U(SCH_1):PAGE173
   J41  A21  PERP1 SCONN168_ME1016810202011-SCONNA   I173 @S9S_MB_2U_LIB.S9S_MB_2U(SCH_1):PAGE227

P3E_PCH_BMC_RX_DP @S9S_MB_2U_LIB.S9S_MB_2U(SCH_1):P3E_PCH_BMC_RX_DP
    U4  U43 SATA_8_PCIE3_8_USB3_8_RXP EMMITSBURG_REV0P9-GFNOCPU04302A   I110 @S9S_MB_2U_LIB.S9S_MB_2U(SCH_1):PAGE173
   J41  A20  PERN1 SCONN168_ME1016810202011-SCONNA   I173 @S9S_MB_2U_LIB.S9S_MB_2U(SCH_1):PAGE227

P3E_PCH_BMC_TX_C_DN @S9S_MB_2U_LIB.S9S_MB_2U(SCH_1):P3E_PCH_BMC_TX_C_DN
 C2078    2      2 Q_CAP_DIFFBUS_C0201-DIFF BUS_0A    I76 @S9S_MB_2U_LIB.S9S_MB_2U(SCH_1):PAGE173
   J41  A18  PERP0 SCONN168_ME1016810202011-SCONNA   I173 @S9S_MB_2U_LIB.S9S_MB_2U(SCH_1):PAGE227

P3E_PCH_BMC_TX_C_DP @S9S_MB_2U_LIB.S9S_MB_2U(SCH_1):P3E_PCH_BMC_TX_C_DP
 C2077    2      2 Q_CAP_DIFFBUS_C0201-DIFF BUS_0A    I77 @S9S_MB_2U_LIB.S9S_MB_2U(SCH_1):PAGE173
   J41  A17  PERN0 SCONN168_ME1016810202011-SCONNA   I173 @S9S_MB_2U_LIB.S9S_MB_2U(SCH_1):PAGE227

P3E_PCH_BMC_TX_DN @S9S_MB_2U_LIB.S9S_MB_2U(SCH_1):P3E_PCH_BMC_TX_DN
 C2078    1      1 Q_CAP_DIFFBUS_C0201-DIFF BUS_0A    I76 @S9S_MB_2U_LIB.S9S_MB_2U(SCH_1):PAGE173
    U4 AE36 SATA_8_PCIE3_8_USB3_8_TXN EMMITSBURG_REV0P9-GFNOCPU04302A   I110 @S9S_MB_2U_LIB.S9S_MB_2U(SCH_1):PAGE173

P3E_PCH_BMC_TX_DP @S9S_MB_2U_LIB.S9S_MB_2U(SCH_1):P3E_PCH_BMC_TX_DP
 C2077    1      1 Q_CAP_DIFFBUS_C0201-DIFF BUS_0A    I77 @S9S_MB_2U_LIB.S9S_MB_2U(SCH_1):PAGE173
    U4 AD37 SATA_8_PCIE3_8_USB3_8_TXP EMMITSBURG_REV0P9-GFNOCPU04302A   I110 @S9S_MB_2U_LIB.S9S_MB_2U(SCH_1):PAGE173

P3E_PCH_E1S_RX_DN<0> @S9S_MB_2U_LIB.S9S_MB_2U(SCH_1):P3E_PCH_E1S_RX_DN(0)
   J90  A18 PER_P0 SCONN56_123276793-SCONN56_1-23A   I318 @S9S_MB_2U_LIB.S9S_MB_2U(SCH_1):PAGE297
    U4 AA41 SATA_4_PCIE3_4_USB3_4_RXN EMMITSBURG_REV0P9-GFNOCPU04302A   I110 @S9S_MB_2U_LIB.S9S_MB_2U(SCH_1):PAGE173

P3E_PCH_E1S_RX_DN<1> @S9S_MB_2U_LIB.S9S_MB_2U(SCH_1):P3E_PCH_E1S_RX_DN(1)
   J90  A20 PER_N1 SCONN56_123276793-SCONN56_1-23A   I318 @S9S_MB_2U_LIB.S9S_MB_2U(SCH_1):PAGE297
    U4  Y40 SATA_5_PCIE3_5_USB3_5_RXN EMMITSBURG_REV0P9-GFNOCPU04302A   I110 @S9S_MB_2U_LIB.S9S_MB_2U(SCH_1):PAGE173

P3E_PCH_E1S_RX_DN<2> @S9S_MB_2U_LIB.S9S_MB_2U(SCH_1):P3E_PCH_E1S_RX_DN(2)
   J90  A23 PER_N2 SCONN56_123276793-SCONN56_1-23A   I318 @S9S_MB_2U_LIB.S9S_MB_2U(SCH_1):PAGE297
    U4  W41 SATA_6_PCIE3_6_USB3_6_RXN EMMITSBURG_REV0P9-GFNOCPU04302A   I110 @S9S_MB_2U_LIB.S9S_MB_2U(SCH_1):PAGE173

P3E_PCH_E1S_RX_DN<3> @S9S_MB_2U_LIB.S9S_MB_2U(SCH_1):P3E_PCH_E1S_RX_DN(3)
   J90  A26 PER_N3 SCONN56_123276793-SCONN56_1-23A   I318 @S9S_MB_2U_LIB.S9S_MB_2U(SCH_1):PAGE297
    U4  V40 SATA_7_PCIE3_7_USB3_7_RXN EMMITSBURG_REV0P9-GFNOCPU04302A   I110 @S9S_MB_2U_LIB.S9S_MB_2U(SCH_1):PAGE173

P3E_PCH_E1S_RX_DP<0> @S9S_MB_2U_LIB.S9S_MB_2U(SCH_1):P3E_PCH_E1S_RX_DP(0)
   J90  A17 PER_N0 SCONN56_123276793-SCONN56_1-23A   I318 @S9S_MB_2U_LIB.S9S_MB_2U(SCH_1):PAGE297
    U4 AA43 SATA_4_PCIE3_4_USB3_4_RXP EMMITSBURG_REV0P9-GFNOCPU04302A   I110 @S9S_MB_2U_LIB.S9S_MB_2U(SCH_1):PAGE173

P3E_PCH_E1S_RX_DP<1> @S9S_MB_2U_LIB.S9S_MB_2U(SCH_1):P3E_PCH_E1S_RX_DP(1)
   J90  A21 PER_P1 SCONN56_123276793-SCONN56_1-23A   I318 @S9S_MB_2U_LIB.S9S_MB_2U(SCH_1):PAGE297
    U4  Y42 SATA_5_PCIE3_5_USB3_5_RXP EMMITSBURG_REV0P9-GFNOCPU04302A   I110 @S9S_MB_2U_LIB.S9S_MB_2U(SCH_1):PAGE173

P3E_PCH_E1S_RX_DP<2> @S9S_MB_2U_LIB.S9S_MB_2U(SCH_1):P3E_PCH_E1S_RX_DP(2)
   J90  A24 PER_P2 SCONN56_123276793-SCONN56_1-23A   I318 @S9S_MB_2U_LIB.S9S_MB_2U(SCH_1):PAGE297
    U4  W43 SATA_6_PCIE3_6_USB3_6_RXP EMMITSBURG_REV0P9-GFNOCPU04302A   I110 @S9S_MB_2U_LIB.S9S_MB_2U(SCH_1):PAGE173

P3E_PCH_E1S_RX_DP<3> @S9S_MB_2U_LIB.S9S_MB_2U(SCH_1):P3E_PCH_E1S_RX_DP(3)
   J90  A27 PER_P3 SCONN56_123276793-SCONN56_1-23A   I318 @S9S_MB_2U_LIB.S9S_MB_2U(SCH_1):PAGE297
    U4  V42 SATA_7_PCIE3_7_USB3_7_RXP EMMITSBURG_REV0P9-GFNOCPU04302A   I110 @S9S_MB_2U_LIB.S9S_MB_2U(SCH_1):PAGE173

P3E_PCH_E1S_TX_C_DN<0> @S9S_MB_2U_LIB.S9S_MB_2U(SCH_1):P3E_PCH_E1S_TX_C_DN(0)
   J90  B18 PET_P0 SCONN56_123276793-SCONN56_1-23A   I318 @S9S_MB_2U_LIB.S9S_MB_2U(SCH_1):PAGE297
 C1996    2      2 Q_CAP_DIFFBUS_C0201-DIFF BUS_0A    I68 @S9S_MB_2U_LIB.S9S_MB_2U(SCH_1):PAGE173

P3E_PCH_E1S_TX_C_DN<1> @S9S_MB_2U_LIB.S9S_MB_2U(SCH_1):P3E_PCH_E1S_TX_C_DN(1)
   J90  B21 PET_P1 SCONN56_123276793-SCONN56_1-23A   I318 @S9S_MB_2U_LIB.S9S_MB_2U(SCH_1):PAGE297
 C1994    2      2 Q_CAP_DIFFBUS_C0201-DIFF BUS_0A    I70 @S9S_MB_2U_LIB.S9S_MB_2U(SCH_1):PAGE173

P3E_PCH_E1S_TX_C_DN<2> @S9S_MB_2U_LIB.S9S_MB_2U(SCH_1):P3E_PCH_E1S_TX_C_DN(2)
   J90  B23 PET_N2 SCONN56_123276793-SCONN56_1-23A   I318 @S9S_MB_2U_LIB.S9S_MB_2U(SCH_1):PAGE297
 C1992    2      2 Q_CAP_DIFFBUS_C0201-DIFF BUS_0A    I72 @S9S_MB_2U_LIB.S9S_MB_2U(SCH_1):PAGE173

P3E_PCH_E1S_TX_C_DN<3> @S9S_MB_2U_LIB.S9S_MB_2U(SCH_1):P3E_PCH_E1S_TX_C_DN(3)
   J90  B26 PET_N3 SCONN56_123276793-SCONN56_1-23A   I318 @S9S_MB_2U_LIB.S9S_MB_2U(SCH_1):PAGE297
 C1990    2      2 Q_CAP_DIFFBUS_C0201-DIFF BUS_0A    I74 @S9S_MB_2U_LIB.S9S_MB_2U(SCH_1):PAGE173

P3E_PCH_E1S_TX_C_DP<0> @S9S_MB_2U_LIB.S9S_MB_2U(SCH_1):P3E_PCH_E1S_TX_C_DP(0)
   J90  B17 PET_N0 SCONN56_123276793-SCONN56_1-23A   I318 @S9S_MB_2U_LIB.S9S_MB_2U(SCH_1):PAGE297
 C1995    2      2 Q_CAP_DIFFBUS_C0201-DIFF BUS_0A    I69 @S9S_MB_2U_LIB.S9S_MB_2U(SCH_1):PAGE173

P3E_PCH_E1S_TX_C_DP<1> @S9S_MB_2U_LIB.S9S_MB_2U(SCH_1):P3E_PCH_E1S_TX_C_DP(1)
   J90  B20 PET_N1 SCONN56_123276793-SCONN56_1-23A   I318 @S9S_MB_2U_LIB.S9S_MB_2U(SCH_1):PAGE297
 C1993    2      2 Q_CAP_DIFFBUS_C0201-DIFF BUS_0A    I71 @S9S_MB_2U_LIB.S9S_MB_2U(SCH_1):PAGE173

P3E_PCH_E1S_TX_C_DP<2> @S9S_MB_2U_LIB.S9S_MB_2U(SCH_1):P3E_PCH_E1S_TX_C_DP(2)
   J90  B24 PET_P2 SCONN56_123276793-SCONN56_1-23A   I318 @S9S_MB_2U_LIB.S9S_MB_2U(SCH_1):PAGE297
 C1991    2      2 Q_CAP_DIFFBUS_C0201-DIFF BUS_0A    I73 @S9S_MB_2U_LIB.S9S_MB_2U(SCH_1):PAGE173

P3E_PCH_E1S_TX_C_DP<3> @S9S_MB_2U_LIB.S9S_MB_2U(SCH_1):P3E_PCH_E1S_TX_C_DP(3)
   J90  B27 PET_P3 SCONN56_123276793-SCONN56_1-23A   I318 @S9S_MB_2U_LIB.S9S_MB_2U(SCH_1):PAGE297
 C1989    2      2 Q_CAP_DIFFBUS_C0201-DIFF BUS_0A    I75 @S9S_MB_2U_LIB.S9S_MB_2U(SCH_1):PAGE173

P3E_PCH_E1S_TX_DN<0> @S9S_MB_2U_LIB.S9S_MB_2U(SCH_1):P3E_PCH_E1S_TX_DN(0)
 C1996    1      1 Q_CAP_DIFFBUS_C0201-DIFF BUS_0A    I68 @S9S_MB_2U_LIB.S9S_MB_2U(SCH_1):PAGE173
    U4 AL36 SATA_4_PCIE3_4_USB3_4_TXN EMMITSBURG_REV0P9-GFNOCPU04302A   I110 @S9S_MB_2U_LIB.S9S_MB_2U(SCH_1):PAGE173

P3E_PCH_E1S_TX_DN<1> @S9S_MB_2U_LIB.S9S_MB_2U(SCH_1):P3E_PCH_E1S_TX_DN(1)
 C1994    1      1 Q_CAP_DIFFBUS_C0201-DIFF BUS_0A    I70 @S9S_MB_2U_LIB.S9S_MB_2U(SCH_1):PAGE173
    U4 AH34 SATA_5_PCIE3_5_USB3_5_TXN EMMITSBURG_REV0P9-GFNOCPU04302A   I110 @S9S_MB_2U_LIB.S9S_MB_2U(SCH_1):PAGE173

P3E_PCH_E1S_TX_DN<2> @S9S_MB_2U_LIB.S9S_MB_2U(SCH_1):P3E_PCH_E1S_TX_DN(2)
 C1992    1      1 Q_CAP_DIFFBUS_C0201-DIFF BUS_0A    I72 @S9S_MB_2U_LIB.S9S_MB_2U(SCH_1):PAGE173
    U4 AF37 SATA_6_PCIE3_6_USB3_6_TXN EMMITSBURG_REV0P9-GFNOCPU04302A   I110 @S9S_MB_2U_LIB.S9S_MB_2U(SCH_1):PAGE173

P3E_PCH_E1S_TX_DN<3> @S9S_MB_2U_LIB.S9S_MB_2U(SCH_1):P3E_PCH_E1S_TX_DN(3)
 C1990    1      1 Q_CAP_DIFFBUS_C0201-DIFF BUS_0A    I74 @S9S_MB_2U_LIB.S9S_MB_2U(SCH_1):PAGE173
    U4 AF34 SATA_7_PCIE3_7_USB3_7_TXN EMMITSBURG_REV0P9-GFNOCPU04302A   I110 @S9S_MB_2U_LIB.S9S_MB_2U(SCH_1):PAGE173

P3E_PCH_E1S_TX_DP<0> @S9S_MB_2U_LIB.S9S_MB_2U(SCH_1):P3E_PCH_E1S_TX_DP(0)
 C1995    1      1 Q_CAP_DIFFBUS_C0201-DIFF BUS_0A    I69 @S9S_MB_2U_LIB.S9S_MB_2U(SCH_1):PAGE173
    U4 AM37 SATA_4_PCIE3_4_USB3_4_TXP EMMITSBURG_REV0P9-GFNOCPU04302A   I110 @S9S_MB_2U_LIB.S9S_MB_2U(SCH_1):PAGE173

P3E_PCH_E1S_TX_DP<1> @S9S_MB_2U_LIB.S9S_MB_2U(SCH_1):P3E_PCH_E1S_TX_DP(1)
 C1993    1      1 Q_CAP_DIFFBUS_C0201-DIFF BUS_0A    I71 @S9S_MB_2U_LIB.S9S_MB_2U(SCH_1):PAGE173
    U4 AJ32 SATA_5_PCIE3_5_USB3_5_TXP EMMITSBURG_REV0P9-GFNOCPU04302A   I110 @S9S_MB_2U_LIB.S9S_MB_2U(SCH_1):PAGE173

P3E_PCH_E1S_TX_DP<2> @S9S_MB_2U_LIB.S9S_MB_2U(SCH_1):P3E_PCH_E1S_TX_DP(2)
 C1991    1      1 Q_CAP_DIFFBUS_C0201-DIFF BUS_0A    I73 @S9S_MB_2U_LIB.S9S_MB_2U(SCH_1):PAGE173
    U4 AH37 SATA_6_PCIE3_6_USB3_6_TXP EMMITSBURG_REV0P9-GFNOCPU04302A   I110 @S9S_MB_2U_LIB.S9S_MB_2U(SCH_1):PAGE173

P3E_PCH_E1S_TX_DP<3> @S9S_MB_2U_LIB.S9S_MB_2U(SCH_1):P3E_PCH_E1S_TX_DP(3)
 C1989    1      1 Q_CAP_DIFFBUS_C0201-DIFF BUS_0A    I75 @S9S_MB_2U_LIB.S9S_MB_2U(SCH_1):PAGE173
    U4 AG36 SATA_7_PCIE3_7_USB3_7_TXP EMMITSBURG_REV0P9-GFNOCPU04302A   I110 @S9S_MB_2U_LIB.S9S_MB_2U(SCH_1):PAGE173

P3E_PCH_M2_RX_DN<0> @S9S_MB_2U_LIB.S9S_MB_2U(SCH_1):P3E_PCH_M2_RX_DN(0)
   J59    5  PERN3 SCONN75K_APCI0155P004A-SCONN75A   I178 @S9S_MB_2U_LIB.S9S_MB_2U(SCH_1):PAGE182
    U4 AE41 SATA_0_PCIE3_0_USB3_0_RXN EMMITSBURG_REV0P9-GFNOCPU04302A   I110 @S9S_MB_2U_LIB.S9S_MB_2U(SCH_1):PAGE173

P3E_PCH_M2_RX_DN<1> @S9S_MB_2U_LIB.S9S_MB_2U(SCH_1):P3E_PCH_M2_RX_DN(1)
   J59   17  PERN2 SCONN75K_APCI0155P004A-SCONN75A   I178 @S9S_MB_2U_LIB.S9S_MB_2U(SCH_1):PAGE182
    U4 AD40 SATA_1_PCIE3_1_USB3_1_RXN EMMITSBURG_REV0P9-GFNOCPU04302A   I110 @S9S_MB_2U_LIB.S9S_MB_2U(SCH_1):PAGE173

P3E_PCH_M2_RX_DN<2> @S9S_MB_2U_LIB.S9S_MB_2U(SCH_1):P3E_PCH_M2_RX_DN(2)
   J59   29  PERN1 SCONN75K_APCI0155P004A-SCONN75A   I178 @S9S_MB_2U_LIB.S9S_MB_2U(SCH_1):PAGE182
    U4 AC41 SATA_2_PCIE3_2_USB3_2_RXN EMMITSBURG_REV0P9-GFNOCPU04302A   I110 @S9S_MB_2U_LIB.S9S_MB_2U(SCH_1):PAGE173

P3E_PCH_M2_RX_DN<3> @S9S_MB_2U_LIB.S9S_MB_2U(SCH_1):P3E_PCH_M2_RX_DN(3)
   J59   41 PERN0||SATA-B+ SCONN75K_APCI0155P004A-SCONN75A   I178 @S9S_MB_2U_LIB.S9S_MB_2U(SCH_1):PAGE182
    U4 AB40 SATA_3_PCIE3_3_USB3_3_RXN EMMITSBURG_REV0P9-GFNOCPU04302A   I110 @S9S_MB_2U_LIB.S9S_MB_2U(SCH_1):PAGE173

P3E_PCH_M2_RX_DP<0> @S9S_MB_2U_LIB.S9S_MB_2U(SCH_1):P3E_PCH_M2_RX_DP(0)
   J59    7  PERP3 SCONN75K_APCI0155P004A-SCONN75A   I178 @S9S_MB_2U_LIB.S9S_MB_2U(SCH_1):PAGE182
    U4 AE43 SATA_0_PCIE3_0_USB3_0_RXP EMMITSBURG_REV0P9-GFNOCPU04302A   I110 @S9S_MB_2U_LIB.S9S_MB_2U(SCH_1):PAGE173

P3E_PCH_M2_RX_DP<1> @S9S_MB_2U_LIB.S9S_MB_2U(SCH_1):P3E_PCH_M2_RX_DP(1)
   J59   19  PERP2 SCONN75K_APCI0155P004A-SCONN75A   I178 @S9S_MB_2U_LIB.S9S_MB_2U(SCH_1):PAGE182
    U4 AD42 SATA_1_PCIE3_1_USB3_1_RXP EMMITSBURG_REV0P9-GFNOCPU04302A   I110 @S9S_MB_2U_LIB.S9S_MB_2U(SCH_1):PAGE173

P3E_PCH_M2_RX_DP<2> @S9S_MB_2U_LIB.S9S_MB_2U(SCH_1):P3E_PCH_M2_RX_DP(2)
   J59   31  PERP1 SCONN75K_APCI0155P004A-SCONN75A   I178 @S9S_MB_2U_LIB.S9S_MB_2U(SCH_1):PAGE182
    U4 AC43 SATA_2_PCIE3_2_USB3_2_RXP EMMITSBURG_REV0P9-GFNOCPU04302A   I110 @S9S_MB_2U_LIB.S9S_MB_2U(SCH_1):PAGE173

P3E_PCH_M2_RX_DP<3> @S9S_MB_2U_LIB.S9S_MB_2U(SCH_1):P3E_PCH_M2_RX_DP(3)
   J59   43 PERP0||SATA-B- SCONN75K_APCI0155P004A-SCONN75A   I178 @S9S_MB_2U_LIB.S9S_MB_2U(SCH_1):PAGE182
    U4 AB42 SATA_3_PCIE3_3_USB3_3_RXP EMMITSBURG_REV0P9-GFNOCPU04302A   I110 @S9S_MB_2U_LIB.S9S_MB_2U(SCH_1):PAGE173

P3E_PCH_M2_TX_C_DN<0> @S9S_MB_2U_LIB.S9S_MB_2U(SCH_1):P3E_PCH_M2_TX_C_DN(0)
   J59   13  PETP3 SCONN75K_APCI0155P004A-SCONN75A   I178 @S9S_MB_2U_LIB.S9S_MB_2U(SCH_1):PAGE182
 C1105    2      2 Q_CAP_DIFFBUS_C0201-DIFF BUS_0A    I60 @S9S_MB_2U_LIB.S9S_MB_2U(SCH_1):PAGE173

P3E_PCH_M2_TX_C_DN<1> @S9S_MB_2U_LIB.S9S_MB_2U(SCH_1):P3E_PCH_M2_TX_C_DN(1)
   J59   25  PETP2 SCONN75K_APCI0155P004A-SCONN75A   I178 @S9S_MB_2U_LIB.S9S_MB_2U(SCH_1):PAGE182
 C1103    2      2 Q_CAP_DIFFBUS_C0201-DIFF BUS_0A    I62 @S9S_MB_2U_LIB.S9S_MB_2U(SCH_1):PAGE173

P3E_PCH_M2_TX_C_DN<2> @S9S_MB_2U_LIB.S9S_MB_2U(SCH_1):P3E_PCH_M2_TX_C_DN(2)
   J59   37  PETP1 SCONN75K_APCI0155P004A-SCONN75A   I178 @S9S_MB_2U_LIB.S9S_MB_2U(SCH_1):PAGE182
 C1101    2      2 Q_CAP_DIFFBUS_C0201-DIFF BUS_0A    I65 @S9S_MB_2U_LIB.S9S_MB_2U(SCH_1):PAGE173

P3E_PCH_M2_TX_C_DN<3> @S9S_MB_2U_LIB.S9S_MB_2U(SCH_1):P3E_PCH_M2_TX_C_DN(3)
   J59   49 PETP0||SATA-A+ SCONN75K_APCI0155P004A-SCONN75A   I178 @S9S_MB_2U_LIB.S9S_MB_2U(SCH_1):PAGE182
 C1099    2      2 Q_CAP_DIFFBUS_C0201-DIFF BUS_0A    I66 @S9S_MB_2U_LIB.S9S_MB_2U(SCH_1):PAGE173

P3E_PCH_M2_TX_C_DP<0> @S9S_MB_2U_LIB.S9S_MB_2U(SCH_1):P3E_PCH_M2_TX_C_DP(0)
   J59   11  PETN3 SCONN75K_APCI0155P004A-SCONN75A   I178 @S9S_MB_2U_LIB.S9S_MB_2U(SCH_1):PAGE182
 C1104    2      2 Q_CAP_DIFFBUS_C0201-DIFF BUS_0A    I61 @S9S_MB_2U_LIB.S9S_MB_2U(SCH_1):PAGE173

P3E_PCH_M2_TX_C_DP<1> @S9S_MB_2U_LIB.S9S_MB_2U(SCH_1):P3E_PCH_M2_TX_C_DP(1)
   J59   23  PETN2 SCONN75K_APCI0155P004A-SCONN75A   I178 @S9S_MB_2U_LIB.S9S_MB_2U(SCH_1):PAGE182
 C1102    2      2 Q_CAP_DIFFBUS_C0201-DIFF BUS_0A    I63 @S9S_MB_2U_LIB.S9S_MB_2U(SCH_1):PAGE173

P3E_PCH_M2_TX_C_DP<2> @S9S_MB_2U_LIB.S9S_MB_2U(SCH_1):P3E_PCH_M2_TX_C_DP(2)
   J59   35  PETN1 SCONN75K_APCI0155P004A-SCONN75A   I178 @S9S_MB_2U_LIB.S9S_MB_2U(SCH_1):PAGE182
 C1100    2      2 Q_CAP_DIFFBUS_C0201-DIFF BUS_0A    I64 @S9S_MB_2U_LIB.S9S_MB_2U(SCH_1):PAGE173

P3E_PCH_M2_TX_C_DP<3> @S9S_MB_2U_LIB.S9S_MB_2U(SCH_1):P3E_PCH_M2_TX_C_DP(3)
   J59   47 PETN0||SATA-A- SCONN75K_APCI0155P004A-SCONN75A   I178 @S9S_MB_2U_LIB.S9S_MB_2U(SCH_1):PAGE182
 C1098    2      2 Q_CAP_DIFFBUS_C0201-DIFF BUS_0A    I67 @S9S_MB_2U_LIB.S9S_MB_2U(SCH_1):PAGE173

P3E_PCH_M2_TX_DN<0> @S9S_MB_2U_LIB.S9S_MB_2U(SCH_1):P3E_PCH_M2_TX_DN(0)
 C1105    1      1 Q_CAP_DIFFBUS_C0201-DIFF BUS_0A    I60 @S9S_MB_2U_LIB.S9S_MB_2U(SCH_1):PAGE173
    U4 AL32 SATA_0_PCIE3_0_USB3_0_TXN EMMITSBURG_REV0P9-GFNOCPU04302A   I110 @S9S_MB_2U_LIB.S9S_MB_2U(SCH_1):PAGE173

P3E_PCH_M2_TX_DN<1> @S9S_MB_2U_LIB.S9S_MB_2U(SCH_1):P3E_PCH_M2_TX_DN(1)
 C1103    1      1 Q_CAP_DIFFBUS_C0201-DIFF BUS_0A    I62 @S9S_MB_2U_LIB.S9S_MB_2U(SCH_1):PAGE173
    U4 AN36 SATA_1_PCIE3_1_USB3_1_TXN EMMITSBURG_REV0P9-GFNOCPU04302A   I110 @S9S_MB_2U_LIB.S9S_MB_2U(SCH_1):PAGE173

P3E_PCH_M2_TX_DN<2> @S9S_MB_2U_LIB.S9S_MB_2U(SCH_1):P3E_PCH_M2_TX_DN(2)
 C1101    1      1 Q_CAP_DIFFBUS_C0201-DIFF BUS_0A    I65 @S9S_MB_2U_LIB.S9S_MB_2U(SCH_1):PAGE173
    U4 AR36 SATA_2_PCIE3_2_USB3_2_TXN EMMITSBURG_REV0P9-GFNOCPU04302A   I110 @S9S_MB_2U_LIB.S9S_MB_2U(SCH_1):PAGE173

P3E_PCH_M2_TX_DN<3> @S9S_MB_2U_LIB.S9S_MB_2U(SCH_1):P3E_PCH_M2_TX_DN(3)
 C1099    1      1 Q_CAP_DIFFBUS_C0201-DIFF BUS_0A    I66 @S9S_MB_2U_LIB.S9S_MB_2U(SCH_1):PAGE173
    U4 AK34 SATA_3_PCIE3_3_USB3_3_TXN EMMITSBURG_REV0P9-GFNOCPU04302A   I110 @S9S_MB_2U_LIB.S9S_MB_2U(SCH_1):PAGE173

P3E_PCH_M2_TX_DP<0> @S9S_MB_2U_LIB.S9S_MB_2U(SCH_1):P3E_PCH_M2_TX_DP(0)
 C1104    1      1 Q_CAP_DIFFBUS_C0201-DIFF BUS_0A    I61 @S9S_MB_2U_LIB.S9S_MB_2U(SCH_1):PAGE173
    U4 AK31 SATA_0_PCIE3_0_USB3_0_TXP EMMITSBURG_REV0P9-GFNOCPU04302A   I110 @S9S_MB_2U_LIB.S9S_MB_2U(SCH_1):PAGE173

P3E_PCH_M2_TX_DP<1> @S9S_MB_2U_LIB.S9S_MB_2U(SCH_1):P3E_PCH_M2_TX_DP(1)
 C1102    1      1 Q_CAP_DIFFBUS_C0201-DIFF BUS_0A    I63 @S9S_MB_2U_LIB.S9S_MB_2U(SCH_1):PAGE173
    U4 AP34 SATA_1_PCIE3_1_USB3_1_TXP EMMITSBURG_REV0P9-GFNOCPU04302A   I110 @S9S_MB_2U_LIB.S9S_MB_2U(SCH_1):PAGE173

P3E_PCH_M2_TX_DP<2> @S9S_MB_2U_LIB.S9S_MB_2U(SCH_1):P3E_PCH_M2_TX_DP(2)
 C1100    1      1 Q_CAP_DIFFBUS_C0201-DIFF BUS_0A    I64 @S9S_MB_2U_LIB.S9S_MB_2U(SCH_1):PAGE173
    U4 AT37 SATA_2_PCIE3_2_USB3_2_TXP EMMITSBURG_REV0P9-GFNOCPU04302A   I110 @S9S_MB_2U_LIB.S9S_MB_2U(SCH_1):PAGE173

P3E_PCH_M2_TX_DP<3> @S9S_MB_2U_LIB.S9S_MB_2U(SCH_1):P3E_PCH_M2_TX_DP(3)
 C1098    1      1 Q_CAP_DIFFBUS_C0201-DIFF BUS_0A    I67 @S9S_MB_2U_LIB.S9S_MB_2U(SCH_1):PAGE173
    U4 AM34 SATA_3_PCIE3_3_USB3_3_TXP EMMITSBURG_REV0P9-GFNOCPU04302A   I110 @S9S_MB_2U_LIB.S9S_MB_2U(SCH_1):PAGE173

P3E_PCH_NVS_RX_DN<0> @S9S_MB_2U_LIB.S9S_MB_2U(SCH_1):P3E_PCH_NVS_RX_DN(0)
  J112   N8     N8 CONN160_10131762101LF-CONN160_A    I75 @S9S_MB_2U_LIB.S9S_MB_2U(SCH_1):PAGE149
    U4  M41 SATA_10_PCIE3_10_GBE_0_RXN EMMITSBURG_REV0P9-GFNOCPU04302A   I110 @S9S_MB_2U_LIB.S9S_MB_2U(SCH_1):PAGE173

P3E_PCH_NVS_RX_DN<1> @S9S_MB_2U_LIB.S9S_MB_2U(SCH_1):P3E_PCH_NVS_RX_DN(1)
  J112   O7     O7 CONN160_10131762101LF-CONN160_A    I75 @S9S_MB_2U_LIB.S9S_MB_2U(SCH_1):PAGE149
    U4  L40 SATA_11_PCIE3_11_RXN EMMITSBURG_REV0P9-GFNOCPU04302A   I110 @S9S_MB_2U_LIB.S9S_MB_2U(SCH_1):PAGE173

P3E_PCH_NVS_RX_DP<0> @S9S_MB_2U_LIB.S9S_MB_2U(SCH_1):P3E_PCH_NVS_RX_DP(0)
  J112   O8     O8 CONN160_10131762101LF-CONN160_A    I75 @S9S_MB_2U_LIB.S9S_MB_2U(SCH_1):PAGE149
    U4  M43 SATA_10_PCIE3_10_GBE_0_RXP EMMITSBURG_REV0P9-GFNOCPU04302A   I110 @S9S_MB_2U_LIB.S9S_MB_2U(SCH_1):PAGE173

P3E_PCH_NVS_RX_DP<1> @S9S_MB_2U_LIB.S9S_MB_2U(SCH_1):P3E_PCH_NVS_RX_DP(1)
  J112   P7     P7 CONN160_10131762101LF-CONN160_A    I75 @S9S_MB_2U_LIB.S9S_MB_2U(SCH_1):PAGE149
    U4  L42 SATA_11_PCIE3_11_RXP EMMITSBURG_REV0P9-GFNOCPU04302A   I110 @S9S_MB_2U_LIB.S9S_MB_2U(SCH_1):PAGE173

P3E_PCH_NVS_TX_C_DN<0> @S9S_MB_2U_LIB.S9S_MB_2U(SCH_1):P3E_PCH_NVS_TX_C_DN(0)
  J112   Q8     Q8 CONN160_10131762101LF-CONN160_A    I75 @S9S_MB_2U_LIB.S9S_MB_2U(SCH_1):PAGE149
 C2076    2      2 Q_CAP_DIFFBUS_C0201-DIFF BUS_0A    I79 @S9S_MB_2U_LIB.S9S_MB_2U(SCH_1):PAGE173

P3E_PCH_NVS_TX_C_DN<1> @S9S_MB_2U_LIB.S9S_MB_2U(SCH_1):P3E_PCH_NVS_TX_C_DN(1)
  J112   R7     R7 CONN160_10131762101LF-CONN160_A    I75 @S9S_MB_2U_LIB.S9S_MB_2U(SCH_1):PAGE149
 C2074    2      2 Q_CAP_DIFFBUS_C0201-DIFF BUS_0A    I82 @S9S_MB_2U_LIB.S9S_MB_2U(SCH_1):PAGE173

P3E_PCH_NVS_TX_C_DP<0> @S9S_MB_2U_LIB.S9S_MB_2U(SCH_1):P3E_PCH_NVS_TX_C_DP(0)
  J112   R8     R8 CONN160_10131762101LF-CONN160_A    I75 @S9S_MB_2U_LIB.S9S_MB_2U(SCH_1):PAGE149
 C2075    2      2 Q_CAP_DIFFBUS_C0201-DIFF BUS_0A    I81 @S9S_MB_2U_LIB.S9S_MB_2U(SCH_1):PAGE173

P3E_PCH_NVS_TX_C_DP<1> @S9S_MB_2U_LIB.S9S_MB_2U(SCH_1):P3E_PCH_NVS_TX_C_DP(1)
  J112   S7     S7 CONN160_10131762101LF-CONN160_A    I75 @S9S_MB_2U_LIB.S9S_MB_2U(SCH_1):PAGE149
 C2073    2      2 Q_CAP_DIFFBUS_C0201-DIFF BUS_0A    I83 @S9S_MB_2U_LIB.S9S_MB_2U(SCH_1):PAGE173

P3E_PCH_NVS_TX_DN<0> @S9S_MB_2U_LIB.S9S_MB_2U(SCH_1):P3E_PCH_NVS_TX_DN(0)
 C2076    1      1 Q_CAP_DIFFBUS_C0201-DIFF BUS_0A    I79 @S9S_MB_2U_LIB.S9S_MB_2U(SCH_1):PAGE173
    U4  W36 SATA_10_PCIE3_10_GBE_0_TXN EMMITSBURG_REV0P9-GFNOCPU04302A   I110 @S9S_MB_2U_LIB.S9S_MB_2U(SCH_1):PAGE173

P3E_PCH_NVS_TX_DN<1> @S9S_MB_2U_LIB.S9S_MB_2U(SCH_1):P3E_PCH_NVS_TX_DN(1)
 C2074    1      1 Q_CAP_DIFFBUS_C0201-DIFF BUS_0A    I82 @S9S_MB_2U_LIB.S9S_MB_2U(SCH_1):PAGE173
    U4  T37 SATA_11_PCIE3_11_TXN EMMITSBURG_REV0P9-GFNOCPU04302A   I110 @S9S_MB_2U_LIB.S9S_MB_2U(SCH_1):PAGE173

P3E_PCH_NVS_TX_DP<0> @S9S_MB_2U_LIB.S9S_MB_2U(SCH_1):P3E_PCH_NVS_TX_DP(0)
 C2075    1      1 Q_CAP_DIFFBUS_C0201-DIFF BUS_0A    I81 @S9S_MB_2U_LIB.S9S_MB_2U(SCH_1):PAGE173
    U4  Y37 SATA_10_PCIE3_10_GBE_0_TXP EMMITSBURG_REV0P9-GFNOCPU04302A   I110 @S9S_MB_2U_LIB.S9S_MB_2U(SCH_1):PAGE173

P3E_PCH_NVS_TX_DP<1> @S9S_MB_2U_LIB.S9S_MB_2U(SCH_1):P3E_PCH_NVS_TX_DP(1)
 C2073    1      1 Q_CAP_DIFFBUS_C0201-DIFF BUS_0A    I83 @S9S_MB_2U_LIB.S9S_MB_2U(SCH_1):PAGE173
    U4  V37 SATA_11_PCIE3_11_TXP EMMITSBURG_REV0P9-GFNOCPU04302A   I110 @S9S_MB_2U_LIB.S9S_MB_2U(SCH_1):PAGE173

P3V3 @S9S_MB_2U_LIB.S9S_MB_2U(SCH_1):P3V3
    L3    1      1 Q_INDUCTOR_SMLF-BLM18SG331TN1DA   I170 @S9S_MB_2U_LIB.S9S_MB_2U(SCH_1):PAGE195
    L4    1      1 Q_INDUCTOR_SMLF-BLM18SG331TN1DA   I177 @S9S_MB_2U_LIB.S9S_MB_2U(SCH_1):PAGE195
  R567    1      A Q_RES_0402LF-4.7K,1%,1/16W,EMPA   I179 @S9S_MB_2U_LIB.S9S_MB_2U(SCH_1):PAGE195
  R569    1      A Q_RES_0402LF-4.7K,1%,1/16W,EMPA   I185 @S9S_MB_2U_LIB.S9S_MB_2U(SCH_1):PAGE195
  R573    1      A Q_RES_0402LF-4.7K,1%,1/16W,EMPA   I194 @S9S_MB_2U_LIB.S9S_MB_2U(SCH_1):PAGE195
  R111    1      A Q_RES_0402LF-10K,1%,1/16W,CHIPA    I24 @S9S_MB_2U_LIB.S9S_MB_2U(SCH_1):PAGE212
 R1002    1      A Q_RES_0402LF-4.7K,5%,1/16W,CHIA    I34 @S9S_MB_2U_LIB.S9S_MB_2U(SCH_1):PAGE223
 R1003    1      A Q_RES_0402LF-4.7K,5%,1/16W,CHIA    I38 @S9S_MB_2U_LIB.S9S_MB_2U(SCH_1):PAGE223
 R1000    1      A Q_RES_0402LF-4.7K,5%,1/16W,CHIA    I52 @S9S_MB_2U_LIB.S9S_MB_2U(SCH_1):PAGE223
 R1001    1      A Q_RES_0402LF-4.7K,5%,1/16W,CHIA    I55 @S9S_MB_2U_LIB.S9S_MB_2U(SCH_1):PAGE223
 R3100    2      B Q_RES_0402LF-130,1%,1/16W,CHIPA    I64 @S9S_MB_2U_LIB.S9S_MB_2U(SCH_1):PAGE242
 C2018    1      A Q_CAP_0402-0.1UF,25V,10%,X7R,CA    I26 @S9S_MB_2U_LIB.S9S_MB_2U(SCH_1):PAGE163
 R3574    1      A Q_RES_0402LF-10,1%,1/16W,CHIP,A    I35 @S9S_MB_2U_LIB.S9S_MB_2U(SCH_1):PAGE163
  U264   11    BUS INA230AIRGTR-INA230AIRGTR,SMLFB    I46 @S9S_MB_2U_LIB.S9S_MB_2U(SCH_1):PAGE163
 R2908    1      A Q_RES_0402LF-5.11K,1%,1/16W,CHA   I161 @S9S_MB_2U_LIB.S9S_MB_2U(SCH_1):PAGE239
 C2243    1      A Q_CAP_C0402-1UF,25V,10%,X6S,CHA    I85 @S9S_MB_2U_LIB.S9S_MB_2U(SCH_1):PAGE321
  U301   14    VCC GTL2014PW-GTL2014PW,SMLF,IC,ALA    I91 @S9S_MB_2U_LIB.S9S_MB_2U(SCH_1):PAGE321
  U306   14    VCC GTL2014PW-GTL2014PW,SMLF,IC,ALA    I80 @S9S_MB_2U_LIB.S9S_MB_2U(SCH_1):PAGE322
 C2248    1      A Q_CAP_C0402-1UF,25V,10%,X6S,CHA    I83 @S9S_MB_2U_LIB.S9S_MB_2U(SCH_1):PAGE322
    D7    1      1 BAT547F-BAT547F,SMLF,IC,BC0BATA    I32 @S9S_MB_2U_LIB.S9S_MB_2U(SCH_1):PAGE246
   Q56    1      1 MOSFET_NCH_1D3S-PSMNR58-30YLH,A    I51 @S9S_MB_2U_LIB.S9S_MB_2U(SCH_1):PAGE246
   Q56    2      2 MOSFET_NCH_1D3S-PSMNR58-30YLH,A    I51 @S9S_MB_2U_LIB.S9S_MB_2U(SCH_1):PAGE246
   Q56    3      3 MOSFET_NCH_1D3S-PSMNR58-30YLH,A    I51 @S9S_MB_2U_LIB.S9S_MB_2U(SCH_1):PAGE246
 C1339    1      A Q_CAP_C0402-100NF,50V,10%,X7R,A    I58 @S9S_MB_2U_LIB.S9S_MB_2U(SCH_1):PAGE246
 C1340    1      A Q_CAP_C0805-10UF,16V,10%,X6S,CA    I61 @S9S_MB_2U_LIB.S9S_MB_2U(SCH_1):PAGE246
 PR633    1      A Q_RES_0402LF-0,5%,1/16W,EMPTY,A    I22 @S9S_MB_2U_LIB.S9S_MB_2U(SCH_1):PAGE257
 PR703    1      A Q_RES_0402LF-0,5%,1/16W,EMPTY,A    I34 @S9S_MB_2U_LIB.S9S_MB_2U(SCH_1):PAGE275
 R4016    1      A Q_RES_0402LF-4.32K,1%,1/16W,CHA    I97 @S9S_MB_2U_LIB.S9S_MB_2U(SCH_1):PAGE321
 R4038    1      A Q_RES_0402LF-4.32K,1%,1/16W,CHA   I182 @S9S_MB_2U_LIB.S9S_MB_2U(SCH_1):PAGE322
 R4489    1      A Q_RES_0402LF-4.75K,1%,1/16W,CHA    I30 @S9S_MB_2U_LIB.S9S_MB_2U(SCH_1):PAGE200
 R4491    1      A Q_RES_0402LF-10K,1%,1/16W,CHIPA    I48 @S9S_MB_2U_LIB.S9S_MB_2U(SCH_1):PAGE200
 R4494    2      B Q_RES_0402LF-10K,1%,1/16W,CHIPA    I69 @S9S_MB_2U_LIB.S9S_MB_2U(SCH_1):PAGE200
 C2338    1      A Q_CAP_0402-0.1UF,25V,10%,X7R,CA     I8 @S9S_MB_2U_LIB.S9S_MB_2U(SCH_1):PAGE225
 R4498    1      A Q_RES_0402LF-4.7K,5%,1/16W,CHIA    I11 @S9S_MB_2U_LIB.S9S_MB_2U(SCH_1):PAGE225
 R4499    1      A Q_RES_0402LF-4.7K,5%,1/16W,CHIA    I12 @S9S_MB_2U_LIB.S9S_MB_2U(SCH_1):PAGE225
  U315    8   VCCB PCA9617ADP-PCA9617ADP,SMLF,IC,A    I17 @S9S_MB_2U_LIB.S9S_MB_2U(SCH_1):PAGE225
 R4500    1      A Q_RES_0402LF-10K,1%,1/16W,EMPTA    I32 @S9S_MB_2U_LIB.S9S_MB_2U(SCH_1):PAGE225
 R4516    1      A Q_RES_0402LF-10K,1%,1/16W,CHIPA   I539 @S9S_MB_2U_LIB.S9S_MB_2U(SCH_1):PAGE195
 R4517    1      A Q_RES_0402LF-10K,1%,1/16W,CHIPA   I540 @S9S_MB_2U_LIB.S9S_MB_2U(SCH_1):PAGE195
 R4518    1      A Q_RES_0402LF-10K,1%,1/16W,CHIPA    I77 @S9S_MB_2U_LIB.S9S_MB_2U(SCH_1):PAGE200
 R4519    1      A Q_RES_0402LF-10K,1%,1/16W,CHIPA    I78 @S9S_MB_2U_LIB.S9S_MB_2U(SCH_1):PAGE200
 R4520    1      A Q_RES_0402LF-10K,1%,1/16W,CHIPA    I79 @S9S_MB_2U_LIB.S9S_MB_2U(SCH_1):PAGE200
   L19    1      1 Q_INDUCTOR_SMLF-FCM2012KF-601TA    I81 @S9S_MB_2U_LIB.S9S_MB_2U(SCH_1):PAGE200
   L20    1      1 Q_INDUCTOR_SMLF-FCM2012KF-601TA    I82 @S9S_MB_2U_LIB.S9S_MB_2U(SCH_1):PAGE200
 PR704    1      A Q_RES_0402LF-0,5%,1/16W,EMPTY,A    I17 @S9S_MB_2U_LIB.S9S_MB_2U(SCH_1):PAGE275
 PR443    1      A Q_RES_0402LF-0,5%,1/16W,EMPTY,A    I22 @S9S_MB_2U_LIB.S9S_MB_2U(SCH_1):PAGE262
 PR403    1      A Q_RES_0402LF-0,5%,1/16W,EMPTY,A    I42 @S9S_MB_2U_LIB.S9S_MB_2U(SCH_1):PAGE253
 PR632    1      A Q_RES_0402LF-0,5%,1/16W,EMPTY,A    I40 @S9S_MB_2U_LIB.S9S_MB_2U(SCH_1):PAGE257
 PR640    1      A Q_RES_0402LF-0,5%,1/16W,EMPTY,A    I41 @S9S_MB_2U_LIB.S9S_MB_2U(SCH_1):PAGE271
 PR699    1      A Q_RES_0402LF-0,5%,1/16W,EMPTY,A    I16 @S9S_MB_2U_LIB.S9S_MB_2U(SCH_1):PAGE280
 R1706    1      A Q_RES_0402LF-10K,1%,1/16W,EMPTA    I89 @S9S_MB_2U_LIB.S9S_MB_2U(SCH_1):PAGE246
  U330    3    VCC APX80929SAG7-APX809-29SAG-7,SMA   I105 @S9S_MB_2U_LIB.S9S_MB_2U(SCH_1):PAGE246
 C2360    1      A Q_CAP_0402-0.1UF,25V,10%,X7R,CA   I107 @S9S_MB_2U_LIB.S9S_MB_2U(SCH_1):PAGE246
 R3634    2      B Q_RES_2512LF-0.01,1%,1W,CHIP,CA   I128 @S9S_MB_2U_LIB.S9S_MB_2U(SCH_1):PAGE163
  R242    1      A Q_RES_0402LF-4.75K,1%,1/16W,CHA    I26 @S9S_MB_2U_LIB.S9S_MB_2U(SCH_1):PAGE121
  R241    1      A Q_RES_0402LF-4.75K,1%,1/16W,CHA    I33 @S9S_MB_2U_LIB.S9S_MB_2U(SCH_1):PAGE121
 R4406    1      A Q_RES_0402LF-4.75K,1%,1/16W,CHA    I24 @S9S_MB_2U_LIB.S9S_MB_2U(SCH_1):PAGE122
 R4405    1      A Q_RES_0402LF-4.75K,1%,1/16W,CHA    I27 @S9S_MB_2U_LIB.S9S_MB_2U(SCH_1):PAGE122
 R4412    1      A Q_RES_0402LF-4.75K,1%,1/16W,CHA    I29 @S9S_MB_2U_LIB.S9S_MB_2U(SCH_1):PAGE123
 R4411    1      A Q_RES_0402LF-4.75K,1%,1/16W,CHA    I32 @S9S_MB_2U_LIB.S9S_MB_2U(SCH_1):PAGE123

P3V3_9ZXL045 @S9S_MB_2U_LIB.S9S_MB_2U(SCH_1):P3V3_9ZXL045
 R4475    1      A Q_RES_0603LF-1,1%,1/10W,CHIP,CA    I11 @S9S_MB_2U_LIB.S9S_MB_2U(SCH_1):PAGE200
 R4493    1      A Q_RES_0603LF-1,1%,1/10W,CHIP,CA     I4 @S9S_MB_2U_LIB.S9S_MB_2U(SCH_1):PAGE200
   L19    2      2 Q_INDUCTOR_SMLF-FCM2012KF-601TA    I81 @S9S_MB_2U_LIB.S9S_MB_2U(SCH_1):PAGE200

P3V3_9ZXL045_VDD @S9S_MB_2U_LIB.S9S_MB_2U(SCH_1):P3V3_9ZXL045_VDD
  U314   12   VDD0 9ZXL0451EKILFT-9ZXL0451EKILFT,A     I1 @S9S_MB_2U_LIB.S9S_MB_2U(SCH_1):PAGE200
  U314   16   VDD1 9ZXL0451EKILFT-9ZXL0451EKILFT,A     I1 @S9S_MB_2U_LIB.S9S_MB_2U(SCH_1):PAGE200
  U314   21   VDD2 9ZXL0451EKILFT-9ZXL0451EKILFT,A     I1 @S9S_MB_2U_LIB.S9S_MB_2U(SCH_1):PAGE200
  U314   25   VDD3 9ZXL0451EKILFT-9ZXL0451EKILFT,A     I1 @S9S_MB_2U_LIB.S9S_MB_2U(SCH_1):PAGE200
  U314   29   VDD4 9ZXL0451EKILFT-9ZXL0451EKILFT,A     I1 @S9S_MB_2U_LIB.S9S_MB_2U(SCH_1):PAGE200
 C2328    1      A Q_CAP_C0603-10UF,6.3V,20%,X6S,A    I17 @S9S_MB_2U_LIB.S9S_MB_2U(SCH_1):PAGE200
 C2329    1      A Q_CAP_0402-0.1UF,25V,10%,X7R,CA    I54 @S9S_MB_2U_LIB.S9S_MB_2U(SCH_1):PAGE200
 C2330    1      A Q_CAP_0402-0.1UF,25V,10%,X7R,CA    I55 @S9S_MB_2U_LIB.S9S_MB_2U(SCH_1):PAGE200
 C2333    1      A Q_CAP_0402-0.1UF,25V,10%,X7R,CA    I56 @S9S_MB_2U_LIB.S9S_MB_2U(SCH_1):PAGE200
 C2336    1      A Q_CAP_0402-0.1UF,25V,10%,X7R,CA    I57 @S9S_MB_2U_LIB.S9S_MB_2U(SCH_1):PAGE200
 C2339    1      A Q_CAP_0402-0.1UF,25V,10%,X7R,CA    I71 @S9S_MB_2U_LIB.S9S_MB_2U(SCH_1):PAGE200
   L20    2      2 Q_INDUCTOR_SMLF-FCM2012KF-601TA    I82 @S9S_MB_2U_LIB.S9S_MB_2U(SCH_1):PAGE200

P3V3_9ZXL045_VDDA @S9S_MB_2U_LIB.S9S_MB_2U(SCH_1):P3V3_9ZXL045_VDDA
 C2331    1      A Q_CAP_C0603-10UF,6.3V,20%,X6S,A     I5 @S9S_MB_2U_LIB.S9S_MB_2U(SCH_1):PAGE200
  U314   31   VDDA 9ZXL0451EKILFT-9ZXL0451EKILFT,A     I1 @S9S_MB_2U_LIB.S9S_MB_2U(SCH_1):PAGE200
 R4493    2      B Q_RES_0603LF-1,1%,1/10W,CHIP,CA     I4 @S9S_MB_2U_LIB.S9S_MB_2U(SCH_1):PAGE200
 C2334    1      A Q_CAP_0402-0.1UF,25V,10%,X7R,CA    I58 @S9S_MB_2U_LIB.S9S_MB_2U(SCH_1):PAGE200

P3V3_9ZXL045_VDDR @S9S_MB_2U_LIB.S9S_MB_2U(SCH_1):P3V3_9ZXL045_VDDR
 C2332    1      A Q_CAP_C0603-10UF,6.3V,20%,X6S,A    I10 @S9S_MB_2U_LIB.S9S_MB_2U(SCH_1):PAGE200
 R4475    2      B Q_RES_0603LF-1,1%,1/10W,CHIP,CA    I11 @S9S_MB_2U_LIB.S9S_MB_2U(SCH_1):PAGE200
  U314    2   VDDR 9ZXL0451EKILFT-9ZXL0451EKILFT,A     I1 @S9S_MB_2U_LIB.S9S_MB_2U(SCH_1):PAGE200
 C2335    1      A Q_CAP_0402-0.1UF,25V,10%,X7R,CA    I59 @S9S_MB_2U_LIB.S9S_MB_2U(SCH_1):PAGE200

P3V3_ADC @S9S_MB_2U_LIB.S9S_MB_2U(SCH_1):P3V3_ADC
 R2908    2      B Q_RES_0402LF-5.11K,1%,1/16W,CHA   I161 @S9S_MB_2U_LIB.S9S_MB_2U(SCH_1):PAGE239
 R2843    1      A Q_RES_0402LF-4.7K,1%,1/16W,CHIA   I162 @S9S_MB_2U_LIB.S9S_MB_2U(SCH_1):PAGE239
 R3683    1      A Q_RES_0402LF-0,5%,1/16W,EMPTY,A   I199 @S9S_MB_2U_LIB.S9S_MB_2U(SCH_1):PAGE239
 R3684    1      A Q_RES_0402LF-0,5%,1/16W,CHIP,CA   I200 @S9S_MB_2U_LIB.S9S_MB_2U(SCH_1):PAGE239

P3V3_ADC128_VCC @S9S_MB_2U_LIB.S9S_MB_2U(SCH_1):P3V3_ADC128_VCC
  U269    5     V+ ADC128D818CIMTXNOPB-ADC128D818A   I103 @S9S_MB_2U_LIB.S9S_MB_2U(SCH_1):PAGE239
   L16    2      2 Q_INDUCTOR_SMLF-BLM18PG300SN1DB   I118 @S9S_MB_2U_LIB.S9S_MB_2U(SCH_1):PAGE239
 C2051    1      A Q_CAP_0402-0.1UF,25V,10%,X7R,CA   I127 @S9S_MB_2U_LIB.S9S_MB_2U(SCH_1):PAGE239
 C2052    1      A Q_CAP_0402-0.1UF,25V,10%,X7R,CA   I128 @S9S_MB_2U_LIB.S9S_MB_2U(SCH_1):PAGE239
 R3689    1      A Q_RES_0402LF-4.7K,1%,1/16W,EMPA   I129 @S9S_MB_2U_LIB.S9S_MB_2U(SCH_1):PAGE239

P3V3_ADC_MAM @S9S_MB_2U_LIB.S9S_MB_2U(SCH_1):P3V3_ADC_MAM
  U193    9   AIN4 MAX11617EEET-MAX11617EEE+T,SMLA    I57 @S9S_MB_2U_LIB.S9S_MB_2U(SCH_1):PAGE239
 C2043    1      A Q_CAP_0402-100PF,50V,5%,EMPTY,A   I196 @S9S_MB_2U_LIB.S9S_MB_2U(SCH_1):PAGE239
 R3683    2      B Q_RES_0402LF-0,5%,1/16W,EMPTY,A   I199 @S9S_MB_2U_LIB.S9S_MB_2U(SCH_1):PAGE239

P3V3_ADC_TIC @S9S_MB_2U_LIB.S9S_MB_2U(SCH_1):P3V3_ADC_TIC
  U269   12    IN4 ADC128D818CIMTXNOPB-ADC128D818A   I103 @S9S_MB_2U_LIB.S9S_MB_2U(SCH_1):PAGE239
 C2048    1      A Q_CAP_0402-0.1UF,25V,10%,X7R,CA   I197 @S9S_MB_2U_LIB.S9S_MB_2U(SCH_1):PAGE239
 R3684    2      B Q_RES_0402LF-0,5%,1/16W,CHIP,CA   I200 @S9S_MB_2U_LIB.S9S_MB_2U(SCH_1):PAGE239

P3V3_AUX @S9S_MB_2U_LIB.S9S_MB_2U(SCH_1):P3V3_AUX
    U2 BC21 VCC_3P3_AUX0 SOCKET4677_AZIF0045P001C01CS-SA     I8 @S9S_MB_2U_LIB.S9S_MB_2U(SCH_1):PAGE37
    U2 BA21 VCC_3P3_AUX1 SOCKET4677_AZIF0045P001C01CS-SA     I8 @S9S_MB_2U_LIB.S9S_MB_2U(SCH_1):PAGE37
    C1    1      A Q_CAP_C0402-10UF,6.3V,20%,X6S,A    I15 @S9S_MB_2U_LIB.S9S_MB_2U(SCH_1):PAGE37
   C71    1      A Q_CAP_C0402-10UF,6.3V,20%,X6S,A     I4 @S9S_MB_2U_LIB.S9S_MB_2U(SCH_1):PAGE68
    U1 BC21 VCC_3P3_AUX0 SOCKET4677_AZIF0045P001C01CS-SA     I8 @S9S_MB_2U_LIB.S9S_MB_2U(SCH_1):PAGE68
    U1 BA21 VCC_3P3_AUX1 SOCKET4677_AZIF0045P001C01CS-SA     I8 @S9S_MB_2U_LIB.S9S_MB_2U(SCH_1):PAGE68
  R319    1      A Q_RES_0402LF-10K,1%,1/16W,CHIPA     I8 @S9S_MB_2U_LIB.S9S_MB_2U(SCH_1):PAGE80
    C2    1      A Q_CAP_C0402-2.2UF,6.3V,20%,X6SA   I192 @S9S_MB_2U_LIB.S9S_MB_2U(SCH_1):PAGE82
    J1    3 VIN_MGMT SCONN288_ADR50017P130CC-SCONN2A   I198 @S9S_MB_2U_LIB.S9S_MB_2U(SCH_1):PAGE82
    C5    1      A Q_CAP_C0402-2.2UF,6.3V,20%,X6SA   I120 @S9S_MB_2U_LIB.S9S_MB_2U(SCH_1):PAGE83
    J2    3 VIN_MGMT SCONN288_ADR50017P087CC-SCONN2A   I177 @S9S_MB_2U_LIB.S9S_MB_2U(SCH_1):PAGE83
    C8    1      A Q_CAP_C0402-2.2UF,6.3V,20%,X6SA   I121 @S9S_MB_2U_LIB.S9S_MB_2U(SCH_1):PAGE84
    J4    3 VIN_MGMT SCONN288_ADR50017P087CC-SCONN2A    I23 @S9S_MB_2U_LIB.S9S_MB_2U(SCH_1):PAGE85
   C11    1      A Q_CAP_C0402-2.2UF,6.3V,20%,X6SA   I121 @S9S_MB_2U_LIB.S9S_MB_2U(SCH_1):PAGE85
    J5    3 VIN_MGMT SCONN288_ADR50017P130CC-SCONN2A    I24 @S9S_MB_2U_LIB.S9S_MB_2U(SCH_1):PAGE86
   C14    1      A Q_CAP_C0402-2.2UF,6.3V,20%,X6SA   I120 @S9S_MB_2U_LIB.S9S_MB_2U(SCH_1):PAGE86
    J6    3 VIN_MGMT SCONN288_ADR50017P087CC-SCONN2A    I46 @S9S_MB_2U_LIB.S9S_MB_2U(SCH_1):PAGE87
   C17    1      A Q_CAP_C0402-2.2UF,6.3V,20%,X6SA   I120 @S9S_MB_2U_LIB.S9S_MB_2U(SCH_1):PAGE87
    J7    3 VIN_MGMT SCONN288_ADR50017P130CC-SCONN2A    I12 @S9S_MB_2U_LIB.S9S_MB_2U(SCH_1):PAGE88
   C20    1      A Q_CAP_C0402-2.2UF,6.3V,20%,X6SA   I123 @S9S_MB_2U_LIB.S9S_MB_2U(SCH_1):PAGE88
    J8    3 VIN_MGMT SCONN288_ADR50017P087CC-SCONN2A    I50 @S9S_MB_2U_LIB.S9S_MB_2U(SCH_1):PAGE89
   C23    1      A Q_CAP_C0402-2.2UF,6.3V,20%,X6SA   I121 @S9S_MB_2U_LIB.S9S_MB_2U(SCH_1):PAGE89
    J9    3 VIN_MGMT SCONN288_ADR50017P130CC-SCONN2A    I12 @S9S_MB_2U_LIB.S9S_MB_2U(SCH_1):PAGE90
   C26    1      A Q_CAP_C0402-2.2UF,6.3V,20%,X6SA   I122 @S9S_MB_2U_LIB.S9S_MB_2U(SCH_1):PAGE90
   J10    3 VIN_MGMT SCONN288_ADR50017P087CC-SCONN2A    I13 @S9S_MB_2U_LIB.S9S_MB_2U(SCH_1):PAGE91
   C29    1      A Q_CAP_C0402-2.2UF,6.3V,20%,X6SA   I123 @S9S_MB_2U_LIB.S9S_MB_2U(SCH_1):PAGE91
   J11    3 VIN_MGMT SCONN288_ADR50017P130CC-SCONN2A    I25 @S9S_MB_2U_LIB.S9S_MB_2U(SCH_1):PAGE92
   C32    1      A Q_CAP_C0402-2.2UF,6.3V,20%,X6SA   I122 @S9S_MB_2U_LIB.S9S_MB_2U(SCH_1):PAGE92
   J12    3 VIN_MGMT SCONN288_ADR50017P087CC-SCONN2A    I24 @S9S_MB_2U_LIB.S9S_MB_2U(SCH_1):PAGE93
   C35    1      A Q_CAP_C0402-2.2UF,6.3V,20%,X6SA   I122 @S9S_MB_2U_LIB.S9S_MB_2U(SCH_1):PAGE93
   J13    3 VIN_MGMT SCONN288_ADR50017P130CC-SCONN2A    I11 @S9S_MB_2U_LIB.S9S_MB_2U(SCH_1):PAGE94
   C38    1      A Q_CAP_C0402-2.2UF,6.3V,20%,X6SA   I123 @S9S_MB_2U_LIB.S9S_MB_2U(SCH_1):PAGE94
   J14    3 VIN_MGMT SCONN288_ADR50017P087CC-SCONN2A    I47 @S9S_MB_2U_LIB.S9S_MB_2U(SCH_1):PAGE95
   C41    1      A Q_CAP_C0402-2.2UF,6.3V,20%,X6SA   I121 @S9S_MB_2U_LIB.S9S_MB_2U(SCH_1):PAGE95
   J15    3 VIN_MGMT SCONN288_ADR50017P130CC-SCONN2A    I48 @S9S_MB_2U_LIB.S9S_MB_2U(SCH_1):PAGE96
   C44    1      A Q_CAP_C0402-2.2UF,6.3V,20%,X6SA   I121 @S9S_MB_2U_LIB.S9S_MB_2U(SCH_1):PAGE96
   J16    3 VIN_MGMT SCONN288_ADR50017P087CC-SCONN2A     I6 @S9S_MB_2U_LIB.S9S_MB_2U(SCH_1):PAGE97
   C47    1      A Q_CAP_C0402-2.2UF,6.3V,20%,X6SA    I56 @S9S_MB_2U_LIB.S9S_MB_2U(SCH_1):PAGE97
   J17    3 VIN_MGMT SCONN288_ADR50017P130CC-SCONN2A    I12 @S9S_MB_2U_LIB.S9S_MB_2U(SCH_1):PAGE98
   C50    1      A Q_CAP_C0402-2.2UF,6.3V,20%,X6SA   I122 @S9S_MB_2U_LIB.S9S_MB_2U(SCH_1):PAGE98
   J18    3 VIN_MGMT SCONN288_ADR50017P087CC-SCONN2A    I24 @S9S_MB_2U_LIB.S9S_MB_2U(SCH_1):PAGE99
   C53    1      A Q_CAP_C0402-2.2UF,6.3V,20%,X6SA   I122 @S9S_MB_2U_LIB.S9S_MB_2U(SCH_1):PAGE99
   J19    3 VIN_MGMT SCONN288_ADR50017P130CC-SCONN2A    I25 @S9S_MB_2U_LIB.S9S_MB_2U(SCH_1):PAGE100
   C56    1      A Q_CAP_C0402-2.2UF,6.3V,20%,X6SA   I121 @S9S_MB_2U_LIB.S9S_MB_2U(SCH_1):PAGE100
   J20    3 VIN_MGMT SCONN288_ADR50017P087CC-SCONN2A    I47 @S9S_MB_2U_LIB.S9S_MB_2U(SCH_1):PAGE101
   C59    1      A Q_CAP_C0402-2.2UF,6.3V,20%,X6SA   I121 @S9S_MB_2U_LIB.S9S_MB_2U(SCH_1):PAGE101
   J21    3 VIN_MGMT SCONN288_ADR50017P130CC-SCONN2A    I13 @S9S_MB_2U_LIB.S9S_MB_2U(SCH_1):PAGE102
   C62    1      A Q_CAP_C0402-2.2UF,6.3V,20%,X6SA   I124 @S9S_MB_2U_LIB.S9S_MB_2U(SCH_1):PAGE102
   J22    3 VIN_MGMT SCONN288_ADR50017P087CC-SCONN2A    I51 @S9S_MB_2U_LIB.S9S_MB_2U(SCH_1):PAGE103
   C65    1      A Q_CAP_C0402-2.2UF,6.3V,20%,X6SA   I122 @S9S_MB_2U_LIB.S9S_MB_2U(SCH_1):PAGE103
   J23    3 VIN_MGMT SCONN288_ADR50017P130CC-SCONN2A    I25 @S9S_MB_2U_LIB.S9S_MB_2U(SCH_1):PAGE104
   C68    1      A Q_CAP_C0402-2.2UF,6.3V,20%,X6SA   I122 @S9S_MB_2U_LIB.S9S_MB_2U(SCH_1):PAGE104
   C96    1      A Q_CAP_C0402-2.2UF,6.3V,20%,X6SA   I123 @S9S_MB_2U_LIB.S9S_MB_2U(SCH_1):PAGE105
   J24    3 VIN_MGMT SCONN288_ADR50017P087CC-SCONN2A   I178 @S9S_MB_2U_LIB.S9S_MB_2U(SCH_1):PAGE105
   C93    1      A Q_CAP_C0402-2.2UF,6.3V,20%,X6SA   I122 @S9S_MB_2U_LIB.S9S_MB_2U(SCH_1):PAGE106
   J25    3 VIN_MGMT SCONN288_ADR50017P130CC-SCONN2A   I180 @S9S_MB_2U_LIB.S9S_MB_2U(SCH_1):PAGE106
   C90    1      A Q_CAP_C0402-2.2UF,6.3V,20%,X6SA   I122 @S9S_MB_2U_LIB.S9S_MB_2U(SCH_1):PAGE107
   J26    3 VIN_MGMT SCONN288_ADR50017P087CC-SCONN2A   I180 @S9S_MB_2U_LIB.S9S_MB_2U(SCH_1):PAGE107
   C87    1      A Q_CAP_C0402-2.2UF,6.3V,20%,X6SA   I121 @S9S_MB_2U_LIB.S9S_MB_2U(SCH_1):PAGE108
   J27    3 VIN_MGMT SCONN288_ADR50017P130CC-SCONN2A   I179 @S9S_MB_2U_LIB.S9S_MB_2U(SCH_1):PAGE108
   J28    3 VIN_MGMT SCONN288_ADR50017P087CC-SCONN2A    I47 @S9S_MB_2U_LIB.S9S_MB_2U(SCH_1):PAGE109
   C84    1      A Q_CAP_C0402-2.2UF,6.3V,20%,X6SA   I121 @S9S_MB_2U_LIB.S9S_MB_2U(SCH_1):PAGE109
   C81    1      A Q_CAP_C0402-2.2UF,6.3V,20%,X6SA   I120 @S9S_MB_2U_LIB.S9S_MB_2U(SCH_1):PAGE110
   J29    3 VIN_MGMT SCONN288_ADR50017P130CC-SCONN2A   I179 @S9S_MB_2U_LIB.S9S_MB_2U(SCH_1):PAGE110
   C78    1      A Q_CAP_C0402-2.2UF,6.3V,20%,X6SA    I54 @S9S_MB_2U_LIB.S9S_MB_2U(SCH_1):PAGE111
   J30    3 VIN_MGMT SCONN288_ADR50017P087CC-SCONN2A   I179 @S9S_MB_2U_LIB.S9S_MB_2U(SCH_1):PAGE111
   C75    1      A Q_CAP_C0402-2.2UF,6.3V,20%,X6SA   I124 @S9S_MB_2U_LIB.S9S_MB_2U(SCH_1):PAGE112
   J31    3 VIN_MGMT SCONN288_ADR50017P130CC-SCONN2A   I180 @S9S_MB_2U_LIB.S9S_MB_2U(SCH_1):PAGE112
   C72    1      A Q_CAP_C0402-2.2UF,6.3V,20%,X6SA   I116 @S9S_MB_2U_LIB.S9S_MB_2U(SCH_1):PAGE113
   J32    3 VIN_MGMT SCONN288_ADR50017P087CC-SCONN2A   I179 @S9S_MB_2U_LIB.S9S_MB_2U(SCH_1):PAGE113
  R274    1      A Q_RES_0402LF-10K,1%,1/16W,CHIPA    I88 @S9S_MB_2U_LIB.S9S_MB_2U(SCH_1):PAGE119
  R273    1      A Q_RES_0402LF-10K,1%,1/16W,CHIPA    I89 @S9S_MB_2U_LIB.S9S_MB_2U(SCH_1):PAGE119
  R272    1      A Q_RES_0402LF-10K,1%,1/16W,CHIPA    I90 @S9S_MB_2U_LIB.S9S_MB_2U(SCH_1):PAGE119
  R271    1      A Q_RES_0402LF-10K,1%,1/16W,CHIPA    I92 @S9S_MB_2U_LIB.S9S_MB_2U(SCH_1):PAGE119
  R270    1      A Q_RES_0402LF-10K,1%,1/16W,CHIPA    I93 @S9S_MB_2U_LIB.S9S_MB_2U(SCH_1):PAGE119
  R283    1      A Q_RES_0402LF-10K,1%,1/16W,CHIPA   I147 @S9S_MB_2U_LIB.S9S_MB_2U(SCH_1):PAGE119
  R284    1      A Q_RES_0402LF-10K,1%,1/16W,CHIPA   I148 @S9S_MB_2U_LIB.S9S_MB_2U(SCH_1):PAGE119
  R285    1      A Q_RES_0402LF-10K,1%,1/16W,CHIPA   I150 @S9S_MB_2U_LIB.S9S_MB_2U(SCH_1):PAGE119
  R286    1      A Q_RES_0402LF-10K,1%,1/16W,CHIPA   I151 @S9S_MB_2U_LIB.S9S_MB_2U(SCH_1):PAGE119
  R287    1      A Q_RES_0402LF-10K,1%,1/16W,CHIPA   I152 @S9S_MB_2U_LIB.S9S_MB_2U(SCH_1):PAGE119
  R335    1      A Q_RES_0402LF-1K,1%,1/16W,EMPTYA     I5 @S9S_MB_2U_LIB.S9S_MB_2U(SCH_1):PAGE127
  R333    1      A Q_RES_0402LF-1K,1%,1/16W,EMPTYA     I6 @S9S_MB_2U_LIB.S9S_MB_2U(SCH_1):PAGE127
  R629    1      A Q_RES_0402LF-1K,1%,1/16W,CHIP,A    I13 @S9S_MB_2U_LIB.S9S_MB_2U(SCH_1):PAGE127
  R627    1      A Q_RES_0402LF-1K,1%,1/16W,EMPTYA    I14 @S9S_MB_2U_LIB.S9S_MB_2U(SCH_1):PAGE127
  R331    1      A Q_RES_0402LF-1K,1%,1/16W,EMPTYA    I20 @S9S_MB_2U_LIB.S9S_MB_2U(SCH_1):PAGE127
  R625    1      A Q_RES_0402LF-1K,1%,1/16W,EMPTYA    I24 @S9S_MB_2U_LIB.S9S_MB_2U(SCH_1):PAGE127
  R650    1      A Q_RES_0402LF-1K,1%,1/16W,CHIP,A    I32 @S9S_MB_2U_LIB.S9S_MB_2U(SCH_1):PAGE127
 R1004    1      A Q_RES_0402LF-1K,1%,1/16W,CHIP,A    I35 @S9S_MB_2U_LIB.S9S_MB_2U(SCH_1):PAGE127
  R778    1      A Q_RES_0402LF-1K,1%,1/16W,CHIP,A    I15 @S9S_MB_2U_LIB.S9S_MB_2U(SCH_1):PAGE133
   J42   52     52 SCONN60_ASP21410801-SCONN60_ASA    I44 @S9S_MB_2U_LIB.S9S_MB_2U(SCH_1):PAGE133
  C551    1      A Q_CAP_C0402-1UF,25V,10%,X6S,CHA   I105 @S9S_MB_2U_LIB.S9S_MB_2U(SCH_1):PAGE133
  R766    1      A Q_RES_0402LF-1K,1%,1/16W,EMPTYA   I111 @S9S_MB_2U_LIB.S9S_MB_2U(SCH_1):PAGE133
  R768    1      A Q_RES_0402LF-1K,1%,1/16W,CHIP,A   I112 @S9S_MB_2U_LIB.S9S_MB_2U(SCH_1):PAGE133
  R767    1      A Q_RES_0402LF-1K,1%,1/16W,CHIP,A   I113 @S9S_MB_2U_LIB.S9S_MB_2U(SCH_1):PAGE133
   U17   14    VCC 74CBTLV3126PW-74CBTLV3126PW,SMA    I80 @S9S_MB_2U_LIB.S9S_MB_2U(SCH_1):PAGE134
  C545    1      A Q_CAP_C0402-1UF,25V,10%,X6S,CHA    I93 @S9S_MB_2U_LIB.S9S_MB_2U(SCH_1):PAGE134
   U18   14    VCC 74CBTLV3126PW-74CBTLV3126PW,SMA   I129 @S9S_MB_2U_LIB.S9S_MB_2U(SCH_1):PAGE134
  C546    1      A Q_CAP_C0402-1UF,25V,10%,X6S,CHA   I135 @S9S_MB_2U_LIB.S9S_MB_2U(SCH_1):PAGE134
   U21    5    VCC NC7SB3157_SMLF-NC7SB3157P6X,NCA    I58 @S9S_MB_2U_LIB.S9S_MB_2U(SCH_1):PAGE135
  C541    1      A Q_CAP_C0402-1UF,25V,10%,X6S,CHA    I61 @S9S_MB_2U_LIB.S9S_MB_2U(SCH_1):PAGE135
  C539    1      A Q_CAP_0402-0.1UF,25V,10%,X7R,CA    I70 @S9S_MB_2U_LIB.S9S_MB_2U(SCH_1):PAGE135
   U22    5    VCC NC7SB3157_SMLF-NC7SB3157P6X,NCA    I71 @S9S_MB_2U_LIB.S9S_MB_2U(SCH_1):PAGE135
  C542    1      A Q_CAP_C0402-1UF,25V,10%,X6S,CHA    I80 @S9S_MB_2U_LIB.S9S_MB_2U(SCH_1):PAGE135
  C540    1      A Q_CAP_0402-0.1UF,25V,10%,X7R,CA    I81 @S9S_MB_2U_LIB.S9S_MB_2U(SCH_1):PAGE135
  C544    1      A Q_CAP_0402-0.1UF,25V,10%,X7R,CA    I94 @S9S_MB_2U_LIB.S9S_MB_2U(SCH_1):PAGE135
   U23    5    VCC 74LVC1G02GW_SMLF-74LVC1G02GW,IA    I96 @S9S_MB_2U_LIB.S9S_MB_2U(SCH_1):PAGE135
  C543    1      A Q_CAP_0402-0.1UF,25V,10%,X7R,CA   I100 @S9S_MB_2U_LIB.S9S_MB_2U(SCH_1):PAGE135
  R740    1      A Q_RES_0402LF-10K,1%,1/16W,CHIPA   I107 @S9S_MB_2U_LIB.S9S_MB_2U(SCH_1):PAGE135
  R739    1      A Q_RES_0402LF-10K,1%,1/16W,CHIPA   I109 @S9S_MB_2U_LIB.S9S_MB_2U(SCH_1):PAGE135
   U86   14    VCC 74CBTLV3126PW-74CBTLV3126PW,SMA    I84 @S9S_MB_2U_LIB.S9S_MB_2U(SCH_1):PAGE137
 C1292    1      A Q_CAP_0402-0.1UF,25V,10%,X7R,CA    I90 @S9S_MB_2U_LIB.S9S_MB_2U(SCH_1):PAGE137
 R1370    1      A Q_RES_0402LF-100,1%,1/16W,CHIPA    I98 @S9S_MB_2U_LIB.S9S_MB_2U(SCH_1):PAGE137
   U85    5    VCC NC7SB3157_SMLF-NC7SB3157P6X,NCA   I109 @S9S_MB_2U_LIB.S9S_MB_2U(SCH_1):PAGE137
 C1289    1      A Q_CAP_C0402-1UF,25V,10%,X6S,CHA   I110 @S9S_MB_2U_LIB.S9S_MB_2U(SCH_1):PAGE137
 C1288    1      A Q_CAP_0402-0.1UF,25V,10%,X7R,CA   I112 @S9S_MB_2U_LIB.S9S_MB_2U(SCH_1):PAGE137
   U75    5    VCC 74LVC1G17GW-74LVC1G17GW,SMLF,IA     I1 @S9S_MB_2U_LIB.S9S_MB_2U(SCH_1):PAGE152
 C1173    1      A Q_CAP_0402-0.1UF,25V,10%,X7R,CA     I4 @S9S_MB_2U_LIB.S9S_MB_2U(SCH_1):PAGE152
 C1175    1      A Q_CAP_0402-0.1UF,25V,10%,X7R,CA    I24 @S9S_MB_2U_LIB.S9S_MB_2U(SCH_1):PAGE152
 R1593    1      A Q_RES_0402LF-4.7K,1%,1/16W,CHIA    I42 @S9S_MB_2U_LIB.S9S_MB_2U(SCH_1):PAGE152
  C188    1      A Q_CAP_0402-0.1UF,25V,10%,X7R,CA    I44 @S9S_MB_2U_LIB.S9S_MB_2U(SCH_1):PAGE152
   U90    6    VDD PI6CV304LE-PI6CV304LE,SMLF,IC,A    I46 @S9S_MB_2U_LIB.S9S_MB_2U(SCH_1):PAGE152
 C1275    1      A Q_CAP_0402-0.1UF,25V,10%,X7R,CA    I49 @S9S_MB_2U_LIB.S9S_MB_2U(SCH_1):PAGE152
 C1274    1      A Q_CAP_0402-0.1UF,25V,10%,X7R,CA    I59 @S9S_MB_2U_LIB.S9S_MB_2U(SCH_1):PAGE152
 R1138    1      A Q_RES_0402LF-10K,1%,1/16W,CHIPA    I61 @S9S_MB_2U_LIB.S9S_MB_2U(SCH_1):PAGE152
  U104    5    VCC 74LVC1G07GV-74LVC1G07GV,SMLF,IA    I63 @S9S_MB_2U_LIB.S9S_MB_2U(SCH_1):PAGE152
  U157    5    VCC 74LVC1G07GV-74LVC1G07GV,SMLF,IA    I65 @S9S_MB_2U_LIB.S9S_MB_2U(SCH_1):PAGE152
 C1663    1      A Q_CAP_0402-0.1UF,25V,10%,X7R,CA    I68 @S9S_MB_2U_LIB.S9S_MB_2U(SCH_1):PAGE152
 R2487    1      A Q_RES_0402LF-4.7K,1%,1/16W,EMPA    I71 @S9S_MB_2U_LIB.S9S_MB_2U(SCH_1):PAGE152
 R2488    1      A Q_RES_0402LF-4.7K,1%,1/16W,CHIA    I74 @S9S_MB_2U_LIB.S9S_MB_2U(SCH_1):PAGE152
 R1127    1      A Q_RES_0402LF-1K,1%,1/16W,EMPTYA   I133 @S9S_MB_2U_LIB.S9S_MB_2U(SCH_1):PAGE154
 R3037    1      A Q_RES_0402LF-1K,1%,1/16W,EMPTYA   I134 @S9S_MB_2U_LIB.S9S_MB_2U(SCH_1):PAGE154
 R1123    1      A Q_RES_0402LF-1K,1%,1/16W,EMPTYA   I142 @S9S_MB_2U_LIB.S9S_MB_2U(SCH_1):PAGE154
  C581    1      A Q_CAP_0402-0.1UF,25V,10%,X7R,CA   I148 @S9S_MB_2U_LIB.S9S_MB_2U(SCH_1):PAGE154
  C578    1      A Q_CAP_0402-0.1UF,25V,10%,X7R,CA   I169 @S9S_MB_2U_LIB.S9S_MB_2U(SCH_1):PAGE154
 R1129    1      A Q_RES_0402LF-1K,1%,1/16W,CHIP,A   I172 @S9S_MB_2U_LIB.S9S_MB_2U(SCH_1):PAGE154
 R1198    1      A Q_RES_0402LF-10K,1%,1/16W,CHIPA    I48 @S9S_MB_2U_LIB.S9S_MB_2U(SCH_1):PAGE174
  R696    1      A Q_RES_0402LF-4.75K,1%,1/16W,CHA    I63 @S9S_MB_2U_LIB.S9S_MB_2U(SCH_1):PAGE174
  R453    1      A Q_RES_0402LF-10K,1%,1/16W,CHIPA    I77 @S9S_MB_2U_LIB.S9S_MB_2U(SCH_1):PAGE174
 R1675    2      B Q_RES_0402LF-2.49K,1%,1/16W,CHA    I82 @S9S_MB_2U_LIB.S9S_MB_2U(SCH_1):PAGE174
 R1451    2      B Q_RES_0402LF-2K,1%,1/16W,CHIP,A   I109 @S9S_MB_2U_LIB.S9S_MB_2U(SCH_1):PAGE175
 R1452    2      B Q_RES_0402LF-2K,1%,1/16W,CHIP,A   I112 @S9S_MB_2U_LIB.S9S_MB_2U(SCH_1):PAGE175
 R1453    2      B Q_RES_0402LF-2K,1%,1/16W,CHIP,A   I120 @S9S_MB_2U_LIB.S9S_MB_2U(SCH_1):PAGE175
 R1454    2      B Q_RES_0402LF-2K,1%,1/16W,CHIP,A   I121 @S9S_MB_2U_LIB.S9S_MB_2U(SCH_1):PAGE175
 R1545    2      B Q_RES_0402LF-2K,1%,1/16W,CHIP,A   I137 @S9S_MB_2U_LIB.S9S_MB_2U(SCH_1):PAGE175
 R1546    2      B Q_RES_0402LF-2K,1%,1/16W,CHIP,A   I138 @S9S_MB_2U_LIB.S9S_MB_2U(SCH_1):PAGE175
 R1582    2      B Q_RES_0402LF-2K,1%,1/16W,CHIP,A   I141 @S9S_MB_2U_LIB.S9S_MB_2U(SCH_1):PAGE175
 R1581    2      B Q_RES_0402LF-2K,1%,1/16W,CHIP,A   I142 @S9S_MB_2U_LIB.S9S_MB_2U(SCH_1):PAGE175
 R1583    2      B Q_RES_0402LF-10K,1%,1/16W,CHIPA   I144 @S9S_MB_2U_LIB.S9S_MB_2U(SCH_1):PAGE175
 R1601    2      B Q_RES_0402LF-10K,1%,1/16W,CHIPA   I151 @S9S_MB_2U_LIB.S9S_MB_2U(SCH_1):PAGE175
 R1659    2      B Q_RES_0402LF-10K,1%,1/16W,CHIPA   I181 @S9S_MB_2U_LIB.S9S_MB_2U(SCH_1):PAGE175
 R1828    2      B Q_RES_0402LF-10K,1%,1/16W,CHIPA   I188 @S9S_MB_2U_LIB.S9S_MB_2U(SCH_1):PAGE175
  R635    2      B Q_RES_0402LF-10K,1%,1/16W,CHIPA   I234 @S9S_MB_2U_LIB.S9S_MB_2U(SCH_1):PAGE175
  R727    2      B Q_RES_0402LF-10K,1%,1/16W,CHIPA   I236 @S9S_MB_2U_LIB.S9S_MB_2U(SCH_1):PAGE175
  R770    2      B Q_RES_0402LF-10K,1%,1/16W,CHIPA   I239 @S9S_MB_2U_LIB.S9S_MB_2U(SCH_1):PAGE175
  R913    2      B Q_RES_0402LF-10K,1%,1/16W,CHIPA   I241 @S9S_MB_2U_LIB.S9S_MB_2U(SCH_1):PAGE175
 R2508    1      A Q_RES_0402LF-10K,1%,1/16W,EMPTA   I173 @S9S_MB_2U_LIB.S9S_MB_2U(SCH_1):PAGE176
 R2510    1      A Q_RES_0402LF-10K,1%,1/16W,EMPTA   I175 @S9S_MB_2U_LIB.S9S_MB_2U(SCH_1):PAGE176
  R498    1      A Q_RES_0402LF-10K,1%,1/16W,CHIPA    I24 @S9S_MB_2U_LIB.S9S_MB_2U(SCH_1):PAGE177
   U62    2      A BAS70057F-BAS70-05-7-F,SMLF,ICA    I64 @S9S_MB_2U_LIB.S9S_MB_2U(SCH_1):PAGE177
    U4 AF17 VCCP_3P3_AF17 EMMITSBURG_REV0P9-GFNOCPU04302A    I11 @S9S_MB_2U_LIB.S9S_MB_2U(SCH_1):PAGE178
    U4 AG17 VCCP_3P3_AG17 EMMITSBURG_REV0P9-GFNOCPU04302A    I11 @S9S_MB_2U_LIB.S9S_MB_2U(SCH_1):PAGE178
    U4 AJ17 VCCP_3P3_AJ17 EMMITSBURG_REV0P9-GFNOCPU04302A    I11 @S9S_MB_2U_LIB.S9S_MB_2U(SCH_1):PAGE178
    U4 AK15 VCCP_3P3_AK15 EMMITSBURG_REV0P9-GFNOCPU04302A    I11 @S9S_MB_2U_LIB.S9S_MB_2U(SCH_1):PAGE178
    U4 AL17 VCCP_3P3_AL17 EMMITSBURG_REV0P9-GFNOCPU04302A    I11 @S9S_MB_2U_LIB.S9S_MB_2U(SCH_1):PAGE178
    U4 AD15 VCCP_3P3_DSW_AD15 EMMITSBURG_REV0P9-GFNOCPU04302A    I11 @S9S_MB_2U_LIB.S9S_MB_2U(SCH_1):PAGE178
    U4  V15 VCCP_3P3_DSW_V15 EMMITSBURG_REV0P9-GFNOCPU04302A    I11 @S9S_MB_2U_LIB.S9S_MB_2U(SCH_1):PAGE178
    U4  P21 VCCP_3P3_P21 EMMITSBURG_REV0P9-GFNOCPU04302A    I11 @S9S_MB_2U_LIB.S9S_MB_2U(SCH_1):PAGE178
    U4  T15 VCCP_GPPD_1P8_3P3 EMMITSBURG_REV0P9-GFNOCPU04302A    I11 @S9S_MB_2U_LIB.S9S_MB_2U(SCH_1):PAGE178
    U4 AN20 VCCP_GPPE_1P8_3P3 EMMITSBURG_REV0P9-GFNOCPU04302A    I11 @S9S_MB_2U_LIB.S9S_MB_2U(SCH_1):PAGE178
    U4 AD17 VCCP_GPPI_1P8_3P3 EMMITSBURG_REV0P9-GFNOCPU04302A    I11 @S9S_MB_2U_LIB.S9S_MB_2U(SCH_1):PAGE178
 C1206    1      A Q_CAP_C0402-10UF,6.3V,20%,X6S,A    I78 @S9S_MB_2U_LIB.S9S_MB_2U(SCH_1):PAGE181
 C1201    1      A Q_CAP_C0603-22UF,6.3V,20%,X6S,A    I87 @S9S_MB_2U_LIB.S9S_MB_2U(SCH_1):PAGE181
 C1191    1      A Q_CAP_C0603-22UF,6.3V,20%,X6S,A    I89 @S9S_MB_2U_LIB.S9S_MB_2U(SCH_1):PAGE181
 C1184    1      A Q_CAP_C0603-22UF,6.3V,20%,X6S,A    I91 @S9S_MB_2U_LIB.S9S_MB_2U(SCH_1):PAGE181
 R1396    2      B Q_RES_0402LF-10K,1%,1/16W,CHIPA   I167 @S9S_MB_2U_LIB.S9S_MB_2U(SCH_1):PAGE182
  R487    1      A Q_RES_0402LF-1K,1%,1/16W,CHIP,A   I173 @S9S_MB_2U_LIB.S9S_MB_2U(SCH_1):PAGE182
  R478    1      A Q_RES_0402LF-4.7K,1%,1/16W,CHIA   I176 @S9S_MB_2U_LIB.S9S_MB_2U(SCH_1):PAGE182
 R1271    1      A Q_RES_0402LF-2.21K,1%,1/16W,EMA     I5 @S9S_MB_2U_LIB.S9S_MB_2U(SCH_1):PAGE183
 C1305    1      A Q_CAP_0402-0.1UF,25V,10%,X7R,CA    I52 @S9S_MB_2U_LIB.S9S_MB_2U(SCH_1):PAGE183
 R1700    1      A Q_RES_0402LF-200K,1%,1/16W,CHIA    I72 @S9S_MB_2U_LIB.S9S_MB_2U(SCH_1):PAGE183
  U142    5    VCC NC7SB3157_SMLF-NC7SB3157P6X,NCA    I35 @S9S_MB_2U_LIB.S9S_MB_2U(SCH_1):PAGE185
 C1612    1      A Q_CAP_C0402-1UF,25V,10%,X6S,CHA    I36 @S9S_MB_2U_LIB.S9S_MB_2U(SCH_1):PAGE185
 R2253    1      A Q_RES_0402LF-4.75K,1%,1/16W,CHA    I39 @S9S_MB_2U_LIB.S9S_MB_2U(SCH_1):PAGE185
  R367    1      A Q_RES_0402LF-1K,1%,1/16W,EMPTYA    I11 @S9S_MB_2U_LIB.S9S_MB_2U(SCH_1):PAGE186
  R369    1      A Q_RES_0402LF-1K,1%,1/16W,CHIP,A    I16 @S9S_MB_2U_LIB.S9S_MB_2U(SCH_1):PAGE186
  R371    1      A Q_RES_0402LF-1K,1%,1/16W,EMPTYA    I45 @S9S_MB_2U_LIB.S9S_MB_2U(SCH_1):PAGE186
  R374    1      A Q_RES_0402LF-1K,1%,1/16W,EMPTYA    I60 @S9S_MB_2U_LIB.S9S_MB_2U(SCH_1):PAGE186
  R502    1      A Q_RES_0402LF-20K,1%,1/16W,CHIPA    I68 @S9S_MB_2U_LIB.S9S_MB_2U(SCH_1):PAGE186
  R378    1      A Q_RES_0402LF-1K,1%,1/16W,EMPTYA    I77 @S9S_MB_2U_LIB.S9S_MB_2U(SCH_1):PAGE186
  R380    1      A Q_RES_0402LF-1K,1%,1/16W,EMPTYA    I78 @S9S_MB_2U_LIB.S9S_MB_2U(SCH_1):PAGE186
 R1809    1      A Q_RES_0402LF-20K,1%,1/16W,CHIPA    I89 @S9S_MB_2U_LIB.S9S_MB_2U(SCH_1):PAGE186
  R623    1      A Q_RES_0402LF-1K,1%,1/16W,EMPTYA    I13 @S9S_MB_2U_LIB.S9S_MB_2U(SCH_1):PAGE187
  R613    1      A Q_RES_0402LF-10K,1%,1/16W,CHIPA    I18 @S9S_MB_2U_LIB.S9S_MB_2U(SCH_1):PAGE187
  R607    1      A Q_RES_0402LF-1K,1%,1/16W,EMPTYA    I21 @S9S_MB_2U_LIB.S9S_MB_2U(SCH_1):PAGE187
  R609    1      A Q_RES_0402LF-1K,1%,1/16W,EMPTYA    I39 @S9S_MB_2U_LIB.S9S_MB_2U(SCH_1):PAGE187
  R611    1      A Q_RES_0402LF-1K,1%,1/16W,CHIP,A    I43 @S9S_MB_2U_LIB.S9S_MB_2U(SCH_1):PAGE187
  R619    1      A Q_RES_0402LF-10K,1%,1/16W,CHIPA    I48 @S9S_MB_2U_LIB.S9S_MB_2U(SCH_1):PAGE187
  R615    1      A Q_RES_0402LF-1K,1%,1/16W,CHIP,A    I51 @S9S_MB_2U_LIB.S9S_MB_2U(SCH_1):PAGE187
  R617    1      A Q_RES_0402LF-1K,1%,1/16W,EMPTYA    I54 @S9S_MB_2U_LIB.S9S_MB_2U(SCH_1):PAGE187
  R621    1      A Q_RES_0402LF-1K,1%,1/16W,EMPTYA    I55 @S9S_MB_2U_LIB.S9S_MB_2U(SCH_1):PAGE187
 R1475    1      A Q_RES_0402LF-1K,1%,1/16W,EMPTYA    I44 @S9S_MB_2U_LIB.S9S_MB_2U(SCH_1):PAGE188
 R1477    1      A Q_RES_0402LF-1K,1%,1/16W,EMPTYA    I47 @S9S_MB_2U_LIB.S9S_MB_2U(SCH_1):PAGE188
 R3038    1      A Q_RES_0402LF-5.11K,1%,1/16W,CHA    I57 @S9S_MB_2U_LIB.S9S_MB_2U(SCH_1):PAGE188
 R1220    1      A Q_RES_0402LF-1K,1%,1/16W,EMPTYA    I63 @S9S_MB_2U_LIB.S9S_MB_2U(SCH_1):PAGE188
 R1496    1      A Q_RES_0402LF-10K,1%,1/16W,CHIPA    I71 @S9S_MB_2U_LIB.S9S_MB_2U(SCH_1):PAGE188
 C1647    1      A Q_CAP_0402-0.1UF,25V,10%,X7R,CA    I84 @S9S_MB_2U_LIB.S9S_MB_2U(SCH_1):PAGE190
 R2451    1      A Q_RES_0402LF-10K,1%,1/16W,EMPTA    I94 @S9S_MB_2U_LIB.S9S_MB_2U(SCH_1):PAGE190
 R1820    1      A Q_RES_0402LF-10K,1%,1/16W,CHIPA    I35 @S9S_MB_2U_LIB.S9S_MB_2U(SCH_1):PAGE191
 R3040    1      A Q_RES_0402LF-1K,1%,1/16W,CHIP,A     I1 @S9S_MB_2U_LIB.S9S_MB_2U(SCH_1):PAGE192
 R1257    1      A Q_RES_0402LF-10K,1%,1/16W,CHIPA     I4 @S9S_MB_2U_LIB.S9S_MB_2U(SCH_1):PAGE192
 R3041    1      A Q_RES_0402LF-10K,1%,1/16W,CHIPA     I6 @S9S_MB_2U_LIB.S9S_MB_2U(SCH_1):PAGE192
 R1259    1      A Q_RES_0402LF-10K,1%,1/16W,CHIPA     I8 @S9S_MB_2U_LIB.S9S_MB_2U(SCH_1):PAGE192
 R1449    1      A Q_RES_0402LF-10K,1%,1/16W,CHIPA    I41 @S9S_MB_2U_LIB.S9S_MB_2U(SCH_1):PAGE192
 R1450    1      A Q_RES_0402LF-10K,1%,1/16W,CHIPA    I42 @S9S_MB_2U_LIB.S9S_MB_2U(SCH_1):PAGE192
 R1458    1      A Q_RES_0402LF-10K,1%,1/16W,CHIPA    I50 @S9S_MB_2U_LIB.S9S_MB_2U(SCH_1):PAGE192
 R1459    1      A Q_RES_0402LF-10K,1%,1/16W,CHIPA    I51 @S9S_MB_2U_LIB.S9S_MB_2U(SCH_1):PAGE192
    R8    1      A Q_RES_0402LF-10K,1%,1/16W,CHIPA    I59 @S9S_MB_2U_LIB.S9S_MB_2U(SCH_1):PAGE192
   R71    1      A Q_RES_0402LF-10K,1%,1/16W,CHIPA    I60 @S9S_MB_2U_LIB.S9S_MB_2U(SCH_1):PAGE192
 R1554    1      A Q_RES_0402LF-10K,1%,1/16W,CHIPA    I62 @S9S_MB_2U_LIB.S9S_MB_2U(SCH_1):PAGE192
  R456    1      A Q_RES_0402LF-10K,1%,1/16W,CHIPA    I66 @S9S_MB_2U_LIB.S9S_MB_2U(SCH_1):PAGE192
  R401    1      A Q_RES_0402LF-10K,1%,1/16W,EMPTA    I69 @S9S_MB_2U_LIB.S9S_MB_2U(SCH_1):PAGE192
 R1955    1      A Q_RES_0402LF-10K,1%,1/16W,CHIPA    I72 @S9S_MB_2U_LIB.S9S_MB_2U(SCH_1):PAGE192
 R2342    1      A Q_RES_0402LF-10K,1%,1/16W,CHIPA    I75 @S9S_MB_2U_LIB.S9S_MB_2U(SCH_1):PAGE192
 R1483    1      A Q_RES_0402LF-10K,1%,1/16W,EMPTA   I265 @S9S_MB_2U_LIB.S9S_MB_2U(SCH_1):PAGE197
 R1471    1      A Q_RES_0402LF-4.75K,1%,1/16W,CHA   I267 @S9S_MB_2U_LIB.S9S_MB_2U(SCH_1):PAGE197
 R1305    1      A Q_RES_0402LF-10K,1%,1/16W,EMPTA   I272 @S9S_MB_2U_LIB.S9S_MB_2U(SCH_1):PAGE197
 R1204    1      A Q_RES_0402LF-10K,1%,1/16W,EMPTA   I273 @S9S_MB_2U_LIB.S9S_MB_2U(SCH_1):PAGE197
 R1194    1      A Q_RES_0402LF-4.75K,1%,1/16W,EMA   I277 @S9S_MB_2U_LIB.S9S_MB_2U(SCH_1):PAGE197
  R912    1      A Q_RES_0402LF-4.75K,1%,1/16W,EMA   I278 @S9S_MB_2U_LIB.S9S_MB_2U(SCH_1):PAGE197
 R2481    1      A Q_RES_0402LF-4.75K,1%,1/16W,EMA   I280 @S9S_MB_2U_LIB.S9S_MB_2U(SCH_1):PAGE197
 R1958    1      A Q_RES_0402LF-10K,1%,1/16W,CHIPA   I303 @S9S_MB_2U_LIB.S9S_MB_2U(SCH_1):PAGE197
    L1    1      1 Q_INDUCTOR_SMLF-FCM2012KF-601TA    I20 @S9S_MB_2U_LIB.S9S_MB_2U(SCH_1):PAGE199
   L13    1      1 Q_INDUCTOR_SMLF-FCM2012KF-601TA    I41 @S9S_MB_2U_LIB.S9S_MB_2U(SCH_1):PAGE199
   L14    1      1 Q_INDUCTOR_SMLF-FCM2012KF-601TA    I60 @S9S_MB_2U_LIB.S9S_MB_2U(SCH_1):PAGE199
  R929    1      A Q_RES_0402LF-10K,1%,1/16W,CHIPA    I59 @S9S_MB_2U_LIB.S9S_MB_2U(SCH_1):PAGE210
  R928    1      A Q_RES_0402LF-10K,1%,1/16W,CHIPA    I60 @S9S_MB_2U_LIB.S9S_MB_2U(SCH_1):PAGE210
  R927    1      A Q_RES_0402LF-10K,1%,1/16W,CHIPA    I61 @S9S_MB_2U_LIB.S9S_MB_2U(SCH_1):PAGE210
  R919    1      A Q_RES_0402LF-10K,1%,1/16W,CHIPA    I75 @S9S_MB_2U_LIB.S9S_MB_2U(SCH_1):PAGE210
  R538    1      A Q_RES_0402LF-10K,1%,1/16W,EMPTA     I9 @S9S_MB_2U_LIB.S9S_MB_2U(SCH_1):PAGE219
  R540    1      A Q_RES_0402LF-10K,1%,1/16W,EMPTA    I10 @S9S_MB_2U_LIB.S9S_MB_2U(SCH_1):PAGE219
  C561    1      A Q_CAP_0402-0.1UF,25V,10%,X7R,CA    I18 @S9S_MB_2U_LIB.S9S_MB_2U(SCH_1):PAGE223
  C562    1      A Q_CAP_0402-0.1UF,25V,10%,X7R,CA    I31 @S9S_MB_2U_LIB.S9S_MB_2U(SCH_1):PAGE223
   U28    8   VCCB PCA9617ADP-PCA9617ADP,SMLF,IC,A    I39 @S9S_MB_2U_LIB.S9S_MB_2U(SCH_1):PAGE223
   U29    8   VCCB PCA9617ADP-PCA9617ADP,SMLF,IC,A    I43 @S9S_MB_2U_LIB.S9S_MB_2U(SCH_1):PAGE223
  R968    1      A Q_RES_0402LF-1K,1%,1/16W,CHIP,A    I81 @S9S_MB_2U_LIB.S9S_MB_2U(SCH_1):PAGE223
  R966    1      A Q_RES_0402LF-1K,1%,1/16W,CHIP,A    I82 @S9S_MB_2U_LIB.S9S_MB_2U(SCH_1):PAGE223
  R965    1      A Q_RES_0402LF-1K,1%,1/16W,CHIP,A    I93 @S9S_MB_2U_LIB.S9S_MB_2U(SCH_1):PAGE223
  R967    1      A Q_RES_0402LF-1K,1%,1/16W,CHIP,A    I94 @S9S_MB_2U_LIB.S9S_MB_2U(SCH_1):PAGE223
  R979    1      A Q_RES_0402LF-560,1%,1/16W,CHIPA     I6 @S9S_MB_2U_LIB.S9S_MB_2U(SCH_1):PAGE224
  R977    1      A Q_RES_0402LF-560,1%,1/16W,CHIPA     I8 @S9S_MB_2U_LIB.S9S_MB_2U(SCH_1):PAGE224
  R980    1      A Q_RES_0402LF-560,1%,1/16W,CHIPA    I14 @S9S_MB_2U_LIB.S9S_MB_2U(SCH_1):PAGE224
  R978    1      A Q_RES_0402LF-560,1%,1/16W,CHIPA    I16 @S9S_MB_2U_LIB.S9S_MB_2U(SCH_1):PAGE224
  C569    1      A Q_CAP_0402-0.1UF,25V,10%,X7R,CA    I22 @S9S_MB_2U_LIB.S9S_MB_2U(SCH_1):PAGE224
   U30    8   VCCB PCA9517AD-PCA9517AD,SMLF,IC,ALA    I28 @S9S_MB_2U_LIB.S9S_MB_2U(SCH_1):PAGE224
  C570    1      A Q_CAP_0402-0.1UF,25V,10%,X7R,CA    I33 @S9S_MB_2U_LIB.S9S_MB_2U(SCH_1):PAGE224
   U31    8   VCCB PCA9517AD-PCA9517AD,SMLF,IC,ALA    I37 @S9S_MB_2U_LIB.S9S_MB_2U(SCH_1):PAGE224
 C1613    1      A Q_CAP_0402-0.1UF,25V,10%,X7R,CA    I68 @S9S_MB_2U_LIB.S9S_MB_2U(SCH_1):PAGE224
 R2310    1      A Q_RES_0402LF-10K,1%,1/16W,EMPTA    I83 @S9S_MB_2U_LIB.S9S_MB_2U(SCH_1):PAGE224
 R2308    1      A Q_RES_0402LF-10K,1%,1/16W,EMPTA    I84 @S9S_MB_2U_LIB.S9S_MB_2U(SCH_1):PAGE224
 R2312    1      A Q_RES_0402LF-10K,1%,1/16W,CHIPA   I101 @S9S_MB_2U_LIB.S9S_MB_2U(SCH_1):PAGE224
 R2315    1      A Q_RES_0402LF-10K,1%,1/16W,CHIPA   I103 @S9S_MB_2U_LIB.S9S_MB_2U(SCH_1):PAGE224
 R1383    1      A Q_RES_0402LF-1K,1%,1/16W,CHIP,A     I1 @S9S_MB_2U_LIB.S9S_MB_2U(SCH_1):PAGE226
 R1381    1      A Q_RES_0402LF-1K,1%,1/16W,CHIP,A     I7 @S9S_MB_2U_LIB.S9S_MB_2U(SCH_1):PAGE226
 R3055    1      A Q_RES_0402LF-1K,1%,1/16W,CHIP,A    I11 @S9S_MB_2U_LIB.S9S_MB_2U(SCH_1):PAGE226
 C1291    1      A Q_CAP_C0402-1UF,25V,10%,X6S,CHA    I16 @S9S_MB_2U_LIB.S9S_MB_2U(SCH_1):PAGE226
   U84   14    VCC GTL2014PW-GTL2014PW,SMLF,IC,ALA    I18 @S9S_MB_2U_LIB.S9S_MB_2U(SCH_1):PAGE226
 R1382    1      A Q_RES_0402LF-1K,1%,1/16W,CHIP,A    I20 @S9S_MB_2U_LIB.S9S_MB_2U(SCH_1):PAGE226
 C1322    1      A Q_CAP_0402-0.1UF,25V,10%,X7R,CA    I27 @S9S_MB_2U_LIB.S9S_MB_2U(SCH_1):PAGE226
 R1380    1      A Q_RES_0402LF-1K,1%,1/16W,CHIP,A    I31 @S9S_MB_2U_LIB.S9S_MB_2U(SCH_1):PAGE226
   U97   10    VCC NX3L2267GM-NX3L2267GM,SMLF,IC,A    I38 @S9S_MB_2U_LIB.S9S_MB_2U(SCH_1):PAGE226
 C1290    1      A Q_CAP_C0402-1UF,25V,10%,X6S,CHA    I43 @S9S_MB_2U_LIB.S9S_MB_2U(SCH_1):PAGE226
   U83   14    VCC GTL2014PW-GTL2014PW,SMLF,IC,ALA    I45 @S9S_MB_2U_LIB.S9S_MB_2U(SCH_1):PAGE226
 C1321    1      A Q_CAP_0402-0.1UF,25V,10%,X7R,CA    I55 @S9S_MB_2U_LIB.S9S_MB_2U(SCH_1):PAGE226
   U96   10    VCC NX3L2267GM-NX3L2267GM,SMLF,IC,A    I68 @S9S_MB_2U_LIB.S9S_MB_2U(SCH_1):PAGE226
 R1813    1      A Q_RES_0402LF-10K,1%,1/16W,EMPTA    I79 @S9S_MB_2U_LIB.S9S_MB_2U(SCH_1):PAGE226
 R2506    1      A Q_RES_0402LF-1K,1%,1/16W,CHIP,A    I87 @S9S_MB_2U_LIB.S9S_MB_2U(SCH_1):PAGE226
 R2507    1      A Q_RES_0402LF-1K,1%,1/16W,CHIP,A    I88 @S9S_MB_2U_LIB.S9S_MB_2U(SCH_1):PAGE226
 R1319    2      B Q_RES_0402LF-2K,1%,1/16W,EMPTYA     I2 @S9S_MB_2U_LIB.S9S_MB_2U(SCH_1):PAGE228
 R3062    2      B Q_RES_0402LF-2K,1%,1/16W,EMPTYA     I3 @S9S_MB_2U_LIB.S9S_MB_2U(SCH_1):PAGE228
 R1384    2      B Q_RES_0402LF-2K,1%,1/16W,EMPTYA     I4 @S9S_MB_2U_LIB.S9S_MB_2U(SCH_1):PAGE228
 R1385    2      B Q_RES_0402LF-2K,1%,1/16W,EMPTYA     I5 @S9S_MB_2U_LIB.S9S_MB_2U(SCH_1):PAGE228
 R1386    2      B Q_RES_0402LF-2K,1%,1/16W,EMPTYA     I6 @S9S_MB_2U_LIB.S9S_MB_2U(SCH_1):PAGE228
 R1387    2      B Q_RES_0402LF-2K,1%,1/16W,EMPTYA     I7 @S9S_MB_2U_LIB.S9S_MB_2U(SCH_1):PAGE228
  R601    2      B Q_RES_0402LF-2.2K,5%,1/16W,EMPA   I172 @S9S_MB_2U_LIB.S9S_MB_2U(SCH_1):PAGE228
  R592    2      B Q_RES_0402LF-2.2K,5%,1/16W,EMPA   I173 @S9S_MB_2U_LIB.S9S_MB_2U(SCH_1):PAGE228
 R1460    2      B Q_RES_0402LF-2.2K,5%,1/16W,EMPA   I176 @S9S_MB_2U_LIB.S9S_MB_2U(SCH_1):PAGE228
 R1336    2      B Q_RES_0402LF-2.2K,5%,1/16W,EMPA   I177 @S9S_MB_2U_LIB.S9S_MB_2U(SCH_1):PAGE228
 R2212    2      B Q_RES_0402LF-2.2K,5%,1/16W,EMPA   I202 @S9S_MB_2U_LIB.S9S_MB_2U(SCH_1):PAGE228
 R2213    2      B Q_RES_0402LF-2.2K,5%,1/16W,EMPA   I203 @S9S_MB_2U_LIB.S9S_MB_2U(SCH_1):PAGE228
   U64    8    VCC M24128BWMN6TP-M24128-BWMN6TP,SA    I35 @S9S_MB_2U_LIB.S9S_MB_2U(SCH_1):PAGE231
  R717    1      A Q_RES_0402LF-10K,1%,1/16W,EMPTA    I45 @S9S_MB_2U_LIB.S9S_MB_2U(SCH_1):PAGE231
  R713    1      A Q_RES_0402LF-10K,1%,1/16W,EMPTA    I47 @S9S_MB_2U_LIB.S9S_MB_2U(SCH_1):PAGE231
  C629    1      A Q_CAP_0402-0.1UF,25V,10%,X7R,CA    I55 @S9S_MB_2U_LIB.S9S_MB_2U(SCH_1):PAGE231
  R721    1      A Q_RES_0402LF-10K,1%,1/16W,CHIPA    I62 @S9S_MB_2U_LIB.S9S_MB_2U(SCH_1):PAGE231
 R1332    1      A Q_RES_0402LF-4.7K,5%,1/16W,EMPA    I93 @S9S_MB_2U_LIB.S9S_MB_2U(SCH_1):PAGE231
 R1331    1      A Q_RES_0402LF-4.7K,5%,1/16W,EMPA    I95 @S9S_MB_2U_LIB.S9S_MB_2U(SCH_1):PAGE231
 R1691    1      A Q_RES_0402LF-10K,1%,1/16W,EMPTA     I4 @S9S_MB_2U_LIB.S9S_MB_2U(SCH_1):PAGE232
 R1694    1      A Q_RES_0402LF-10K,1%,1/16W,CHIPA    I33 @S9S_MB_2U_LIB.S9S_MB_2U(SCH_1):PAGE232
 R1765    2      B Q_RES_0805LF-0,5%,1/8W,EMPTY,CA    I13 @S9S_MB_2U_LIB.S9S_MB_2U(SCH_1):PAGE243
 R2375    1      A Q_RES_0402LF-1K,1%,1/16W,CHIP,A    I19 @S9S_MB_2U_LIB.S9S_MB_2U(SCH_1):PAGE252
 R2383    1      A Q_RES_0402LF-1K,1%,1/16W,CHIP,A    I59 @S9S_MB_2U_LIB.S9S_MB_2U(SCH_1):PAGE260
  R361    1      A Q_RES_0402LF-1K,1%,1/16W,CHIP,A    I46 @S9S_MB_2U_LIB.S9S_MB_2U(SCH_1):PAGE264
 C1708    1      A Q_CAP_0402-0.1UF,25V,10%,EMPTYA    I34 @S9S_MB_2U_LIB.S9S_MB_2U(SCH_1):PAGE222
 R2835    1      A Q_RES_0402LF-4.7K,5%,1/16W,CHIA    I14 @S9S_MB_2U_LIB.S9S_MB_2U(SCH_1):PAGE145
 R2834    1      A Q_RES_0402LF-4.7K,5%,1/16W,CHIA    I18 @S9S_MB_2U_LIB.S9S_MB_2U(SCH_1):PAGE145
 R2836    1      A Q_RES_0402LF-4.7K,5%,1/16W,CHIA    I19 @S9S_MB_2U_LIB.S9S_MB_2U(SCH_1):PAGE145
 R2841    1      A Q_RES_0402LF-4.7K,5%,1/16W,CHIA    I24 @S9S_MB_2U_LIB.S9S_MB_2U(SCH_1):PAGE145
 R2842    1      A Q_RES_0402LF-4.7K,5%,1/16W,CHIA    I30 @S9S_MB_2U_LIB.S9S_MB_2U(SCH_1):PAGE145
 R2828    1      A Q_RES_0402LF-100K,1%,1/16W,CHIA    I66 @S9S_MB_2U_LIB.S9S_MB_2U(SCH_1):PAGE145
 R2832    1      A Q_RES_0402LF-100K,1%,1/16W,CHIA    I67 @S9S_MB_2U_LIB.S9S_MB_2U(SCH_1):PAGE145
 R2830    1      A Q_RES_0402LF-100K,1%,1/16W,CHIA    I68 @S9S_MB_2U_LIB.S9S_MB_2U(SCH_1):PAGE145
 C1766    1      A Q_CAP_0402-0.1UF,25V,10%,X7R,CA    I66 @S9S_MB_2U_LIB.S9S_MB_2U(SCH_1):PAGE222
   L15    2      2 Q_INDUCTOR_SMLF-BLM18PG300SN1DA    I62 @S9S_MB_2U_LIB.S9S_MB_2U(SCH_1):PAGE239
  U210    5    VCC 74LVC1G08W57-74LVC1G08W5-7,SMLA   I189 @S9S_MB_2U_LIB.S9S_MB_2U(SCH_1):PAGE154
  U208    5    VCC 74LVC1G08W57-74LVC1G08W5-7,SMLA   I190 @S9S_MB_2U_LIB.S9S_MB_2U(SCH_1):PAGE154
 R2837    1      A Q_RES_0402LF-100K,1%,1/16W,EMPA    I80 @S9S_MB_2U_LIB.S9S_MB_2U(SCH_1):PAGE145
  U181   24    VDD PCA9539RPW-PCA9539RPW,SMLF,IC,A    I66 @S9S_MB_2U_LIB.S9S_MB_2U(SCH_1):PAGE214
 R2695    1      A Q_RES_0402LF-1K,1%,1/16W,EMPTYA    I74 @S9S_MB_2U_LIB.S9S_MB_2U(SCH_1):PAGE214
 R2693    1      A Q_RES_0402LF-1K,1%,1/16W,EMPTYA    I76 @S9S_MB_2U_LIB.S9S_MB_2U(SCH_1):PAGE214
 C1713    1      A Q_CAP_0402-0.1UF,25V,10%,X7R,CA    I87 @S9S_MB_2U_LIB.S9S_MB_2U(SCH_1):PAGE214
 R2923    1      A Q_RES_0402LF-4.7K,5%,1/16W,EMPA    I90 @S9S_MB_2U_LIB.S9S_MB_2U(SCH_1):PAGE214
 R2921    1      A Q_RES_0402LF-10K,1%,1/16W,EMPTA    I93 @S9S_MB_2U_LIB.S9S_MB_2U(SCH_1):PAGE214
  U195    5    VCC 74LVC2G17GW-74LVC2G17GW,SMLF,IA    I65 @S9S_MB_2U_LIB.S9S_MB_2U(SCH_1):PAGE140
 R2815    1      A Q_RES_0402LF-100K,1%,1/16W,EMPA    I68 @S9S_MB_2U_LIB.S9S_MB_2U(SCH_1):PAGE140
 R2820    1      A Q_RES_0402LF-4.7K,5%,1/16W,EMPA    I78 @S9S_MB_2U_LIB.S9S_MB_2U(SCH_1):PAGE140
 C1769    1      A Q_CAP_0402-0.1UF,25V,10%,X7R,CA    I89 @S9S_MB_2U_LIB.S9S_MB_2U(SCH_1):PAGE140
  U196    5    VCC 74LVC2G17GW-74LVC2G17GW,SMLF,IA   I127 @S9S_MB_2U_LIB.S9S_MB_2U(SCH_1):PAGE140
 C1770    1      A Q_CAP_0402-0.1UF,25V,10%,X7R,CA   I140 @S9S_MB_2U_LIB.S9S_MB_2U(SCH_1):PAGE140
 R2912    1      A Q_RES_0402LF-4.7K,5%,1/16W,EMPA   I147 @S9S_MB_2U_LIB.S9S_MB_2U(SCH_1):PAGE140
 R2911    1      A Q_RES_0402LF-4.7K,5%,1/16W,EMPA   I153 @S9S_MB_2U_LIB.S9S_MB_2U(SCH_1):PAGE140
 R2920    1      A Q_RES_0402LF-4.7K,5%,1/16W,CHIA    I84 @S9S_MB_2U_LIB.S9S_MB_2U(SCH_1):PAGE145
 R2919    1      A Q_RES_0402LF-4.7K,5%,1/16W,CHIA    I91 @S9S_MB_2U_LIB.S9S_MB_2U(SCH_1):PAGE145
 R2933    1      A Q_RES_0402LF-4.7K,5%,1/16W,CHIA    I97 @S9S_MB_2U_LIB.S9S_MB_2U(SCH_1):PAGE145
 R2934    1      A Q_RES_0402LF-4.7K,5%,1/16W,CHIA   I101 @S9S_MB_2U_LIB.S9S_MB_2U(SCH_1):PAGE145
 R2935    1      A Q_RES_0402LF-4.7K,5%,1/16W,CHIA   I109 @S9S_MB_2U_LIB.S9S_MB_2U(SCH_1):PAGE145
 R2936    1      A Q_RES_0402LF-100K,1%,1/16W,EMPA   I162 @S9S_MB_2U_LIB.S9S_MB_2U(SCH_1):PAGE140
 C1775    1      A Q_CAP_0402-0.1UF,25V,10%,X7R,CA    I14 @S9S_MB_2U_LIB.S9S_MB_2U(SCH_1):PAGE230
 R2946    1      A Q_RES_0402LF-4.7K,5%,1/16W,EMPA    I25 @S9S_MB_2U_LIB.S9S_MB_2U(SCH_1):PAGE230
 R2940    1      A Q_RES_0402LF-4.7K,5%,1/16W,EMPA    I28 @S9S_MB_2U_LIB.S9S_MB_2U(SCH_1):PAGE230
 U5201   12    VCC TUSB211IRWBR-TUSB211IRWBR,SMLFA    I84 @S9S_MB_2U_LIB.S9S_MB_2U(SCH_1):PAGE155
 C5229    1      A Q_CAP_C0402-1UF,25V,10%,EMPTY,A    I88 @S9S_MB_2U_LIB.S9S_MB_2U(SCH_1):PAGE155
 C5234    1      A Q_CAP_0402-0.1UF,25V,10%,EMPTYA    I92 @S9S_MB_2U_LIB.S9S_MB_2U(SCH_1):PAGE155
 R3004    2      B Q_RES_0402LF-2.2K,5%,1/16W,EMPA   I230 @S9S_MB_2U_LIB.S9S_MB_2U(SCH_1):PAGE228
 R2999    2      B Q_RES_0402LF-2.2K,5%,1/16W,EMPA   I231 @S9S_MB_2U_LIB.S9S_MB_2U(SCH_1):PAGE228
 R3035    1      A Q_RES_0402LF-4.7K,5%,1/16W,CHIA   I127 @S9S_MB_2U_LIB.S9S_MB_2U(SCH_1):PAGE145
 R3034    1      A Q_RES_0402LF-4.7K,5%,1/16W,CHIA   I129 @S9S_MB_2U_LIB.S9S_MB_2U(SCH_1):PAGE145
 R3029    1      A Q_RES_0402LF-4.7K,5%,1/16W,CHIA   I144 @S9S_MB_2U_LIB.S9S_MB_2U(SCH_1):PAGE145
 R3030    1      A Q_RES_0402LF-4.7K,5%,1/16W,CHIA   I146 @S9S_MB_2U_LIB.S9S_MB_2U(SCH_1):PAGE145
 R1371    2      B Q_RES_0402LF-130,1%,1/16W,CHIPA    I49 @S9S_MB_2U_LIB.S9S_MB_2U(SCH_1):PAGE304
 R3080    2      B Q_RES_0402LF-130,1%,1/16W,CHIPA    I50 @S9S_MB_2U_LIB.S9S_MB_2U(SCH_1):PAGE304
 R3079    2      B Q_RES_0402LF-130,1%,1/16W,CHIPA    I51 @S9S_MB_2U_LIB.S9S_MB_2U(SCH_1):PAGE304
 R3081    2      B Q_RES_0402LF-130,1%,1/16W,CHIPA    I52 @S9S_MB_2U_LIB.S9S_MB_2U(SCH_1):PAGE304
 R3084    2      B Q_RES_0402LF-130,1%,1/16W,CHIPA    I53 @S9S_MB_2U_LIB.S9S_MB_2U(SCH_1):PAGE304
 R3082    2      B Q_RES_0402LF-130,1%,1/16W,CHIPA    I54 @S9S_MB_2U_LIB.S9S_MB_2U(SCH_1):PAGE304
 R3083    2      B Q_RES_0402LF-130,1%,1/16W,CHIPA    I57 @S9S_MB_2U_LIB.S9S_MB_2U(SCH_1):PAGE304
 R3086    2      B Q_RES_0402LF-130,1%,1/16W,CHIPA    I49 @S9S_MB_2U_LIB.S9S_MB_2U(SCH_1):PAGE305
 R3087    2      B Q_RES_0402LF-130,1%,1/16W,CHIPA    I50 @S9S_MB_2U_LIB.S9S_MB_2U(SCH_1):PAGE305
 R3089    2      B Q_RES_0402LF-130,1%,1/16W,CHIPA    I51 @S9S_MB_2U_LIB.S9S_MB_2U(SCH_1):PAGE305
 R3088    2      B Q_RES_0402LF-130,1%,1/16W,CHIPA    I52 @S9S_MB_2U_LIB.S9S_MB_2U(SCH_1):PAGE305
 R3091    2      B Q_RES_0402LF-130,1%,1/16W,CHIPA    I53 @S9S_MB_2U_LIB.S9S_MB_2U(SCH_1):PAGE305
 R3090    2      B Q_RES_0402LF-130,1%,1/16W,CHIPA    I54 @S9S_MB_2U_LIB.S9S_MB_2U(SCH_1):PAGE305
 R3092    2      B Q_RES_0402LF-130,1%,1/16W,CHIPA    I55 @S9S_MB_2U_LIB.S9S_MB_2U(SCH_1):PAGE305
 R3095    2      B Q_RES_0402LF-130,1%,1/16W,CHIPA    I12 @S9S_MB_2U_LIB.S9S_MB_2U(SCH_1):PAGE306
 R3096    2      B Q_RES_0402LF-130,1%,1/16W,CHIPA    I15 @S9S_MB_2U_LIB.S9S_MB_2U(SCH_1):PAGE306
 R3094    2      B Q_RES_0402LF-130,1%,1/16W,CHIPA    I16 @S9S_MB_2U_LIB.S9S_MB_2U(SCH_1):PAGE306
 R3093    2      B Q_RES_0402LF-130,1%,1/16W,CHIPA    I20 @S9S_MB_2U_LIB.S9S_MB_2U(SCH_1):PAGE306
 R3098    2      B Q_RES_0402LF-130,1%,1/16W,CHIPA    I37 @S9S_MB_2U_LIB.S9S_MB_2U(SCH_1):PAGE306
 R3097    2      B Q_RES_0402LF-130,1%,1/16W,CHIPA    I38 @S9S_MB_2U_LIB.S9S_MB_2U(SCH_1):PAGE306
 R3099    2      B Q_RES_0402LF-130,1%,1/16W,CHIPA    I41 @S9S_MB_2U_LIB.S9S_MB_2U(SCH_1):PAGE306
 R3068    2      B Q_RES_0402LF-130,1%,1/16W,CHIPA    I38 @S9S_MB_2U_LIB.S9S_MB_2U(SCH_1):PAGE241
 R3069    2      B Q_RES_0402LF-130,1%,1/16W,CHIPA    I39 @S9S_MB_2U_LIB.S9S_MB_2U(SCH_1):PAGE241
 R1044    2      B Q_RES_0402LF-130,1%,1/16W,CHIPA    I40 @S9S_MB_2U_LIB.S9S_MB_2U(SCH_1):PAGE241
 R3070    2      B Q_RES_0402LF-130,1%,1/16W,CHIPA    I41 @S9S_MB_2U_LIB.S9S_MB_2U(SCH_1):PAGE241
 R3073    2      B Q_RES_0402LF-130,1%,1/16W,CHIPA    I12 @S9S_MB_2U_LIB.S9S_MB_2U(SCH_1):PAGE242
 R3074    2      B Q_RES_0402LF-130,1%,1/16W,CHIPA    I14 @S9S_MB_2U_LIB.S9S_MB_2U(SCH_1):PAGE242
 R3072    2      B Q_RES_0402LF-130,1%,1/16W,CHIPA    I15 @S9S_MB_2U_LIB.S9S_MB_2U(SCH_1):PAGE242
 R3071    2      B Q_RES_0402LF-130,1%,1/16W,CHIPA    I19 @S9S_MB_2U_LIB.S9S_MB_2U(SCH_1):PAGE242
 R3075    2      B Q_RES_0402LF-130,1%,1/16W,CHIPA    I37 @S9S_MB_2U_LIB.S9S_MB_2U(SCH_1):PAGE242
 R3078    2      B Q_RES_0402LF-130,1%,1/16W,CHIPA    I41 @S9S_MB_2U_LIB.S9S_MB_2U(SCH_1):PAGE242
 R3085    2      B Q_RES_0402LF-130,1%,1/16W,CHIPA    I62 @S9S_MB_2U_LIB.S9S_MB_2U(SCH_1):PAGE304
  OSC1    4    VDD Q_OSC4P_SMLF-50MHZ,OSC,BF65000A    I76 @S9S_MB_2U_LIB.S9S_MB_2U(SCH_1):PAGE152
    J3    3 VIN_MGMT SCONN288_ADR50017P130CC-SCONN2A   I180 @S9S_MB_2U_LIB.S9S_MB_2U(SCH_1):PAGE84
  C579    1      A Q_CAP_0402-0.1UF,25V,10%,X7R,CA   I192 @S9S_MB_2U_LIB.S9S_MB_2U(SCH_1):PAGE154
  U143   20    VDD PCA9545APW-PCA9545APW,SMLF,IC,A   I106 @S9S_MB_2U_LIB.S9S_MB_2U(SCH_1):PAGE224
 R3127    1      A Q_RES_0402LF-10K,1%,1/16W,CHIPA   I109 @S9S_MB_2U_LIB.S9S_MB_2U(SCH_1):PAGE224
 R3130    1      A Q_RES_0402LF-10K,1%,1/16W,CHIPA   I110 @S9S_MB_2U_LIB.S9S_MB_2U(SCH_1):PAGE224
 R3131    1      A Q_RES_0402LF-10K,1%,1/16W,CHIPA   I111 @S9S_MB_2U_LIB.S9S_MB_2U(SCH_1):PAGE224
 C1809    1      A Q_CAP_0402-0.1UF,25V,10%,X7R,CA    I26 @S9S_MB_2U_LIB.S9S_MB_2U(SCH_1):PAGE131
 R3155    1      A Q_RES_0402LF-1K,1%,1/16W,CHIP,A     I7 @S9S_MB_2U_LIB.S9S_MB_2U(SCH_1):PAGE132
   U50    5    VCC 74LVC1G08W57-74LVC1G08W5-7,SMLA     I9 @S9S_MB_2U_LIB.S9S_MB_2U(SCH_1):PAGE132
 C1818    1      A Q_CAP_0402-0.1UF,25V,10%,X7R,CA    I15 @S9S_MB_2U_LIB.S9S_MB_2U(SCH_1):PAGE132
 R3149    1      A Q_RES_0402LF-1K,1%,1/16W,EMPTYA    I29 @S9S_MB_2U_LIB.S9S_MB_2U(SCH_1):PAGE132
 R3153    1      A Q_RES_0402LF-1K,1%,1/16W,EMPTYA    I32 @S9S_MB_2U_LIB.S9S_MB_2U(SCH_1):PAGE132
   U53    5    VCC 74LVC1G08W57-74LVC1G08W5-7,SMLA    I56 @S9S_MB_2U_LIB.S9S_MB_2U(SCH_1):PAGE132
 R3151    1      A Q_RES_0402LF-1K,1%,1/16W,EMPTYA    I31 @S9S_MB_2U_LIB.S9S_MB_2U(SCH_1):PAGE132
 C1817    1      A Q_CAP_0402-0.1UF,25V,10%,X7R,CA    I39 @S9S_MB_2U_LIB.S9S_MB_2U(SCH_1):PAGE132
 C1820    1      A Q_CAP_0402-0.1UF,25V,10%,X7R,CA    I58 @S9S_MB_2U_LIB.S9S_MB_2U(SCH_1):PAGE132
 C1821    1      A Q_CAP_0402-0.1UF,25V,10%,X7R,CA    I12 @S9S_MB_2U_LIB.S9S_MB_2U(SCH_1):PAGE156
 C1822    1      A Q_CAP_0402-0.1UF,25V,10%,X7R,CA    I27 @S9S_MB_2U_LIB.S9S_MB_2U(SCH_1):PAGE156
 R3184    1      A Q_RES_0402LF-4.7K,1%,1/16W,CHIA    I28 @S9S_MB_2U_LIB.S9S_MB_2U(SCH_1):PAGE156
  U218    5    VCC 74LVC1G07GV-74LVC1G07GV,SMLF,IA    I31 @S9S_MB_2U_LIB.S9S_MB_2U(SCH_1):PAGE156
 C1823    1      A Q_CAP_0402-0.1UF,25V,10%,X7R,CA    I33 @S9S_MB_2U_LIB.S9S_MB_2U(SCH_1):PAGE156
  U207    5    VCC 74LVC1G17GW-74LVC1G17GW,SMLF,IA    I35 @S9S_MB_2U_LIB.S9S_MB_2U(SCH_1):PAGE156
 R3190    1      A Q_RES_0402LF-4.7K,1%,1/16W,CHIA    I42 @S9S_MB_2U_LIB.S9S_MB_2U(SCH_1):PAGE156
 C1824    1      A Q_CAP_0402-0.1UF,25V,10%,X7R,CA    I47 @S9S_MB_2U_LIB.S9S_MB_2U(SCH_1):PAGE156
 R3192    1      A Q_RES_0402LF-4.7K,1%,1/16W,EMPA    I59 @S9S_MB_2U_LIB.S9S_MB_2U(SCH_1):PAGE156
  U219    5    VCC 74LVC1G07GV-74LVC1G07GV,SMLF,IA    I61 @S9S_MB_2U_LIB.S9S_MB_2U(SCH_1):PAGE156
 C1825    1      A Q_CAP_0402-0.1UF,25V,10%,X7R,CA    I17 @S9S_MB_2U_LIB.S9S_MB_2U(SCH_1):PAGE307
  U222   14    VCC 74CBTLV3126PW-74CBTLV3126PW,SMA    I32 @S9S_MB_2U_LIB.S9S_MB_2U(SCH_1):PAGE307
 C1826    1      A Q_CAP_0402-0.1UF,25V,10%,X7R,CA    I33 @S9S_MB_2U_LIB.S9S_MB_2U(SCH_1):PAGE307
 C1827    1      A Q_CAP_0402-0.1UF,25V,10%,X7R,CA    I77 @S9S_MB_2U_LIB.S9S_MB_2U(SCH_1):PAGE307
  U223   14    VCC 74CBTLV3126PW-74CBTLV3126PW,SMA    I78 @S9S_MB_2U_LIB.S9S_MB_2U(SCH_1):PAGE307
 R3227    2      B Q_RES_0402LF-2.2K,5%,1/16W,EMPA   I250 @S9S_MB_2U_LIB.S9S_MB_2U(SCH_1):PAGE228
 R3226    2      B Q_RES_0402LF-2.2K,5%,1/16W,EMPA   I251 @S9S_MB_2U_LIB.S9S_MB_2U(SCH_1):PAGE228
 R3225    2      B Q_RES_0402LF-2K,1%,1/16W,CHIP,A   I130 @S9S_MB_2U_LIB.S9S_MB_2U(SCH_1):PAGE224
 R3224    2      B Q_RES_0402LF-2K,1%,1/16W,CHIP,A   I131 @S9S_MB_2U_LIB.S9S_MB_2U(SCH_1):PAGE224
 R3222    2      B Q_RES_0402LF-2K,1%,1/16W,CHIP,A   I132 @S9S_MB_2U_LIB.S9S_MB_2U(SCH_1):PAGE224
 R3223    2      B Q_RES_0402LF-2K,1%,1/16W,CHIP,A   I133 @S9S_MB_2U_LIB.S9S_MB_2U(SCH_1):PAGE224
 C1841    1      A Q_CAP_0402-0.1UF,25V,10%,X7R,CA    I65 @S9S_MB_2U_LIB.S9S_MB_2U(SCH_1):PAGE156
 R3241    2      B Q_RES_0402LF-2.2K,5%,1/16W,EMPA   I258 @S9S_MB_2U_LIB.S9S_MB_2U(SCH_1):PAGE228
 R3240    2      B Q_RES_0402LF-2.2K,5%,1/16W,EMPA   I259 @S9S_MB_2U_LIB.S9S_MB_2U(SCH_1):PAGE228
 R3242    2      B Q_RES_0402LF-2.2K,5%,1/16W,EMPA   I260 @S9S_MB_2U_LIB.S9S_MB_2U(SCH_1):PAGE228
 R3243    2      B Q_RES_0402LF-2.2K,5%,1/16W,EMPA   I261 @S9S_MB_2U_LIB.S9S_MB_2U(SCH_1):PAGE228
  U235    1   VCCA PCA9617ADP-PCA9617ADP,SMLF,IC,A     I5 @S9S_MB_2U_LIB.S9S_MB_2U(SCH_1):PAGE216
 C1859    1      A Q_CAP_0402-0.1UF,25V,10%,X7R,CA    I10 @S9S_MB_2U_LIB.S9S_MB_2U(SCH_1):PAGE216
 C1860    1      A Q_CAP_0402-0.1UF,25V,10%,X7R,CA    I17 @S9S_MB_2U_LIB.S9S_MB_2U(SCH_1):PAGE216
  U236    1   VCCA PCA9617ADP-PCA9617ADP,SMLF,IC,A    I28 @S9S_MB_2U_LIB.S9S_MB_2U(SCH_1):PAGE216
 R3277    1      A Q_RES_0402LF-1K,1%,1/16W,EMPTYA    I16 @S9S_MB_2U_LIB.S9S_MB_2U(SCH_1):PAGE136
 C1867    1      A Q_CAP_C0805-10UF,25V,10%,X6S,CA    I48 @S9S_MB_2U_LIB.S9S_MB_2U(SCH_1):PAGE136
 R3289    1      A Q_RES_0402LF-1K,1%,1/16W,EMPTYA    I69 @S9S_MB_2U_LIB.S9S_MB_2U(SCH_1):PAGE136
  U241    8    VCC 74LVC2G08DP-74LVC2G08DP,SMLF,IA     I1 @S9S_MB_2U_LIB.S9S_MB_2U(SCH_1):PAGE170
  U240    8    VCC 74LVC2G08DP-74LVC2G08DP,SMLF,IA    I11 @S9S_MB_2U_LIB.S9S_MB_2U(SCH_1):PAGE170
  U242    8    VCC 74LVC2G08DP-74LVC2G08DP,SMLF,IA    I13 @S9S_MB_2U_LIB.S9S_MB_2U(SCH_1):PAGE170
  U243    5    VCC NC7SB3157_SMLF-NC7SB3157P6X,NCB    I15 @S9S_MB_2U_LIB.S9S_MB_2U(SCH_1):PAGE170
  U244    5    VCC NC7SB3157_SMLF-NC7SB3157P6X,NCB    I16 @S9S_MB_2U_LIB.S9S_MB_2U(SCH_1):PAGE170
  U246    5    VCC NC7SB3157_SMLF-NC7SB3157P6X,NCB    I17 @S9S_MB_2U_LIB.S9S_MB_2U(SCH_1):PAGE170
  U245    5    VCC NC7SB3157_SMLF-NC7SB3157P6X,NCB    I18 @S9S_MB_2U_LIB.S9S_MB_2U(SCH_1):PAGE170
 C1875    1      A Q_CAP_0402-0.1UF,25V,10%,X7R,CA    I21 @S9S_MB_2U_LIB.S9S_MB_2U(SCH_1):PAGE170
 C1874    1      A Q_CAP_0402-0.1UF,25V,10%,X7R,CA    I22 @S9S_MB_2U_LIB.S9S_MB_2U(SCH_1):PAGE170
 C1880    1      A Q_CAP_0402-0.1UF,25V,10%,X7R,CA    I27 @S9S_MB_2U_LIB.S9S_MB_2U(SCH_1):PAGE170
 C1879    1      A Q_CAP_0402-0.1UF,25V,10%,X7R,CA    I31 @S9S_MB_2U_LIB.S9S_MB_2U(SCH_1):PAGE170
 C1877    1      A Q_CAP_0402-0.1UF,25V,10%,X7R,CA    I34 @S9S_MB_2U_LIB.S9S_MB_2U(SCH_1):PAGE170
 C1878    1      A Q_CAP_0402-0.1UF,25V,10%,X7R,CA    I37 @S9S_MB_2U_LIB.S9S_MB_2U(SCH_1):PAGE170
 C1876    1      A Q_CAP_0402-0.1UF,25V,10%,X7R,CA    I41 @S9S_MB_2U_LIB.S9S_MB_2U(SCH_1):PAGE170
 R2133    1      A Q_RES_0402LF-1K,1%,1/16W,CHIP,A    I86 @S9S_MB_2U_LIB.S9S_MB_2U(SCH_1):PAGE189
 R1320    1      A Q_RES_0402LF-1K,1%,1/16W,CHIP,A    I89 @S9S_MB_2U_LIB.S9S_MB_2U(SCH_1):PAGE189
 R1325    1      A Q_RES_0402LF-1K,1%,1/16W,CHIP,A    I93 @S9S_MB_2U_LIB.S9S_MB_2U(SCH_1):PAGE189
 R1339    1      A Q_RES_0402LF-10K,1%,1/16W,CHIPA   I100 @S9S_MB_2U_LIB.S9S_MB_2U(SCH_1):PAGE189
 R3321    1      A Q_RES_0402LF-4.7K,5%,1/16W,CHIA   I158 @S9S_MB_2U_LIB.S9S_MB_2U(SCH_1):PAGE145
 R3320    1      A Q_RES_0402LF-4.7K,5%,1/16W,CHIA   I162 @S9S_MB_2U_LIB.S9S_MB_2U(SCH_1):PAGE145
 C1803    1      A Q_CAP_0402-0.1UF,25V,10%,X7R,CA   I166 @S9S_MB_2U_LIB.S9S_MB_2U(SCH_1):PAGE140
 R3318    1      A Q_RES_0402LF-100K,1%,1/16W,EMPA   I171 @S9S_MB_2U_LIB.S9S_MB_2U(SCH_1):PAGE145
 C1882    1      A Q_CAP_0402-0.1UF,25V,10%,X7R,CA    I80 @S9S_MB_2U_LIB.S9S_MB_2U(SCH_1):PAGE201
 C1320    1      A Q_CAP_0402-0.1UF,25V,10%,X7R,CA   I126 @S9S_MB_2U_LIB.S9S_MB_2U(SCH_1):PAGE313
  OSC2    4    VDD Q_OSC4P_SMLF-25MHZ,OSC,BF62500A   I127 @S9S_MB_2U_LIB.S9S_MB_2U(SCH_1):PAGE313
 R1099    1      A Q_RES_0402LF-10K,1%,1/16W,CHIPA   I129 @S9S_MB_2U_LIB.S9S_MB_2U(SCH_1):PAGE313
 R1465    1      A Q_RES_0402LF-10K,1%,1/16W,EMPTA     I3 @S9S_MB_2U_LIB.S9S_MB_2U(SCH_1):PAGE312
 R1106    1      A Q_RES_0402LF-10K,1%,1/16W,CHIPA     I5 @S9S_MB_2U_LIB.S9S_MB_2U(SCH_1):PAGE312
 R1823    1      A Q_RES_0402LF-1K,1%,1/16W,CHIP,A     I4 @S9S_MB_2U_LIB.S9S_MB_2U(SCH_1):PAGE311
 R3249    1      A Q_RES_0402LF-10K,1%,1/16W,CHIPA    I29 @S9S_MB_2U_LIB.S9S_MB_2U(SCH_1):PAGE311
 R3349    1      A Q_RES_0603LF-1,1%,1/10W,CHIP,CA    I60 @S9S_MB_2U_LIB.S9S_MB_2U(SCH_1):PAGE202
 R3346    1      A Q_RES_0603LF-1,1%,1/10W,CHIP,CA    I63 @S9S_MB_2U_LIB.S9S_MB_2U(SCH_1):PAGE202
 R3348    1      A Q_RES_0603LF-1,1%,1/10W,CHIP,CA    I67 @S9S_MB_2U_LIB.S9S_MB_2U(SCH_1):PAGE202
 R3347    1      A Q_RES_0603LF-1,1%,1/10W,CHIP,CA    I72 @S9S_MB_2U_LIB.S9S_MB_2U(SCH_1):PAGE202
 R3345    1      A Q_RES_0603LF-1,1%,1/10W,CHIP,CA    I81 @S9S_MB_2U_LIB.S9S_MB_2U(SCH_1):PAGE202
 R3344    1      A Q_RES_0603LF-1,1%,1/10W,CHIP,CA   I108 @S9S_MB_2U_LIB.S9S_MB_2U(SCH_1):PAGE202
 R2524    1      A Q_RES_0402LF-1K,1%,1/16W,CHIP,A    I17 @S9S_MB_2U_LIB.S9S_MB_2U(SCH_1):PAGE270
 R2525    1      A Q_RES_0402LF-1K,1%,1/16W,CHIP,A    I18 @S9S_MB_2U_LIB.S9S_MB_2U(SCH_1):PAGE270
 R2365    1      A Q_RES_0402LF-1K,1%,1/16W,CHIP,A    I50 @S9S_MB_2U_LIB.S9S_MB_2U(SCH_1):PAGE252
 R3458    1      A Q_RES_0603LF-1,1%,1/10W,CHIP,CA   I119 @S9S_MB_2U_LIB.S9S_MB_2U(SCH_1):PAGE202
 R4645    1      A Q_RES_0402LF-1K,1%,1/16W,EMPTYA    I16 @S9S_MB_2U_LIB.S9S_MB_2U(SCH_1):PAGE159
 R4655    1      A Q_RES_0402LF-1K,1%,1/16W,EMPTYA    I62 @S9S_MB_2U_LIB.S9S_MB_2U(SCH_1):PAGE159
 R4656    1      A Q_RES_0402LF-1K,1%,1/16W,CHIP,A    I66 @S9S_MB_2U_LIB.S9S_MB_2U(SCH_1):PAGE159
 R3386    1      A Q_RES_0402LF-1K,1%,1/16W,CHIP,A    I81 @S9S_MB_2U_LIB.S9S_MB_2U(SCH_1):PAGE159
  U328   15    VIN DS125BR111RTWR-DS125BR111RTWR,A    I95 @S9S_MB_2U_LIB.S9S_MB_2U(SCH_1):PAGE159
 R3435    1      A Q_RES_0402LF-4.7K,5%,1/16W,CHIA    I23 @S9S_MB_2U_LIB.S9S_MB_2U(SCH_1):PAGE299
 R3437    1      A Q_RES_0402LF-4.7K,5%,1/16W,CHIA    I27 @S9S_MB_2U_LIB.S9S_MB_2U(SCH_1):PAGE299
 R3434    1      A Q_RES_0402LF-4.7K,5%,1/16W,CHIA    I39 @S9S_MB_2U_LIB.S9S_MB_2U(SCH_1):PAGE299
 R3436    1      A Q_RES_0402LF-4.7K,5%,1/16W,CHIA    I45 @S9S_MB_2U_LIB.S9S_MB_2U(SCH_1):PAGE299
 R3433    1      A Q_RES_0402LF-4.7K,5%,1/16W,CHIA    I49 @S9S_MB_2U_LIB.S9S_MB_2U(SCH_1):PAGE299
 R3432    1      A Q_RES_0402LF-4.7K,5%,1/16W,CHIA    I53 @S9S_MB_2U_LIB.S9S_MB_2U(SCH_1):PAGE299
 R3438    1      A Q_RES_0402LF-4.7K,5%,1/16W,CHIA    I55 @S9S_MB_2U_LIB.S9S_MB_2U(SCH_1):PAGE299
 R3439    1      A Q_RES_0402LF-4.7K,5%,1/16W,CHIA    I59 @S9S_MB_2U_LIB.S9S_MB_2U(SCH_1):PAGE299
  U253    5    VCC 74LVC2G17GW-74LVC2G17GW,SMLF,IA    I26 @S9S_MB_2U_LIB.S9S_MB_2U(SCH_1):PAGE160
 C1958    1      A Q_CAP_0402-0.1UF,25V,10%,X7R,CA    I29 @S9S_MB_2U_LIB.S9S_MB_2U(SCH_1):PAGE160
 R3456    1      A Q_RES_0402LF-100K,1%,1/16W,EMPA   I124 @S9S_MB_2U_LIB.S9S_MB_2U(SCH_1):PAGE160
 R3451    1      A Q_RES_0402LF-4.7K,5%,1/16W,EMPA   I127 @S9S_MB_2U_LIB.S9S_MB_2U(SCH_1):PAGE160
 R3429    1      A Q_RES_0402LF-100K,1%,1/16W,EMPA   I130 @S9S_MB_2U_LIB.S9S_MB_2U(SCH_1):PAGE299
 R3465    1      A Q_RES_0402LF-10K,1%,1/16W,CHIPA   I132 @S9S_MB_2U_LIB.S9S_MB_2U(SCH_1):PAGE299
 R3464    1      A Q_RES_0402LF-54.9K,1%,1/16W,CHA   I134 @S9S_MB_2U_LIB.S9S_MB_2U(SCH_1):PAGE299
 C1957    1      A Q_CAP_0402-0.1UF,25V,10%,X7R,CA   I148 @S9S_MB_2U_LIB.S9S_MB_2U(SCH_1):PAGE160
  U252    5    VCC 74LVC2G17GW-74LVC2G17GW,SMLF,IA   I153 @S9S_MB_2U_LIB.S9S_MB_2U(SCH_1):PAGE160
 C1963    1      A Q_CAP_0402-0.1UF,25V,10%,X7R,CA    I13 @S9S_MB_2U_LIB.S9S_MB_2U(SCH_1):PAGE296
  U255    5    VCC 74LVC2G07DW7-74LVC2G07DW-7,SMLA    I16 @S9S_MB_2U_LIB.S9S_MB_2U(SCH_1):PAGE296
 R3459    1      A Q_RES_0402LF-4.7K,5%,1/16W,CHIA    I29 @S9S_MB_2U_LIB.S9S_MB_2U(SCH_1):PAGE296
 R3461    1      A Q_RES_0402LF-54.9K,1%,1/16W,CHA    I35 @S9S_MB_2U_LIB.S9S_MB_2U(SCH_1):PAGE296
 R3453    1      A Q_RES_0402LF-100K,1%,1/16W,EMPA   I164 @S9S_MB_2U_LIB.S9S_MB_2U(SCH_1):PAGE160
 R3448    1      A Q_RES_0402LF-4.7K,5%,1/16W,EMPA   I168 @S9S_MB_2U_LIB.S9S_MB_2U(SCH_1):PAGE160
  U256    5    VCC 74LVC2G17GW-74LVC2G17GW,SMLF,IA   I173 @S9S_MB_2U_LIB.S9S_MB_2U(SCH_1):PAGE160
 C1977    1      A Q_CAP_0402-0.1UF,25V,10%,X7R,CA   I175 @S9S_MB_2U_LIB.S9S_MB_2U(SCH_1):PAGE160
 R3470    1      A Q_RES_0402LF-10K,1%,1/16W,EMPTA   I145 @S9S_MB_2U_LIB.S9S_MB_2U(SCH_1):PAGE299
 R3475    1      A Q_RES_0402LF-4.7K,5%,1/16W,CHIA   I154 @S9S_MB_2U_LIB.S9S_MB_2U(SCH_1):PAGE299
 R3474    1      A Q_RES_0402LF-4.7K,5%,1/16W,CHIA   I158 @S9S_MB_2U_LIB.S9S_MB_2U(SCH_1):PAGE299
 R3487    1      A Q_RES_0402LF-10K,1%,1/16W,CHIPA   I166 @S9S_MB_2U_LIB.S9S_MB_2U(SCH_1):PAGE299
 R3488    1      A Q_RES_0402LF-4.7K,5%,1/16W,CHIA    I40 @S9S_MB_2U_LIB.S9S_MB_2U(SCH_1):PAGE296
 R3492    1      A Q_RES_0402LF-54.9K,1%,1/16W,CHA    I47 @S9S_MB_2U_LIB.S9S_MB_2U(SCH_1):PAGE296
  U257    5    VCC 74LVC2G07DW7-74LVC2G07DW-7,SMLA    I50 @S9S_MB_2U_LIB.S9S_MB_2U(SCH_1):PAGE296
 R3494    1      A Q_RES_0402LF-54.9K,1%,1/16W,CHA    I55 @S9S_MB_2U_LIB.S9S_MB_2U(SCH_1):PAGE296
 R3490    1      A Q_RES_0402LF-4.7K,5%,1/16W,CHIA    I57 @S9S_MB_2U_LIB.S9S_MB_2U(SCH_1):PAGE296
 C1979    1      A Q_CAP_0402-0.1UF,25V,10%,X7R,CA    I67 @S9S_MB_2U_LIB.S9S_MB_2U(SCH_1):PAGE296
 R3498    1      A Q_RES_0402LF-54.9K,1%,1/16W,CHA   I167 @S9S_MB_2U_LIB.S9S_MB_2U(SCH_1):PAGE299
 R3512    1      A Q_RES_0402LF-100K,1%,1/16W,EMPA   I174 @S9S_MB_2U_LIB.S9S_MB_2U(SCH_1):PAGE145
 R3514    1      A Q_RES_0402LF-54.9K,1%,1/16W,CHA   I175 @S9S_MB_2U_LIB.S9S_MB_2U(SCH_1):PAGE145
 R3510    1      A Q_RES_0402LF-54.9K,1%,1/16W,CHA   I176 @S9S_MB_2U_LIB.S9S_MB_2U(SCH_1):PAGE145
 R3317    1      A Q_RES_0402LF-4.7K,5%,1/16W,EMPA   I190 @S9S_MB_2U_LIB.S9S_MB_2U(SCH_1):PAGE140
 R3506    1      A Q_RES_0402LF-4.7K,5%,1/16W,EMPA   I193 @S9S_MB_2U_LIB.S9S_MB_2U(SCH_1):PAGE140
 R3504    1      A Q_RES_0402LF-4.7K,5%,1/16W,CHIA   I174 @S9S_MB_2U_LIB.S9S_MB_2U(SCH_1):PAGE299
 R3503    1      A Q_RES_0402LF-4.7K,5%,1/16W,CHIA   I177 @S9S_MB_2U_LIB.S9S_MB_2U(SCH_1):PAGE299
 R3525    1      A Q_RES_0402LF-54.9K,1%,1/16W,CHA   I184 @S9S_MB_2U_LIB.S9S_MB_2U(SCH_1):PAGE299
 R2910    1      A Q_RES_0402LF-100K,1%,1/16W,EMPA   I187 @S9S_MB_2U_LIB.S9S_MB_2U(SCH_1):PAGE160
 R2914    1      A Q_RES_0402LF-4.7K,5%,1/16W,EMPA   I192 @S9S_MB_2U_LIB.S9S_MB_2U(SCH_1):PAGE160
 C1997    1      A Q_CAP_0402-0.1UF,25V,10%,X7R,CA    I89 @S9S_MB_2U_LIB.S9S_MB_2U(SCH_1):PAGE183
 C2013    1      A Q_CAP_0402-0.1UF,25V,10%,X7R,CA    I42 @S9S_MB_2U_LIB.S9S_MB_2U(SCH_1):PAGE163
  U264    9     VS INA230AIRGTR-INA230AIRGTR,SMLFB    I46 @S9S_MB_2U_LIB.S9S_MB_2U(SCH_1):PAGE163
 C2014    1      A Q_CAP_0402-0.1UF,25V,10%,X7R,CA    I65 @S9S_MB_2U_LIB.S9S_MB_2U(SCH_1):PAGE163
  U265    9     VS INA230AIRGTR-INA230AIRGTR,SMLFB    I69 @S9S_MB_2U_LIB.S9S_MB_2U(SCH_1):PAGE163
  U266    9     VS INA230AIRGTR-INA230AIRGTR,SMLFB    I30 @S9S_MB_2U_LIB.S9S_MB_2U(SCH_1):PAGE295
 C2015    1      A Q_CAP_0402-0.1UF,25V,10%,X7R,CA    I34 @S9S_MB_2U_LIB.S9S_MB_2U(SCH_1):PAGE295
 R3623    1      A Q_RES_0402LF-4.7K,1%,1/16W,CHIA    I86 @S9S_MB_2U_LIB.S9S_MB_2U(SCH_1):PAGE163
 R3621    1      A Q_RES_0402LF-4.7K,1%,1/16W,EMPA    I87 @S9S_MB_2U_LIB.S9S_MB_2U(SCH_1):PAGE163
 R3624    1      A Q_RES_0402LF-4.7K,1%,1/16W,CHIA    I89 @S9S_MB_2U_LIB.S9S_MB_2U(SCH_1):PAGE163
 R3622    1      A Q_RES_0402LF-4.7K,1%,1/16W,CHIA    I90 @S9S_MB_2U_LIB.S9S_MB_2U(SCH_1):PAGE163
 R3628    1      A Q_RES_0402LF-4.7K,1%,1/16W,EMPA    I88 @S9S_MB_2U_LIB.S9S_MB_2U(SCH_1):PAGE295
 R3627    1      A Q_RES_0402LF-4.7K,1%,1/16W,CHIA    I89 @S9S_MB_2U_LIB.S9S_MB_2U(SCH_1):PAGE295
 R3638    1      A Q_RES_0402LF-10K,1%,1/16W,CHIPA   I378 @S9S_MB_2U_LIB.S9S_MB_2U(SCH_1):PAGE197
 R3639    1      A Q_RES_0402LF-10K,1%,1/16W,CHIPA   I379 @S9S_MB_2U_LIB.S9S_MB_2U(SCH_1):PAGE197
 R3640    1      A Q_RES_0402LF-10K,1%,1/16W,CHIPA   I380 @S9S_MB_2U_LIB.S9S_MB_2U(SCH_1):PAGE197
 R3641    1      A Q_RES_0402LF-10K,1%,1/16W,CHIPA   I381 @S9S_MB_2U_LIB.S9S_MB_2U(SCH_1):PAGE197
 R3642    1      A Q_RES_0402LF-10K,1%,1/16W,CHIPA   I382 @S9S_MB_2U_LIB.S9S_MB_2U(SCH_1):PAGE197
 R3643    1      A Q_RES_0402LF-10K,1%,1/16W,CHIPA   I383 @S9S_MB_2U_LIB.S9S_MB_2U(SCH_1):PAGE197
 R3660    1      A Q_RES_0402LF-10K,1%,1/16W,CHIPA   I159 @S9S_MB_2U_LIB.S9S_MB_2U(SCH_1):PAGE155
 R3655    1      A Q_RES_0402LF-0,5%,1/16W,CHIP,CA   I161 @S9S_MB_2U_LIB.S9S_MB_2U(SCH_1):PAGE155
 R3663    1      A Q_RES_0402LF-10K,1%,1/16W,CHIPA   I186 @S9S_MB_2U_LIB.S9S_MB_2U(SCH_1):PAGE155
 R3656    1      A Q_RES_0402LF-10K,1%,1/16W,EMPTA   I194 @S9S_MB_2U_LIB.S9S_MB_2U(SCH_1):PAGE155
 R3657    1      A Q_RES_0402LF-10K,1%,1/16W,EMPTA   I195 @S9S_MB_2U_LIB.S9S_MB_2U(SCH_1):PAGE155
 R3658    1      A Q_RES_0402LF-10K,1%,1/16W,EMPTA   I196 @S9S_MB_2U_LIB.S9S_MB_2U(SCH_1):PAGE155
 R3659    1      A Q_RES_0402LF-10K,1%,1/16W,EMPTA   I198 @S9S_MB_2U_LIB.S9S_MB_2U(SCH_1):PAGE155
   L16    1      1 Q_INDUCTOR_SMLF-BLM18PG300SN1DB   I118 @S9S_MB_2U_LIB.S9S_MB_2U(SCH_1):PAGE239
 R2907    1      A Q_RES_0402LF-5.11K,1%,1/16W,CHA   I141 @S9S_MB_2U_LIB.S9S_MB_2U(SCH_1):PAGE239
 R3667    1      A Q_RES_0402LF-1K,1%,1/16W,EMPTYA   I224 @S9S_MB_2U_LIB.S9S_MB_2U(SCH_1):PAGE239
 R3669    1      A Q_RES_0402LF-1K,1%,1/16W,EMPTYA   I228 @S9S_MB_2U_LIB.S9S_MB_2U(SCH_1):PAGE239
 C2010    1      A Q_CAP_0402-0.1UF,25V,10%,X7R,CA    I16 @S9S_MB_2U_LIB.S9S_MB_2U(SCH_1):PAGE161
 R3703    1      A Q_RES_0402LF-10K,1%,1/16W,EMPTA     I3 @S9S_MB_2U_LIB.S9S_MB_2U(SCH_1):PAGE221
 R3706    1      A Q_RES_0402LF-10K,1%,1/16W,EMPTA     I9 @S9S_MB_2U_LIB.S9S_MB_2U(SCH_1):PAGE221
 R3708    1      A Q_RES_0402LF-10K,1%,1/16W,EMPTA    I10 @S9S_MB_2U_LIB.S9S_MB_2U(SCH_1):PAGE221
 R3732    1      A Q_RES_0402LF-2.2K,5%,1/16W,CHIA    I34 @S9S_MB_2U_LIB.S9S_MB_2U(SCH_1):PAGE221
 R3729    1      A Q_RES_0402LF-2.2K,5%,1/16W,CHIA    I48 @S9S_MB_2U_LIB.S9S_MB_2U(SCH_1):PAGE221
 R3730    1      A Q_RES_0402LF-2.2K,5%,1/16W,CHIA    I49 @S9S_MB_2U_LIB.S9S_MB_2U(SCH_1):PAGE221
 R3728    1      A Q_RES_0402LF-2.2K,5%,1/16W,CHIA    I50 @S9S_MB_2U_LIB.S9S_MB_2U(SCH_1):PAGE221
 R3727    1      A Q_RES_0402LF-2.2K,5%,1/16W,CHIA    I51 @S9S_MB_2U_LIB.S9S_MB_2U(SCH_1):PAGE221
 R3726    1      A Q_RES_0402LF-2.2K,5%,1/16W,CHIA    I52 @S9S_MB_2U_LIB.S9S_MB_2U(SCH_1):PAGE221
 R3725    1      A Q_RES_0402LF-2.2K,5%,1/16W,CHIA    I53 @S9S_MB_2U_LIB.S9S_MB_2U(SCH_1):PAGE221
 R3723    1      A Q_RES_0402LF-2.2K,5%,1/16W,CHIA    I55 @S9S_MB_2U_LIB.S9S_MB_2U(SCH_1):PAGE221
 R3724    1      A Q_RES_0402LF-2.2K,5%,1/16W,CHIA    I56 @S9S_MB_2U_LIB.S9S_MB_2U(SCH_1):PAGE221
 R3731    1      A Q_RES_0402LF-2.2K,5%,1/16W,CHIA    I98 @S9S_MB_2U_LIB.S9S_MB_2U(SCH_1):PAGE221
 C2067    1      A Q_CAP_0402-0.1UF,25V,10%,X7R,CA   I125 @S9S_MB_2U_LIB.S9S_MB_2U(SCH_1):PAGE295
  U276    9     VS INA230AIRGTR-INA230AIRGTR,SMLFB   I129 @S9S_MB_2U_LIB.S9S_MB_2U(SCH_1):PAGE295
  U263    9     VS INA230AIRGTR-INA230AIRGTR,SMLFB    I94 @S9S_MB_2U_LIB.S9S_MB_2U(SCH_1):PAGE163
 C2012    1      A Q_CAP_0402-0.1UF,25V,10%,X7R,CA    I98 @S9S_MB_2U_LIB.S9S_MB_2U(SCH_1):PAGE163
  U278    5    VCC 74LVC1G08W57-74LVC1G08W5-7,SMLA    I31 @S9S_MB_2U_LIB.S9S_MB_2U(SCH_1):PAGE230
 R2304    1      A Q_RES_0402LF-10K,1%,1/16W,CHIPA   I159 @S9S_MB_2U_LIB.S9S_MB_2U(SCH_1):PAGE297
  U145    5    VCC 74LVC1G126SE7-74LVC1G126SE-7,SA   I163 @S9S_MB_2U_LIB.S9S_MB_2U(SCH_1):PAGE297
 R2282    1      A Q_RES_0402LF-10K,1%,1/16W,CHIPA   I169 @S9S_MB_2U_LIB.S9S_MB_2U(SCH_1):PAGE297
 C1614    1      A Q_CAP_0402-0.1UF,25V,10%,X7R,CA   I170 @S9S_MB_2U_LIB.S9S_MB_2U(SCH_1):PAGE297
 R3298    1      A Q_RES_0402LF-10K,1%,1/16W,CHIPA   I306 @S9S_MB_2U_LIB.S9S_MB_2U(SCH_1):PAGE182
 C1873    1      A Q_CAP_0402-0.1UF,25V,10%,X7R,CA   I308 @S9S_MB_2U_LIB.S9S_MB_2U(SCH_1):PAGE182
  U239    5    VCC 74LVC1G126SE7-74LVC1G126SE-7,SA   I315 @S9S_MB_2U_LIB.S9S_MB_2U(SCH_1):PAGE182
 R3296    1      A Q_RES_0402LF-4.7K,1%,1/16W,CHIA   I324 @S9S_MB_2U_LIB.S9S_MB_2U(SCH_1):PAGE182
 C2007    1      A Q_CAP_C0402-1UF,25V,10%,X6S,CHA   I326 @S9S_MB_2U_LIB.S9S_MB_2U(SCH_1):PAGE182
  U259    5    VCC SN74LVC2G07DCKR_SMLF-SN74LVC2GA   I327 @S9S_MB_2U_LIB.S9S_MB_2U(SCH_1):PAGE182
 R2121    1      A Q_RES_0402LF-4.7K,5%,1/16W,CHIA   I337 @S9S_MB_2U_LIB.S9S_MB_2U(SCH_1):PAGE182
  U279    8   VCCB PCA9617ADP-PCA9617ADP,SMLF,IC,A    I93 @S9S_MB_2U_LIB.S9S_MB_2U(SCH_1):PAGE183
 R3771    1      A Q_RES_0402LF-10K,1%,1/16W,CHIPA   I291 @S9S_MB_2U_LIB.S9S_MB_2U(SCH_1):PAGE297
 R2125    1      A Q_RES_0402LF-4.7K,5%,1/16W,CHIA   I296 @S9S_MB_2U_LIB.S9S_MB_2U(SCH_1):PAGE297
 R3773    1      A Q_RES_0402LF-4.7K,5%,1/16W,EMPA   I299 @S9S_MB_2U_LIB.S9S_MB_2U(SCH_1):PAGE297
 C1592    1      A Q_CAP_0402-0.1UF,25V,10%,X7R,CA   I304 @S9S_MB_2U_LIB.S9S_MB_2U(SCH_1):PAGE297
  U134    5    VCC 74LVC2G07DW7-74LVC2G07DW-7,SMLA   I305 @S9S_MB_2U_LIB.S9S_MB_2U(SCH_1):PAGE297
  U150    5    VCC 74LVC2G17GW-74LVC2G17GW,SMLF,IA     I2 @S9S_MB_2U_LIB.S9S_MB_2U(SCH_1):PAGE213
 C1619    1      A Q_CAP_0402-0.1UF,25V,10%,X7R,CA     I5 @S9S_MB_2U_LIB.S9S_MB_2U(SCH_1):PAGE213
 R2355    1      A Q_RES_0402LF-4.7K,5%,1/16W,EMPA     I7 @S9S_MB_2U_LIB.S9S_MB_2U(SCH_1):PAGE213
 R4761    1      A Q_RES_0402LF-10K,1%,1/16W,CHIPA    I70 @S9S_MB_2U_LIB.S9S_MB_2U(SCH_1):PAGE131
  U286    5    VCC 74LVC1G126SE7-74LVC1G126SE-7,SA    I80 @S9S_MB_2U_LIB.S9S_MB_2U(SCH_1):PAGE307
  U225    5    VCC 74LVC1G126SE7-74LVC1G126SE-7,SA    I74 @S9S_MB_2U_LIB.S9S_MB_2U(SCH_1):PAGE156
  U217    5    VCC 74LVC1G126SE7-74LVC1G126SE-7,SA    I79 @S9S_MB_2U_LIB.S9S_MB_2U(SCH_1):PAGE156
   U82    5    VCC 74LVC1G126SE7-74LVC1G126SE-7,SA    I79 @S9S_MB_2U_LIB.S9S_MB_2U(SCH_1):PAGE152
  U204    5    VCC 74LVC1G126SE7-74LVC1G126SE-7,SA   I195 @S9S_MB_2U_LIB.S9S_MB_2U(SCH_1):PAGE140
  U154    5    VCC 74LVC1G07SE7-74LVC1G07SE-7,SMLA    I95 @S9S_MB_2U_LIB.S9S_MB_2U(SCH_1):PAGE190
 R1841    1      A Q_RES_0402LF-10K,1%,1/16W,CHIPA   I275 @S9S_MB_2U_LIB.S9S_MB_2U(SCH_1):PAGE207
  R494    1      A Q_RES_0402LF-1K,1%,1/16W,CHIP,A    I98 @S9S_MB_2U_LIB.S9S_MB_2U(SCH_1):PAGE174
 R3938    2      B Q_RES_0402LF-10K,1%,1/16W,CHIPA   I272 @S9S_MB_2U_LIB.S9S_MB_2U(SCH_1):PAGE175
PR3967    1      A Q_RES_0402LF-10,1%,1/16W,CHIP,A    I39 @S9S_MB_2U_LIB.S9S_MB_2U(SCH_1):PAGE324
 R3977    1      A Q_RES_0402LF-100K,1%,1/16W,CHIA    I48 @S9S_MB_2U_LIB.S9S_MB_2U(SCH_1):PAGE324
PC2200    1      A Q_CAP_C0402-1UF,25V,10%,EMPTY,A     I9 @S9S_MB_2U_LIB.S9S_MB_2U(SCH_1):PAGE323
 C2246    1      A Q_CAP_C0402-1UF,25V,10%,X6S,CHA     I9 @S9S_MB_2U_LIB.S9S_MB_2U(SCH_1):PAGE322
  U304   14    VCC GTL2014PW-GTL2014PW,SMLF,IC,ALA    I27 @S9S_MB_2U_LIB.S9S_MB_2U(SCH_1):PAGE322
  U305   14    VCC GTL2014PW-GTL2014PW,SMLF,IC,ALA    I44 @S9S_MB_2U_LIB.S9S_MB_2U(SCH_1):PAGE322
 C2247    1      A Q_CAP_C0402-1UF,25V,10%,X6S,CHA    I59 @S9S_MB_2U_LIB.S9S_MB_2U(SCH_1):PAGE322
 R4078    1      A Q_RES_0402LF-10K,1%,1/16W,EMPTA   I127 @S9S_MB_2U_LIB.S9S_MB_2U(SCH_1):PAGE201
 R4081    1      A Q_RES_0402LF-10K,1%,1/16W,CHIPA   I135 @S9S_MB_2U_LIB.S9S_MB_2U(SCH_1):PAGE201
 R4080    1      A Q_RES_0402LF-10K,1%,1/16W,CHIPA   I142 @S9S_MB_2U_LIB.S9S_MB_2U(SCH_1):PAGE201
 R1216    1      A Q_RES_0402LF-1.5K,1%,1/16W,CHIA     I1 @S9S_MB_2U_LIB.S9S_MB_2U(SCH_1):PAGE80
  R321    1      A Q_RES_0402LF-10K,1%,1/16W,CHIPA     I2 @S9S_MB_2U_LIB.S9S_MB_2U(SCH_1):PAGE80
  R320    1      A Q_RES_0402LF-10K,1%,1/16W,CHIPA     I7 @S9S_MB_2U_LIB.S9S_MB_2U(SCH_1):PAGE80
 R1217    1      A Q_RES_0402LF-1.5K,1%,1/16W,CHIA    I22 @S9S_MB_2U_LIB.S9S_MB_2U(SCH_1):PAGE80
  R327    1      A Q_RES_0402LF-10K,1%,1/16W,CHIPA    I25 @S9S_MB_2U_LIB.S9S_MB_2U(SCH_1):PAGE80
  R326    1      A Q_RES_0402LF-10K,1%,1/16W,CHIPA    I26 @S9S_MB_2U_LIB.S9S_MB_2U(SCH_1):PAGE80
  R325    1      A Q_RES_0402LF-10K,1%,1/16W,CHIPA    I27 @S9S_MB_2U_LIB.S9S_MB_2U(SCH_1):PAGE80
 R1908    1      A Q_RES_0402LF-1K,1%,1/16W,CHIP,A    I22 @S9S_MB_2U_LIB.S9S_MB_2U(SCH_1):PAGE153
PR3789    1      A Q_RES_0402LF-25.5K,1%,1/16W,CHA    I70 @S9S_MB_2U_LIB.S9S_MB_2U(SCH_1):PAGE153
 R1150    1      A Q_RES_0402LF-10K,1%,1/16W,CHIPA    I74 @S9S_MB_2U_LIB.S9S_MB_2U(SCH_1):PAGE153
 R4762    1      A Q_RES_0402LF-10K,1%,1/16W,CHIPA    I76 @S9S_MB_2U_LIB.S9S_MB_2U(SCH_1):PAGE153
 R3816    1      A Q_RES_0402LF-100K,1%,1/16W,EMPA    I80 @S9S_MB_2U_LIB.S9S_MB_2U(SCH_1):PAGE131
PC2208    1      A Q_CAP_C0402-1UF,25V,10%,X6S,CHA    I17 @S9S_MB_2U_LIB.S9S_MB_2U(SCH_1):PAGE324
 R1857    1      A Q_RES_0402LF-10K,1%,1/16W,CHIPA    I18 @S9S_MB_2U_LIB.S9S_MB_2U(SCH_1):PAGE229
PR4007    2      B Q_RES_0402LF-10K,1%,1/16W,CHIPA    I48 @S9S_MB_2U_LIB.S9S_MB_2U(SCH_1):PAGE229
 C1332    1      A Q_CAP_C0402-100NF,50V,10%,X7R,A    I48 @S9S_MB_2U_LIB.S9S_MB_2U(SCH_1):PAGE246
 C1333    1      A Q_CAP_C0805-10UF,16V,10%,X6S,CA    I49 @S9S_MB_2U_LIB.S9S_MB_2U(SCH_1):PAGE246
 C1338    1      A Q_CAP_C0805-10UF,16V,10%,EMPTYA    I50 @S9S_MB_2U_LIB.S9S_MB_2U(SCH_1):PAGE246
   Q56    5      5 MOSFET_NCH_1D3S-PSMNR58-30YLH,A    I51 @S9S_MB_2U_LIB.S9S_MB_2U(SCH_1):PAGE246
PR1647    1      A Q_RES_0402LF-10K,1%,1/16W,EMPTA    I26 @S9S_MB_2U_LIB.S9S_MB_2U(SCH_1):PAGE248
 PR395    1      A Q_RES_0402LF-0,5%,1/16W,CHIP,CA     I8 @S9S_MB_2U_LIB.S9S_MB_2U(SCH_1):PAGE249
 R2406    1      A Q_RES_0402LF-10K,1%,1/16W,EMPTA     I9 @S9S_MB_2U_LIB.S9S_MB_2U(SCH_1):PAGE267
 R2522    1      A Q_RES_0402LF-1K,1%,1/16W,CHIP,A    I25 @S9S_MB_2U_LIB.S9S_MB_2U(SCH_1):PAGE270
  R307    1      A Q_RES_0402LF-1K,1%,1/16W,CHIP,A    I61 @S9S_MB_2U_LIB.S9S_MB_2U(SCH_1):PAGE270
 R2573    1      A Q_RES_0402LF-1K,1%,1/16W,CHIP,A    I73 @S9S_MB_2U_LIB.S9S_MB_2U(SCH_1):PAGE278
 R2575    1      A Q_RES_0402LF-1K,1%,1/16W,CHIP,A    I46 @S9S_MB_2U_LIB.S9S_MB_2U(SCH_1):PAGE282
 R2583    1      A Q_RES_0402LF-10K,1%,1/16W,CHIPA    I27 @S9S_MB_2U_LIB.S9S_MB_2U(SCH_1):PAGE285
 R2584    1      A Q_RES_0402LF-10K,1%,1/16W,CHIPA    I31 @S9S_MB_2U_LIB.S9S_MB_2U(SCH_1):PAGE286
   L17    1      1 Q_INDUCTOR_SMLF-FCM2012KF-601TA   I155 @S9S_MB_2U_LIB.S9S_MB_2U(SCH_1):PAGE201
 R4093    1      A Q_RES_0402LF-4.7K,1%,1/16W,CHIA   I149 @S9S_MB_2U_LIB.S9S_MB_2U(SCH_1):PAGE295
 R4094    1      A Q_RES_0402LF-4.7K,1%,1/16W,CHIA   I151 @S9S_MB_2U_LIB.S9S_MB_2U(SCH_1):PAGE295
 R4091    1      A Q_RES_0402LF-4.7K,1%,1/16W,CHIA   I122 @S9S_MB_2U_LIB.S9S_MB_2U(SCH_1):PAGE163
 R4090    1      A Q_RES_0402LF-4.7K,1%,1/16W,CHIA   I124 @S9S_MB_2U_LIB.S9S_MB_2U(SCH_1):PAGE163
 R4092    1      A Q_RES_0402LF-4.7K,1%,1/16W,CHIA   I126 @S9S_MB_2U_LIB.S9S_MB_2U(SCH_1):PAGE163
 R3529    1      A Q_RES_0402LF-10K,1%,1/16W,CHIPA    I99 @S9S_MB_2U_LIB.S9S_MB_2U(SCH_1):PAGE183
 R3322    1      A Q_RES_0402LF-4.7K,1%,1/16W,CHIA   I157 @S9S_MB_2U_LIB.S9S_MB_2U(SCH_1):PAGE201
 R2909    1      A Q_RES_0402LF-4.7K,5%,1/16W,CHIA   I198 @S9S_MB_2U_LIB.S9S_MB_2U(SCH_1):PAGE140
  U248    5    VCC 74LVC1G32GW_SMLF-74LVC1G32GW,IA   I158 @S9S_MB_2U_LIB.S9S_MB_2U(SCH_1):PAGE201
 R4128    1      A Q_RES_0402LF-4.7K,5%,1/16W,CHIA     I5 @S9S_MB_2U_LIB.S9S_MB_2U(SCH_1):PAGE143
 R4125    1      A Q_RES_0402LF-4.7K,5%,1/16W,CHIA     I9 @S9S_MB_2U_LIB.S9S_MB_2U(SCH_1):PAGE143
 R4119    1      A Q_RES_0402LF-54.9K,1%,1/16W,EMA    I13 @S9S_MB_2U_LIB.S9S_MB_2U(SCH_1):PAGE143
 R4130    1      A Q_RES_0402LF-4.7K,5%,1/16W,CHIA    I21 @S9S_MB_2U_LIB.S9S_MB_2U(SCH_1):PAGE143
 R4127    1      A Q_RES_0402LF-4.7K,5%,1/16W,CHIA    I27 @S9S_MB_2U_LIB.S9S_MB_2U(SCH_1):PAGE143
 R4123    1      A Q_RES_0402LF-54.9K,1%,1/16W,EMA    I31 @S9S_MB_2U_LIB.S9S_MB_2U(SCH_1):PAGE143
 R4129    1      A Q_RES_0402LF-4.7K,5%,1/16W,CHIA    I36 @S9S_MB_2U_LIB.S9S_MB_2U(SCH_1):PAGE143
 R4126    1      A Q_RES_0402LF-4.7K,5%,1/16W,CHIA    I43 @S9S_MB_2U_LIB.S9S_MB_2U(SCH_1):PAGE143
 R4140    1      A Q_RES_0402LF-4.7K,5%,1/16W,CHIA    I52 @S9S_MB_2U_LIB.S9S_MB_2U(SCH_1):PAGE143
 R4142    1      A Q_RES_0402LF-4.7K,5%,1/16W,CHIA    I60 @S9S_MB_2U_LIB.S9S_MB_2U(SCH_1):PAGE143
 R4141    1      A Q_RES_0402LF-4.7K,5%,1/16W,CHIA    I64 @S9S_MB_2U_LIB.S9S_MB_2U(SCH_1):PAGE143
 R4137    1      A Q_RES_0402LF-4.7K,5%,1/16W,CHIA    I72 @S9S_MB_2U_LIB.S9S_MB_2U(SCH_1):PAGE143
 R4139    1      A Q_RES_0402LF-4.7K,5%,1/16W,CHIA    I76 @S9S_MB_2U_LIB.S9S_MB_2U(SCH_1):PAGE143
 R4138    1      A Q_RES_0402LF-4.7K,5%,1/16W,CHIA    I81 @S9S_MB_2U_LIB.S9S_MB_2U(SCH_1):PAGE143
 R4131    1      A Q_RES_0402LF-54.9K,1%,1/16W,EMA    I85 @S9S_MB_2U_LIB.S9S_MB_2U(SCH_1):PAGE143
 R4133    1      A Q_RES_0402LF-54.9K,1%,1/16W,EMA    I95 @S9S_MB_2U_LIB.S9S_MB_2U(SCH_1):PAGE143
 R4155    1      A Q_RES_0402LF-4.7K,5%,1/16W,CHIA   I100 @S9S_MB_2U_LIB.S9S_MB_2U(SCH_1):PAGE143
 R4156    1      A Q_RES_0402LF-4.7K,5%,1/16W,CHIA   I101 @S9S_MB_2U_LIB.S9S_MB_2U(SCH_1):PAGE143
 R4160    1      A Q_RES_0402LF-54.9K,1%,1/16W,EMA     I4 @S9S_MB_2U_LIB.S9S_MB_2U(SCH_1):PAGE139
 R4162    1      A Q_RES_0402LF-54.9K,1%,1/16W,EMA     I9 @S9S_MB_2U_LIB.S9S_MB_2U(SCH_1):PAGE139
 R4158    1      A Q_RES_0402LF-54.9K,1%,1/16W,EMA    I14 @S9S_MB_2U_LIB.S9S_MB_2U(SCH_1):PAGE139
 R4165    1      A Q_RES_0402LF-4.7K,5%,1/16W,CHIA    I18 @S9S_MB_2U_LIB.S9S_MB_2U(SCH_1):PAGE139
 R4166    1      A Q_RES_0402LF-4.7K,5%,1/16W,CHIA    I23 @S9S_MB_2U_LIB.S9S_MB_2U(SCH_1):PAGE139
 R4164    1      A Q_RES_0402LF-4.7K,5%,1/16W,CHIA    I27 @S9S_MB_2U_LIB.S9S_MB_2U(SCH_1):PAGE139
 R4168    1      A Q_RES_0402LF-4.7K,5%,1/16W,CHIA    I35 @S9S_MB_2U_LIB.S9S_MB_2U(SCH_1):PAGE139
 R4169    1      A Q_RES_0402LF-4.7K,5%,1/16W,CHIA    I39 @S9S_MB_2U_LIB.S9S_MB_2U(SCH_1):PAGE139
 R4167    1      A Q_RES_0402LF-4.7K,5%,1/16W,CHIA    I47 @S9S_MB_2U_LIB.S9S_MB_2U(SCH_1):PAGE139
 R4176    1      A Q_RES_0402LF-10K,1%,1/16W,CHIPA    I16 @S9S_MB_2U_LIB.S9S_MB_2U(SCH_1):PAGE243
 R4198    1      A Q_RES_0402LF-1K,1%,1/16W,EMPTYA    I82 @S9S_MB_2U_LIB.S9S_MB_2U(SCH_1):PAGE161
 R4206    1      A Q_RES_0402LF-1K,1%,1/16W,EMPTYA    I86 @S9S_MB_2U_LIB.S9S_MB_2U(SCH_1):PAGE161
 R4190    1      A Q_RES_0402LF-1K,1%,1/16W,EMPTYA    I91 @S9S_MB_2U_LIB.S9S_MB_2U(SCH_1):PAGE161
 R4204    1      A Q_RES_0402LF-1K,1%,1/16W,EMPTYA    I94 @S9S_MB_2U_LIB.S9S_MB_2U(SCH_1):PAGE161
 R4196    1      A Q_RES_0402LF-1K,1%,1/16W,EMPTYA    I95 @S9S_MB_2U_LIB.S9S_MB_2U(SCH_1):PAGE161
 R4188    1      A Q_RES_0402LF-1K,1%,1/16W,EMPTYA   I101 @S9S_MB_2U_LIB.S9S_MB_2U(SCH_1):PAGE161
 C2276    1      A Q_CAP_0402-0.1UF,25V,10%,X7R,CA   I104 @S9S_MB_2U_LIB.S9S_MB_2U(SCH_1):PAGE161
 C2275    1      A Q_CAP_0402-0.1UF,25V,10%,X7R,CA   I119 @S9S_MB_2U_LIB.S9S_MB_2U(SCH_1):PAGE161
 R4186    1      A Q_RES_0402LF-1K,1%,1/16W,EMPTYA   I122 @S9S_MB_2U_LIB.S9S_MB_2U(SCH_1):PAGE161
 R4194    1      A Q_RES_0402LF-1K,1%,1/16W,EMPTYA   I128 @S9S_MB_2U_LIB.S9S_MB_2U(SCH_1):PAGE161
 R4202    1      A Q_RES_0402LF-1K,1%,1/16W,EMPTYA   I129 @S9S_MB_2U_LIB.S9S_MB_2U(SCH_1):PAGE161
 C2274    1      A Q_CAP_0402-0.1UF,25V,10%,X7R,CA   I139 @S9S_MB_2U_LIB.S9S_MB_2U(SCH_1):PAGE161
 R4184    1      A Q_RES_0402LF-1K,1%,1/16W,EMPTYA   I142 @S9S_MB_2U_LIB.S9S_MB_2U(SCH_1):PAGE161
 R4192    1      A Q_RES_0402LF-1K,1%,1/16W,EMPTYA   I148 @S9S_MB_2U_LIB.S9S_MB_2U(SCH_1):PAGE161
 R4200    1      A Q_RES_0402LF-1K,1%,1/16W,EMPTYA   I149 @S9S_MB_2U_LIB.S9S_MB_2U(SCH_1):PAGE161
 PR176    2      B Q_RES_0402LF-1,1%,1/16W,CHIP,CA   I133 @S9S_MB_2U_LIB.S9S_MB_2U(SCH_1):PAGE252
 R2398    1      A Q_RES_0402LF-1K,1%,1/16W,CHIP,A    I79 @S9S_MB_2U_LIB.S9S_MB_2U(SCH_1):PAGE260
 PR372    1      A Q_RES_0402LF-1K,1%,1/16W,CHIP,A    I14 @S9S_MB_2U_LIB.S9S_MB_2U(SCH_1):PAGE264
 R2357    1      A Q_RES_0402LF-10K,1%,1/16W,CHIPA    I32 @S9S_MB_2U_LIB.S9S_MB_2U(SCH_1):PAGE248
  U308    5    VCC 74LVC2G07DW7-74LVC2G07DW-7,SMLA    I37 @S9S_MB_2U_LIB.S9S_MB_2U(SCH_1):PAGE230
 C2283    1      A Q_CAP_0402-0.1UF,25V,10%,X7R,CA    I40 @S9S_MB_2U_LIB.S9S_MB_2U(SCH_1):PAGE230
 R4264    1      A Q_RES_0402LF-4.7K,5%,1/16W,CHIA    I47 @S9S_MB_2U_LIB.S9S_MB_2U(SCH_1):PAGE230
 R4270    1      A Q_RES_0402LF-2.2K,5%,1/16W,EMPA    I99 @S9S_MB_2U_LIB.S9S_MB_2U(SCH_1):PAGE221
 R4269    1      A Q_RES_0402LF-2.2K,5%,1/16W,EMPA   I102 @S9S_MB_2U_LIB.S9S_MB_2U(SCH_1):PAGE221
  U270    8    VCC LM75BD-LM75BD,SMLF,IC,AL0075BDA   I164 @S9S_MB_2U_LIB.S9S_MB_2U(SCH_1):PAGE161
  U271    8    VCC LM75BD-LM75BD,SMLF,IC,AL0075BDA   I165 @S9S_MB_2U_LIB.S9S_MB_2U(SCH_1):PAGE161
  U272    8    VCC LM75BD-LM75BD,SMLF,IC,AL0075BDA   I166 @S9S_MB_2U_LIB.S9S_MB_2U(SCH_1):PAGE161
  U273    8    VCC LM75BD-LM75BD,SMLF,IC,AL0075BDA   I167 @S9S_MB_2U_LIB.S9S_MB_2U(SCH_1):PAGE161
 R4281    1      A Q_RES_0402LF-1K,1%,1/16W,EMPTYA     I7 @S9S_MB_2U_LIB.S9S_MB_2U(SCH_1):PAGE162
 R4284    1      A Q_RES_0402LF-1K,1%,1/16W,EMPTYA    I41 @S9S_MB_2U_LIB.S9S_MB_2U(SCH_1):PAGE162
 R4036    1      A Q_RES_0402LF-4.32K,1%,1/16W,CHA   I128 @S9S_MB_2U_LIB.S9S_MB_2U(SCH_1):PAGE322
 R4037    1      A Q_RES_0402LF-4.32K,1%,1/16W,CHA   I130 @S9S_MB_2U_LIB.S9S_MB_2U(SCH_1):PAGE322
  R947    1      A Q_RES_0402LF-10K,1%,1/16W,CHIPA    I11 @S9S_MB_2U_LIB.S9S_MB_2U(SCH_1):PAGE115
  R946    1      A Q_RES_0402LF-10K,1%,1/16W,CHIPA    I14 @S9S_MB_2U_LIB.S9S_MB_2U(SCH_1):PAGE115
  R945    1      A Q_RES_0402LF-10K,1%,1/16W,CHIPA    I16 @S9S_MB_2U_LIB.S9S_MB_2U(SCH_1):PAGE115
  R944    1      A Q_RES_0402LF-10K,1%,1/16W,CHIPA    I19 @S9S_MB_2U_LIB.S9S_MB_2U(SCH_1):PAGE115
   D49    2      C SCHOTTKY_12-B0530WS7F,SMLF,IC,A    I22 @S9S_MB_2U_LIB.S9S_MB_2U(SCH_1):PAGE115
   D48    2      C SCHOTTKY_12-B0530WS7F,SMLF,IC,A    I25 @S9S_MB_2U_LIB.S9S_MB_2U(SCH_1):PAGE115
   D47    2      C SCHOTTKY_12-B0530WS7F,SMLF,IC,A    I27 @S9S_MB_2U_LIB.S9S_MB_2U(SCH_1):PAGE115
  R941    1      A Q_RES_0402LF-10K,1%,1/16W,CHIPA    I45 @S9S_MB_2U_LIB.S9S_MB_2U(SCH_1):PAGE115
  R940    1      A Q_RES_0402LF-10K,1%,1/16W,CHIPA    I48 @S9S_MB_2U_LIB.S9S_MB_2U(SCH_1):PAGE115
   D43    2      C SCHOTTKY_12-B0530WS7F,SMLF,IC,A    I54 @S9S_MB_2U_LIB.S9S_MB_2U(SCH_1):PAGE115
   D42    2      C SCHOTTKY_12-B0530WS7F,SMLF,IC,A    I59 @S9S_MB_2U_LIB.S9S_MB_2U(SCH_1):PAGE115
 PU205  1_2    VCC MP5016GQHLZ-MP5016GQH-L-Z,SMLFA    I50 @S9S_MB_2U_LIB.S9S_MB_2U(SCH_1):PAGE236
PC2159    1      A Q_CAP_C0402-1UF,25V,10%,EMPTY,A    I55 @S9S_MB_2U_LIB.S9S_MB_2U(SCH_1):PAGE236
PC2169    1      A Q_CAP_C0402-1UF,25V,10%,EMPTY,A    I48 @S9S_MB_2U_LIB.S9S_MB_2U(SCH_1):PAGE237
   D46    2      C SCHOTTKY_12-B0530WS7F,SMLF,IC,A    I29 @S9S_MB_2U_LIB.S9S_MB_2U(SCH_1):PAGE115
  R943    1      A Q_RES_0402LF-10K,1%,1/16W,CHIPA    I37 @S9S_MB_2U_LIB.S9S_MB_2U(SCH_1):PAGE115
  R942    1      A Q_RES_0402LF-10K,1%,1/16W,CHIPA    I40 @S9S_MB_2U_LIB.S9S_MB_2U(SCH_1):PAGE115
   D45    2      C SCHOTTKY_12-B0530WS7F,SMLF,IC,A    I50 @S9S_MB_2U_LIB.S9S_MB_2U(SCH_1):PAGE115
   D44    2      C SCHOTTKY_12-B0530WS7F,SMLF,IC,A    I52 @S9S_MB_2U_LIB.S9S_MB_2U(SCH_1):PAGE115
 R4448    1      A Q_RES_0402LF-10K,1%,1/16W,EMPTA     I9 @S9S_MB_2U_LIB.S9S_MB_2U(SCH_1):PAGE194
  U312   12    VCC TUSB211IRWBR-TUSB211IRWBR,SMLFA    I20 @S9S_MB_2U_LIB.S9S_MB_2U(SCH_1):PAGE194
 R4459    1      A Q_RES_0402LF-10K,1%,1/16W,EMPTA    I22 @S9S_MB_2U_LIB.S9S_MB_2U(SCH_1):PAGE194
 R4458    1      A Q_RES_0402LF-10K,1%,1/16W,EMPTA    I23 @S9S_MB_2U_LIB.S9S_MB_2U(SCH_1):PAGE194
 R4457    1      A Q_RES_0402LF-10K,1%,1/16W,EMPTA    I24 @S9S_MB_2U_LIB.S9S_MB_2U(SCH_1):PAGE194
 R4456    1      A Q_RES_0402LF-10K,1%,1/16W,EMPTA    I25 @S9S_MB_2U_LIB.S9S_MB_2U(SCH_1):PAGE194
 R4452    1      A Q_RES_0402LF-10K,1%,1/16W,EMPTA    I27 @S9S_MB_2U_LIB.S9S_MB_2U(SCH_1):PAGE194
 R4450    1      A Q_RES_0402LF-0,5%,1/16W,EMPTY,A    I41 @S9S_MB_2U_LIB.S9S_MB_2U(SCH_1):PAGE194
 C2323    1      A Q_CAP_C0402-1UF,25V,10%,EMPTY,A    I56 @S9S_MB_2U_LIB.S9S_MB_2U(SCH_1):PAGE194
 C2324    1      A Q_CAP_0402-0.1UF,25V,10%,EMPTYA    I58 @S9S_MB_2U_LIB.S9S_MB_2U(SCH_1):PAGE194
 R4211    1      A Q_RES_0402LF-200K,1%,1/16W,CHIA   I168 @S9S_MB_2U_LIB.S9S_MB_2U(SCH_1):PAGE161
 R4209    1      A Q_RES_0402LF-200K,1%,1/16W,EMPA   I169 @S9S_MB_2U_LIB.S9S_MB_2U(SCH_1):PAGE161
 R4210    1      A Q_RES_0402LF-200K,1%,1/16W,EMPA   I170 @S9S_MB_2U_LIB.S9S_MB_2U(SCH_1):PAGE161
 R4208    1      A Q_RES_0402LF-200K,1%,1/16W,EMPA   I171 @S9S_MB_2U_LIB.S9S_MB_2U(SCH_1):PAGE161
 C2337    1      A Q_CAP_0402-0.1UF,25V,10%,X7R,CA     I5 @S9S_MB_2U_LIB.S9S_MB_2U(SCH_1):PAGE225
  U315    1   VCCA PCA9617ADP-PCA9617ADP,SMLF,IC,A    I17 @S9S_MB_2U_LIB.S9S_MB_2U(SCH_1):PAGE225
 R2392    1      A Q_RES_0402LF-1K,1%,1/16W,CHIP,A    I18 @S9S_MB_2U_LIB.S9S_MB_2U(SCH_1):PAGE260
 R2404    1      A Q_RES_0402LF-1K,1%,1/16W,CHIP,A    I85 @S9S_MB_2U_LIB.S9S_MB_2U(SCH_1):PAGE264
 PR323    2      B Q_RES_0402LF-1,1%,1/16W,CHIP,CA   I126 @S9S_MB_2U_LIB.S9S_MB_2U(SCH_1):PAGE270
 R2589    1      A Q_RES_0402LF-1K,1%,1/16W,CHIP,A    I20 @S9S_MB_2U_LIB.S9S_MB_2U(SCH_1):PAGE252
 R1713    2      B Q_RES_0402LF-4.7K,5%,1/16W,EMPA    I40 @S9S_MB_2U_LIB.S9S_MB_2U(SCH_1):PAGE252
 PR215    1      A Q_RES_0402LF-1K,1%,1/16W,CHIP,A    I18 @S9S_MB_2U_LIB.S9S_MB_2U(SCH_1):PAGE282
 PR217    1      A Q_RES_0402LF-1K,1%,1/16W,CHIP,A    I20 @S9S_MB_2U_LIB.S9S_MB_2U(SCH_1):PAGE282
  R223    1      A Q_RES_0402LF-1K,1%,1/16W,CHIP,A    I85 @S9S_MB_2U_LIB.S9S_MB_2U(SCH_1):PAGE282
  D141    1      A SCHOTTKY_12-1N5819HW,SMLF,IC,BA    I91 @S9S_MB_2U_LIB.S9S_MB_2U(SCH_1):PAGE210
 R4515    1      A Q_RES_0402LF-100K,1%,1/16W,CHIA   I200 @S9S_MB_2U_LIB.S9S_MB_2U(SCH_1):PAGE140
 R4173    1      A Q_RES_0402LF-100K,1%,1/16W,EMPA   I202 @S9S_MB_2U_LIB.S9S_MB_2U(SCH_1):PAGE140
 R4521    1      A Q_RES_0402LF-10K,1%,1/16W,CHIPA   I163 @S9S_MB_2U_LIB.S9S_MB_2U(SCH_1):PAGE201
 R4546    1      A Q_RES_0402LF-4.7K,5%,1/16W,EMPA    I50 @S9S_MB_2U_LIB.S9S_MB_2U(SCH_1):PAGE139
 R4545    1      A Q_RES_0402LF-4.7K,5%,1/16W,CHIA    I57 @S9S_MB_2U_LIB.S9S_MB_2U(SCH_1):PAGE139
 R4551    1      A Q_RES_0402LF-54.9K,1%,1/16W,EMA    I51 @S9S_MB_2U_LIB.S9S_MB_2U(SCH_1):PAGE230
 R4553    1      A Q_RES_0402LF-4.7K,5%,1/16W,CHIA    I55 @S9S_MB_2U_LIB.S9S_MB_2U(SCH_1):PAGE230
 R4554    1      A Q_RES_0402LF-4.7K,5%,1/16W,CHIA    I59 @S9S_MB_2U_LIB.S9S_MB_2U(SCH_1):PAGE230
  U212    5    VCC 74LVC2G07DW7-74LVC2G07DW-7,SMLA    I23 @S9S_MB_2U_LIB.S9S_MB_2U(SCH_1):PAGE153
  U211    5    VCC 74LVC2G07DW7-74LVC2G07DW-7,SMLA    I26 @S9S_MB_2U_LIB.S9S_MB_2U(SCH_1):PAGE153
  C593    1      A Q_CAP_0402-0.1UF,25V,10%,X7R,CA    I27 @S9S_MB_2U_LIB.S9S_MB_2U(SCH_1):PAGE153
 R1149    1      A Q_RES_0402LF-10K,1%,1/16W,CHIPA    I50 @S9S_MB_2U_LIB.S9S_MB_2U(SCH_1):PAGE153
 R3799    1      A Q_RES_0402LF-100K,1%,1/16W,EMPA    I90 @S9S_MB_2U_LIB.S9S_MB_2U(SCH_1):PAGE153
 R3797    1      A Q_RES_0402LF-100K,1%,1/16W,EMPA    I92 @S9S_MB_2U_LIB.S9S_MB_2U(SCH_1):PAGE153
 R3134    1      A Q_RES_0402LF-1K,1%,1/16W,CHIP,A     I3 @S9S_MB_2U_LIB.S9S_MB_2U(SCH_1):PAGE131
 R3136    1      A Q_RES_0402LF-1K,1%,1/16W,CHIP,A     I5 @S9S_MB_2U_LIB.S9S_MB_2U(SCH_1):PAGE131
 R3133    1      A Q_RES_0402LF-1K,1%,1/16W,CHIP,A    I11 @S9S_MB_2U_LIB.S9S_MB_2U(SCH_1):PAGE131
 R3135    1      A Q_RES_0402LF-1K,1%,1/16W,CHIP,A    I13 @S9S_MB_2U_LIB.S9S_MB_2U(SCH_1):PAGE131
   U59    5    VCC 74LVC2G07DW7-74LVC2G07DW-7,SMLA    I19 @S9S_MB_2U_LIB.S9S_MB_2U(SCH_1):PAGE131
   U58    5    VCC 74LVC2G07DW7-74LVC2G07DW-7,SMLA    I25 @S9S_MB_2U_LIB.S9S_MB_2U(SCH_1):PAGE131
PC2140    1      A Q_CAP_C0402-1UF,25V,10%,X6S,CHA    I52 @S9S_MB_2U_LIB.S9S_MB_2U(SCH_1):PAGE131
 R3147    1      A Q_RES_0402LF-10K,1%,1/16W,CHIPA    I66 @S9S_MB_2U_LIB.S9S_MB_2U(SCH_1):PAGE131
 R3825    1      A Q_RES_0402LF-100K,1%,1/16W,EMPA    I81 @S9S_MB_2U_LIB.S9S_MB_2U(SCH_1):PAGE131
 PU200   A3  IN_A3 MAX15090BEWIT-MAX15090BEWI+T,SB    I90 @S9S_MB_2U_LIB.S9S_MB_2U(SCH_1):PAGE131
 PU200   A5  IN_A5 MAX15090BEWIT-MAX15090BEWI+T,SB    I90 @S9S_MB_2U_LIB.S9S_MB_2U(SCH_1):PAGE131
 PU200   B3  IN_B3 MAX15090BEWIT-MAX15090BEWI+T,SB    I90 @S9S_MB_2U_LIB.S9S_MB_2U(SCH_1):PAGE131
 PU200   B5  IN_B5 MAX15090BEWIT-MAX15090BEWI+T,SB    I90 @S9S_MB_2U_LIB.S9S_MB_2U(SCH_1):PAGE131
 PU200   C3  IN_C3 MAX15090BEWIT-MAX15090BEWI+T,SB    I90 @S9S_MB_2U_LIB.S9S_MB_2U(SCH_1):PAGE131
 PU200   C5  IN_C5 MAX15090BEWIT-MAX15090BEWI+T,SB    I90 @S9S_MB_2U_LIB.S9S_MB_2U(SCH_1):PAGE131
 PU200   D5  IN_D5 MAX15090BEWIT-MAX15090BEWI+T,SB    I90 @S9S_MB_2U_LIB.S9S_MB_2U(SCH_1):PAGE131
PR3782    1      A Q_RES_0402LF-10,1%,1/16W,CHIP,A    I92 @S9S_MB_2U_LIB.S9S_MB_2U(SCH_1):PAGE131
 PU207  1_2    VCC MP5016GQHLZ-MP5016GQH-L-Z,SMLFA    I51 @S9S_MB_2U_LIB.S9S_MB_2U(SCH_1):PAGE237
 R3979    1      A Q_RES_0402LF-100K,1%,1/16W,CHIA    I50 @S9S_MB_2U_LIB.S9S_MB_2U(SCH_1):PAGE324
 R3978    1      A Q_RES_0402LF-100K,1%,1/16W,EMPA    I76 @S9S_MB_2U_LIB.S9S_MB_2U(SCH_1):PAGE324
 PU293  1_2    VCC MP5016GQHLZ-MP5016GQH-L-Z,SMLFA    I31 @S9S_MB_2U_LIB.S9S_MB_2U(SCH_1):PAGE323
PR3951    2      B Q_RES_0402LF-10K,1%,1/16W,CHIPA    I54 @S9S_MB_2U_LIB.S9S_MB_2U(SCH_1):PAGE323
 R1854    1      A Q_RES_0402LF-10K,1%,1/16W,CHIPA     I2 @S9S_MB_2U_LIB.S9S_MB_2U(SCH_1):PAGE229
 R4013    1      A Q_RES_0402LF-100K,1%,1/16W,EMPA    I79 @S9S_MB_2U_LIB.S9S_MB_2U(SCH_1):PAGE229
 R4015    1      A Q_RES_0402LF-100K,1%,1/16W,EMPA    I81 @S9S_MB_2U_LIB.S9S_MB_2U(SCH_1):PAGE229
 R2407    1      A Q_RES_0402LF-10K,1%,1/16W,CHIPA    I45 @S9S_MB_2U_LIB.S9S_MB_2U(SCH_1):PAGE267
PR3338    1      A Q_RES_0402LF-0,5%,1/16W,CHIP,CA    I13 @S9S_MB_2U_LIB.S9S_MB_2U(SCH_1):PAGE286
 R4543    1      A Q_RES_0402LF-4.7K,5%,1/16W,CHIA    I85 @S9S_MB_2U_LIB.S9S_MB_2U(SCH_1):PAGE139
  U316    5    VCC 74LVC2G17GW-74LVC2G17GW,SMLF,IA    I86 @S9S_MB_2U_LIB.S9S_MB_2U(SCH_1):PAGE139
 R4547    1      A Q_RES_0402LF-100K,1%,1/16W,EMPA    I89 @S9S_MB_2U_LIB.S9S_MB_2U(SCH_1):PAGE139
 C2341    1      A Q_CAP_0402-0.1UF,25V,10%,X7R,CA    I93 @S9S_MB_2U_LIB.S9S_MB_2U(SCH_1):PAGE139
 R4549    1      A Q_RES_0402LF-4.7K,5%,1/16W,EMPA    I98 @S9S_MB_2U_LIB.S9S_MB_2U(SCH_1):PAGE139
   U39   24    VCC TCA9548APWR-TCA9548APWR,SMLF,IA   I103 @S9S_MB_2U_LIB.S9S_MB_2U(SCH_1):PAGE221
 C2056    1      A Q_CAP_0402-0.1UF,25V,10%,X7R,CA   I106 @S9S_MB_2U_LIB.S9S_MB_2U(SCH_1):PAGE221
 R3705    1      A Q_RES_0402LF-10K,1%,1/16W,EMPTA   I147 @S9S_MB_2U_LIB.S9S_MB_2U(SCH_1):PAGE221
 R4561    1      A Q_RES_0402LF-4.7K,5%,1/16W,CHIA   I116 @S9S_MB_2U_LIB.S9S_MB_2U(SCH_1):PAGE143
 R4560    1      A Q_RES_0402LF-4.7K,5%,1/16W,CHIA   I124 @S9S_MB_2U_LIB.S9S_MB_2U(SCH_1):PAGE143
 R4562    1      A Q_RES_0402LF-100K,1%,1/16W,EMPA   I132 @S9S_MB_2U_LIB.S9S_MB_2U(SCH_1):PAGE143
 C2344    1      A Q_CAP_0402-0.1UF,25V,10%,X7R,CA    I87 @S9S_MB_2U_LIB.S9S_MB_2U(SCH_1):PAGE152
 C2345    1      A Q_CAP_0402-0.1UF,25V,10%,X7R,CA    I81 @S9S_MB_2U_LIB.S9S_MB_2U(SCH_1):PAGE156
 R4597    1      A Q_RES_0402LF-10K,1%,1/16W,EMPTA    I22 @S9S_MB_2U_LIB.S9S_MB_2U(SCH_1):PAGE184
 R4586    1      A Q_RES_0402LF-10K,1%,1/16W,CHIPA    I62 @S9S_MB_2U_LIB.S9S_MB_2U(SCH_1):PAGE184
 R1195    1      A Q_RES_0402LF-130,1%,1/16W,CHIPA   I278 @S9S_MB_2U_LIB.S9S_MB_2U(SCH_1):PAGE207
  R366    1      A Q_RES_0402LF-249,1%,1/16W,CHIPA   I280 @S9S_MB_2U_LIB.S9S_MB_2U(SCH_1):PAGE207
  U209   24    VDD PCA9555APW-PCA9555APW,SMLF,IC,A   I206 @S9S_MB_2U_LIB.S9S_MB_2U(SCH_1):PAGE154
   U51   24    VDD PCA9555APW-PCA9555APW,SMLF,IC,A    I66 @S9S_MB_2U_LIB.S9S_MB_2U(SCH_1):PAGE132
 R4604    1      A Q_RES_0402LF-4.7K,5%,1/16W,CHIA    I18 @S9S_MB_2U_LIB.S9S_MB_2U(SCH_1):PAGE213
 R4605    1      A Q_RES_0402LF-4.7K,5%,1/16W,CHIA    I22 @S9S_MB_2U_LIB.S9S_MB_2U(SCH_1):PAGE213
 C1243    1      A Q_CAP_C0805-47UF,6.3V,20%,X6S,A   I162 @S9S_MB_2U_LIB.S9S_MB_2U(SCH_1):PAGE181
 C1245    1      A Q_CAP_C0805-47UF,6.3V,20%,X6S,A   I163 @S9S_MB_2U_LIB.S9S_MB_2U(SCH_1):PAGE181
   U16    5    VCC 74LVC1G66GV-74LVC1G66GV,SMLF,IA   I115 @S9S_MB_2U_LIB.S9S_MB_2U(SCH_1):PAGE135
 R1493    1      A Q_RES_0402LF-1K,1%,1/16W,CHIP,A   I191 @S9S_MB_2U_LIB.S9S_MB_2U(SCH_1):PAGE312
  U322    5    VCC 74LVC1G08W57-74LVC1G08W5-7,SMLA   I221 @S9S_MB_2U_LIB.S9S_MB_2U(SCH_1):PAGE154
 C2346    1      A Q_CAP_0402-0.1UF,25V,10%,X7R,CA   I223 @S9S_MB_2U_LIB.S9S_MB_2U(SCH_1):PAGE154
 R3160    1      A Q_RES_0402LF-1K,1%,1/16W,EMPTYA   I235 @S9S_MB_2U_LIB.S9S_MB_2U(SCH_1):PAGE154
 C2347    1      A Q_CAP_0402-0.1UF,25V,10%,X7R,CA    I90 @S9S_MB_2U_LIB.S9S_MB_2U(SCH_1):PAGE132
  U323    5    VCC 74LVC1G08W57-74LVC1G08W5-7,SMLA    I92 @S9S_MB_2U_LIB.S9S_MB_2U(SCH_1):PAGE132
 R1132    1      A Q_RES_0402LF-1K,1%,1/16W,EMPTYA    I95 @S9S_MB_2U_LIB.S9S_MB_2U(SCH_1):PAGE132
 PR220    2      B Q_RES_0402LF-1,1%,1/16W,CHIP,CA    I78 @S9S_MB_2U_LIB.S9S_MB_2U(SCH_1):PAGE282
 R2571    1      A Q_RES_0402LF-1K,1%,1/16W,CHIP,A    I30 @S9S_MB_2U_LIB.S9S_MB_2U(SCH_1):PAGE278
 R2569    1      A Q_RES_0402LF-1K,1%,1/16W,CHIP,A    I49 @S9S_MB_2U_LIB.S9S_MB_2U(SCH_1):PAGE278
 R2568    1      A Q_RES_0402LF-1K,1%,1/16W,CHIP,A    I50 @S9S_MB_2U_LIB.S9S_MB_2U(SCH_1):PAGE278
 R2556    1      A Q_RES_0402LF-1K,1%,1/16W,CHIP,A   I105 @S9S_MB_2U_LIB.S9S_MB_2U(SCH_1):PAGE278
 PR283    2      B Q_RES_0402LF-1,1%,1/16W,CHIP,CA   I108 @S9S_MB_2U_LIB.S9S_MB_2U(SCH_1):PAGE278
 PR370    1      A Q_RES_0402LF-1K,1%,1/16W,CHIP,A    I13 @S9S_MB_2U_LIB.S9S_MB_2U(SCH_1):PAGE264
 PR375    2      B Q_RES_0402LF-1,1%,1/16W,CHIP,CA    I80 @S9S_MB_2U_LIB.S9S_MB_2U(SCH_1):PAGE264
 R2373    1      A Q_RES_0402LF-1K,1%,1/16W,CHIP,A    I23 @S9S_MB_2U_LIB.S9S_MB_2U(SCH_1):PAGE252
 R1712    2      B Q_RES_0402LF-4.7K,5%,1/16W,EMPA    I42 @S9S_MB_2U_LIB.S9S_MB_2U(SCH_1):PAGE252
 R2377    1      A Q_RES_0402LF-1K,1%,1/16W,CHIP,A    I54 @S9S_MB_2U_LIB.S9S_MB_2U(SCH_1):PAGE252
 R2551    1      A Q_RES_0402LF-1K,1%,1/16W,CHIP,A    I15 @S9S_MB_2U_LIB.S9S_MB_2U(SCH_1):PAGE270
 R2396    1      A Q_RES_0402LF-1K,1%,1/16W,CHIP,A    I13 @S9S_MB_2U_LIB.S9S_MB_2U(SCH_1):PAGE260
 R2393    1      A Q_RES_0402LF-1K,1%,1/16W,CHIP,A    I17 @S9S_MB_2U_LIB.S9S_MB_2U(SCH_1):PAGE260
 PR130    2      B Q_RES_0402LF-1,1%,1/16W,CHIP,CA   I100 @S9S_MB_2U_LIB.S9S_MB_2U(SCH_1):PAGE260
  U321    5    VCC 74LVC1G66GV-74LVC1G66GV,SMLF,IA    I92 @S9S_MB_2U_LIB.S9S_MB_2U(SCH_1):PAGE156
  U320    5    VCC 74LVC1G66GV-74LVC1G66GV,SMLF,IA    I92 @S9S_MB_2U_LIB.S9S_MB_2U(SCH_1):PAGE152
PR1326    1      A Q_RES_0402LF-0,5%,1/16W,CHIP,CA     I3 @S9S_MB_2U_LIB.S9S_MB_2U(SCH_1):PAGE248
PR1338    1      A Q_RES_0402LF-0,5%,1/16W,CHIP,CA     I3 @S9S_MB_2U_LIB.S9S_MB_2U(SCH_1):PAGE285
 C2364    1      A Q_CAP_0402-0.1UF,25V,10%,EMPTYA    I33 @S9S_MB_2U_LIB.S9S_MB_2U(SCH_1):PAGE240
 R4692    1      A Q_RES_0402LF-4.7K,1%,1/16W,EMPA    I35 @S9S_MB_2U_LIB.S9S_MB_2U(SCH_1):PAGE240
 R3925    2      B Q_RES_0402LF-1K,1%,1/16W,CHIP,A    I33 @S9S_MB_2U_LIB.S9S_MB_2U(SCH_1):PAGE303
 C2458    1      A Q_CAP_0402-0.1UF,25V,10%,EMPTYA     I8 @S9S_MB_2U_LIB.S9S_MB_2U(SCH_1):PAGE327
  U345    1    VDD NCT7718W-NCT7718W,SMLF,EMPTY,AA    I10 @S9S_MB_2U_LIB.S9S_MB_2U(SCH_1):PAGE327
 R4686    1      A Q_RES_0402LF-10.5K,1%,1/16W,EMA    I17 @S9S_MB_2U_LIB.S9S_MB_2U(SCH_1):PAGE327
 R4685    1      A Q_RES_0402LF-10.5K,1%,1/16W,EMA    I23 @S9S_MB_2U_LIB.S9S_MB_2U(SCH_1):PAGE327
  PJ42   12     12 SCONN21_9193031121LF-SCONN21_9A    I34 @S9S_MB_2U_LIB.S9S_MB_2U(SCH_1):PAGE327
 R2230    1      A Q_RES_0402LF-10K,1%,1/16W,CHIPA    I39 @S9S_MB_2U_LIB.S9S_MB_2U(SCH_1):PAGE326
 R2233    1      A Q_RES_0402LF-10K,1%,1/16W,CHIPA    I41 @S9S_MB_2U_LIB.S9S_MB_2U(SCH_1):PAGE326
 R4620    1      A Q_RES_0402LF-4.7K,5%,1/16W,CHIA    I45 @S9S_MB_2U_LIB.S9S_MB_2U(SCH_1):PAGE326
 R4671    1      A Q_RES_0402LF-10K,1%,1/16W,EMPTA    I51 @S9S_MB_2U_LIB.S9S_MB_2U(SCH_1):PAGE326
 R4672    1      A Q_RES_0402LF-10K,1%,1/16W,EMPTA    I53 @S9S_MB_2U_LIB.S9S_MB_2U(SCH_1):PAGE326
 R3271    1      A Q_RES_0402LF-1K,1%,1/16W,EMPTYA     I9 @S9S_MB_2U_LIB.S9S_MB_2U(SCH_1):PAGE136
 R3269    1      A Q_RES_0402LF-1K,1%,1/16W,EMPTYA    I15 @S9S_MB_2U_LIB.S9S_MB_2U(SCH_1):PAGE136
 R3275    1      A Q_RES_0402LF-1K,1%,1/16W,EMPTYA    I21 @S9S_MB_2U_LIB.S9S_MB_2U(SCH_1):PAGE136
 R3280    1      A Q_RES_0402LF-1K,1%,1/16W,EMPTYA    I32 @S9S_MB_2U_LIB.S9S_MB_2U(SCH_1):PAGE136
 C1863    1      A Q_CAP_0402-0.1UF,25V,10%,X7R,CA    I49 @S9S_MB_2U_LIB.S9S_MB_2U(SCH_1):PAGE136
  U237    1   VDD1 PI3EQX12902AZLEX-PI3EQX12902AZA    I50 @S9S_MB_2U_LIB.S9S_MB_2U(SCH_1):PAGE136
  U237   10   VDD2 PI3EQX12902AZLEX-PI3EQX12902AZA    I50 @S9S_MB_2U_LIB.S9S_MB_2U(SCH_1):PAGE136
  U237   16   VDD3 PI3EQX12902AZLEX-PI3EQX12902AZA    I50 @S9S_MB_2U_LIB.S9S_MB_2U(SCH_1):PAGE136
  U237   25   VDD4 PI3EQX12902AZLEX-PI3EQX12902AZA    I50 @S9S_MB_2U_LIB.S9S_MB_2U(SCH_1):PAGE136
 C1864    1      A Q_CAP_0402-0.1UF,25V,10%,X7R,CA    I51 @S9S_MB_2U_LIB.S9S_MB_2U(SCH_1):PAGE136
 C1865    1      A Q_CAP_0402-0.1UF,25V,10%,X7R,CA    I52 @S9S_MB_2U_LIB.S9S_MB_2U(SCH_1):PAGE136
 C1866    1      A Q_CAP_0402-0.1UF,25V,10%,X7R,CA    I53 @S9S_MB_2U_LIB.S9S_MB_2U(SCH_1):PAGE136
 R3283    1      A Q_RES_0402LF-1K,1%,1/16W,EMPTYA    I57 @S9S_MB_2U_LIB.S9S_MB_2U(SCH_1):PAGE136
 R3286    1      A Q_RES_0402LF-1K,1%,1/16W,EMPTYA    I64 @S9S_MB_2U_LIB.S9S_MB_2U(SCH_1):PAGE136
 R3292    1      A Q_RES_0402LF-4.7K,1%,1/16W,CHIA    I85 @S9S_MB_2U_LIB.S9S_MB_2U(SCH_1):PAGE136
 R3266    1      A Q_RES_0402LF-4.7K,1%,1/16W,CHIA    I89 @S9S_MB_2U_LIB.S9S_MB_2U(SCH_1):PAGE136
 R4642    1      A Q_RES_0402LF-1K,1%,1/16W,EMPTYA     I7 @S9S_MB_2U_LIB.S9S_MB_2U(SCH_1):PAGE159
 R4644    1      A Q_RES_0402LF-1K,1%,1/16W,EMPTYA    I11 @S9S_MB_2U_LIB.S9S_MB_2U(SCH_1):PAGE159
 R4643    1      A Q_RES_0402LF-1K,1%,1/16W,EMPTYA    I13 @S9S_MB_2U_LIB.S9S_MB_2U(SCH_1):PAGE159
 R4648    1      A Q_RES_0402LF-1K,1%,1/16W,EMPTYA    I72 @S9S_MB_2U_LIB.S9S_MB_2U(SCH_1):PAGE159
 R4649    1      A Q_RES_0402LF-1K,1%,1/16W,EMPTYA    I74 @S9S_MB_2U_LIB.S9S_MB_2U(SCH_1):PAGE159
 C2355    1      A Q_CAP_C0402-1UF,25V,10%,X6S,CHA    I96 @S9S_MB_2U_LIB.S9S_MB_2U(SCH_1):PAGE159
 C2356    1      A Q_CAP_C0805-10UF,16V,10%,X6S,CA    I98 @S9S_MB_2U_LIB.S9S_MB_2U(SCH_1):PAGE159
 R2344    1      A Q_RES_0402LF-4.7K,5%,1/16W,CHIA    I45 @S9S_MB_2U_LIB.S9S_MB_2U(SCH_1):PAGE314
 R1681    1      A Q_RES_0402LF-10K,1%,1/16W,CHIPA    I47 @S9S_MB_2U_LIB.S9S_MB_2U(SCH_1):PAGE314
 R2346    1      A Q_RES_0402LF-4.7K,5%,1/16W,CHIA    I51 @S9S_MB_2U_LIB.S9S_MB_2U(SCH_1):PAGE314
 R1551    1      A Q_RES_0402LF-4.7K,1%,1/16W,EMPA   I179 @S9S_MB_2U_LIB.S9S_MB_2U(SCH_1):PAGE314
  U224    5    VCC 74LVC1G126SE7-74LVC1G126SE-7,SA     I7 @S9S_MB_2U_LIB.S9S_MB_2U(SCH_1):PAGE151
 C1840    1      A Q_CAP_0402-0.1UF,25V,10%,X7R,CA     I8 @S9S_MB_2U_LIB.S9S_MB_2U(SCH_1):PAGE151
   U66    5    VCC 74LVC1G126SE7-74LVC1G126SE-7,SA    I15 @S9S_MB_2U_LIB.S9S_MB_2U(SCH_1):PAGE151
  C639    1      A Q_CAP_0402-0.1UF,25V,10%,X7R,CA    I22 @S9S_MB_2U_LIB.S9S_MB_2U(SCH_1):PAGE151
   U68   14    VCC 74CBTLV3126PW-74CBTLV3126PW,SMA    I30 @S9S_MB_2U_LIB.S9S_MB_2U(SCH_1):PAGE151
  C641    1      A Q_CAP_0402-0.1UF,25V,10%,X7R,CA    I32 @S9S_MB_2U_LIB.S9S_MB_2U(SCH_1):PAGE151
   U67   14    VCC 74CBTLV3126PW-74CBTLV3126PW,SMA    I39 @S9S_MB_2U_LIB.S9S_MB_2U(SCH_1):PAGE151
  C640    1      A Q_CAP_0402-0.1UF,25V,10%,X7R,CA    I40 @S9S_MB_2U_LIB.S9S_MB_2U(SCH_1):PAGE151
  R735    1      A Q_RES_0402LF-10K,1%,1/16W,CHIPA    I13 @S9S_MB_2U_LIB.S9S_MB_2U(SCH_1):PAGE209
 R1660    2      B Q_RES_0402LF-10K,1%,1/16W,EMPTA    I14 @S9S_MB_2U_LIB.S9S_MB_2U(SCH_1):PAGE209
 R1558    2      B Q_RES_0402LF-10K,1%,1/16W,EMPTA    I15 @S9S_MB_2U_LIB.S9S_MB_2U(SCH_1):PAGE209
 R1401    2      B Q_RES_0402LF-10K,1%,1/16W,CHIPA    I16 @S9S_MB_2U_LIB.S9S_MB_2U(SCH_1):PAGE209
 R1399    2      B Q_RES_0402LF-10K,1%,1/16W,CHIPA    I17 @S9S_MB_2U_LIB.S9S_MB_2U(SCH_1):PAGE209
 R1492    2      B Q_RES_0402LF-10K,1%,1/16W,CHIPA    I35 @S9S_MB_2U_LIB.S9S_MB_2U(SCH_1):PAGE209
 R1474    2      B Q_RES_0402LF-1K,1%,1/16W,CHIP,A    I36 @S9S_MB_2U_LIB.S9S_MB_2U(SCH_1):PAGE209
 R1473    2      B Q_RES_0402LF-1K,1%,1/16W,CHIP,A    I37 @S9S_MB_2U_LIB.S9S_MB_2U(SCH_1):PAGE209
 R1741    2      B Q_RES_0402LF-1K,1%,1/16W,CHIP,A    I38 @S9S_MB_2U_LIB.S9S_MB_2U(SCH_1):PAGE209
 R2244    2      B Q_RES_0402LF-10K,1%,1/16W,CHIPA    I39 @S9S_MB_2U_LIB.S9S_MB_2U(SCH_1):PAGE209
  R139    2      B Q_RES_0402LF-10K,1%,1/16W,EMPTA    I40 @S9S_MB_2U_LIB.S9S_MB_2U(SCH_1):PAGE209
 R1440    2      B Q_RES_0402LF-10K,1%,1/16W,EMPTA    I41 @S9S_MB_2U_LIB.S9S_MB_2U(SCH_1):PAGE209
 R1437    2      B Q_RES_0402LF-10K,1%,1/16W,CHIPA    I42 @S9S_MB_2U_LIB.S9S_MB_2U(SCH_1):PAGE209
 R1435    2      B Q_RES_0402LF-10K,1%,1/16W,CHIPA    I43 @S9S_MB_2U_LIB.S9S_MB_2U(SCH_1):PAGE209
 R1434    2      B Q_RES_0402LF-10K,1%,1/16W,CHIPA    I44 @S9S_MB_2U_LIB.S9S_MB_2U(SCH_1):PAGE209
 R1467    1      A Q_RES_0402LF-4.7K,1%,1/16W,EMPA   I178 @S9S_MB_2U_LIB.S9S_MB_2U(SCH_1):PAGE314
PR3339    1      A Q_RES_0402LF-0,5%,1/16W,CHIP,CA    I10 @S9S_MB_2U_LIB.S9S_MB_2U(SCH_1):PAGE268
 R2409    1      A Q_RES_0402LF-10K,1%,1/16W,CHIPA    I32 @S9S_MB_2U_LIB.S9S_MB_2U(SCH_1):PAGE268
 R4275    1      A Q_RES_0402LF-1K,1%,1/16W,EMPTYA     I3 @S9S_MB_2U_LIB.S9S_MB_2U(SCH_1):PAGE162
 R4273    1      A Q_RES_0402LF-1K,1%,1/16W,EMPTYA    I12 @S9S_MB_2U_LIB.S9S_MB_2U(SCH_1):PAGE162
 R4279    1      A Q_RES_0402LF-1K,1%,1/16W,EMPTYA    I18 @S9S_MB_2U_LIB.S9S_MB_2U(SCH_1):PAGE162
   L18    1      1 Q_INDUCTOR_SMLF-BLM15PX121SN1DB    I35 @S9S_MB_2U_LIB.S9S_MB_2U(SCH_1):PAGE162
 R4287    1      A Q_RES_0402LF-1K,1%,1/16W,EMPTYA    I49 @S9S_MB_2U_LIB.S9S_MB_2U(SCH_1):PAGE162
 R4291    1      A Q_RES_0402LF-4.7K,1%,1/16W,EMPA    I65 @S9S_MB_2U_LIB.S9S_MB_2U(SCH_1):PAGE162
 R4289    1      A Q_RES_0402LF-4.7K,1%,1/16W,EMPA    I69 @S9S_MB_2U_LIB.S9S_MB_2U(SCH_1):PAGE162
 R4711    2      B Q_RES_0402LF-249,1%,1/16W,CHIPA    I68 @S9S_MB_2U_LIB.S9S_MB_2U(SCH_1):PAGE241
 R4710    1      A Q_RES_0402LF-4.7K,5%,1/16W,CHIA    I74 @S9S_MB_2U_LIB.S9S_MB_2U(SCH_1):PAGE241
 R4719    1      A Q_RES_0402LF-10K,1%,1/16W,CHIPA    I32 @S9S_MB_2U_LIB.S9S_MB_2U(SCH_1):PAGE213
 C2370    1      A Q_CAP_0402-0.1UF,25V,10%,EMPTYA    I35 @S9S_MB_2U_LIB.S9S_MB_2U(SCH_1):PAGE213
  U332    5    VCC 74LVC2G07DW7-74LVC2G07DW-7,SMLB    I37 @S9S_MB_2U_LIB.S9S_MB_2U(SCH_1):PAGE213
 R4716    1      A Q_RES_0402LF-8.45K,1%,1/16W,EMA    I40 @S9S_MB_2U_LIB.S9S_MB_2U(SCH_1):PAGE213
 R4722    2      B Q_RES_0402LF-10K,1%,1/16W,CHIPA   I246 @S9S_MB_2U_LIB.S9S_MB_2U(SCH_1):PAGE176
 R4121    1      A Q_RES_0402LF-10K,1%,1/16W,CHIPA   I143 @S9S_MB_2U_LIB.S9S_MB_2U(SCH_1):PAGE143
 R4135    1      A Q_RES_0402LF-10K,1%,1/16W,CHIPA   I144 @S9S_MB_2U_LIB.S9S_MB_2U(SCH_1):PAGE143
 R4726    1      A Q_RES_0402LF-4.7K,5%,1/16W,CHIA    I18 @S9S_MB_2U_LIB.S9S_MB_2U(SCH_1):PAGE147
 R4733    1      A Q_RES_0402LF-4.7K,5%,1/16W,CHIA    I25 @S9S_MB_2U_LIB.S9S_MB_2U(SCH_1):PAGE147
 R4725    1      A Q_RES_0402LF-4.7K,5%,1/16W,CHIA    I28 @S9S_MB_2U_LIB.S9S_MB_2U(SCH_1):PAGE147
 R4727    1      A Q_RES_0402LF-10K,1%,1/16W,CHIPA    I33 @S9S_MB_2U_LIB.S9S_MB_2U(SCH_1):PAGE147
 R4732    1      A Q_RES_0402LF-4.7K,5%,1/16W,CHIA    I36 @S9S_MB_2U_LIB.S9S_MB_2U(SCH_1):PAGE147
 R4730    1      A Q_RES_0402LF-10K,1%,1/16W,CHIPA    I41 @S9S_MB_2U_LIB.S9S_MB_2U(SCH_1):PAGE147
 R4740    1      A Q_RES_0402LF-4.7K,5%,1/16W,CHIA    I50 @S9S_MB_2U_LIB.S9S_MB_2U(SCH_1):PAGE147
 R4739    1      A Q_RES_0402LF-4.7K,5%,1/16W,CHIA    I54 @S9S_MB_2U_LIB.S9S_MB_2U(SCH_1):PAGE147
 R4737    1      A Q_RES_0402LF-10K,1%,1/16W,CHIPA    I58 @S9S_MB_2U_LIB.S9S_MB_2U(SCH_1):PAGE147
 R4153    1      A Q_RES_0402LF-10K,1%,1/16W,CHIPA   I145 @S9S_MB_2U_LIB.S9S_MB_2U(SCH_1):PAGE143
 C2376    1      A Q_CAP_0402-0.1UF,25V,10%,X7R,CA   I241 @S9S_MB_2U_LIB.S9S_MB_2U(SCH_1):PAGE154
  U334    5    VCC 74LVC1G08W57-74LVC1G08W5-7,SMLA   I243 @S9S_MB_2U_LIB.S9S_MB_2U(SCH_1):PAGE154
 R4745    1      A Q_RES_0402LF-10K,1%,1/16W,CHIPA   I256 @S9S_MB_2U_LIB.S9S_MB_2U(SCH_1):PAGE154
 R4756    1      A Q_RES_0402LF-10K,1%,1/16W,CHIPA   I105 @S9S_MB_2U_LIB.S9S_MB_2U(SCH_1):PAGE132
  U335    5    VCC 74LVC1G08W57-74LVC1G08W5-7,SMLA   I108 @S9S_MB_2U_LIB.S9S_MB_2U(SCH_1):PAGE132
 C2377    1      A Q_CAP_0402-0.1UF,25V,10%,X7R,CA   I110 @S9S_MB_2U_LIB.S9S_MB_2U(SCH_1):PAGE132
 R4763    1      A Q_RES_0402LF-10K,1%,1/16W,CHIPA   I119 @S9S_MB_2U_LIB.S9S_MB_2U(SCH_1):PAGE132
 R4764    1      A Q_RES_0402LF-10K,1%,1/16W,CHIPA   I257 @S9S_MB_2U_LIB.S9S_MB_2U(SCH_1):PAGE154
 R4768    2      B Q_RES_0402LF-10K,1%,1/16W,CHIPA   I315 @S9S_MB_2U_LIB.S9S_MB_2U(SCH_1):PAGE175
 R4784    1      A Q_RES_0402LF-10K,1%,1/16W,EMPTA     I6 @S9S_MB_2U_LIB.S9S_MB_2U(SCH_1):PAGE329
 R4772    1      A Q_RES_0402LF-10K,1%,1/16W,EMPTA    I21 @S9S_MB_2U_LIB.S9S_MB_2U(SCH_1):PAGE329
 R4785    1      A Q_RES_0402LF-10K,1%,1/16W,EMPTA    I25 @S9S_MB_2U_LIB.S9S_MB_2U(SCH_1):PAGE329
 R4773    1      A Q_RES_0402LF-10K,1%,1/16W,EMPTA    I42 @S9S_MB_2U_LIB.S9S_MB_2U(SCH_1):PAGE329
 R4789    1      A Q_RES_0402LF-10K,1%,1/16W,EMPTA    I49 @S9S_MB_2U_LIB.S9S_MB_2U(SCH_1):PAGE329
 R4786    1      A Q_RES_0402LF-10K,1%,1/16W,EMPTA    I65 @S9S_MB_2U_LIB.S9S_MB_2U(SCH_1):PAGE329
 R4792    1      A Q_RES_0402LF-10K,1%,1/16W,EMPTA    I57 @S9S_MB_2U_LIB.S9S_MB_2U(SCH_1):PAGE326
 R4797    1      A Q_RES_0402LF-10K,1%,1/16W,EMPTA    I80 @S9S_MB_2U_LIB.S9S_MB_2U(SCH_1):PAGE326
 R4801    1      A Q_RES_0402LF-4.7K,5%,1/16W,CHIA    I65 @S9S_MB_2U_LIB.S9S_MB_2U(SCH_1):PAGE147
 R4800    1      A Q_RES_0402LF-4.7K,5%,1/16W,CHIA    I70 @S9S_MB_2U_LIB.S9S_MB_2U(SCH_1):PAGE147
 R4798    1      A Q_RES_0402LF-10K,1%,1/16W,CHIPA    I75 @S9S_MB_2U_LIB.S9S_MB_2U(SCH_1):PAGE147
 R4804    1      A Q_RES_0402LF-1K,1%,1/16W,EMPTYA    I97 @S9S_MB_2U_LIB.S9S_MB_2U(SCH_1):PAGE326
 R4805    1      A Q_RES_0402LF-1K,1%,1/16W,EMPTYA    I99 @S9S_MB_2U_LIB.S9S_MB_2U(SCH_1):PAGE326
 R1906    1      A Q_RES_0402LF-1K,1%,1/16W,CHIP,A     I7 @S9S_MB_2U_LIB.S9S_MB_2U(SCH_1):PAGE153
 R1905    1      A Q_RES_0402LF-1K,1%,1/16W,CHIP,A    I13 @S9S_MB_2U_LIB.S9S_MB_2U(SCH_1):PAGE153
 R1907    1      A Q_RES_0402LF-1K,1%,1/16W,CHIP,A    I25 @S9S_MB_2U_LIB.S9S_MB_2U(SCH_1):PAGE153
  C592    1      A Q_CAP_0402-0.1UF,25V,10%,X7R,CA    I30 @S9S_MB_2U_LIB.S9S_MB_2U(SCH_1):PAGE153
 PU202   A3  IN_A3 MAX15090BEWIT-MAX15090BEWI+T,SB    I61 @S9S_MB_2U_LIB.S9S_MB_2U(SCH_1):PAGE153
 PU202   A5  IN_A5 MAX15090BEWIT-MAX15090BEWI+T,SB    I61 @S9S_MB_2U_LIB.S9S_MB_2U(SCH_1):PAGE153
 PU202   B3  IN_B3 MAX15090BEWIT-MAX15090BEWI+T,SB    I61 @S9S_MB_2U_LIB.S9S_MB_2U(SCH_1):PAGE153
 PU202   B5  IN_B5 MAX15090BEWIT-MAX15090BEWI+T,SB    I61 @S9S_MB_2U_LIB.S9S_MB_2U(SCH_1):PAGE153
 PU202   C3  IN_C3 MAX15090BEWIT-MAX15090BEWI+T,SB    I61 @S9S_MB_2U_LIB.S9S_MB_2U(SCH_1):PAGE153
 PU202   C5  IN_C5 MAX15090BEWIT-MAX15090BEWI+T,SB    I61 @S9S_MB_2U_LIB.S9S_MB_2U(SCH_1):PAGE153
 PU202   D5  IN_D5 MAX15090BEWIT-MAX15090BEWI+T,SB    I61 @S9S_MB_2U_LIB.S9S_MB_2U(SCH_1):PAGE153
PC5328    1      A Q_CAP_C0402-1UF,25V,10%,X6S,CHA    I66 @S9S_MB_2U_LIB.S9S_MB_2U(SCH_1):PAGE153
PR3798    1      A Q_RES_0402LF-10,1%,1/16W,CHIP,A    I73 @S9S_MB_2U_LIB.S9S_MB_2U(SCH_1):PAGE153
 R3796    1      A Q_RES_0402LF-100K,1%,1/16W,CHIA   I108 @S9S_MB_2U_LIB.S9S_MB_2U(SCH_1):PAGE153
 R3783    1      A Q_RES_0402LF-100K,1%,1/16W,CHIA   I110 @S9S_MB_2U_LIB.S9S_MB_2U(SCH_1):PAGE153
PR3839    2      B Q_RES_0402LF-10K,1%,1/16W,CHIPA    I75 @S9S_MB_2U_LIB.S9S_MB_2U(SCH_1):PAGE236
 R4532    1      A Q_RES_0402LF-10K,1%,1/16W,CHIPA    I76 @S9S_MB_2U_LIB.S9S_MB_2U(SCH_1):PAGE236
 C1810    1      A Q_CAP_0402-0.1UF,25V,10%,X7R,CA    I21 @S9S_MB_2U_LIB.S9S_MB_2U(SCH_1):PAGE131
PR3795    1      A Q_RES_0402LF-25.5K,1%,1/16W,CHA    I53 @S9S_MB_2U_LIB.S9S_MB_2U(SCH_1):PAGE131
 R3145    1      A Q_RES_0402LF-10K,1%,1/16W,CHIPA    I64 @S9S_MB_2U_LIB.S9S_MB_2U(SCH_1):PAGE131
 R3833    1      A Q_RES_0402LF-100K,1%,1/16W,CHIA   I108 @S9S_MB_2U_LIB.S9S_MB_2U(SCH_1):PAGE131
 R3826    1      A Q_RES_0402LF-100K,1%,1/16W,CHIA   I110 @S9S_MB_2U_LIB.S9S_MB_2U(SCH_1):PAGE131
PR3851    2      B Q_RES_0402LF-10K,1%,1/16W,CHIPA    I74 @S9S_MB_2U_LIB.S9S_MB_2U(SCH_1):PAGE237
 R3848    1      A Q_RES_0402LF-10K,1%,1/16W,CHIPA    I75 @S9S_MB_2U_LIB.S9S_MB_2U(SCH_1):PAGE237
 R3948    1      A Q_RES_0402LF-10K,1%,1/16W,CHIPA    I64 @S9S_MB_2U_LIB.S9S_MB_2U(SCH_1):PAGE323
PR3963    1      A Q_RES_0402LF-25.5K,1%,1/16W,CHA    I18 @S9S_MB_2U_LIB.S9S_MB_2U(SCH_1):PAGE324
 PU295   A3  IN_A3 MAX15090BEWIT-MAX15090BEWI+T,SB    I35 @S9S_MB_2U_LIB.S9S_MB_2U(SCH_1):PAGE324
 PU295   A5  IN_A5 MAX15090BEWIT-MAX15090BEWI+T,SB    I35 @S9S_MB_2U_LIB.S9S_MB_2U(SCH_1):PAGE324
 PU295   B3  IN_B3 MAX15090BEWIT-MAX15090BEWI+T,SB    I35 @S9S_MB_2U_LIB.S9S_MB_2U(SCH_1):PAGE324
 PU295   B5  IN_B5 MAX15090BEWIT-MAX15090BEWI+T,SB    I35 @S9S_MB_2U_LIB.S9S_MB_2U(SCH_1):PAGE324
 PU295   C3  IN_C3 MAX15090BEWIT-MAX15090BEWI+T,SB    I35 @S9S_MB_2U_LIB.S9S_MB_2U(SCH_1):PAGE324
 PU295   C5  IN_C5 MAX15090BEWIT-MAX15090BEWI+T,SB    I35 @S9S_MB_2U_LIB.S9S_MB_2U(SCH_1):PAGE324
 PU295   D5  IN_D5 MAX15090BEWIT-MAX15090BEWI+T,SB    I35 @S9S_MB_2U_LIB.S9S_MB_2U(SCH_1):PAGE324
 R3976    1      A Q_RES_0402LF-100K,1%,1/16W,EMPA    I73 @S9S_MB_2U_LIB.S9S_MB_2U(SCH_1):PAGE324
 PR836    2      B Q_RES_0402LF-1K,1%,1/16W,EMPTYA   I121 @S9S_MB_2U_LIB.S9S_MB_2U(SCH_1):PAGE245
 PC569    2      B Q_CAP_0402-220PF,50V,10%,X7R,TA   I127 @S9S_MB_2U_LIB.S9S_MB_2U(SCH_1):PAGE245
 PR831    2      B Q_RES_0402LF-47K,0.1%,1/16W,CHA   I128 @S9S_MB_2U_LIB.S9S_MB_2U(SCH_1):PAGE245
  PL66    2      2 Q_INDUCTOR_SMLF-1.5UH/53A,IND,A   I129 @S9S_MB_2U_LIB.S9S_MB_2U(SCH_1):PAGE245
PC1866    1      A Q_CAPP_THLF-560UF,6.3V,20%,OSCA   I131 @S9S_MB_2U_LIB.S9S_MB_2U(SCH_1):PAGE245
PC1867    1      A Q_CAPP_THLF-560UF,6.3V,20%,OSCA   I132 @S9S_MB_2U_LIB.S9S_MB_2U(SCH_1):PAGE245
PC1868    1      A Q_CAP_C0805-22UF,10V,20%,X6S,CA   I133 @S9S_MB_2U_LIB.S9S_MB_2U(SCH_1):PAGE245
PC1599    1      A Q_CAP_C0805-22UF,10V,20%,X6S,CA   I134 @S9S_MB_2U_LIB.S9S_MB_2U(SCH_1):PAGE245
PC1600    1      A Q_CAP_C0805-22UF,10V,20%,X6S,CA   I136 @S9S_MB_2U_LIB.S9S_MB_2U(SCH_1):PAGE245
PC1869    1      A Q_CAP_0402-0.1UF,25V,10%,X7R,CA   I137 @S9S_MB_2U_LIB.S9S_MB_2U(SCH_1):PAGE245
  PR73    1      A Q_RES_0402LF-10K,1%,1/16W,CHIPA   I139 @S9S_MB_2U_LIB.S9S_MB_2U(SCH_1):PAGE245
 R2359    1      A Q_RES_0402LF-10K,1%,1/16W,CHIPA    I31 @S9S_MB_2U_LIB.S9S_MB_2U(SCH_1):PAGE249
PR1335    1      A Q_RES_0402LF-0,5%,1/16W,CHIP,CA     I5 @S9S_MB_2U_LIB.S9S_MB_2U(SCH_1):PAGE267
 R2338    1      A Q_RES_0402LF-10K,1%,1/16W,EMPTA     I5 @S9S_MB_2U_LIB.S9S_MB_2U(SCH_1):PAGE268
 R2367    1      A Q_RES_0402LF-10K,1%,1/16W,EMPTA    I14 @S9S_MB_2U_LIB.S9S_MB_2U(SCH_1):PAGE285
 R2384    1      A Q_RES_0402LF-10K,1%,1/16W,EMPTA     I5 @S9S_MB_2U_LIB.S9S_MB_2U(SCH_1):PAGE286
 R3836    1      A Q_RES_0402LF-10K,1%,1/16W,CHIPA    I92 @S9S_MB_2U_LIB.S9S_MB_2U(SCH_1):PAGE229
 C1317    1      A Q_CAP_0402-0.1UF,25V,10%,X7R,CA     I9 @S9S_MB_2U_LIB.S9S_MB_2U(SCH_1):PAGE232
   U95    5    VCC 74LVC1G07SE7-74LVC1G07SE-7,SMLA    I11 @S9S_MB_2U_LIB.S9S_MB_2U(SCH_1):PAGE232
 R1690    1      A Q_RES_0402LF-10K,1%,1/16W,CHIPA    I22 @S9S_MB_2U_LIB.S9S_MB_2U(SCH_1):PAGE232
 C1315    1      A Q_CAP_C0402-1UF,25V,10%,X6S,CHA    I24 @S9S_MB_2U_LIB.S9S_MB_2U(SCH_1):PAGE232
  U117    6    VCC TPS3895ADRYR-TPS3895ADRYR,SMLFA    I26 @S9S_MB_2U_LIB.S9S_MB_2U(SCH_1):PAGE232
   U94    6    VCC ADM1086AKSZREEL7-ADM1086AKSZ-RA    I27 @S9S_MB_2U_LIB.S9S_MB_2U(SCH_1):PAGE232
 R2486    1      A Q_RES_0402LF-10K,1%,1/16W,CHIPA    I40 @S9S_MB_2U_LIB.S9S_MB_2U(SCH_1):PAGE232
   U15   16    VCC QS3VH257QG8_SMLF-QS3VH257QG8,IA    I19 @S9S_MB_2U_LIB.S9S_MB_2U(SCH_1):PAGE217
  C538    1      A Q_CAP_0402-0.1UF,25V,10%,X7R,CA    I24 @S9S_MB_2U_LIB.S9S_MB_2U(SCH_1):PAGE217
   R87    1      A Q_RES_0402LF-1K,1%,1/16W,EMPTYA    I43 @S9S_MB_2U_LIB.S9S_MB_2U(SCH_1):PAGE217
 R4580    1      A Q_RES_0402LF-10K,1%,1/16W,EMPTA     I5 @S9S_MB_2U_LIB.S9S_MB_2U(SCH_1):PAGE184
 R4591    1      A Q_RES_0402LF-10K,1%,1/16W,EMPTA     I6 @S9S_MB_2U_LIB.S9S_MB_2U(SCH_1):PAGE184
 R4582    1      A Q_RES_0402LF-10K,1%,1/16W,EMPTA    I23 @S9S_MB_2U_LIB.S9S_MB_2U(SCH_1):PAGE184
 R4584    1      A Q_RES_0402LF-10K,1%,1/16W,EMPTA    I24 @S9S_MB_2U_LIB.S9S_MB_2U(SCH_1):PAGE184
 R2950    1      A Q_RES_0402LF-4.7K,5%,1/16W,EMPA     I4 @S9S_MB_2U_LIB.S9S_MB_2U(SCH_1):PAGE233
  U192    8    VCC LTC4307CMS8-LTC4307CMS8,SMLF,IA    I16 @S9S_MB_2U_LIB.S9S_MB_2U(SCH_1):PAGE233
 C1751    1      A Q_CAP_0402-0.1UF,25V,10%,X7R,CA    I19 @S9S_MB_2U_LIB.S9S_MB_2U(SCH_1):PAGE233
 R2805    1      A Q_RES_0402LF-4.7K,5%,1/16W,EMPA    I22 @S9S_MB_2U_LIB.S9S_MB_2U(SCH_1):PAGE233
 R2807    1      A Q_RES_0402LF-4.7K,5%,1/16W,EMPA    I24 @S9S_MB_2U_LIB.S9S_MB_2U(SCH_1):PAGE233
 R4701    1      A Q_RES_0402LF-4.7K,5%,1/16W,CHIA    I41 @S9S_MB_2U_LIB.S9S_MB_2U(SCH_1):PAGE233
   U14   16    VCC QS3VH257QG8_SMLF-QS3VH257QG8,IA    I12 @S9S_MB_2U_LIB.S9S_MB_2U(SCH_1):PAGE218
  C537    1      A Q_CAP_0402-0.1UF,25V,10%,X7R,CA    I25 @S9S_MB_2U_LIB.S9S_MB_2U(SCH_1):PAGE218
  U200    8    VCC LTC4307CMS8-LTC4307CMS8,SMLF,IA    I11 @S9S_MB_2U_LIB.S9S_MB_2U(SCH_1):PAGE222
 C1796    1      A Q_CAP_0402-0.1UF,25V,10%,X7R,CA    I20 @S9S_MB_2U_LIB.S9S_MB_2U(SCH_1):PAGE222
 R3521    1      A Q_RES_0402LF-54.9K,1%,1/16W,CHA    I23 @S9S_MB_2U_LIB.S9S_MB_2U(SCH_1):PAGE222
 R3522    1      A Q_RES_0402LF-54.9K,1%,1/16W,CHA    I25 @S9S_MB_2U_LIB.S9S_MB_2U(SCH_1):PAGE222
  U176    8    VCC LTC4307CMS8-LTC4307CMS8,SMLF,EA    I31 @S9S_MB_2U_LIB.S9S_MB_2U(SCH_1):PAGE222
  U175    8    VCC LTC4307CMS8-LTC4307CMS8,SMLF,IA    I50 @S9S_MB_2U_LIB.S9S_MB_2U(SCH_1):PAGE222
 C1707    1      A Q_CAP_0402-0.1UF,25V,10%,X7R,CA    I58 @S9S_MB_2U_LIB.S9S_MB_2U(SCH_1):PAGE222
 R2667    1      A Q_RES_0402LF-10K,1%,1/16W,CHIPA    I59 @S9S_MB_2U_LIB.S9S_MB_2U(SCH_1):PAGE222
 R2669    1      A Q_RES_0402LF-10K,1%,1/16W,CHIPA    I61 @S9S_MB_2U_LIB.S9S_MB_2U(SCH_1):PAGE222
  U194    8    VCC LTC4307CMS8-LTC4307CMS8,SMLF,IA    I63 @S9S_MB_2U_LIB.S9S_MB_2U(SCH_1):PAGE222
 R2668    1      A Q_RES_0402LF-4.7K,5%,1/16W,EMPA    I75 @S9S_MB_2U_LIB.S9S_MB_2U(SCH_1):PAGE222
 R2670    1      A Q_RES_0402LF-4.7K,5%,1/16W,EMPA    I77 @S9S_MB_2U_LIB.S9S_MB_2U(SCH_1):PAGE222
 R3523    1      A Q_RES_0402LF-54.9K,1%,1/16W,CHA    I80 @S9S_MB_2U_LIB.S9S_MB_2U(SCH_1):PAGE222
 R3524    1      A Q_RES_0402LF-54.9K,1%,1/16W,CHA    I81 @S9S_MB_2U_LIB.S9S_MB_2U(SCH_1):PAGE222
  R536    1      A Q_RES_0402LF-10K,1%,1/16W,EMPTA     I3 @S9S_MB_2U_LIB.S9S_MB_2U(SCH_1):PAGE219
 R1822    1      A Q_RES_0402LF-10K,1%,1/16W,CHIPA    I18 @S9S_MB_2U_LIB.S9S_MB_2U(SCH_1):PAGE219
 R1090    1      A Q_RES_0402LF-2.2K,5%,1/16W,CHIA    I20 @S9S_MB_2U_LIB.S9S_MB_2U(SCH_1):PAGE219
 R1089    1      A Q_RES_0402LF-2.2K,5%,1/16W,CHIA    I21 @S9S_MB_2U_LIB.S9S_MB_2U(SCH_1):PAGE219
  R651    1      A Q_RES_0402LF-2.2K,5%,1/16W,CHIA    I22 @S9S_MB_2U_LIB.S9S_MB_2U(SCH_1):PAGE219
  R652    1      A Q_RES_0402LF-2.2K,5%,1/16W,CHIA    I23 @S9S_MB_2U_LIB.S9S_MB_2U(SCH_1):PAGE219
 R2985    1      A Q_RES_0402LF-10K,1%,1/16W,CHIPA    I24 @S9S_MB_2U_LIB.S9S_MB_2U(SCH_1):PAGE219
 R2984    1      A Q_RES_0402LF-10K,1%,1/16W,CHIPA    I25 @S9S_MB_2U_LIB.S9S_MB_2U(SCH_1):PAGE219
   U36   24    VCC TCA9548APWR-TCA9548APWR,SMLF,IA    I45 @S9S_MB_2U_LIB.S9S_MB_2U(SCH_1):PAGE219
  C174    1      A Q_CAP_0402-0.1UF,25V,10%,X7R,CA    I47 @S9S_MB_2U_LIB.S9S_MB_2U(SCH_1):PAGE219
 R3535    1      A Q_RES_0402LF-2.2K,5%,1/16W,CHIA    I49 @S9S_MB_2U_LIB.S9S_MB_2U(SCH_1):PAGE219
 R3536    1      A Q_RES_0402LF-2.2K,5%,1/16W,CHIA    I50 @S9S_MB_2U_LIB.S9S_MB_2U(SCH_1):PAGE219
 R3583    1      A Q_RES_0402LF-2.2K,5%,1/16W,CHIA    I51 @S9S_MB_2U_LIB.S9S_MB_2U(SCH_1):PAGE219
 R3582    1      A Q_RES_0402LF-2.2K,5%,1/16W,CHIA    I52 @S9S_MB_2U_LIB.S9S_MB_2U(SCH_1):PAGE219
 R3396    1      A Q_RES_0402LF-2.2K,5%,1/16W,CHIA    I53 @S9S_MB_2U_LIB.S9S_MB_2U(SCH_1):PAGE219
 R3395    1      A Q_RES_0402LF-2.2K,5%,1/16W,CHIA    I54 @S9S_MB_2U_LIB.S9S_MB_2U(SCH_1):PAGE219
 R2205    1      A Q_RES_0402LF-2.2K,5%,1/16W,EMPA    I56 @S9S_MB_2U_LIB.S9S_MB_2U(SCH_1):PAGE219
 R2204    1      A Q_RES_0402LF-2.2K,5%,1/16W,EMPA    I57 @S9S_MB_2U_LIB.S9S_MB_2U(SCH_1):PAGE219
 R4634    1      A Q_RES_0402LF-1K,1%,1/16W,EMPTYA     I4 @S9S_MB_2U_LIB.S9S_MB_2U(SCH_1):PAGE235
 R4623    1      A Q_RES_0402LF-1K,1%,1/16W,CHIP,A    I11 @S9S_MB_2U_LIB.S9S_MB_2U(SCH_1):PAGE235
  U327   14    VCC 74CBTLV3126PW-74CBTLV3126PW,SMA    I19 @S9S_MB_2U_LIB.S9S_MB_2U(SCH_1):PAGE235
 C2348    1      A Q_CAP_0402-0.1UF,25V,10%,X7R,CA    I23 @S9S_MB_2U_LIB.S9S_MB_2U(SCH_1):PAGE235
  U331    9     VS INA230AIRGTR-INA230AIRGTR,SMLFA    I39 @S9S_MB_2U_LIB.S9S_MB_2U(SCH_1):PAGE240
 R4589    1      A Q_RES_0402LF-10K,1%,1/16W,CHIPA    I63 @S9S_MB_2U_LIB.S9S_MB_2U(SCH_1):PAGE184
 R4579    1      A Q_RES_0402LF-10K,1%,1/16W,CHIPA    I67 @S9S_MB_2U_LIB.S9S_MB_2U(SCH_1):PAGE184

P3V3_AUX_ADC @S9S_MB_2U_LIB.S9S_MB_2U(SCH_1):P3V3_AUX_ADC
 R2907    2      B Q_RES_0402LF-5.11K,1%,1/16W,CHA   I141 @S9S_MB_2U_LIB.S9S_MB_2U(SCH_1):PAGE239
 R1785    1      A Q_RES_0402LF-4.7K,1%,1/16W,CHIA   I149 @S9S_MB_2U_LIB.S9S_MB_2U(SCH_1):PAGE239
 R3681    1      A Q_RES_0402LF-0,5%,1/16W,EMPTY,A   I176 @S9S_MB_2U_LIB.S9S_MB_2U(SCH_1):PAGE239
 R3682    1      A Q_RES_0402LF-0,5%,1/16W,CHIP,CA   I179 @S9S_MB_2U_LIB.S9S_MB_2U(SCH_1):PAGE239

P3V3_AUX_ADC_MAM @S9S_MB_2U_LIB.S9S_MB_2U(SCH_1):P3V3_AUX_ADC_MAM
  U193   10   AIN5 MAX11617EEET-MAX11617EEE+T,SMLA    I57 @S9S_MB_2U_LIB.S9S_MB_2U(SCH_1):PAGE239
 R3681    2      B Q_RES_0402LF-0,5%,1/16W,EMPTY,A   I176 @S9S_MB_2U_LIB.S9S_MB_2U(SCH_1):PAGE239
 C2042    1      A Q_CAP_0402-100PF,50V,5%,EMPTY,A   I180 @S9S_MB_2U_LIB.S9S_MB_2U(SCH_1):PAGE239

P3V3_AUX_ADC_TIC @S9S_MB_2U_LIB.S9S_MB_2U(SCH_1):P3V3_AUX_ADC_TIC
  U269   11    IN5 ADC128D818CIMTXNOPB-ADC128D818A   I103 @S9S_MB_2U_LIB.S9S_MB_2U(SCH_1):PAGE239
 R3682    2      B Q_RES_0402LF-0,5%,1/16W,CHIP,CA   I179 @S9S_MB_2U_LIB.S9S_MB_2U(SCH_1):PAGE239
 C2047    1      A Q_CAP_0402-0.1UF,25V,10%,X7R,CA   I181 @S9S_MB_2U_LIB.S9S_MB_2U(SCH_1):PAGE239

P3V3_AUX_BMC_D @S9S_MB_2U_LIB.S9S_MB_2U(SCH_1):P3V3_AUX_BMC_D
   J43    1      1 CONN8_210HP1080BR1-CONN8_210-HA    I79 @S9S_MB_2U_LIB.S9S_MB_2U(SCH_1):PAGE210
  C554    1      A Q_CAP_0402-0.1UF,25V,10%,X7R,CA    I86 @S9S_MB_2U_LIB.S9S_MB_2U(SCH_1):PAGE210
  C563    1      A Q_CAP_C0805-10UF,25V,10%,X6S,CA    I88 @S9S_MB_2U_LIB.S9S_MB_2U(SCH_1):PAGE210
  D141    2      C SCHOTTKY_12-1N5819HW,SMLF,IC,BA    I91 @S9S_MB_2U_LIB.S9S_MB_2U(SCH_1):PAGE210

P3V3_AUX_CLK_GEN_VDDA100M_CK440 @S9S_MB_2U_LIB.S9S_MB_2U(SCH_1):P3V3_AUX_CLK_GEN_VDDA100M_CK440
   U13  B17 VDDA100M 9SQ440NQQI8-9SQ440NQQI8,SMLF,IA   I180 @S9S_MB_2U_LIB.S9S_MB_2U(SCH_1):PAGE197
  C172    1      A Q_CAP_C0603-10UF,6.3V,20%,X6S,A     I6 @S9S_MB_2U_LIB.S9S_MB_2U(SCH_1):PAGE199
  R519    2      B Q_RES_0603LF-1,1%,1/10W,CHIP,CA     I7 @S9S_MB_2U_LIB.S9S_MB_2U(SCH_1):PAGE199
  C173    1      A Q_CAP_C0402-0.047UF,25V,10%,X7A    I78 @S9S_MB_2U_LIB.S9S_MB_2U(SCH_1):PAGE199

P3V3_AUX_CLK_GEN_VDDA25M_CK440 @S9S_MB_2U_LIB.S9S_MB_2U(SCH_1):P3V3_AUX_CLK_GEN_VDDA25M_CK440
   U13   B1 VDDA25M 9SQ440NQQI8-9SQ440NQQI8,SMLF,IA   I180 @S9S_MB_2U_LIB.S9S_MB_2U(SCH_1):PAGE197
  R442    2      B Q_RES_0603LF-1,1%,1/10W,CHIP,CA    I36 @S9S_MB_2U_LIB.S9S_MB_2U(SCH_1):PAGE199
 C1313    1      A Q_CAP_C0603-10UF,6.3V,20%,X6S,A    I48 @S9S_MB_2U_LIB.S9S_MB_2U(SCH_1):PAGE199
  C114    1      A Q_CAP_C0402-0.047UF,25V,10%,X7A    I79 @S9S_MB_2U_LIB.S9S_MB_2U(SCH_1):PAGE199

P3V3_AUX_CLK_GEN_VDDMXCK_CK440 @S9S_MB_2U_LIB.S9S_MB_2U(SCH_1):P3V3_AUX_CLK_GEN_VDDMXCK_CK440
   U13  B29 VDDMXCK_B29 9SQ440NQQI8-9SQ440NQQI8,SMLF,IA   I180 @S9S_MB_2U_LIB.S9S_MB_2U(SCH_1):PAGE197
   U13  B32 VDDMXCK_B32 9SQ440NQQI8-9SQ440NQQI8,SMLF,IA   I180 @S9S_MB_2U_LIB.S9S_MB_2U(SCH_1):PAGE197
   U13  B35 VDDMXCK_B35 9SQ440NQQI8-9SQ440NQQI8,SMLF,IA   I180 @S9S_MB_2U_LIB.S9S_MB_2U(SCH_1):PAGE197
   U13  B40 VDDMXCK_B40 9SQ440NQQI8-9SQ440NQQI8,SMLF,IA   I180 @S9S_MB_2U_LIB.S9S_MB_2U(SCH_1):PAGE197
  R447    1      A Q_RES_0603LF-1,1%,1/10W,CHIP,CA    I55 @S9S_MB_2U_LIB.S9S_MB_2U(SCH_1):PAGE199
 C1312    1      A Q_CAP_C0402-1UF,25V,10%,X6S,CHA    I58 @S9S_MB_2U_LIB.S9S_MB_2U(SCH_1):PAGE199
 C1310    1      A Q_CAP_C0603-10UF,6.3V,20%,X6S,A    I59 @S9S_MB_2U_LIB.S9S_MB_2U(SCH_1):PAGE199
   L14    2      2 Q_INDUCTOR_SMLF-FCM2012KF-601TA    I60 @S9S_MB_2U_LIB.S9S_MB_2U(SCH_1):PAGE199
  C119    1      A Q_CAP_C0402-0.047UF,25V,10%,X7A    I86 @S9S_MB_2U_LIB.S9S_MB_2U(SCH_1):PAGE199
  C117    1      A Q_CAP_C0402-0.047UF,25V,10%,X7A    I87 @S9S_MB_2U_LIB.S9S_MB_2U(SCH_1):PAGE199
  C116    1      A Q_CAP_C0402-0.047UF,25V,10%,X7A    I88 @S9S_MB_2U_LIB.S9S_MB_2U(SCH_1):PAGE199
  C115    1      A Q_CAP_C0402-0.047UF,25V,10%,X7A    I89 @S9S_MB_2U_LIB.S9S_MB_2U(SCH_1):PAGE199

P3V3_AUX_CLK_GEN_VDDPT_CK440 @S9S_MB_2U_LIB.S9S_MB_2U(SCH_1):P3V3_AUX_CLK_GEN_VDDPT_CK440
   U13   B6  VDDPT 9SQ440NQQI8-9SQ440NQQI8,SMLF,IA   I180 @S9S_MB_2U_LIB.S9S_MB_2U(SCH_1):PAGE197
 C1314    1      A Q_CAP_C0603-10UF,6.3V,20%,X6S,A    I53 @S9S_MB_2U_LIB.S9S_MB_2U(SCH_1):PAGE199
  R447    2      B Q_RES_0603LF-1,1%,1/10W,CHIP,CA    I55 @S9S_MB_2U_LIB.S9S_MB_2U(SCH_1):PAGE199
  C120    1      A Q_CAP_C0402-0.047UF,25V,10%,X7A    I85 @S9S_MB_2U_LIB.S9S_MB_2U(SCH_1):PAGE199

P3V3_AUX_CLK_GEN_VDDXTAL_CK440 @S9S_MB_2U_LIB.S9S_MB_2U(SCH_1):P3V3_AUX_CLK_GEN_VDDXTAL_CK440
   U13  A12 VDDXTAL 9SQ440NQQI8-9SQ440NQQI8,SMLF,IA   I180 @S9S_MB_2U_LIB.S9S_MB_2U(SCH_1):PAGE197
  R442    1      A Q_RES_0603LF-1,1%,1/10W,CHIP,CA    I36 @S9S_MB_2U_LIB.S9S_MB_2U(SCH_1):PAGE199
   L13    2      2 Q_INDUCTOR_SMLF-FCM2012KF-601TA    I41 @S9S_MB_2U_LIB.S9S_MB_2U(SCH_1):PAGE199
 C1311    1      A Q_CAP_C0402-1UF,25V,10%,X6S,CHA    I43 @S9S_MB_2U_LIB.S9S_MB_2U(SCH_1):PAGE199
 C1309    1      A Q_CAP_C0603-10UF,6.3V,20%,X6S,A    I44 @S9S_MB_2U_LIB.S9S_MB_2U(SCH_1):PAGE199
  C112    1      A Q_CAP_C0402-0.047UF,25V,10%,X7A    I80 @S9S_MB_2U_LIB.S9S_MB_2U(SCH_1):PAGE199
  C111    1      A Q_CAP_C0402-0.047UF,25V,10%,X7A    I81 @S9S_MB_2U_LIB.S9S_MB_2U(SCH_1):PAGE199

P3V3_AUX_CLK_GEN_VDD_CK440 @S9S_MB_2U_LIB.S9S_MB_2U(SCH_1):P3V3_AUX_CLK_GEN_VDD_CK440
   U13  B21 VDD100M_B21 9SQ440NQQI8-9SQ440NQQI8,SMLF,IA   I180 @S9S_MB_2U_LIB.S9S_MB_2U(SCH_1):PAGE197
   U13  B23 VDD100M_B23 9SQ440NQQI8-9SQ440NQQI8,SMLF,IA   I180 @S9S_MB_2U_LIB.S9S_MB_2U(SCH_1):PAGE197
  R519    1      A Q_RES_0603LF-1,1%,1/10W,CHIP,CA     I7 @S9S_MB_2U_LIB.S9S_MB_2U(SCH_1):PAGE199
  C108    1      A Q_CAP_C0603-10UF,6.3V,20%,X6S,A    I19 @S9S_MB_2U_LIB.S9S_MB_2U(SCH_1):PAGE199
    L1    2      2 Q_INDUCTOR_SMLF-FCM2012KF-601TA    I20 @S9S_MB_2U_LIB.S9S_MB_2U(SCH_1):PAGE199
  C110    1      A Q_CAP_C0402-0.047UF,25V,10%,X7A    I76 @S9S_MB_2U_LIB.S9S_MB_2U(SCH_1):PAGE199
  C171    1      A Q_CAP_C0402-0.047UF,25V,10%,X7A    I77 @S9S_MB_2U_LIB.S9S_MB_2U(SCH_1):PAGE199
  C107    1      A Q_CAP_C0402-1UF,25V,10%,X6S,CHA    I82 @S9S_MB_2U_LIB.S9S_MB_2U(SCH_1):PAGE199

P3V3_AUX_EN @S9S_MB_2U_LIB.S9S_MB_2U(SCH_1):P3V3_AUX_EN
  D145    2      2 Q_DIODE_SMLF-SDMK0340L-7-F,IC,A    I71 @S9S_MB_2U_LIB.S9S_MB_2U(SCH_1):PAGE245
 R1571    2      B Q_RES_0402LF-100K,1%,1/16W,CHIA    I72 @S9S_MB_2U_LIB.S9S_MB_2U(SCH_1):PAGE245
 C2541    1      A Q_CAP_C0402-0.22UF,25V,10%,X7RA    I73 @S9S_MB_2U_LIB.S9S_MB_2U(SCH_1):PAGE245
 R3118    1      A Q_RES_0402LF-86.6K,1%,1/16W,EMA    I76 @S9S_MB_2U_LIB.S9S_MB_2U(SCH_1):PAGE245
 R3117    2      B Q_RES_0402LF-510K,5%,1/16W,EMPA    I78 @S9S_MB_2U_LIB.S9S_MB_2U(SCH_1):PAGE245
   PU9   27     EN IR3889MTRPBF-IR3889MTRPBF,SMLFA    I95 @S9S_MB_2U_LIB.S9S_MB_2U(SCH_1):PAGE245

P3V3_AUX_FB @S9S_MB_2U_LIB.S9S_MB_2U(SCH_1):P3V3_AUX_FB
   PU9   30     FB IR3889MTRPBF-IR3889MTRPBF,SMLFA    I95 @S9S_MB_2U_LIB.S9S_MB_2U(SCH_1):PAGE245
 PR830    1      A Q_RES_0402LF-15K,0.1%,1/16W,CHA   I125 @S9S_MB_2U_LIB.S9S_MB_2U(SCH_1):PAGE245
 PC569    1      A Q_CAP_0402-220PF,50V,10%,X7R,TA   I127 @S9S_MB_2U_LIB.S9S_MB_2U(SCH_1):PAGE245
 PR831    1      A Q_RES_0402LF-47K,0.1%,1/16W,CHA   I128 @S9S_MB_2U_LIB.S9S_MB_2U(SCH_1):PAGE245

P3V3_AUX_FPGA_VCCIO0 @S9S_MB_2U_LIB.S9S_MB_2U(SCH_1):P3V3_AUX_FPGA_VCCIO0
 C1932    1      A Q_CAP_C0402-0.01UF,50V,10%,X7RA     I9 @S9S_MB_2U_LIB.S9S_MB_2U(SCH_1):PAGE202
 C1929    1      A Q_CAP_C0402-0.01UF,50V,10%,X7RA    I33 @S9S_MB_2U_LIB.S9S_MB_2U(SCH_1):PAGE202
 C1926    1      A Q_CAP_C0402-0.01UF,50V,10%,X7RA    I34 @S9S_MB_2U_LIB.S9S_MB_2U(SCH_1):PAGE202
 C1917    1      A Q_CAP_C0402-0.01UF,50V,10%,X7RA    I35 @S9S_MB_2U_LIB.S9S_MB_2U(SCH_1):PAGE202
 C1914    1      A Q_CAP_C0402-0.01UF,50V,10%,X7RA    I36 @S9S_MB_2U_LIB.S9S_MB_2U(SCH_1):PAGE202
 C1905    1      A Q_CAP_0402-0.1UF,25V,10%,X7R,CA    I41 @S9S_MB_2U_LIB.S9S_MB_2U(SCH_1):PAGE202
 C1901    1      A Q_CAP_C0402-0.01UF,50V,10%,X7RA    I42 @S9S_MB_2U_LIB.S9S_MB_2U(SCH_1):PAGE202
 C1895    1      A Q_CAP_C0402-0.01UF,50V,10%,X7RA    I43 @S9S_MB_2U_LIB.S9S_MB_2U(SCH_1):PAGE202
 C1910    1      A Q_CAP_C0402-0.01UF,50V,10%,X7RA    I44 @S9S_MB_2U_LIB.S9S_MB_2U(SCH_1):PAGE202
 C1945    1      A Q_CAP_0402-0.1UF,25V,10%,X7R,CA    I62 @S9S_MB_2U_LIB.S9S_MB_2U(SCH_1):PAGE202
 R3346    2      B Q_RES_0603LF-1,1%,1/10W,CHIP,CA    I63 @S9S_MB_2U_LIB.S9S_MB_2U(SCH_1):PAGE202
 C1938    1      A Q_CAP_C0402-10UF,6.3V,20%,X6S,A    I64 @S9S_MB_2U_LIB.S9S_MB_2U(SCH_1):PAGE202
  U249   C7 VCCIO0_1 LCMXO3LF9400C5BG484C-LCMXO3LF-A   I102 @S9S_MB_2U_LIB.S9S_MB_2U(SCH_1):PAGE202
  U249  C12 VCCIO0_2 LCMXO3LF9400C5BG484C-LCMXO3LF-A   I102 @S9S_MB_2U_LIB.S9S_MB_2U(SCH_1):PAGE202
  U249  C16 VCCIO0_3 LCMXO3LF9400C5BG484C-LCMXO3LF-A   I102 @S9S_MB_2U_LIB.S9S_MB_2U(SCH_1):PAGE202
  U249  G10 VCCIO0_4 LCMXO3LF9400C5BG484C-LCMXO3LF-A   I102 @S9S_MB_2U_LIB.S9S_MB_2U(SCH_1):PAGE202
  U249  G13 VCCIO0_5 LCMXO3LF9400C5BG484C-LCMXO3LF-A   I102 @S9S_MB_2U_LIB.S9S_MB_2U(SCH_1):PAGE202
  U249   H9 VCCIO0_6 LCMXO3LF9400C5BG484C-LCMXO3LF-A   I102 @S9S_MB_2U_LIB.S9S_MB_2U(SCH_1):PAGE202
  U249  H11 VCCIO0_7 LCMXO3LF9400C5BG484C-LCMXO3LF-A   I102 @S9S_MB_2U_LIB.S9S_MB_2U(SCH_1):PAGE202
  U249  H12 VCCIO0_8 LCMXO3LF9400C5BG484C-LCMXO3LF-A   I102 @S9S_MB_2U_LIB.S9S_MB_2U(SCH_1):PAGE202
  U249  H14 VCCIO0_9 LCMXO3LF9400C5BG484C-LCMXO3LF-A   I102 @S9S_MB_2U_LIB.S9S_MB_2U(SCH_1):PAGE202

P3V3_AUX_FPGA_VCCIO1 @S9S_MB_2U_LIB.S9S_MB_2U(SCH_1):P3V3_AUX_FPGA_VCCIO1
 C1933    1      A Q_CAP_C0402-0.01UF,50V,10%,X7RA    I12 @S9S_MB_2U_LIB.S9S_MB_2U(SCH_1):PAGE202
 C1930    1      A Q_CAP_C0402-0.01UF,50V,10%,X7RA    I37 @S9S_MB_2U_LIB.S9S_MB_2U(SCH_1):PAGE202
 C1927    1      A Q_CAP_C0402-0.01UF,50V,10%,X7RA    I38 @S9S_MB_2U_LIB.S9S_MB_2U(SCH_1):PAGE202
 C1918    1      A Q_CAP_C0402-0.01UF,50V,10%,X7RA    I39 @S9S_MB_2U_LIB.S9S_MB_2U(SCH_1):PAGE202
 C1915    1      A Q_CAP_C0402-0.01UF,50V,10%,X7RA    I40 @S9S_MB_2U_LIB.S9S_MB_2U(SCH_1):PAGE202
 C1906    1      A Q_CAP_0402-0.1UF,25V,10%,X7R,CA    I45 @S9S_MB_2U_LIB.S9S_MB_2U(SCH_1):PAGE202
 C1902    1      A Q_CAP_C0402-0.01UF,50V,10%,X7RA    I46 @S9S_MB_2U_LIB.S9S_MB_2U(SCH_1):PAGE202
 C1896    1      A Q_CAP_C0402-0.01UF,50V,10%,X7RA    I47 @S9S_MB_2U_LIB.S9S_MB_2U(SCH_1):PAGE202
 C1911    1      A Q_CAP_C0402-0.01UF,50V,10%,X7RA    I48 @S9S_MB_2U_LIB.S9S_MB_2U(SCH_1):PAGE202
 C1946    1      A Q_CAP_0402-0.1UF,25V,10%,X7R,CA    I65 @S9S_MB_2U_LIB.S9S_MB_2U(SCH_1):PAGE202
 C1939    1      A Q_CAP_C0402-10UF,6.3V,20%,X6S,A    I66 @S9S_MB_2U_LIB.S9S_MB_2U(SCH_1):PAGE202
 R3348    2      B Q_RES_0603LF-1,1%,1/10W,CHIP,CA    I67 @S9S_MB_2U_LIB.S9S_MB_2U(SCH_1):PAGE202
  U249  F20 VCCIO1_1 LCMXO3LF9400C5BG484C-LCMXO3LF-A   I102 @S9S_MB_2U_LIB.S9S_MB_2U(SCH_1):PAGE202
  U249  J15 VCCIO1_2 LCMXO3LF9400C5BG484C-LCMXO3LF-A   I102 @S9S_MB_2U_LIB.S9S_MB_2U(SCH_1):PAGE202
  U249  K15 VCCIO1_3 LCMXO3LF9400C5BG484C-LCMXO3LF-A   I102 @S9S_MB_2U_LIB.S9S_MB_2U(SCH_1):PAGE202
  U249  L15 VCCIO1_4 LCMXO3LF9400C5BG484C-LCMXO3LF-A   I102 @S9S_MB_2U_LIB.S9S_MB_2U(SCH_1):PAGE202
  U249  M15 VCCIO1_5 LCMXO3LF9400C5BG484C-LCMXO3LF-A   I102 @S9S_MB_2U_LIB.S9S_MB_2U(SCH_1):PAGE202
  U249  M18 VCCIO1_6 LCMXO3LF9400C5BG484C-LCMXO3LF-A   I102 @S9S_MB_2U_LIB.S9S_MB_2U(SCH_1):PAGE202
  U249  N15 VCCIO1_7 LCMXO3LF9400C5BG484C-LCMXO3LF-A   I102 @S9S_MB_2U_LIB.S9S_MB_2U(SCH_1):PAGE202
  U249  P15 VCCIO1_8 LCMXO3LF9400C5BG484C-LCMXO3LF-A   I102 @S9S_MB_2U_LIB.S9S_MB_2U(SCH_1):PAGE202
  U249  V20 VCCIO1_9 LCMXO3LF9400C5BG484C-LCMXO3LF-A   I102 @S9S_MB_2U_LIB.S9S_MB_2U(SCH_1):PAGE202

P3V3_AUX_FPGA_VCCIO2 @S9S_MB_2U_LIB.S9S_MB_2U(SCH_1):P3V3_AUX_FPGA_VCCIO2
 C1146    1      A Q_CAP_C0402-0.01UF,50V,10%,X7RA    I15 @S9S_MB_2U_LIB.S9S_MB_2U(SCH_1):PAGE202
 C1142    1      A Q_CAP_C0402-0.01UF,50V,10%,X7RA    I49 @S9S_MB_2U_LIB.S9S_MB_2U(SCH_1):PAGE202
 C1138    1      A Q_CAP_C0402-0.01UF,50V,10%,X7RA    I50 @S9S_MB_2U_LIB.S9S_MB_2U(SCH_1):PAGE202
 C1133    1      A Q_CAP_C0402-0.01UF,50V,10%,X7RA    I51 @S9S_MB_2U_LIB.S9S_MB_2U(SCH_1):PAGE202
 C1127    1      A Q_CAP_C0402-0.01UF,50V,10%,X7RA    I52 @S9S_MB_2U_LIB.S9S_MB_2U(SCH_1):PAGE202
 C1122    1      A Q_CAP_0402-0.1UF,25V,10%,X7R,CA    I56 @S9S_MB_2U_LIB.S9S_MB_2U(SCH_1):PAGE202
 C1900    1      A Q_CAP_C0402-0.01UF,50V,10%,X7RA    I57 @S9S_MB_2U_LIB.S9S_MB_2U(SCH_1):PAGE202
 C1894    1      A Q_CAP_C0402-0.01UF,50V,10%,X7RA    I58 @S9S_MB_2U_LIB.S9S_MB_2U(SCH_1):PAGE202
 C1909    1      A Q_CAP_C0402-0.01UF,50V,10%,X7RA    I59 @S9S_MB_2U_LIB.S9S_MB_2U(SCH_1):PAGE202
 C1944    1      A Q_CAP_0402-0.1UF,25V,10%,X7R,CA    I70 @S9S_MB_2U_LIB.S9S_MB_2U(SCH_1):PAGE202
 C1937    1      A Q_CAP_C0402-10UF,6.3V,20%,X6S,A    I71 @S9S_MB_2U_LIB.S9S_MB_2U(SCH_1):PAGE202
 R3347    2      B Q_RES_0603LF-1,1%,1/10W,CHIP,CA    I72 @S9S_MB_2U_LIB.S9S_MB_2U(SCH_1):PAGE202
  U249   R9 VCCIO2_1 LCMXO3LF9400C5BG484C-LCMXO3LF-A   I102 @S9S_MB_2U_LIB.S9S_MB_2U(SCH_1):PAGE202
  U249  R10 VCCIO2_2 LCMXO3LF9400C5BG484C-LCMXO3LF-A   I102 @S9S_MB_2U_LIB.S9S_MB_2U(SCH_1):PAGE202
  U249  R11 VCCIO2_3 LCMXO3LF9400C5BG484C-LCMXO3LF-A   I102 @S9S_MB_2U_LIB.S9S_MB_2U(SCH_1):PAGE202
  U249  R12 VCCIO2_4 LCMXO3LF9400C5BG484C-LCMXO3LF-A   I102 @S9S_MB_2U_LIB.S9S_MB_2U(SCH_1):PAGE202
  U249  R13 VCCIO2_5 LCMXO3LF9400C5BG484C-LCMXO3LF-A   I102 @S9S_MB_2U_LIB.S9S_MB_2U(SCH_1):PAGE202
  U249  R14 VCCIO2_6 LCMXO3LF9400C5BG484C-LCMXO3LF-A   I102 @S9S_MB_2U_LIB.S9S_MB_2U(SCH_1):PAGE202
  U249   W7 VCCIO2_7 LCMXO3LF9400C5BG484C-LCMXO3LF-A   I102 @S9S_MB_2U_LIB.S9S_MB_2U(SCH_1):PAGE202
  U249  W11 VCCIO2_8 LCMXO3LF9400C5BG484C-LCMXO3LF-A   I102 @S9S_MB_2U_LIB.S9S_MB_2U(SCH_1):PAGE202
  U249  W16 VCCIO2_9 LCMXO3LF9400C5BG484C-LCMXO3LF-A   I102 @S9S_MB_2U_LIB.S9S_MB_2U(SCH_1):PAGE202
 R4086    1      A Q_RES_0402LF-10K,1%,1/16W,CHIPA    I86 @S9S_MB_2U_LIB.S9S_MB_2U(SCH_1):PAGE312

P3V3_AUX_FPGA_VCCIO3 @S9S_MB_2U_LIB.S9S_MB_2U(SCH_1):P3V3_AUX_FPGA_VCCIO3
 C1118    1      A Q_CAP_C0402-0.01UF,50V,10%,X7RA    I97 @S9S_MB_2U_LIB.S9S_MB_2U(SCH_1):PAGE202
 C1113    1      A Q_CAP_C0402-0.01UF,50V,10%,X7RA    I99 @S9S_MB_2U_LIB.S9S_MB_2U(SCH_1):PAGE202
 C1124    1      A Q_CAP_C0402-0.01UF,50V,10%,X7RA   I100 @S9S_MB_2U_LIB.S9S_MB_2U(SCH_1):PAGE202
 C1941    1      A Q_CAP_0402-0.1UF,25V,10%,X7R,CA   I101 @S9S_MB_2U_LIB.S9S_MB_2U(SCH_1):PAGE202
  U249   N8 VCCIO3_1 LCMXO3LF9400C5BG484C-LCMXO3LF-A   I102 @S9S_MB_2U_LIB.S9S_MB_2U(SCH_1):PAGE202
  U249   P8 VCCIO3_2 LCMXO3LF9400C5BG484C-LCMXO3LF-A   I102 @S9S_MB_2U_LIB.S9S_MB_2U(SCH_1):PAGE202
  U249   V3 VCCIO3_3 LCMXO3LF9400C5BG484C-LCMXO3LF-A   I102 @S9S_MB_2U_LIB.S9S_MB_2U(SCH_1):PAGE202
 C1842    1      A Q_CAP_C0402-10UF,6.3V,20%,X6S,A   I107 @S9S_MB_2U_LIB.S9S_MB_2U(SCH_1):PAGE202
 R3344    2      B Q_RES_0603LF-1,1%,1/10W,CHIP,CA   I108 @S9S_MB_2U_LIB.S9S_MB_2U(SCH_1):PAGE202

P3V3_AUX_FPGA_VCCIO4 @S9S_MB_2U_LIB.S9S_MB_2U(SCH_1):P3V3_AUX_FPGA_VCCIO4
 C1899    1      A Q_CAP_C0402-0.01UF,50V,10%,X7RA    I74 @S9S_MB_2U_LIB.S9S_MB_2U(SCH_1):PAGE202
 C1893    1      A Q_CAP_C0402-0.01UF,50V,10%,X7RA    I76 @S9S_MB_2U_LIB.S9S_MB_2U(SCH_1):PAGE202
 C1908    1      A Q_CAP_C0402-0.01UF,50V,10%,X7RA    I77 @S9S_MB_2U_LIB.S9S_MB_2U(SCH_1):PAGE202
 C1942    1      A Q_CAP_0402-0.1UF,25V,10%,X7R,CA    I80 @S9S_MB_2U_LIB.S9S_MB_2U(SCH_1):PAGE202
 R3345    2      B Q_RES_0603LF-1,1%,1/10W,CHIP,CA    I81 @S9S_MB_2U_LIB.S9S_MB_2U(SCH_1):PAGE202
 C1935    1      A Q_CAP_C0402-10UF,6.3V,20%,X6S,A    I82 @S9S_MB_2U_LIB.S9S_MB_2U(SCH_1):PAGE202
  U249   L8 VCCIO4_1 LCMXO3LF9400C5BG484C-LCMXO3LF-A   I102 @S9S_MB_2U_LIB.S9S_MB_2U(SCH_1):PAGE202
  U249   M8 VCCIO4_2 LCMXO3LF9400C5BG484C-LCMXO3LF-A   I102 @S9S_MB_2U_LIB.S9S_MB_2U(SCH_1):PAGE202
  U249   M3 VCCIO4_3 LCMXO3LF9400C5BG484C-LCMXO3LF-A   I102 @S9S_MB_2U_LIB.S9S_MB_2U(SCH_1):PAGE202

P3V3_AUX_FPGA_VCCIO5 @S9S_MB_2U_LIB.S9S_MB_2U(SCH_1):P3V3_AUX_FPGA_VCCIO5
 C1904    1      A Q_CAP_C0402-0.01UF,50V,10%,X7RA    I18 @S9S_MB_2U_LIB.S9S_MB_2U(SCH_1):PAGE202
 C1898    1      A Q_CAP_C0402-0.01UF,50V,10%,X7RA    I20 @S9S_MB_2U_LIB.S9S_MB_2U(SCH_1):PAGE202
 C1913    1      A Q_CAP_C0402-0.01UF,50V,10%,X7RA    I53 @S9S_MB_2U_LIB.S9S_MB_2U(SCH_1):PAGE202
 C1947    1      A Q_CAP_0402-0.1UF,25V,10%,X7R,CA    I54 @S9S_MB_2U_LIB.S9S_MB_2U(SCH_1):PAGE202
 C1940    1      A Q_CAP_C0402-10UF,6.3V,20%,X6S,A    I55 @S9S_MB_2U_LIB.S9S_MB_2U(SCH_1):PAGE202
 R3349    2      B Q_RES_0603LF-1,1%,1/10W,CHIP,CA    I60 @S9S_MB_2U_LIB.S9S_MB_2U(SCH_1):PAGE202
  U249   F3 VCCIO5_1 LCMXO3LF9400C5BG484C-LCMXO3LF-A   I102 @S9S_MB_2U_LIB.S9S_MB_2U(SCH_1):PAGE202
  U249   J8 VCCIO5_2 LCMXO3LF9400C5BG484C-LCMXO3LF-A   I102 @S9S_MB_2U_LIB.S9S_MB_2U(SCH_1):PAGE202
  U249   K8 VCCIO5_3 LCMXO3LF9400C5BG484C-LCMXO3LF-A   I102 @S9S_MB_2U_LIB.S9S_MB_2U(SCH_1):PAGE202

P3V3_AUX_ILIM @S9S_MB_2U_LIB.S9S_MB_2U(SCH_1):P3V3_AUX_ILIM
 PR834    1      A Q_RES_0402LF-21.5K,1%,1/16W,CHA    I91 @S9S_MB_2U_LIB.S9S_MB_2U(SCH_1):PAGE245
   PU9    1   ILIM IR3889MTRPBF-IR3889MTRPBF,SMLFA    I95 @S9S_MB_2U_LIB.S9S_MB_2U(SCH_1):PAGE245

P3V3_AUX_MODE @S9S_MB_2U_LIB.S9S_MB_2U(SCH_1):P3V3_AUX_MODE
 PR832    1      A Q_RES_0402LF-0,5%,1/16W,CHIP,CA    I84 @S9S_MB_2U_LIB.S9S_MB_2U(SCH_1):PAGE245
   PU9   36 TON||MODE IR3889MTRPBF-IR3889MTRPBF,SMLFA    I95 @S9S_MB_2U_LIB.S9S_MB_2U(SCH_1):PAGE245

P3V3_AUX_SS @S9S_MB_2U_LIB.S9S_MB_2U(SCH_1):P3V3_AUX_SS
 PR833    1      A Q_RES_0402LF-1.5K,1%,1/16W,EMPA    I89 @S9S_MB_2U_LIB.S9S_MB_2U(SCH_1):PAGE245
   PU9   29 SS||LATCH IR3889MTRPBF-IR3889MTRPBF,SMLFA    I95 @S9S_MB_2U_LIB.S9S_MB_2U(SCH_1):PAGE245

P3V3_AUX_USB_BUF @S9S_MB_2U_LIB.S9S_MB_2U(SCH_1):P3V3_AUX_USB_BUF
   L18    2      2 Q_INDUCTOR_SMLF-BLM15PX121SN1DB    I35 @S9S_MB_2U_LIB.S9S_MB_2U(SCH_1):PAGE162
 C2284    1      A Q_CAP_C0805-22UF,16V,20%,X6S,CB    I37 @S9S_MB_2U_LIB.S9S_MB_2U(SCH_1):PAGE162
  U309    5  VDD_1 PI3EQX1002EZREX-PI3EQX1002EZREA    I43 @S9S_MB_2U_LIB.S9S_MB_2U(SCH_1):PAGE162
  U309   17  VDD_2 PI3EQX1002EZREX-PI3EQX1002EZREA    I43 @S9S_MB_2U_LIB.S9S_MB_2U(SCH_1):PAGE162
 C2285    1      A Q_CAP_0402-0.1UF,25V,10%,X7R,CA    I44 @S9S_MB_2U_LIB.S9S_MB_2U(SCH_1):PAGE162
 C2286    1      A Q_CAP_0402-0.1UF,25V,10%,X7R,CA    I45 @S9S_MB_2U_LIB.S9S_MB_2U(SCH_1):PAGE162

P3V3_AUX_USB_HUB @S9S_MB_2U_LIB.S9S_MB_2U(SCH_1):P3V3_AUX_USB_HUB
  U268    5 AVDD<0> GL852GOHY60-GL852G-OHY60,SMLF,A   I100 @S9S_MB_2U_LIB.S9S_MB_2U(SCH_1):PAGE155
  U268    9 AVDD<1> GL852GOHY60-GL852G-OHY60,SMLF,A   I100 @S9S_MB_2U_LIB.S9S_MB_2U(SCH_1):PAGE155
  U268   14 AVDD<2> GL852GOHY60-GL852G-OHY60,SMLF,A   I100 @S9S_MB_2U_LIB.S9S_MB_2U(SCH_1):PAGE155
  U268   27     V5 GL852GOHY60-GL852G-OHY60,SMLF,A   I100 @S9S_MB_2U_LIB.S9S_MB_2U(SCH_1):PAGE155
  U268   28    V33 GL852GOHY60-GL852G-OHY60,SMLF,A   I100 @S9S_MB_2U_LIB.S9S_MB_2U(SCH_1):PAGE155
 C2034    1      A Q_CAP_0402-0.1UF,25V,10%,X7R,CA   I142 @S9S_MB_2U_LIB.S9S_MB_2U(SCH_1):PAGE155
 C2033    1      A Q_CAP_0402-0.1UF,25V,10%,X7R,CA   I143 @S9S_MB_2U_LIB.S9S_MB_2U(SCH_1):PAGE155
 C2032    1      A Q_CAP_0402-0.1UF,25V,10%,X7R,CA   I145 @S9S_MB_2U_LIB.S9S_MB_2U(SCH_1):PAGE155
 C2035    1      A Q_CAP_C0402-1UF,25V,10%,X6S,CHA   I147 @S9S_MB_2U_LIB.S9S_MB_2U(SCH_1):PAGE155
 C2031    1      A Q_CAP_C0402-1UF,25V,10%,X6S,CHA   I148 @S9S_MB_2U_LIB.S9S_MB_2U(SCH_1):PAGE155
 R3655    2      B Q_RES_0402LF-0,5%,1/16W,CHIP,CA   I161 @S9S_MB_2U_LIB.S9S_MB_2U(SCH_1):PAGE155
 C2040    1      A Q_CAP_0402-0.1UF,25V,10%,X7R,CA   I162 @S9S_MB_2U_LIB.S9S_MB_2U(SCH_1):PAGE155
 C2039    1      A Q_CAP_0402-0.1UF,25V,10%,X7R,CA   I163 @S9S_MB_2U_LIB.S9S_MB_2U(SCH_1):PAGE155
 C2038    1      A Q_CAP_C0402-10UF,6.3V,20%,X6S,A   I164 @S9S_MB_2U_LIB.S9S_MB_2U(SCH_1):PAGE155
 R3662    1      A Q_RES_0402LF-0,5%,1/16W,CHIP,CA   I167 @S9S_MB_2U_LIB.S9S_MB_2U(SCH_1):PAGE155

P3V3_AUX_USB_HUB_2 @S9S_MB_2U_LIB.S9S_MB_2U(SCH_1):P3V3_AUX_USB_HUB_2
  U313    5 AVDD<0> GL852GOHY60-GL852G-OHY60,SMLF,B    I40 @S9S_MB_2U_LIB.S9S_MB_2U(SCH_1):PAGE194
  U313    9 AVDD<1> GL852GOHY60-GL852G-OHY60,SMLF,B    I40 @S9S_MB_2U_LIB.S9S_MB_2U(SCH_1):PAGE194
  U313   14 AVDD<2> GL852GOHY60-GL852G-OHY60,SMLF,B    I40 @S9S_MB_2U_LIB.S9S_MB_2U(SCH_1):PAGE194
  U313   27     V5 GL852GOHY60-GL852G-OHY60,SMLF,B    I40 @S9S_MB_2U_LIB.S9S_MB_2U(SCH_1):PAGE194
  U313   28    V33 GL852GOHY60-GL852G-OHY60,SMLF,B    I40 @S9S_MB_2U_LIB.S9S_MB_2U(SCH_1):PAGE194
 R4450    2      B Q_RES_0402LF-0,5%,1/16W,EMPTY,A    I41 @S9S_MB_2U_LIB.S9S_MB_2U(SCH_1):PAGE194
 C2313    1      A Q_CAP_C0402-10UF,6.3V,20%,EMPTA    I43 @S9S_MB_2U_LIB.S9S_MB_2U(SCH_1):PAGE194
 C2314    1      A Q_CAP_0402-0.1UF,25V,10%,EMPTYA    I45 @S9S_MB_2U_LIB.S9S_MB_2U(SCH_1):PAGE194
 C2315    1      A Q_CAP_0402-0.1UF,25V,10%,EMPTYA    I46 @S9S_MB_2U_LIB.S9S_MB_2U(SCH_1):PAGE194
 C2316    1      A Q_CAP_C0402-1UF,25V,10%,EMPTY,A    I47 @S9S_MB_2U_LIB.S9S_MB_2U(SCH_1):PAGE194
 C2318    1      A Q_CAP_0402-0.1UF,25V,10%,EMPTYA    I49 @S9S_MB_2U_LIB.S9S_MB_2U(SCH_1):PAGE194
 R4462    1      A Q_RES_0402LF-0,5%,1/16W,EMPTY,A    I50 @S9S_MB_2U_LIB.S9S_MB_2U(SCH_1):PAGE194
 C2319    1      A Q_CAP_0402-0.1UF,25V,10%,EMPTYA    I51 @S9S_MB_2U_LIB.S9S_MB_2U(SCH_1):PAGE194
 C2320    1      A Q_CAP_0402-0.1UF,25V,10%,EMPTYA    I52 @S9S_MB_2U_LIB.S9S_MB_2U(SCH_1):PAGE194
 C2322    1      A Q_CAP_C0402-1UF,25V,10%,EMPTY,A    I53 @S9S_MB_2U_LIB.S9S_MB_2U(SCH_1):PAGE194

P3V3_AUX_VCC @S9S_MB_2U_LIB.S9S_MB_2U(SCH_1):P3V3_AUX_VCC
 PC591    1      A Q_CAP_C0603-2.2UF,16V,10%,X6S,A    I93 @S9S_MB_2U_LIB.S9S_MB_2U(SCH_1):PAGE245
 PR389    2      B Q_RES_0402LF-1,1%,1/16W,CHIP,CA    I94 @S9S_MB_2U_LIB.S9S_MB_2U(SCH_1):PAGE245
   PU9    4 VCC||LDO IR3889MTRPBF-IR3889MTRPBF,SMLFA    I95 @S9S_MB_2U_LIB.S9S_MB_2U(SCH_1):PAGE245

P3V3_AUX_VDRV @S9S_MB_2U_LIB.S9S_MB_2U(SCH_1):P3V3_AUX_VDRV
 PC581    1      A Q_CAP_C0603-4.7UF,16V,10%,X6S,A    I86 @S9S_MB_2U_LIB.S9S_MB_2U(SCH_1):PAGE245
 PR389    1      A Q_RES_0402LF-1,1%,1/16W,CHIP,CA    I94 @S9S_MB_2U_LIB.S9S_MB_2U(SCH_1):PAGE245
   PU9    5   VDRV IR3889MTRPBF-IR3889MTRPBF,SMLFA    I95 @S9S_MB_2U_LIB.S9S_MB_2U(SCH_1):PAGE245

P3V3_AUX_VOS @S9S_MB_2U_LIB.S9S_MB_2U(SCH_1):P3V3_AUX_VOS
   PU9   28    NC1 IR3889MTRPBF-IR3889MTRPBF,SMLFA    I95 @S9S_MB_2U_LIB.S9S_MB_2U(SCH_1):PAGE245
 PR836    1      A Q_RES_0402LF-1K,1%,1/16W,EMPTYA   I121 @S9S_MB_2U_LIB.S9S_MB_2U(SCH_1):PAGE245

P3V3_DB2000_FB_VDD @S9S_MB_2U_LIB.S9S_MB_2U(SCH_1):P3V3_DB2000_FB_VDD
  R572    1      A Q_RES_0603LF-2.2,1%,1/10W,CHIPA   I162 @S9S_MB_2U_LIB.S9S_MB_2U(SCH_1):PAGE195
  R571    1      A Q_RES_0603LF-2.2,1%,1/10W,CHIPA   I163 @S9S_MB_2U_LIB.S9S_MB_2U(SCH_1):PAGE195
    L4    2      2 Q_INDUCTOR_SMLF-BLM18SG331TN1DA   I177 @S9S_MB_2U_LIB.S9S_MB_2U(SCH_1):PAGE195

P3V3_DB2000_VDD @S9S_MB_2U_LIB.S9S_MB_2U(SCH_1):P3V3_DB2000_VDD
   U38   B2 VDDO3.3_B2 9QXL2001BNHGI8-9QXL2001BNHGI8,A   I119 @S9S_MB_2U_LIB.S9S_MB_2U(SCH_1):PAGE195
   U38  B11 VDDO3.3_B11 9QXL2001BNHGI8-9QXL2001BNHGI8,A   I119 @S9S_MB_2U_LIB.S9S_MB_2U(SCH_1):PAGE195
   U38   L2 VDDO3.3_L2 9QXL2001BNHGI8-9QXL2001BNHGI8,A   I119 @S9S_MB_2U_LIB.S9S_MB_2U(SCH_1):PAGE195
   U38  L11 VDDO3.3_L11 9QXL2001BNHGI8-9QXL2001BNHGI8,A   I119 @S9S_MB_2U_LIB.S9S_MB_2U(SCH_1):PAGE195
    L3    2      2 Q_INDUCTOR_SMLF-BLM18SG331TN1DA   I170 @S9S_MB_2U_LIB.S9S_MB_2U(SCH_1):PAGE195
  C204    1      A Q_CAP_0402-0.1UF,25V,10%,X7R,CA   I171 @S9S_MB_2U_LIB.S9S_MB_2U(SCH_1):PAGE195
  C205    1      A Q_CAP_0402-0.1UF,25V,10%,X7R,CA   I172 @S9S_MB_2U_LIB.S9S_MB_2U(SCH_1):PAGE195
  C206    1      A Q_CAP_0402-0.1UF,25V,10%,X7R,CA   I173 @S9S_MB_2U_LIB.S9S_MB_2U(SCH_1):PAGE195
  C207    1      A Q_CAP_0402-0.1UF,25V,10%,X7R,CA   I174 @S9S_MB_2U_LIB.S9S_MB_2U(SCH_1):PAGE195
 C1409    1      A Q_CAP_C0603-10UF,6.3V,20%,X6S,A   I419 @S9S_MB_2U_LIB.S9S_MB_2U(SCH_1):PAGE195

P3V3_DB2000_VDDA @S9S_MB_2U_LIB.S9S_MB_2U(SCH_1):P3V3_DB2000_VDDA
   U38   B6 VDDA3.3 9QXL2001BNHGI8-9QXL2001BNHGI8,A   I119 @S9S_MB_2U_LIB.S9S_MB_2U(SCH_1):PAGE195
  R572    2      B Q_RES_0603LF-2.2,1%,1/10W,CHIPA   I162 @S9S_MB_2U_LIB.S9S_MB_2U(SCH_1):PAGE195
  C209    1      A Q_CAP_C0603-10UF,6.3V,20%,X6S,A   I164 @S9S_MB_2U_LIB.S9S_MB_2U(SCH_1):PAGE195
  C211    1      A Q_CAP_0402-0.1UF,25V,10%,X7R,CA   I165 @S9S_MB_2U_LIB.S9S_MB_2U(SCH_1):PAGE195

P3V3_DB2000_VDDR @S9S_MB_2U_LIB.S9S_MB_2U(SCH_1):P3V3_DB2000_VDDR
   U38   H2 VDDR3.3 9QXL2001BNHGI8-9QXL2001BNHGI8,A   I119 @S9S_MB_2U_LIB.S9S_MB_2U(SCH_1):PAGE195
  R571    2      B Q_RES_0603LF-2.2,1%,1/10W,CHIPA   I163 @S9S_MB_2U_LIB.S9S_MB_2U(SCH_1):PAGE195
  C208    1      A Q_CAP_C0603-10UF,6.3V,20%,X6S,A   I167 @S9S_MB_2U_LIB.S9S_MB_2U(SCH_1):PAGE195
  C210    1      A Q_CAP_0402-0.1UF,25V,10%,X7R,CA   I168 @S9S_MB_2U_LIB.S9S_MB_2U(SCH_1):PAGE195

P3V3_E1S_0 @S9S_MB_2U_LIB.S9S_MB_2U(SCH_1):P3V3_E1S_0
 R3532    1      A Q_RES_0402LF-4.7K,5%,1/16W,CHIA    I78 @S9S_MB_2U_LIB.S9S_MB_2U(SCH_1):PAGE183
 R3530    1      A Q_RES_0402LF-4.7K,5%,1/16W,CHIA    I80 @S9S_MB_2U_LIB.S9S_MB_2U(SCH_1):PAGE183
 C1998    1      A Q_CAP_0402-0.1UF,25V,10%,X7R,CA    I82 @S9S_MB_2U_LIB.S9S_MB_2U(SCH_1):PAGE183
 R3760    1      A Q_RES_0402LF-10,1%,1/16W,CHIP,A   I134 @S9S_MB_2U_LIB.S9S_MB_2U(SCH_1):PAGE295
  U279    1   VCCA PCA9617ADP-PCA9617ADP,SMLF,IC,A    I93 @S9S_MB_2U_LIB.S9S_MB_2U(SCH_1):PAGE183
 C1283    1      A Q_CAP_0402-0.1UF,25V,10%,X7R,CA   I245 @S9S_MB_2U_LIB.S9S_MB_2U(SCH_1):PAGE297
 C1282    1      A Q_CAP_0402-0.1UF,25V,10%,X7R,CA   I247 @S9S_MB_2U_LIB.S9S_MB_2U(SCH_1):PAGE297
 R2317    1      A Q_RES_0402LF-10K,1%,1/16W,CHIPA   I264 @S9S_MB_2U_LIB.S9S_MB_2U(SCH_1):PAGE297
 R1673    1      A Q_RES_0402LF-10K,1%,1/16W,CHIPA   I312 @S9S_MB_2U_LIB.S9S_MB_2U(SCH_1):PAGE297
 R2287    1      A Q_RES_0402LF-10K,1%,1/16W,CHIPA   I313 @S9S_MB_2U_LIB.S9S_MB_2U(SCH_1):PAGE297
   J90  B11 P3V3_AUX SCONN56_123276793-SCONN56_1-23A   I318 @S9S_MB_2U_LIB.S9S_MB_2U(SCH_1):PAGE297
 R3767    1      A Q_RES_2512LF-0.01,1%,1W,CHIP,CA   I153 @S9S_MB_2U_LIB.S9S_MB_2U(SCH_1):PAGE295
 C2378    1      A Q_CAP_0402-0.1UF,25V,10%,X7R,CA   I327 @S9S_MB_2U_LIB.S9S_MB_2U(SCH_1):PAGE297
  U336    3    VCC APX80929SAG7-APX809-29SAG-7,SMA   I329 @S9S_MB_2U_LIB.S9S_MB_2U(SCH_1):PAGE297

P3V3_E1S_0_EN_G @S9S_MB_2U_LIB.S9S_MB_2U(SCH_1):P3V3_E1S_0_EN_G
  Q126    5     G2 MOSFET_NCH_DUAL-PJT138K,SMLF,IA     I4 @S9S_MB_2U_LIB.S9S_MB_2U(SCH_1):PAGE324
 R4072    2      B Q_RES_0402LF-10K,1%,1/16W,CHIPA     I6 @S9S_MB_2U_LIB.S9S_MB_2U(SCH_1):PAGE324
  Q126    6     D1 MOSFET_NCH_DUAL-PJT138K,SMLF,IA     I3 @S9S_MB_2U_LIB.S9S_MB_2U(SCH_1):PAGE324

P3V3_E1S_0_R @S9S_MB_2U_LIB.S9S_MB_2U(SCH_1):P3V3_E1S_0_R
  U276   11    BUS INA230AIRGTR-INA230AIRGTR,SMLFB   I129 @S9S_MB_2U_LIB.S9S_MB_2U(SCH_1):PAGE295
 R3758    1      A Q_RES_0402LF-10,1%,1/16W,CHIP,A   I132 @S9S_MB_2U_LIB.S9S_MB_2U(SCH_1):PAGE295
 C2069    1      A Q_CAP_0402-0.1UF,25V,10%,X7R,CA   I142 @S9S_MB_2U_LIB.S9S_MB_2U(SCH_1):PAGE295
PR4527    1      A Q_RES_0402LF-10M,1%,1/16W,CHIPA    I43 @S9S_MB_2U_LIB.S9S_MB_2U(SCH_1):PAGE324
 PD113    C      C SCHOTTKY_AC-B340A-13-F,SMLF,ICA    I46 @S9S_MB_2U_LIB.S9S_MB_2U(SCH_1):PAGE324
PC2204    1      A Q_CAP_C0805-10UF,16V,10%,EMPTYB    I34 @S9S_MB_2U_LIB.S9S_MB_2U(SCH_1):PAGE323
 PU293  6_7 SOURCE MP5016GQHLZ-MP5016GQH-L-Z,SMLFA    I31 @S9S_MB_2U_LIB.S9S_MB_2U(SCH_1):PAGE323
 R3767    2      B Q_RES_2512LF-0.01,1%,1W,CHIP,CA   I153 @S9S_MB_2U_LIB.S9S_MB_2U(SCH_1):PAGE295
 PU295   A4 OUT_A4 MAX15090BEWIT-MAX15090BEWI+T,SB    I35 @S9S_MB_2U_LIB.S9S_MB_2U(SCH_1):PAGE324
 PU295   B4 OUT_B4 MAX15090BEWIT-MAX15090BEWI+T,SB    I35 @S9S_MB_2U_LIB.S9S_MB_2U(SCH_1):PAGE324
 PU295   B6 OUT_B6 MAX15090BEWIT-MAX15090BEWI+T,SB    I35 @S9S_MB_2U_LIB.S9S_MB_2U(SCH_1):PAGE324
 PU295   C4 OUT_C4 MAX15090BEWIT-MAX15090BEWI+T,SB    I35 @S9S_MB_2U_LIB.S9S_MB_2U(SCH_1):PAGE324
 PU295   C6 OUT_C6 MAX15090BEWIT-MAX15090BEWI+T,SB    I35 @S9S_MB_2U_LIB.S9S_MB_2U(SCH_1):PAGE324
 PU295   D4 OUT_D4 MAX15090BEWIT-MAX15090BEWI+T,SB    I35 @S9S_MB_2U_LIB.S9S_MB_2U(SCH_1):PAGE324
 PU295   D6 OUT_D6 MAX15090BEWIT-MAX15090BEWI+T,SB    I35 @S9S_MB_2U_LIB.S9S_MB_2U(SCH_1):PAGE324
PC2213    1      A Q_CAP_C0402-0.01UF,50V,10%,EMPA    I42 @S9S_MB_2U_LIB.S9S_MB_2U(SCH_1):PAGE324
PC2218    1      A Q_CAP_0402-0.1UF,25V,10%,X7R,CA    I52 @S9S_MB_2U_LIB.S9S_MB_2U(SCH_1):PAGE324
PC2220    1      A Q_CAP_C0805-10UF,16V,10%,X6S,CB    I53 @S9S_MB_2U_LIB.S9S_MB_2U(SCH_1):PAGE324

P3V3_E1S_CB_0 @S9S_MB_2U_LIB.S9S_MB_2U(SCH_1):P3V3_E1S_CB_0
PR3969    1      A Q_RES_0402LF-2.49K,1%,1/16W,CHA    I34 @S9S_MB_2U_LIB.S9S_MB_2U(SCH_1):PAGE324
 PU295   B1     CB MAX15090BEWIT-MAX15090BEWI+T,SB    I35 @S9S_MB_2U_LIB.S9S_MB_2U(SCH_1):PAGE324

P3V3_E1S_DVDT_0 @S9S_MB_2U_LIB.S9S_MB_2U(SCH_1):P3V3_E1S_DVDT_0
PC2201    1      A Q_CAP_0402-0.068UF,16V,10%,EMPA    I30 @S9S_MB_2U_LIB.S9S_MB_2U(SCH_1):PAGE323
 PU293   10  DV_DT MP5016GQHLZ-MP5016GQH-L-Z,SMLFA    I31 @S9S_MB_2U_LIB.S9S_MB_2U(SCH_1):PAGE323

P3V3_E1S_EN_0_R2 @S9S_MB_2U_LIB.S9S_MB_2U(SCH_1):P3V3_E1S_EN_0_R2
 R3946    2      B Q_RES_0402LF-0,5%,1/16W,EMPTY,A     I5 @S9S_MB_2U_LIB.S9S_MB_2U(SCH_1):PAGE323
 PU293    9     EN MP5016GQHLZ-MP5016GQH-L-Z,SMLFA    I31 @S9S_MB_2U_LIB.S9S_MB_2U(SCH_1):PAGE323

P3V3_E1S_EN_1_R @S9S_MB_2U_LIB.S9S_MB_2U(SCH_1):P3V3_E1S_EN_1_R
 R4063    2      B Q_RES_0402LF-0,5%,1/16W,CHIP,CA     I1 @S9S_MB_2U_LIB.S9S_MB_2U(SCH_1):PAGE324
  Q126    2     G1 MOSFET_NCH_DUAL-PJT138K,SMLF,IA     I3 @S9S_MB_2U_LIB.S9S_MB_2U(SCH_1):PAGE324

P3V3_E1S_FAULT_0 @S9S_MB_2U_LIB.S9S_MB_2U(SCH_1):P3V3_E1S_FAULT_0
 R3977    2      B Q_RES_0402LF-100K,1%,1/16W,CHIA    I48 @S9S_MB_2U_LIB.S9S_MB_2U(SCH_1):PAGE324
 PU295   C7 FAULT# MAX15090BEWIT-MAX15090BEWI+T,SB    I35 @S9S_MB_2U_LIB.S9S_MB_2U(SCH_1):PAGE324

P3V3_E1S_GATE_0 @S9S_MB_2U_LIB.S9S_MB_2U(SCH_1):P3V3_E1S_GATE_0
PR4527    2      B Q_RES_0402LF-10M,1%,1/16W,CHIPA    I43 @S9S_MB_2U_LIB.S9S_MB_2U(SCH_1):PAGE324
PC2216    1      A Q_CAP_C0402-6800PF,50V,10%,X7RA    I45 @S9S_MB_2U_LIB.S9S_MB_2U(SCH_1):PAGE324
 PU295   A6   GATE MAX15090BEWIT-MAX15090BEWI+T,SB    I35 @S9S_MB_2U_LIB.S9S_MB_2U(SCH_1):PAGE324
PC2213    2      B Q_CAP_C0402-0.01UF,50V,10%,EMPA    I42 @S9S_MB_2U_LIB.S9S_MB_2U(SCH_1):PAGE324

P3V3_E1S_GATE_0_PU293 @S9S_MB_2U_LIB.S9S_MB_2U(SCH_1):P3V3_E1S_GATE_0_PU293
PC2203    1      A Q_CAP_0402-100PF,50V,5%,EMPTY,A    I32 @S9S_MB_2U_LIB.S9S_MB_2U(SCH_1):PAGE323
 PU293    8   GATE MP5016GQHLZ-MP5016GQH-L-Z,SMLFA    I31 @S9S_MB_2U_LIB.S9S_MB_2U(SCH_1):PAGE323

P3V3_E1S_ILIMIT_0 @S9S_MB_2U_LIB.S9S_MB_2U(SCH_1):P3V3_E1S_ILIMIT_0
 PU293    4 ILIMIT MP5016GQHLZ-MP5016GQH-L-Z,SMLFA    I31 @S9S_MB_2U_LIB.S9S_MB_2U(SCH_1):PAGE323
PR3947    2      B Q_RES_0402LF-2.8K,1%,1/16W,EMPA     I6 @S9S_MB_2U_LIB.S9S_MB_2U(SCH_1):PAGE323

P3V3_E1S_MODE_0 @S9S_MB_2U_LIB.S9S_MB_2U(SCH_1):P3V3_E1S_MODE_0
PC2197    1      A Q_CAP_C0402-39PF,50V,5%,EMPTY,A     I3 @S9S_MB_2U_LIB.S9S_MB_2U(SCH_1):PAGE323
PR3945    1      A Q_RES_0402LF-71.5K,1%,1/16W,EMA     I4 @S9S_MB_2U_LIB.S9S_MB_2U(SCH_1):PAGE323
 PU293    5   MODE MP5016GQHLZ-MP5016GQH-L-Z,SMLFA    I31 @S9S_MB_2U_LIB.S9S_MB_2U(SCH_1):PAGE323

P3V3_E1S_OV_0 @S9S_MB_2U_LIB.S9S_MB_2U(SCH_1):P3V3_E1S_OV_0
PR3965    1      A Q_RES_0402LF-15K,1%,1/16W,CHIPA    I13 @S9S_MB_2U_LIB.S9S_MB_2U(SCH_1):PAGE324
PR3964    2      B Q_RES_0402LF-7.15K,1%,1/16W,CHA    I14 @S9S_MB_2U_LIB.S9S_MB_2U(SCH_1):PAGE324
 PU295   D3     OV MAX15090BEWIT-MAX15090BEWI+T,SB    I35 @S9S_MB_2U_LIB.S9S_MB_2U(SCH_1):PAGE324

P3V3_E1S_PWRGD_0 @S9S_MB_2U_LIB.S9S_MB_2U(SCH_1):P3V3_E1S_PWRGD_0
 R3973    1      A Q_RES_0402LF-0,5%,1/16W,CHIP,CA    I44 @S9S_MB_2U_LIB.S9S_MB_2U(SCH_1):PAGE324
 PU295   D7     PG MAX15090BEWIT-MAX15090BEWI+T,SB    I35 @S9S_MB_2U_LIB.S9S_MB_2U(SCH_1):PAGE324

P3V3_E1S_REG_0 @S9S_MB_2U_LIB.S9S_MB_2U(SCH_1):P3V3_E1S_REG_0
 PU295   D1    REG MAX15090BEWIT-MAX15090BEWI+T,SB    I35 @S9S_MB_2U_LIB.S9S_MB_2U(SCH_1):PAGE324
PC2212    2      B Q_CAP_C0402-1UF,25V,10%,X6S,CHA    I38 @S9S_MB_2U_LIB.S9S_MB_2U(SCH_1):PAGE324

P3V3_E1S_SENSE_0 @S9S_MB_2U_LIB.S9S_MB_2U(SCH_1):P3V3_E1S_SENSE_0
PR3971    1      A Q_RES_0402LF-9.76K,1%,1/16W,CHA    I41 @S9S_MB_2U_LIB.S9S_MB_2U(SCH_1):PAGE324
 PU295   A1 ISENSE MAX15090BEWIT-MAX15090BEWI+T,SB    I35 @S9S_MB_2U_LIB.S9S_MB_2U(SCH_1):PAGE324

P3V3_E1S_UV_0 @S9S_MB_2U_LIB.S9S_MB_2U(SCH_1):P3V3_E1S_UV_0
PR3964    1      A Q_RES_0402LF-7.15K,1%,1/16W,CHA    I14 @S9S_MB_2U_LIB.S9S_MB_2U(SCH_1):PAGE324
 R3959    2      B Q_RES_0402LF-0,5%,1/16W,CHIP,CA    I15 @S9S_MB_2U_LIB.S9S_MB_2U(SCH_1):PAGE324
PR3963    2      B Q_RES_0402LF-25.5K,1%,1/16W,CHA    I18 @S9S_MB_2U_LIB.S9S_MB_2U(SCH_1):PAGE324
 PU295   D2     UV MAX15090BEWIT-MAX15090BEWI+T,SB    I35 @S9S_MB_2U_LIB.S9S_MB_2U(SCH_1):PAGE324

P3V3_E1S_UV_0_R @S9S_MB_2U_LIB.S9S_MB_2U(SCH_1):P3V3_E1S_UV_0_R
  Q126    3     D2 MOSFET_NCH_DUAL-PJT138K,SMLF,IA     I4 @S9S_MB_2U_LIB.S9S_MB_2U(SCH_1):PAGE324
 R3959    1      A Q_RES_0402LF-0,5%,1/16W,CHIP,CA    I15 @S9S_MB_2U_LIB.S9S_MB_2U(SCH_1):PAGE324

P3V3_E1S_VCC_0 @S9S_MB_2U_LIB.S9S_MB_2U(SCH_1):P3V3_E1S_VCC_0
PR3967    2      B Q_RES_0402LF-10,1%,1/16W,CHIP,A    I39 @S9S_MB_2U_LIB.S9S_MB_2U(SCH_1):PAGE324
PC2210    1      A Q_CAP_C0402-1UF,25V,10%,X6S,CHA    I37 @S9S_MB_2U_LIB.S9S_MB_2U(SCH_1):PAGE324
 PU295   A2    VCC MAX15090BEWIT-MAX15090BEWI+T,SB    I35 @S9S_MB_2U_LIB.S9S_MB_2U(SCH_1):PAGE324

P3V3_M2_0 @S9S_MB_2U_LIB.S9S_MB_2U(SCH_1):P3V3_M2_0
 C1920    1      A Q_CAP_C0603-22UF,6.3V,20%,X6S,A    I88 @S9S_MB_2U_LIB.S9S_MB_2U(SCH_1):PAGE182
 C1921    1      A Q_CAP_C0603-22UF,6.3V,20%,X6S,A    I90 @S9S_MB_2U_LIB.S9S_MB_2U(SCH_1):PAGE182
 C1922    1      A Q_CAP_C0603-22UF,6.3V,20%,X6S,A    I96 @S9S_MB_2U_LIB.S9S_MB_2U(SCH_1):PAGE182
 C1923    1      A Q_CAP_0402-0.1UF,25V,10%,X7R,CA    I97 @S9S_MB_2U_LIB.S9S_MB_2U(SCH_1):PAGE182
 C1924    1      A Q_CAP_0402-0.1UF,25V,10%,X7R,CA    I98 @S9S_MB_2U_LIB.S9S_MB_2U(SCH_1):PAGE182
 C1925    1      A Q_CAP_0402-0.1UF,25V,10%,X7R,CA   I100 @S9S_MB_2U_LIB.S9S_MB_2U(SCH_1):PAGE182
   J59    2 3.3V_1 SCONN75K_APCI0155P004A-SCONN75A   I178 @S9S_MB_2U_LIB.S9S_MB_2U(SCH_1):PAGE182
   J59    4 3.3V_2 SCONN75K_APCI0155P004A-SCONN75A   I178 @S9S_MB_2U_LIB.S9S_MB_2U(SCH_1):PAGE182
   J59   12 3.3V_3 SCONN75K_APCI0155P004A-SCONN75A   I178 @S9S_MB_2U_LIB.S9S_MB_2U(SCH_1):PAGE182
   J59   14 3.3V_4 SCONN75K_APCI0155P004A-SCONN75A   I178 @S9S_MB_2U_LIB.S9S_MB_2U(SCH_1):PAGE182
   J59   16 3.3V_5 SCONN75K_APCI0155P004A-SCONN75A   I178 @S9S_MB_2U_LIB.S9S_MB_2U(SCH_1):PAGE182
   J59   18 3.3V_6 SCONN75K_APCI0155P004A-SCONN75A   I178 @S9S_MB_2U_LIB.S9S_MB_2U(SCH_1):PAGE182
   J59   70 3.3V_7 SCONN75K_APCI0155P004A-SCONN75A   I178 @S9S_MB_2U_LIB.S9S_MB_2U(SCH_1):PAGE182
   J59   72 3.3V_8 SCONN75K_APCI0155P004A-SCONN75A   I178 @S9S_MB_2U_LIB.S9S_MB_2U(SCH_1):PAGE182
   J59   74 3.3V_9 SCONN75K_APCI0155P004A-SCONN75A   I178 @S9S_MB_2U_LIB.S9S_MB_2U(SCH_1):PAGE182
 R3575    1      A Q_RES_0402LF-10,1%,1/16W,CHIP,A    I33 @S9S_MB_2U_LIB.S9S_MB_2U(SCH_1):PAGE163
 R3295    1      A Q_RES_0402LF-4.7K,1%,1/16W,CHIA   I317 @S9S_MB_2U_LIB.S9S_MB_2U(SCH_1):PAGE182
 R3634    1      A Q_RES_2512LF-0.01,1%,1W,CHIP,CA   I128 @S9S_MB_2U_LIB.S9S_MB_2U(SCH_1):PAGE163

P3V3_MAX11617_VDD @S9S_MB_2U_LIB.S9S_MB_2U(SCH_1):P3V3_MAX11617 _VDD
  U193   16    VDD MAX11617EEET-MAX11617EEE+T,SMLA    I57 @S9S_MB_2U_LIB.S9S_MB_2U(SCH_1):PAGE239
 C1757    1      A Q_CAP_0402-0.1UF,25V,10%,EMPTYA    I58 @S9S_MB_2U_LIB.S9S_MB_2U(SCH_1):PAGE239
 C1768    1      A Q_CAP_C0805-10UF,16V,10%,EMPTYA    I61 @S9S_MB_2U_LIB.S9S_MB_2U(SCH_1):PAGE239
   L15    1      1 Q_INDUCTOR_SMLF-BLM18PG300SN1DA    I62 @S9S_MB_2U_LIB.S9S_MB_2U(SCH_1):PAGE239

P3V3_OCP_1_EN_G @S9S_MB_2U_LIB.S9S_MB_2U(SCH_1):P3V3_OCP_1_EN_G
 R4070    2      B Q_RES_0402LF-10K,1%,1/16W,CHIPA    I62 @S9S_MB_2U_LIB.S9S_MB_2U(SCH_1):PAGE153
  Q124    6     D1 MOSFET_NCH_DUAL-PJT138K,SMLF,IA    I21 @S9S_MB_2U_LIB.S9S_MB_2U(SCH_1):PAGE153
  Q124    5     G2 MOSFET_NCH_DUAL-PJT138K,SMLF,IA    I36 @S9S_MB_2U_LIB.S9S_MB_2U(SCH_1):PAGE153

P3V3_OCP_2_EN_G @S9S_MB_2U_LIB.S9S_MB_2U(SCH_1):P3V3_OCP_2_EN_G
  Q119    6     D1 MOSFET_NCH_DUAL-PJT138K,SMLF,IA    I38 @S9S_MB_2U_LIB.S9S_MB_2U(SCH_1):PAGE131
 R4067    2      B Q_RES_0402LF-10K,1%,1/16W,CHIPA    I40 @S9S_MB_2U_LIB.S9S_MB_2U(SCH_1):PAGE131
  Q119    5     G2 MOSFET_NCH_DUAL-PJT138K,SMLF,IA    I42 @S9S_MB_2U_LIB.S9S_MB_2U(SCH_1):PAGE131

P3V3_OCP_CB_1 @S9S_MB_2U_LIB.S9S_MB_2U(SCH_1):P3V3_OCP_CB_1
PR3780    1      A Q_RES_0402LF-5.36K,1%,1/16W,CHA    I60 @S9S_MB_2U_LIB.S9S_MB_2U(SCH_1):PAGE153
 PU202   B1     CB MAX15090BEWIT-MAX15090BEWI+T,SB    I61 @S9S_MB_2U_LIB.S9S_MB_2U(SCH_1):PAGE153

P3V3_OCP_CB_2 @S9S_MB_2U_LIB.S9S_MB_2U(SCH_1):P3V3_OCP_CB_2
PR3822    1      A Q_RES_0402LF-5.36K,1%,1/16W,CHA    I89 @S9S_MB_2U_LIB.S9S_MB_2U(SCH_1):PAGE131
 PU200   B1     CB MAX15090BEWIT-MAX15090BEWI+T,SB    I90 @S9S_MB_2U_LIB.S9S_MB_2U(SCH_1):PAGE131

P3V3_OCP_DVDT_1 @S9S_MB_2U_LIB.S9S_MB_2U(SCH_1):P3V3_OCP_DVDT_1
PC2161    1      A Q_CAP_0402-0.068UF,16V,10%,EMPA    I49 @S9S_MB_2U_LIB.S9S_MB_2U(SCH_1):PAGE236
 PU205   10  DV_DT MP5016GQHLZ-MP5016GQH-L-Z,SMLFA    I50 @S9S_MB_2U_LIB.S9S_MB_2U(SCH_1):PAGE236

P3V3_OCP_DVDT_2 @S9S_MB_2U_LIB.S9S_MB_2U(SCH_1):P3V3_OCP_DVDT_2
PC1321    1      A Q_CAP_0402-0.068UF,16V,10%,EMPA    I50 @S9S_MB_2U_LIB.S9S_MB_2U(SCH_1):PAGE237
 PU207   10  DV_DT MP5016GQHLZ-MP5016GQH-L-Z,SMLFA    I51 @S9S_MB_2U_LIB.S9S_MB_2U(SCH_1):PAGE237

P3V3_OCP_EN_1_R @S9S_MB_2U_LIB.S9S_MB_2U(SCH_1):P3V3_OCP_EN_1_R
 R4069    1      A Q_RES_0402LF-4.7K,5%,1/16W,CHIA    I20 @S9S_MB_2U_LIB.S9S_MB_2U(SCH_1):PAGE153
 R5487    2      B Q_RES_0402LF-0,5%,1/16W,CHIP,CA    I19 @S9S_MB_2U_LIB.S9S_MB_2U(SCH_1):PAGE153
  Q124    2     G1 MOSFET_NCH_DUAL-PJT138K,SMLF,IA    I21 @S9S_MB_2U_LIB.S9S_MB_2U(SCH_1):PAGE153

P3V3_OCP_EN_1_R2 @S9S_MB_2U_LIB.S9S_MB_2U(SCH_1):P3V3_OCP_EN_1_R2
 R3845    2      B Q_RES_0402LF-0,5%,1/16W,EMPTY,A    I46 @S9S_MB_2U_LIB.S9S_MB_2U(SCH_1):PAGE236
 PU205    9     EN MP5016GQHLZ-MP5016GQH-L-Z,SMLFA    I50 @S9S_MB_2U_LIB.S9S_MB_2U(SCH_1):PAGE236

P3V3_OCP_EN_2 @S9S_MB_2U_LIB.S9S_MB_2U(SCH_1):P3V3_OCP_EN_2
 R3631    2      B Q_RES_0402LF-0,5%,1/16W,EMPTY,A    I44 @S9S_MB_2U_LIB.S9S_MB_2U(SCH_1):PAGE237
 PU207    9     EN MP5016GQHLZ-MP5016GQH-L-Z,SMLFA    I51 @S9S_MB_2U_LIB.S9S_MB_2U(SCH_1):PAGE237

P3V3_OCP_EN_2_R @S9S_MB_2U_LIB.S9S_MB_2U(SCH_1):P3V3_OCP_EN_2_R
  Q119    2     G1 MOSFET_NCH_DUAL-PJT138K,SMLF,IA    I38 @S9S_MB_2U_LIB.S9S_MB_2U(SCH_1):PAGE131
 R4060    2      B Q_RES_0402LF-0,5%,1/16W,CHIP,CA    I35 @S9S_MB_2U_LIB.S9S_MB_2U(SCH_1):PAGE131
 R4066    1      A Q_RES_0402LF-4.7K,5%,1/16W,CHIA    I37 @S9S_MB_2U_LIB.S9S_MB_2U(SCH_1):PAGE131

P3V3_OCP_FAULT_1 @S9S_MB_2U_LIB.S9S_MB_2U(SCH_1):P3V3_OCP_FAULT_1
 PU202   C7 FAULT# MAX15090BEWIT-MAX15090BEWI+T,SB    I61 @S9S_MB_2U_LIB.S9S_MB_2U(SCH_1):PAGE153
 R3796    2      B Q_RES_0402LF-100K,1%,1/16W,CHIA   I108 @S9S_MB_2U_LIB.S9S_MB_2U(SCH_1):PAGE153

P3V3_OCP_FAULT_2 @S9S_MB_2U_LIB.S9S_MB_2U(SCH_1):P3V3_OCP_FAULT_2
 PU200   C7 FAULT# MAX15090BEWIT-MAX15090BEWI+T,SB    I90 @S9S_MB_2U_LIB.S9S_MB_2U(SCH_1):PAGE131
 R3833    2      B Q_RES_0402LF-100K,1%,1/16W,CHIA   I108 @S9S_MB_2U_LIB.S9S_MB_2U(SCH_1):PAGE131

P3V3_OCP_GATE_1 @S9S_MB_2U_LIB.S9S_MB_2U(SCH_1):P3V3_OCP_GATE_1
PC2162    1      A Q_CAP_0402-100PF,50V,5%,EMPTY,A    I52 @S9S_MB_2U_LIB.S9S_MB_2U(SCH_1):PAGE236
 PU205    8   GATE MP5016GQHLZ-MP5016GQH-L-Z,SMLFA    I50 @S9S_MB_2U_LIB.S9S_MB_2U(SCH_1):PAGE236

P3V3_OCP_GATE_2 @S9S_MB_2U_LIB.S9S_MB_2U(SCH_1):P3V3_OCP_GATE_2
 PU200   A6   GATE MAX15090BEWIT-MAX15090BEWI+T,SB    I90 @S9S_MB_2U_LIB.S9S_MB_2U(SCH_1):PAGE131
PC2151    1      A Q_CAP_C0402-6800PF,50V,10%,X7RA    I96 @S9S_MB_2U_LIB.S9S_MB_2U(SCH_1):PAGE131
PC2149    2      B Q_CAP_C0402-0.01UF,50V,10%,EMPA   I105 @S9S_MB_2U_LIB.S9S_MB_2U(SCH_1):PAGE131
PR4523    2      B Q_RES_0402LF-10M,1%,1/16W,CHIPA   I106 @S9S_MB_2U_LIB.S9S_MB_2U(SCH_1):PAGE131

P3V3_OCP_GATE_PU202_1 @S9S_MB_2U_LIB.S9S_MB_2U(SCH_1):P3V3_OCP_GATE_PU202_1
PC2089    1      A Q_CAP_C0402-6800PF,50V,10%,X7RA   I107 @S9S_MB_2U_LIB.S9S_MB_2U(SCH_1):PAGE153
PC2144    2      B Q_CAP_C0402-0.01UF,50V,10%,EMPA   I101 @S9S_MB_2U_LIB.S9S_MB_2U(SCH_1):PAGE153
PR4525    2      B Q_RES_0402LF-10M,1%,1/16W,CHIPA   I103 @S9S_MB_2U_LIB.S9S_MB_2U(SCH_1):PAGE153
 PU202   A6   GATE MAX15090BEWIT-MAX15090BEWI+T,SB    I61 @S9S_MB_2U_LIB.S9S_MB_2U(SCH_1):PAGE153

P3V3_OCP_GATE_PU207_2 @S9S_MB_2U_LIB.S9S_MB_2U(SCH_1):P3V3_OCP_GATE_PU207_2
PC1322    1      A Q_CAP_0402-100PF,50V,5%,EMPTY,A    I54 @S9S_MB_2U_LIB.S9S_MB_2U(SCH_1):PAGE237
 PU207    8   GATE MP5016GQHLZ-MP5016GQH-L-Z,SMLFA    I51 @S9S_MB_2U_LIB.S9S_MB_2U(SCH_1):PAGE237

P3V3_OCP_ILIMIT_1 @S9S_MB_2U_LIB.S9S_MB_2U(SCH_1):P3V3_OCP_ILIMIT_1
 PU205    4 ILIMIT MP5016GQHLZ-MP5016GQH-L-Z,SMLFA    I50 @S9S_MB_2U_LIB.S9S_MB_2U(SCH_1):PAGE236
PR3846    2      B Q_RES_0402LF-1.33K,1%,1/16W,EMA    I45 @S9S_MB_2U_LIB.S9S_MB_2U(SCH_1):PAGE236

P3V3_OCP_ILIMIT_2 @S9S_MB_2U_LIB.S9S_MB_2U(SCH_1):P3V3_OCP_ILIMIT_2
PR3856    2      B Q_RES_0402LF-1.33K,1%,1/16W,EMA    I46 @S9S_MB_2U_LIB.S9S_MB_2U(SCH_1):PAGE237
 PU207    4 ILIMIT MP5016GQHLZ-MP5016GQH-L-Z,SMLFA    I51 @S9S_MB_2U_LIB.S9S_MB_2U(SCH_1):PAGE237

P3V3_OCP_MODE_1 @S9S_MB_2U_LIB.S9S_MB_2U(SCH_1):P3V3_OCP_MODE_1
PC2157    1      A Q_CAP_C0402-39PF,50V,5%,EMPTY,A    I42 @S9S_MB_2U_LIB.S9S_MB_2U(SCH_1):PAGE236
PR3844    1      A Q_RES_0402LF-71.5K,1%,1/16W,EMA    I43 @S9S_MB_2U_LIB.S9S_MB_2U(SCH_1):PAGE236
 PU205    5   MODE MP5016GQHLZ-MP5016GQH-L-Z,SMLFA    I50 @S9S_MB_2U_LIB.S9S_MB_2U(SCH_1):PAGE236

P3V3_OCP_MODE_2 @S9S_MB_2U_LIB.S9S_MB_2U(SCH_1):P3V3_OCP_MODE_2
PR3855    1      A Q_RES_0402LF-71.5K,1%,1/16W,EMA    I43 @S9S_MB_2U_LIB.S9S_MB_2U(SCH_1):PAGE237
PC2168    1      A Q_CAP_C0402-39PF,50V,5%,EMPTY,A    I35 @S9S_MB_2U_LIB.S9S_MB_2U(SCH_1):PAGE237
 PU207    5   MODE MP5016GQHLZ-MP5016GQH-L-Z,SMLFA    I51 @S9S_MB_2U_LIB.S9S_MB_2U(SCH_1):PAGE237

P3V3_OCP_OV_1 @S9S_MB_2U_LIB.S9S_MB_2U(SCH_1):P3V3_OCP_OV_1
PR3791    1      A Q_RES_0402LF-15K,1%,1/16W,CHIPA    I58 @S9S_MB_2U_LIB.S9S_MB_2U(SCH_1):PAGE153
 PU202   D3     OV MAX15090BEWIT-MAX15090BEWI+T,SB    I61 @S9S_MB_2U_LIB.S9S_MB_2U(SCH_1):PAGE153
PR3790    2      B Q_RES_0402LF-7.15K,1%,1/16W,CHA    I68 @S9S_MB_2U_LIB.S9S_MB_2U(SCH_1):PAGE153

P3V3_OCP_OV_2 @S9S_MB_2U_LIB.S9S_MB_2U(SCH_1):P3V3_OCP_OV_2
PR3812    1      A Q_RES_0402LF-15K,1%,1/16W,CHIPA    I48 @S9S_MB_2U_LIB.S9S_MB_2U(SCH_1):PAGE131
 PU200   D3     OV MAX15090BEWIT-MAX15090BEWI+T,SB    I90 @S9S_MB_2U_LIB.S9S_MB_2U(SCH_1):PAGE131
PR3829    2      B Q_RES_0402LF-7.15K,1%,1/16W,CHA    I50 @S9S_MB_2U_LIB.S9S_MB_2U(SCH_1):PAGE131

P3V3_OCP_PWRGD_1 @S9S_MB_2U_LIB.S9S_MB_2U(SCH_1):P3V3_OCP_PWRGD_1
 R3794    1      A Q_RES_0402LF-0,5%,1/16W,CHIP,CA   I105 @S9S_MB_2U_LIB.S9S_MB_2U(SCH_1):PAGE153
 PU202   D7     PG MAX15090BEWIT-MAX15090BEWI+T,SB    I61 @S9S_MB_2U_LIB.S9S_MB_2U(SCH_1):PAGE153

P3V3_OCP_PWRGD_2 @S9S_MB_2U_LIB.S9S_MB_2U(SCH_1):P3V3_OCP_PWRGD_2
 R3832    1      A Q_RES_0402LF-0,5%,1/16W,CHIP,CA    I97 @S9S_MB_2U_LIB.S9S_MB_2U(SCH_1):PAGE131
 PU200   D7     PG MAX15090BEWIT-MAX15090BEWI+T,SB    I90 @S9S_MB_2U_LIB.S9S_MB_2U(SCH_1):PAGE131

P3V3_OCP_REG_1 @S9S_MB_2U_LIB.S9S_MB_2U(SCH_1):P3V3_OCP_REG_1
PC2093    2      B Q_CAP_C0402-1UF,25V,10%,X6S,CHA    I72 @S9S_MB_2U_LIB.S9S_MB_2U(SCH_1):PAGE153
 PU202   D1    REG MAX15090BEWIT-MAX15090BEWI+T,SB    I61 @S9S_MB_2U_LIB.S9S_MB_2U(SCH_1):PAGE153

P3V3_OCP_REG_2 @S9S_MB_2U_LIB.S9S_MB_2U(SCH_1):P3V3_OCP_REG_2
PC2147    2      B Q_CAP_C0402-1UF,25V,10%,X6S,CHA    I87 @S9S_MB_2U_LIB.S9S_MB_2U(SCH_1):PAGE131
 PU200   D1    REG MAX15090BEWIT-MAX15090BEWI+T,SB    I90 @S9S_MB_2U_LIB.S9S_MB_2U(SCH_1):PAGE131

P3V3_OCP_SENSE_1 @S9S_MB_2U_LIB.S9S_MB_2U(SCH_1):P3V3_OCP_SENSE_1
PR5481    1      A Q_RES_0402LF-4.53K,1%,1/16W,CHA   I102 @S9S_MB_2U_LIB.S9S_MB_2U(SCH_1):PAGE153
 PU202   A1 ISENSE MAX15090BEWIT-MAX15090BEWI+T,SB    I61 @S9S_MB_2U_LIB.S9S_MB_2U(SCH_1):PAGE153

P3V3_OCP_SENSE_2 @S9S_MB_2U_LIB.S9S_MB_2U(SCH_1):P3V3_OCP_SENSE_2
 PU200   A1 ISENSE MAX15090BEWIT-MAX15090BEWI+T,SB    I90 @S9S_MB_2U_LIB.S9S_MB_2U(SCH_1):PAGE131
PR3824    1      A Q_RES_0402LF-4.53K,1%,1/16W,CHA    I95 @S9S_MB_2U_LIB.S9S_MB_2U(SCH_1):PAGE131

P3V3_OCP_SFF @S9S_MB_2U_LIB.S9S_MB_2U(SCH_1):P3V3_OCP_SFF
 R1592    1      A Q_RES_0402LF-10K,1%,1/16W,CHIPA    I37 @S9S_MB_2U_LIB.S9S_MB_2U(SCH_1):PAGE152
 R1824    1      A Q_RES_0402LF-10K,1%,1/16W,CHIPA    I62 @S9S_MB_2U_LIB.S9S_MB_2U(SCH_1):PAGE152
  R409    1      A Q_RES_0402LF-4.7K,1%,1/16W,EMPA     I5 @S9S_MB_2U_LIB.S9S_MB_2U(SCH_1):PAGE150
  R414    1      A Q_RES_0402LF-4.7K,1%,1/16W,EMPA     I6 @S9S_MB_2U_LIB.S9S_MB_2U(SCH_1):PAGE150
 C1237    1      A Q_CAP_0402-0.1UF,25V,10%,X7R,CA   I114 @S9S_MB_2U_LIB.S9S_MB_2U(SCH_1):PAGE150
 C1238    1      A Q_CAP_0402-0.1UF,25V,10%,X7R,CA   I115 @S9S_MB_2U_LIB.S9S_MB_2U(SCH_1):PAGE150
 C1239    1      A Q_CAP_0402-0.1UF,25V,10%,X7R,CA   I116 @S9S_MB_2U_LIB.S9S_MB_2U(SCH_1):PAGE150
 C1240    1      A Q_CAP_0402-0.1UF,25V,10%,X7R,CA   I168 @S9S_MB_2U_LIB.S9S_MB_2U(SCH_1):PAGE150
 C1862    1      A Q_CAP_0402-0.1UF,25V,10%,X7R,CA    I23 @S9S_MB_2U_LIB.S9S_MB_2U(SCH_1):PAGE216
  U236    8   VCCB PCA9617ADP-PCA9617ADP,SMLF,IC,A    I28 @S9S_MB_2U_LIB.S9S_MB_2U(SCH_1):PAGE216
 R3501    1      A Q_RES_0402LF-4.7K,5%,1/16W,CHIA    I30 @S9S_MB_2U_LIB.S9S_MB_2U(SCH_1):PAGE216
 R3500    1      A Q_RES_0402LF-4.7K,5%,1/16W,CHIA    I31 @S9S_MB_2U_LIB.S9S_MB_2U(SCH_1):PAGE216
 R3603    1      A Q_RES_0402LF-10,1%,1/16W,CHIP,A    I43 @S9S_MB_2U_LIB.S9S_MB_2U(SCH_1):PAGE295
   J37  B11 +3.3V_EDGE SCONN168_ME1016810202011-SCONNA   I199 @S9S_MB_2U_LIB.S9S_MB_2U(SCH_1):PAGE150
  R423    2      B Q_RES_0402LF-1K,1%,1/16W,CHIP,A   I212 @S9S_MB_2U_LIB.S9S_MB_2U(SCH_1):PAGE150
  R421    2      B Q_RES_0402LF-10K,1%,1/16W,CHIPA   I217 @S9S_MB_2U_LIB.S9S_MB_2U(SCH_1):PAGE150
  R420    2      B Q_RES_0402LF-1K,1%,1/16W,CHIP,A   I218 @S9S_MB_2U_LIB.S9S_MB_2U(SCH_1):PAGE150
   U52    3    VCC APX80929SAG7-APX809-29SAG-7,SMA   I228 @S9S_MB_2U_LIB.S9S_MB_2U(SCH_1):PAGE154
  C580    1      A Q_CAP_0402-0.1UF,25V,10%,X7R,CA   I229 @S9S_MB_2U_LIB.S9S_MB_2U(SCH_1):PAGE154
 R3645    1      A Q_RES_2512LF-0.01,1%,1W,CHIP,CA   I152 @S9S_MB_2U_LIB.S9S_MB_2U(SCH_1):PAGE295

P3V3_OCP_SFF_R @S9S_MB_2U_LIB.S9S_MB_2U(SCH_1):P3V3_OCP_SFF_R
  U266   11    BUS INA230AIRGTR-INA230AIRGTR,SMLFB    I30 @S9S_MB_2U_LIB.S9S_MB_2U(SCH_1):PAGE295
 R3602    1      A Q_RES_0402LF-10,1%,1/16W,CHIP,A    I41 @S9S_MB_2U_LIB.S9S_MB_2U(SCH_1):PAGE295
 C2024    1      A Q_CAP_0402-0.1UF,25V,10%,X7R,CA    I50 @S9S_MB_2U_LIB.S9S_MB_2U(SCH_1):PAGE295
 PU205  6_7 SOURCE MP5016GQHLZ-MP5016GQH-L-Z,SMLFA    I50 @S9S_MB_2U_LIB.S9S_MB_2U(SCH_1):PAGE236
PC2144    1      A Q_CAP_C0402-0.01UF,50V,10%,EMPA   I101 @S9S_MB_2U_LIB.S9S_MB_2U(SCH_1):PAGE153
PR4525    1      A Q_RES_0402LF-10M,1%,1/16W,CHIPA   I103 @S9S_MB_2U_LIB.S9S_MB_2U(SCH_1):PAGE153
 PD103    C      C SCHOTTKY_AC-B340A-13-F,SMLF,ICA   I104 @S9S_MB_2U_LIB.S9S_MB_2U(SCH_1):PAGE153
PC2163    1      A Q_CAP_C0805-10UF,16V,10%,EMPTYB    I54 @S9S_MB_2U_LIB.S9S_MB_2U(SCH_1):PAGE236
 R3645    2      B Q_RES_2512LF-0.01,1%,1W,CHIP,CA   I152 @S9S_MB_2U_LIB.S9S_MB_2U(SCH_1):PAGE295
 PU202   A4 OUT_A4 MAX15090BEWIT-MAX15090BEWI+T,SB    I61 @S9S_MB_2U_LIB.S9S_MB_2U(SCH_1):PAGE153
 PU202   B4 OUT_B4 MAX15090BEWIT-MAX15090BEWI+T,SB    I61 @S9S_MB_2U_LIB.S9S_MB_2U(SCH_1):PAGE153
 PU202   B6 OUT_B6 MAX15090BEWIT-MAX15090BEWI+T,SB    I61 @S9S_MB_2U_LIB.S9S_MB_2U(SCH_1):PAGE153
 PU202   C4 OUT_C4 MAX15090BEWIT-MAX15090BEWI+T,SB    I61 @S9S_MB_2U_LIB.S9S_MB_2U(SCH_1):PAGE153
 PU202   C6 OUT_C6 MAX15090BEWIT-MAX15090BEWI+T,SB    I61 @S9S_MB_2U_LIB.S9S_MB_2U(SCH_1):PAGE153
 PU202   D4 OUT_D4 MAX15090BEWIT-MAX15090BEWI+T,SB    I61 @S9S_MB_2U_LIB.S9S_MB_2U(SCH_1):PAGE153
 PU202   D6 OUT_D6 MAX15090BEWIT-MAX15090BEWI+T,SB    I61 @S9S_MB_2U_LIB.S9S_MB_2U(SCH_1):PAGE153
PC2091    1      A Q_CAP_0402-0.1UF,25V,10%,X7R,CA   I111 @S9S_MB_2U_LIB.S9S_MB_2U(SCH_1):PAGE153
PC2081    1      A Q_CAP_C0805-10UF,16V,10%,X6S,CB   I113 @S9S_MB_2U_LIB.S9S_MB_2U(SCH_1):PAGE153

P3V3_OCP_UV_1 @S9S_MB_2U_LIB.S9S_MB_2U(SCH_1):P3V3_OCP_UV_1
PR3789    2      B Q_RES_0402LF-25.5K,1%,1/16W,CHA    I70 @S9S_MB_2U_LIB.S9S_MB_2U(SCH_1):PAGE153
 PU202   D2     UV MAX15090BEWIT-MAX15090BEWI+T,SB    I61 @S9S_MB_2U_LIB.S9S_MB_2U(SCH_1):PAGE153
 R3785    2      B Q_RES_0402LF-0,5%,1/16W,CHIP,CA    I64 @S9S_MB_2U_LIB.S9S_MB_2U(SCH_1):PAGE153
PR3790    1      A Q_RES_0402LF-7.15K,1%,1/16W,CHA    I68 @S9S_MB_2U_LIB.S9S_MB_2U(SCH_1):PAGE153

P3V3_OCP_UV_1_R1 @S9S_MB_2U_LIB.S9S_MB_2U(SCH_1):P3V3_OCP_UV_1_R1
  Q124    3     D2 MOSFET_NCH_DUAL-PJT138K,SMLF,IA    I36 @S9S_MB_2U_LIB.S9S_MB_2U(SCH_1):PAGE153
 R3785    1      A Q_RES_0402LF-0,5%,1/16W,CHIP,CA    I64 @S9S_MB_2U_LIB.S9S_MB_2U(SCH_1):PAGE153

P3V3_OCP_UV_2 @S9S_MB_2U_LIB.S9S_MB_2U(SCH_1):P3V3_OCP_UV_2
 R3807    2      B Q_RES_0402LF-0,5%,1/16W,CHIP,CA    I47 @S9S_MB_2U_LIB.S9S_MB_2U(SCH_1):PAGE131
 PU200   D2     UV MAX15090BEWIT-MAX15090BEWI+T,SB    I90 @S9S_MB_2U_LIB.S9S_MB_2U(SCH_1):PAGE131
PR3829    1      A Q_RES_0402LF-7.15K,1%,1/16W,CHA    I50 @S9S_MB_2U_LIB.S9S_MB_2U(SCH_1):PAGE131
PR3795    2      B Q_RES_0402LF-25.5K,1%,1/16W,CHA    I53 @S9S_MB_2U_LIB.S9S_MB_2U(SCH_1):PAGE131

P3V3_OCP_UV_2_R1 @S9S_MB_2U_LIB.S9S_MB_2U(SCH_1):P3V3_OCP_UV_2_R1
  Q119    3     D2 MOSFET_NCH_DUAL-PJT138K,SMLF,IA    I42 @S9S_MB_2U_LIB.S9S_MB_2U(SCH_1):PAGE131
 R3807    1      A Q_RES_0402LF-0,5%,1/16W,CHIP,CA    I47 @S9S_MB_2U_LIB.S9S_MB_2U(SCH_1):PAGE131

P3V3_OCP_V3_2 @S9S_MB_2U_LIB.S9S_MB_2U(SCH_1):P3V3_OCP_V3_2
 R3166    1      A Q_RES_0402LF-4.7K,1%,1/16W,EMPA    I23 @S9S_MB_2U_LIB.S9S_MB_2U(SCH_1):PAGE146
 R3162    1      A Q_RES_0402LF-4.7K,1%,1/16W,CHIA    I26 @S9S_MB_2U_LIB.S9S_MB_2U(SCH_1):PAGE146
 R3182    1      A Q_RES_0402LF-10K,1%,1/16W,CHIPA     I6 @S9S_MB_2U_LIB.S9S_MB_2U(SCH_1):PAGE156
 R3183    1      A Q_RES_0402LF-10K,1%,1/16W,CHIPA     I7 @S9S_MB_2U_LIB.S9S_MB_2U(SCH_1):PAGE156
 R3173    2      B Q_RES_0402LF-1K,1%,1/16W,CHIP,A   I165 @S9S_MB_2U_LIB.S9S_MB_2U(SCH_1):PAGE146
 C1835    1      A Q_CAP_0402-0.1UF,25V,10%,X7R,CA   I173 @S9S_MB_2U_LIB.S9S_MB_2U(SCH_1):PAGE146
 C1836    1      A Q_CAP_0402-0.1UF,25V,10%,X7R,CA   I174 @S9S_MB_2U_LIB.S9S_MB_2U(SCH_1):PAGE146
 C1837    1      A Q_CAP_0402-0.1UF,25V,10%,X7R,CA   I175 @S9S_MB_2U_LIB.S9S_MB_2U(SCH_1):PAGE146
 C1838    1      A Q_CAP_0402-0.1UF,25V,10%,X7R,CA   I177 @S9S_MB_2U_LIB.S9S_MB_2U(SCH_1):PAGE146
  U235    8   VCCB PCA9617ADP-PCA9617ADP,SMLF,IC,A     I5 @S9S_MB_2U_LIB.S9S_MB_2U(SCH_1):PAGE216
 C1861    1      A Q_CAP_0402-0.1UF,25V,10%,X7R,CA    I11 @S9S_MB_2U_LIB.S9S_MB_2U(SCH_1):PAGE216
 R3520    1      A Q_RES_0402LF-4.7K,5%,1/16W,CHIA    I33 @S9S_MB_2U_LIB.S9S_MB_2U(SCH_1):PAGE216
 R3519    1      A Q_RES_0402LF-4.7K,5%,1/16W,CHIA    I34 @S9S_MB_2U_LIB.S9S_MB_2U(SCH_1):PAGE216
 R3571    1      A Q_RES_0402LF-10,1%,1/16W,CHIP,A   I110 @S9S_MB_2U_LIB.S9S_MB_2U(SCH_1):PAGE163
   J35  B11 +3.3V_EDGE SCONN168_ME1016810202011-SCONNA   I303 @S9S_MB_2U_LIB.S9S_MB_2U(SCH_1):PAGE146
 R3174    2      B Q_RES_0402LF-10K,1%,1/16W,CHIPA   I333 @S9S_MB_2U_LIB.S9S_MB_2U(SCH_1):PAGE146
 R3176    2      B Q_RES_0402LF-1K,1%,1/16W,CHIP,A   I336 @S9S_MB_2U_LIB.S9S_MB_2U(SCH_1):PAGE146
  U216    3    VCC APX80929SAG7-APX809-29SAG-7,SMA    I85 @S9S_MB_2U_LIB.S9S_MB_2U(SCH_1):PAGE132
 C1819    1      A Q_CAP_0402-0.1UF,25V,10%,X7R,CA    I87 @S9S_MB_2U_LIB.S9S_MB_2U(SCH_1):PAGE132
 R3633    1      A Q_RES_2512LF-0.01,1%,1W,CHIP,CA   I127 @S9S_MB_2U_LIB.S9S_MB_2U(SCH_1):PAGE163

P3V3_OCP_V3_2_R @S9S_MB_2U_LIB.S9S_MB_2U(SCH_1):P3V3_OCP_V3_2_R
  U263   11    BUS INA230AIRGTR-INA230AIRGTR,SMLFB    I94 @S9S_MB_2U_LIB.S9S_MB_2U(SCH_1):PAGE163
 R3570    1      A Q_RES_0402LF-10,1%,1/16W,CHIP,A   I109 @S9S_MB_2U_LIB.S9S_MB_2U(SCH_1):PAGE163
 C2017    1      A Q_CAP_0402-0.1UF,25V,10%,X7R,CA   I114 @S9S_MB_2U_LIB.S9S_MB_2U(SCH_1):PAGE163
 PU200   A4 OUT_A4 MAX15090BEWIT-MAX15090BEWI+T,SB    I90 @S9S_MB_2U_LIB.S9S_MB_2U(SCH_1):PAGE131
 PU200   B4 OUT_B4 MAX15090BEWIT-MAX15090BEWI+T,SB    I90 @S9S_MB_2U_LIB.S9S_MB_2U(SCH_1):PAGE131
 PU200   B6 OUT_B6 MAX15090BEWIT-MAX15090BEWI+T,SB    I90 @S9S_MB_2U_LIB.S9S_MB_2U(SCH_1):PAGE131
 PU200   C4 OUT_C4 MAX15090BEWIT-MAX15090BEWI+T,SB    I90 @S9S_MB_2U_LIB.S9S_MB_2U(SCH_1):PAGE131
 PU200   C6 OUT_C6 MAX15090BEWIT-MAX15090BEWI+T,SB    I90 @S9S_MB_2U_LIB.S9S_MB_2U(SCH_1):PAGE131
 PU200   D4 OUT_D4 MAX15090BEWIT-MAX15090BEWI+T,SB    I90 @S9S_MB_2U_LIB.S9S_MB_2U(SCH_1):PAGE131
 PU200   D6 OUT_D6 MAX15090BEWIT-MAX15090BEWI+T,SB    I90 @S9S_MB_2U_LIB.S9S_MB_2U(SCH_1):PAGE131
PC2149    1      A Q_CAP_C0402-0.01UF,50V,10%,EMPA   I105 @S9S_MB_2U_LIB.S9S_MB_2U(SCH_1):PAGE131
 PD109    C      C SCHOTTKY_AC-B340A-13-F,SMLF,ICA   I107 @S9S_MB_2U_LIB.S9S_MB_2U(SCH_1):PAGE131
PC2137    1      A Q_CAP_0402-0.1UF,25V,10%,X7R,CA   I109 @S9S_MB_2U_LIB.S9S_MB_2U(SCH_1):PAGE131
 PU207  6_7 SOURCE MP5016GQHLZ-MP5016GQH-L-Z,SMLFA    I51 @S9S_MB_2U_LIB.S9S_MB_2U(SCH_1):PAGE237
PC2173    1      A Q_CAP_C0805-10UF,16V,10%,EMPTYB    I56 @S9S_MB_2U_LIB.S9S_MB_2U(SCH_1):PAGE237
 R3633    2      B Q_RES_2512LF-0.01,1%,1W,CHIP,CA   I127 @S9S_MB_2U_LIB.S9S_MB_2U(SCH_1):PAGE163
PC2142    1      A Q_CAP_C0805-10UF,16V,10%,X6S,CB   I113 @S9S_MB_2U_LIB.S9S_MB_2U(SCH_1):PAGE131
PR4523    1      A Q_RES_0402LF-10M,1%,1/16W,CHIPA   I106 @S9S_MB_2U_LIB.S9S_MB_2U(SCH_1):PAGE131

P3V3_OCP_VCC_1 @S9S_MB_2U_LIB.S9S_MB_2U(SCH_1):P3V3_OCP_VCC_1
PC2086    1      A Q_CAP_C0402-1UF,25V,10%,X6S,CHA    I71 @S9S_MB_2U_LIB.S9S_MB_2U(SCH_1):PAGE153
 PU202   A2    VCC MAX15090BEWIT-MAX15090BEWI+T,SB    I61 @S9S_MB_2U_LIB.S9S_MB_2U(SCH_1):PAGE153
PR3798    2      B Q_RES_0402LF-10,1%,1/16W,CHIP,A    I73 @S9S_MB_2U_LIB.S9S_MB_2U(SCH_1):PAGE153

P3V3_OCP_VCC_2 @S9S_MB_2U_LIB.S9S_MB_2U(SCH_1):P3V3_OCP_VCC_2
 PU200   A2    VCC MAX15090BEWIT-MAX15090BEWI+T,SB    I90 @S9S_MB_2U_LIB.S9S_MB_2U(SCH_1):PAGE131
PR3782    2      B Q_RES_0402LF-10,1%,1/16W,CHIP,A    I92 @S9S_MB_2U_LIB.S9S_MB_2U(SCH_1):PAGE131
 PC190    1      A Q_CAP_C0402-1UF,25V,10%,X6S,CHA    I91 @S9S_MB_2U_LIB.S9S_MB_2U(SCH_1):PAGE131

P3V3_PDB_AUX_ADC @S9S_MB_2U_LIB.S9S_MB_2U(SCH_1):P3V3_PDB_AUX_ADC
 R4567    1      A Q_RES_0402LF-5.11K,1%,1/16W,CHA   I348 @S9S_MB_2U_LIB.S9S_MB_2U(SCH_1):PAGE239
   J45   A3     A3 CONN60_101062636003K02LF-CONN6A    I12 @S9S_MB_2U_LIB.S9S_MB_2U(SCH_1):PAGE233

P3V3_PDB_AUX_ADC_MAM @S9S_MB_2U_LIB.S9S_MB_2U(SCH_1):P3V3_PDB_AUX_ADC_MAM
  U193   11   AIN6 MAX11617EEET-MAX11617EEE+T,SMLA    I57 @S9S_MB_2U_LIB.S9S_MB_2U(SCH_1):PAGE239
 C2045    1      A Q_CAP_0402-100PF,50V,5%,EMPTY,A   I236 @S9S_MB_2U_LIB.S9S_MB_2U(SCH_1):PAGE239
 R3687    2      B Q_RES_0402LF-0,5%,1/16W,EMPTY,A   I240 @S9S_MB_2U_LIB.S9S_MB_2U(SCH_1):PAGE239

P3V3_PDB_AUX_ADC_TIC @S9S_MB_2U_LIB.S9S_MB_2U(SCH_1):P3V3_PDB_AUX_ADC_TIC
  U269   10    IN6 ADC128D818CIMTXNOPB-ADC128D818A   I103 @S9S_MB_2U_LIB.S9S_MB_2U(SCH_1):PAGE239
 C2050    1      A Q_CAP_0402-0.1UF,25V,10%,X7R,CA   I238 @S9S_MB_2U_LIB.S9S_MB_2U(SCH_1):PAGE239
 R3688    2      B Q_RES_0402LF-0,5%,1/16W,CHIP,CA   I241 @S9S_MB_2U_LIB.S9S_MB_2U(SCH_1):PAGE239

P3V3_PWRGD_CLKGEN @S9S_MB_2U_LIB.S9S_MB_2U(SCH_1):P3V3_PWRGD_CLKGEN
 R4080    2      B Q_RES_0402LF-10K,1%,1/16W,CHIPA   I142 @S9S_MB_2U_LIB.S9S_MB_2U(SCH_1):PAGE201
  U247   22 ^CKPWRGD_PD# 9FGL0251DKILFT-9FGL0251DKILFT,A   I167 @S9S_MB_2U_LIB.S9S_MB_2U(SCH_1):PAGE201

P3V3_RTC_AUX @S9S_MB_2U_LIB.S9S_MB_2U(SCH_1):P3V3_RTC_AUX
   U62    3      C BAS70057F-BAS70-05-7-F,SMLF,ICA    I64 @S9S_MB_2U_LIB.S9S_MB_2U(SCH_1):PAGE177
  C611    1      A Q_CAP_C0402-1UF,25V,10%,X6S,CHA    I65 @S9S_MB_2U_LIB.S9S_MB_2U(SCH_1):PAGE177
 R1202    1      A Q_RES_0402LF-20K,1%,1/16W,CHIPA    I70 @S9S_MB_2U_LIB.S9S_MB_2U(SCH_1):PAGE177
    U4 AH15 VCCRTC EMMITSBURG_REV0P9-GFNOCPU04302A    I11 @S9S_MB_2U_LIB.S9S_MB_2U(SCH_1):PAGE178
 R2966    1      A Q_RES_0402LF-1M,1%,1/16W,CHIP,A    I96 @S9S_MB_2U_LIB.S9S_MB_2U(SCH_1):PAGE174
 R1340    1      A Q_RES_0402LF-20K,1%,1/16W,CHIPA   I127 @S9S_MB_2U_LIB.S9S_MB_2U(SCH_1):PAGE189

P3V_BAT @S9S_MB_2U_LIB.S9S_MB_2U(SCH_1):P3V_BAT
 R1203    1      A Q_RES_0402LF-1K,1%,1/16W,CHIP,A    I62 @S9S_MB_2U_LIB.S9S_MB_2U(SCH_1):PAGE177
   BT1    1      1 CONN2_AAABAT029Y19-CONN2_AAA-BA    I63 @S9S_MB_2U_LIB.S9S_MB_2U(SCH_1):PAGE177

P3V_BAT_R @S9S_MB_2U_LIB.S9S_MB_2U(SCH_1):P3V_BAT_R
 R1203    2      B Q_RES_0402LF-1K,1%,1/16W,CHIP,A    I62 @S9S_MB_2U_LIB.S9S_MB_2U(SCH_1):PAGE177
   U62    1      B BAS70057F-BAS70-05-7-F,SMLF,ICA    I64 @S9S_MB_2U_LIB.S9S_MB_2U(SCH_1):PAGE177
 R2994    2      B Q_RES_0402LF-0,5%,1/16W,CHIP,CA    I58 @S9S_MB_2U_LIB.S9S_MB_2U(SCH_1):PAGE227

P3V_BAT_R1 @S9S_MB_2U_LIB.S9S_MB_2U(SCH_1):P3V_BAT_R1
 R2994    1      A Q_RES_0402LF-0,5%,1/16W,CHIP,CA    I58 @S9S_MB_2U_LIB.S9S_MB_2U(SCH_1):PAGE227
   J41  B41 GND_B41 SCONN168_ME1016810202011-SCONNA   I173 @S9S_MB_2U_LIB.S9S_MB_2U(SCH_1):PAGE227

P5E_CPU0_PE0_RX_DN<0> @S9S_MB_2U_LIB.S9S_MB_2U(SCH_1):P5E_CPU0_PE0_RX_DN(0)
    U2  K10 PE0_RX_DN0 SOCKET4677_AZIF0045P001C01CS-SA    I37 @S9S_MB_2U_LIB.S9S_MB_2U(SCH_1):PAGE29
  J107   B8     B8 CONN112_10137002101LF-CONN112_A    I38 @S9S_MB_2U_LIB.S9S_MB_2U(SCH_1):PAGE317

P5E_CPU0_PE0_RX_DN<10> @S9S_MB_2U_LIB.S9S_MB_2U(SCH_1):P5E_CPU0_PE0_RX_DN(10)
    U2 AK10 PE0_RX_DN10 SOCKET4677_AZIF0045P001C01CS-SA    I37 @S9S_MB_2U_LIB.S9S_MB_2U(SCH_1):PAGE29
  J108   B6     B6 CONN112_10137002101LF-CONN112_A    I76 @S9S_MB_2U_LIB.S9S_MB_2U(SCH_1):PAGE320

P5E_CPU0_PE0_RX_DN<11> @S9S_MB_2U_LIB.S9S_MB_2U(SCH_1):P5E_CPU0_PE0_RX_DN(11)
    U2 AM10 PE0_RX_DN11 SOCKET4677_AZIF0045P001C01CS-SA    I37 @S9S_MB_2U_LIB.S9S_MB_2U(SCH_1):PAGE29
  J108   D5     D5 CONN112_10137002101LF-CONN112_A    I76 @S9S_MB_2U_LIB.S9S_MB_2U(SCH_1):PAGE320

P5E_CPU0_PE0_RX_DN<12> @S9S_MB_2U_LIB.S9S_MB_2U(SCH_1):P5E_CPU0_PE0_RX_DN(12)
    U2 AP10 PE0_RX_DN12 SOCKET4677_AZIF0045P001C01CS-SA    I37 @S9S_MB_2U_LIB.S9S_MB_2U(SCH_1):PAGE29
  J108   B4     B4 CONN112_10137002101LF-CONN112_A    I57 @S9S_MB_2U_LIB.S9S_MB_2U(SCH_1):PAGE320

P5E_CPU0_PE0_RX_DN<13> @S9S_MB_2U_LIB.S9S_MB_2U(SCH_1):P5E_CPU0_PE0_RX_DN(13)
    U2  AU9 PE0_RX_DN13 SOCKET4677_AZIF0045P001C01CS-SA    I37 @S9S_MB_2U_LIB.S9S_MB_2U(SCH_1):PAGE29
  J108   C3     C3 CONN112_10137002101LF-CONN112_A    I57 @S9S_MB_2U_LIB.S9S_MB_2U(SCH_1):PAGE320

P5E_CPU0_PE0_RX_DN<14> @S9S_MB_2U_LIB.S9S_MB_2U(SCH_1):P5E_CPU0_PE0_RX_DN(14)
    U2 AV10 PE0_RX_DN14 SOCKET4677_AZIF0045P001C01CS-SA    I37 @S9S_MB_2U_LIB.S9S_MB_2U(SCH_1):PAGE29
  J108   B2     B2 CONN112_10137002101LF-CONN112_A    I57 @S9S_MB_2U_LIB.S9S_MB_2U(SCH_1):PAGE320

P5E_CPU0_PE0_RX_DN<15> @S9S_MB_2U_LIB.S9S_MB_2U(SCH_1):P5E_CPU0_PE0_RX_DN(15)
    U2  BA9 PE0_RX_DN15 SOCKET4677_AZIF0045P001C01CS-SA    I37 @S9S_MB_2U_LIB.S9S_MB_2U(SCH_1):PAGE29
  J108   C1     C1 CONN112_10137002101LF-CONN112_A    I57 @S9S_MB_2U_LIB.S9S_MB_2U(SCH_1):PAGE320

P5E_CPU0_PE0_RX_DN<1> @S9S_MB_2U_LIB.S9S_MB_2U(SCH_1):P5E_CPU0_PE0_RX_DN(1)
    U2  M10 PE0_RX_DN1 SOCKET4677_AZIF0045P001C01CS-SA    I37 @S9S_MB_2U_LIB.S9S_MB_2U(SCH_1):PAGE29
  J107   D7     D7 CONN112_10137002101LF-CONN112_A    I38 @S9S_MB_2U_LIB.S9S_MB_2U(SCH_1):PAGE317

P5E_CPU0_PE0_RX_DN<2> @S9S_MB_2U_LIB.S9S_MB_2U(SCH_1):P5E_CPU0_PE0_RX_DN(2)
    U2  P10 PE0_RX_DN2 SOCKET4677_AZIF0045P001C01CS-SA    I37 @S9S_MB_2U_LIB.S9S_MB_2U(SCH_1):PAGE29
  J107   B6     B6 CONN112_10137002101LF-CONN112_A    I38 @S9S_MB_2U_LIB.S9S_MB_2U(SCH_1):PAGE317

P5E_CPU0_PE0_RX_DN<3> @S9S_MB_2U_LIB.S9S_MB_2U(SCH_1):P5E_CPU0_PE0_RX_DN(3)
    U2  T10 PE0_RX_DN3 SOCKET4677_AZIF0045P001C01CS-SA    I37 @S9S_MB_2U_LIB.S9S_MB_2U(SCH_1):PAGE29
  J107   D5     D5 CONN112_10137002101LF-CONN112_A    I38 @S9S_MB_2U_LIB.S9S_MB_2U(SCH_1):PAGE317

P5E_CPU0_PE0_RX_DN<4> @S9S_MB_2U_LIB.S9S_MB_2U(SCH_1):P5E_CPU0_PE0_RX_DN(4)
    U2  V10 PE0_RX_DN4 SOCKET4677_AZIF0045P001C01CS-SA    I37 @S9S_MB_2U_LIB.S9S_MB_2U(SCH_1):PAGE29
  J107   B4     B4 CONN112_10137002101LF-CONN112_A    I58 @S9S_MB_2U_LIB.S9S_MB_2U(SCH_1):PAGE317

P5E_CPU0_PE0_RX_DN<5> @S9S_MB_2U_LIB.S9S_MB_2U(SCH_1):P5E_CPU0_PE0_RX_DN(5)
    U2  AA9 PE0_RX_DN5 SOCKET4677_AZIF0045P001C01CS-SA    I37 @S9S_MB_2U_LIB.S9S_MB_2U(SCH_1):PAGE29
  J107   C3     C3 CONN112_10137002101LF-CONN112_A    I58 @S9S_MB_2U_LIB.S9S_MB_2U(SCH_1):PAGE317

P5E_CPU0_PE0_RX_DN<6> @S9S_MB_2U_LIB.S9S_MB_2U(SCH_1):P5E_CPU0_PE0_RX_DN(6)
    U2 AB10 PE0_RX_DN6 SOCKET4677_AZIF0045P001C01CS-SA    I37 @S9S_MB_2U_LIB.S9S_MB_2U(SCH_1):PAGE29
  J107   B2     B2 CONN112_10137002101LF-CONN112_A    I58 @S9S_MB_2U_LIB.S9S_MB_2U(SCH_1):PAGE317

P5E_CPU0_PE0_RX_DN<7> @S9S_MB_2U_LIB.S9S_MB_2U(SCH_1):P5E_CPU0_PE0_RX_DN(7)
    U2  AE9 PE0_RX_DN7 SOCKET4677_AZIF0045P001C01CS-SA    I37 @S9S_MB_2U_LIB.S9S_MB_2U(SCH_1):PAGE29
  J107   C1     C1 CONN112_10137002101LF-CONN112_A    I58 @S9S_MB_2U_LIB.S9S_MB_2U(SCH_1):PAGE317

P5E_CPU0_PE0_RX_DN<8> @S9S_MB_2U_LIB.S9S_MB_2U(SCH_1):P5E_CPU0_PE0_RX_DN(8)
    U2 AF10 PE0_RX_DN8 SOCKET4677_AZIF0045P001C01CS-SA    I37 @S9S_MB_2U_LIB.S9S_MB_2U(SCH_1):PAGE29
  J108   B8     B8 CONN112_10137002101LF-CONN112_A    I76 @S9S_MB_2U_LIB.S9S_MB_2U(SCH_1):PAGE320

P5E_CPU0_PE0_RX_DN<9> @S9S_MB_2U_LIB.S9S_MB_2U(SCH_1):P5E_CPU0_PE0_RX_DN(9)
    U2  AJ9 PE0_RX_DN9 SOCKET4677_AZIF0045P001C01CS-SA    I37 @S9S_MB_2U_LIB.S9S_MB_2U(SCH_1):PAGE29
  J108   C7     C7 CONN112_10137002101LF-CONN112_A    I76 @S9S_MB_2U_LIB.S9S_MB_2U(SCH_1):PAGE320

P5E_CPU0_PE0_RX_DP<0> @S9S_MB_2U_LIB.S9S_MB_2U(SCH_1):P5E_CPU0_PE0_RX_DP(0)
    U2  L11 PE0_RX_DP0 SOCKET4677_AZIF0045P001C01CS-SA    I37 @S9S_MB_2U_LIB.S9S_MB_2U(SCH_1):PAGE29
  J107   C8     C8 CONN112_10137002101LF-CONN112_A    I38 @S9S_MB_2U_LIB.S9S_MB_2U(SCH_1):PAGE317

P5E_CPU0_PE0_RX_DP<10> @S9S_MB_2U_LIB.S9S_MB_2U(SCH_1):P5E_CPU0_PE0_RX_DP(10)
    U2 AL11 PE0_RX_DP10 SOCKET4677_AZIF0045P001C01CS-SA    I37 @S9S_MB_2U_LIB.S9S_MB_2U(SCH_1):PAGE29
  J108   C6     C6 CONN112_10137002101LF-CONN112_A    I76 @S9S_MB_2U_LIB.S9S_MB_2U(SCH_1):PAGE320

P5E_CPU0_PE0_RX_DP<11> @S9S_MB_2U_LIB.S9S_MB_2U(SCH_1):P5E_CPU0_PE0_RX_DP(11)
    U2  AN9 PE0_RX_DP11 SOCKET4677_AZIF0045P001C01CS-SA    I37 @S9S_MB_2U_LIB.S9S_MB_2U(SCH_1):PAGE29
  J108   C5     C5 CONN112_10137002101LF-CONN112_A    I76 @S9S_MB_2U_LIB.S9S_MB_2U(SCH_1):PAGE320

P5E_CPU0_PE0_RX_DP<12> @S9S_MB_2U_LIB.S9S_MB_2U(SCH_1):P5E_CPU0_PE0_RX_DP(12)
    U2 AR11 PE0_RX_DP12 SOCKET4677_AZIF0045P001C01CS-SA    I37 @S9S_MB_2U_LIB.S9S_MB_2U(SCH_1):PAGE29
  J108   C4     C4 CONN112_10137002101LF-CONN112_A    I57 @S9S_MB_2U_LIB.S9S_MB_2U(SCH_1):PAGE320

P5E_CPU0_PE0_RX_DP<13> @S9S_MB_2U_LIB.S9S_MB_2U(SCH_1):P5E_CPU0_PE0_RX_DP(13)
    U2 AT10 PE0_RX_DP13 SOCKET4677_AZIF0045P001C01CS-SA    I37 @S9S_MB_2U_LIB.S9S_MB_2U(SCH_1):PAGE29
  J108   D3     D3 CONN112_10137002101LF-CONN112_A    I57 @S9S_MB_2U_LIB.S9S_MB_2U(SCH_1):PAGE320

P5E_CPU0_PE0_RX_DP<14> @S9S_MB_2U_LIB.S9S_MB_2U(SCH_1):P5E_CPU0_PE0_RX_DP(14)
    U2 AW11 PE0_RX_DP14 SOCKET4677_AZIF0045P001C01CS-SA    I37 @S9S_MB_2U_LIB.S9S_MB_2U(SCH_1):PAGE29
  J108   C2     C2 CONN112_10137002101LF-CONN112_A    I57 @S9S_MB_2U_LIB.S9S_MB_2U(SCH_1):PAGE320

P5E_CPU0_PE0_RX_DP<15> @S9S_MB_2U_LIB.S9S_MB_2U(SCH_1):P5E_CPU0_PE0_RX_DP(15)
    U2 AY10 PE0_RX_DP15 SOCKET4677_AZIF0045P001C01CS-SA    I37 @S9S_MB_2U_LIB.S9S_MB_2U(SCH_1):PAGE29
  J108   D1     D1 CONN112_10137002101LF-CONN112_A    I57 @S9S_MB_2U_LIB.S9S_MB_2U(SCH_1):PAGE320

P5E_CPU0_PE0_RX_DP<1> @S9S_MB_2U_LIB.S9S_MB_2U(SCH_1):P5E_CPU0_PE0_RX_DP(1)
    U2   N9 PE0_RX_DP1 SOCKET4677_AZIF0045P001C01CS-SA    I37 @S9S_MB_2U_LIB.S9S_MB_2U(SCH_1):PAGE29
  J107   C7     C7 CONN112_10137002101LF-CONN112_A    I38 @S9S_MB_2U_LIB.S9S_MB_2U(SCH_1):PAGE317

P5E_CPU0_PE0_RX_DP<2> @S9S_MB_2U_LIB.S9S_MB_2U(SCH_1):P5E_CPU0_PE0_RX_DP(2)
    U2  R11 PE0_RX_DP2 SOCKET4677_AZIF0045P001C01CS-SA    I37 @S9S_MB_2U_LIB.S9S_MB_2U(SCH_1):PAGE29
  J107   C6     C6 CONN112_10137002101LF-CONN112_A    I38 @S9S_MB_2U_LIB.S9S_MB_2U(SCH_1):PAGE317

P5E_CPU0_PE0_RX_DP<3> @S9S_MB_2U_LIB.S9S_MB_2U(SCH_1):P5E_CPU0_PE0_RX_DP(3)
    U2   U9 PE0_RX_DP3 SOCKET4677_AZIF0045P001C01CS-SA    I37 @S9S_MB_2U_LIB.S9S_MB_2U(SCH_1):PAGE29
  J107   C5     C5 CONN112_10137002101LF-CONN112_A    I38 @S9S_MB_2U_LIB.S9S_MB_2U(SCH_1):PAGE317

P5E_CPU0_PE0_RX_DP<4> @S9S_MB_2U_LIB.S9S_MB_2U(SCH_1):P5E_CPU0_PE0_RX_DP(4)
    U2  W11 PE0_RX_DP4 SOCKET4677_AZIF0045P001C01CS-SA    I37 @S9S_MB_2U_LIB.S9S_MB_2U(SCH_1):PAGE29
  J107   C4     C4 CONN112_10137002101LF-CONN112_A    I58 @S9S_MB_2U_LIB.S9S_MB_2U(SCH_1):PAGE317

P5E_CPU0_PE0_RX_DP<5> @S9S_MB_2U_LIB.S9S_MB_2U(SCH_1):P5E_CPU0_PE0_RX_DP(5)
    U2  Y10 PE0_RX_DP5 SOCKET4677_AZIF0045P001C01CS-SA    I37 @S9S_MB_2U_LIB.S9S_MB_2U(SCH_1):PAGE29
  J107   D3     D3 CONN112_10137002101LF-CONN112_A    I58 @S9S_MB_2U_LIB.S9S_MB_2U(SCH_1):PAGE317

P5E_CPU0_PE0_RX_DP<6> @S9S_MB_2U_LIB.S9S_MB_2U(SCH_1):P5E_CPU0_PE0_RX_DP(6)
    U2 AC11 PE0_RX_DP6 SOCKET4677_AZIF0045P001C01CS-SA    I37 @S9S_MB_2U_LIB.S9S_MB_2U(SCH_1):PAGE29
  J107   C2     C2 CONN112_10137002101LF-CONN112_A    I58 @S9S_MB_2U_LIB.S9S_MB_2U(SCH_1):PAGE317

P5E_CPU0_PE0_RX_DP<7> @S9S_MB_2U_LIB.S9S_MB_2U(SCH_1):P5E_CPU0_PE0_RX_DP(7)
    U2 AD10 PE0_RX_DP7 SOCKET4677_AZIF0045P001C01CS-SA    I37 @S9S_MB_2U_LIB.S9S_MB_2U(SCH_1):PAGE29
  J107   D1     D1 CONN112_10137002101LF-CONN112_A    I58 @S9S_MB_2U_LIB.S9S_MB_2U(SCH_1):PAGE317

P5E_CPU0_PE0_RX_DP<8> @S9S_MB_2U_LIB.S9S_MB_2U(SCH_1):P5E_CPU0_PE0_RX_DP(8)
    U2 AG11 PE0_RX_DP8 SOCKET4677_AZIF0045P001C01CS-SA    I37 @S9S_MB_2U_LIB.S9S_MB_2U(SCH_1):PAGE29
  J108   C8     C8 CONN112_10137002101LF-CONN112_A    I76 @S9S_MB_2U_LIB.S9S_MB_2U(SCH_1):PAGE320

P5E_CPU0_PE0_RX_DP<9> @S9S_MB_2U_LIB.S9S_MB_2U(SCH_1):P5E_CPU0_PE0_RX_DP(9)
    U2 AH10 PE0_RX_DP9 SOCKET4677_AZIF0045P001C01CS-SA    I37 @S9S_MB_2U_LIB.S9S_MB_2U(SCH_1):PAGE29
  J108   D7     D7 CONN112_10137002101LF-CONN112_A    I76 @S9S_MB_2U_LIB.S9S_MB_2U(SCH_1):PAGE320

P5E_CPU0_PE0_TX_C_DN<0> @S9S_MB_2U_LIB.S9S_MB_2U(SCH_1):P5E_CPU0_PE0_TX_C_DN(0)
  C932    1      1 Q_CAP_DIFFBUS_C0201-DIFF BUS_0A    I21 @S9S_MB_2U_LIB.S9S_MB_2U(SCH_1):PAGE164
  J107   H8     H8 CONN112_10137002101LF-CONN112_A    I38 @S9S_MB_2U_LIB.S9S_MB_2U(SCH_1):PAGE317

P5E_CPU0_PE0_TX_C_DN<10> @S9S_MB_2U_LIB.S9S_MB_2U(SCH_1):P5E_CPU0_PE0_TX_C_DN(10)
  C912    1      1 Q_CAP_DIFFBUS_C0201-DIFF BUS_0A    I58 @S9S_MB_2U_LIB.S9S_MB_2U(SCH_1):PAGE164
  J108   H6     H6 CONN112_10137002101LF-CONN112_A    I76 @S9S_MB_2U_LIB.S9S_MB_2U(SCH_1):PAGE320

P5E_CPU0_PE0_TX_C_DN<11> @S9S_MB_2U_LIB.S9S_MB_2U(SCH_1):P5E_CPU0_PE0_TX_C_DN(11)
  C910    1      1 Q_CAP_DIFFBUS_C0201-DIFF BUS_0A    I60 @S9S_MB_2U_LIB.S9S_MB_2U(SCH_1):PAGE164
  J108   I5     I5 CONN112_10137002101LF-CONN112_A    I76 @S9S_MB_2U_LIB.S9S_MB_2U(SCH_1):PAGE320

P5E_CPU0_PE0_TX_C_DN<12> @S9S_MB_2U_LIB.S9S_MB_2U(SCH_1):P5E_CPU0_PE0_TX_C_DN(12)
  C908    1      1 Q_CAP_DIFFBUS_C0201-DIFF BUS_0A    I62 @S9S_MB_2U_LIB.S9S_MB_2U(SCH_1):PAGE164
  J108   H4     H4 CONN112_10137002101LF-CONN112_A    I57 @S9S_MB_2U_LIB.S9S_MB_2U(SCH_1):PAGE320

P5E_CPU0_PE0_TX_C_DN<13> @S9S_MB_2U_LIB.S9S_MB_2U(SCH_1):P5E_CPU0_PE0_TX_C_DN(13)
  C906    1      1 Q_CAP_DIFFBUS_C0201-DIFF BUS_0A    I63 @S9S_MB_2U_LIB.S9S_MB_2U(SCH_1):PAGE164
  J108   I3     I3 CONN112_10137002101LF-CONN112_A    I57 @S9S_MB_2U_LIB.S9S_MB_2U(SCH_1):PAGE320

P5E_CPU0_PE0_TX_C_DN<14> @S9S_MB_2U_LIB.S9S_MB_2U(SCH_1):P5E_CPU0_PE0_TX_C_DN(14)
  C904    1      1 Q_CAP_DIFFBUS_C0201-DIFF BUS_0A    I66 @S9S_MB_2U_LIB.S9S_MB_2U(SCH_1):PAGE164
  J108   H2     H2 CONN112_10137002101LF-CONN112_A    I57 @S9S_MB_2U_LIB.S9S_MB_2U(SCH_1):PAGE320

P5E_CPU0_PE0_TX_C_DN<15> @S9S_MB_2U_LIB.S9S_MB_2U(SCH_1):P5E_CPU0_PE0_TX_C_DN(15)
  C902    1      1 Q_CAP_DIFFBUS_C0201-DIFF BUS_0A    I68 @S9S_MB_2U_LIB.S9S_MB_2U(SCH_1):PAGE164
  J108   I1     I1 CONN112_10137002101LF-CONN112_A    I57 @S9S_MB_2U_LIB.S9S_MB_2U(SCH_1):PAGE320

P5E_CPU0_PE0_TX_C_DN<1> @S9S_MB_2U_LIB.S9S_MB_2U(SCH_1):P5E_CPU0_PE0_TX_C_DN(1)
  C930    1      1 Q_CAP_DIFFBUS_C0201-DIFF BUS_0A    I24 @S9S_MB_2U_LIB.S9S_MB_2U(SCH_1):PAGE164
  J107   I7     I7 CONN112_10137002101LF-CONN112_A    I38 @S9S_MB_2U_LIB.S9S_MB_2U(SCH_1):PAGE317

P5E_CPU0_PE0_TX_C_DN<2> @S9S_MB_2U_LIB.S9S_MB_2U(SCH_1):P5E_CPU0_PE0_TX_C_DN(2)
  C928    1      1 Q_CAP_DIFFBUS_C0201-DIFF BUS_0A    I25 @S9S_MB_2U_LIB.S9S_MB_2U(SCH_1):PAGE164
  J107   H6     H6 CONN112_10137002101LF-CONN112_A    I38 @S9S_MB_2U_LIB.S9S_MB_2U(SCH_1):PAGE317

P5E_CPU0_PE0_TX_C_DN<3> @S9S_MB_2U_LIB.S9S_MB_2U(SCH_1):P5E_CPU0_PE0_TX_C_DN(3)
  C926    1      1 Q_CAP_DIFFBUS_C0201-DIFF BUS_0A    I28 @S9S_MB_2U_LIB.S9S_MB_2U(SCH_1):PAGE164
  J107   I5     I5 CONN112_10137002101LF-CONN112_A    I38 @S9S_MB_2U_LIB.S9S_MB_2U(SCH_1):PAGE317

P5E_CPU0_PE0_TX_C_DN<4> @S9S_MB_2U_LIB.S9S_MB_2U(SCH_1):P5E_CPU0_PE0_TX_C_DN(4)
  C924    1      1 Q_CAP_DIFFBUS_C0201-DIFF BUS_0A    I30 @S9S_MB_2U_LIB.S9S_MB_2U(SCH_1):PAGE164
  J107   H4     H4 CONN112_10137002101LF-CONN112_A    I58 @S9S_MB_2U_LIB.S9S_MB_2U(SCH_1):PAGE317

P5E_CPU0_PE0_TX_C_DN<5> @S9S_MB_2U_LIB.S9S_MB_2U(SCH_1):P5E_CPU0_PE0_TX_C_DN(5)
  C922    1      1 Q_CAP_DIFFBUS_C0201-DIFF BUS_0A    I32 @S9S_MB_2U_LIB.S9S_MB_2U(SCH_1):PAGE164
  J107   I3     I3 CONN112_10137002101LF-CONN112_A    I58 @S9S_MB_2U_LIB.S9S_MB_2U(SCH_1):PAGE317

P5E_CPU0_PE0_TX_C_DN<6> @S9S_MB_2U_LIB.S9S_MB_2U(SCH_1):P5E_CPU0_PE0_TX_C_DN(6)
  C920    1      1 Q_CAP_DIFFBUS_C0201-DIFF BUS_0A    I34 @S9S_MB_2U_LIB.S9S_MB_2U(SCH_1):PAGE164
  J107   H2     H2 CONN112_10137002101LF-CONN112_A    I58 @S9S_MB_2U_LIB.S9S_MB_2U(SCH_1):PAGE317

P5E_CPU0_PE0_TX_C_DN<7> @S9S_MB_2U_LIB.S9S_MB_2U(SCH_1):P5E_CPU0_PE0_TX_C_DN(7)
  C918    1      1 Q_CAP_DIFFBUS_C0201-DIFF BUS_0A    I35 @S9S_MB_2U_LIB.S9S_MB_2U(SCH_1):PAGE164
  J107   I1     I1 CONN112_10137002101LF-CONN112_A    I58 @S9S_MB_2U_LIB.S9S_MB_2U(SCH_1):PAGE317

P5E_CPU0_PE0_TX_C_DN<8> @S9S_MB_2U_LIB.S9S_MB_2U(SCH_1):P5E_CPU0_PE0_TX_C_DN(8)
  C916    1      1 Q_CAP_DIFFBUS_C0201-DIFF BUS_0A    I53 @S9S_MB_2U_LIB.S9S_MB_2U(SCH_1):PAGE164
  J108   H8     H8 CONN112_10137002101LF-CONN112_A    I76 @S9S_MB_2U_LIB.S9S_MB_2U(SCH_1):PAGE320

P5E_CPU0_PE0_TX_C_DN<9> @S9S_MB_2U_LIB.S9S_MB_2U(SCH_1):P5E_CPU0_PE0_TX_C_DN(9)
  C914    1      1 Q_CAP_DIFFBUS_C0201-DIFF BUS_0A    I56 @S9S_MB_2U_LIB.S9S_MB_2U(SCH_1):PAGE164
  J108   I7     I7 CONN112_10137002101LF-CONN112_A    I76 @S9S_MB_2U_LIB.S9S_MB_2U(SCH_1):PAGE320

P5E_CPU0_PE0_TX_C_DP<0> @S9S_MB_2U_LIB.S9S_MB_2U(SCH_1):P5E_CPU0_PE0_TX_C_DP(0)
  C933    1      1 Q_CAP_DIFFBUS_C0201-DIFF BUS_0A    I22 @S9S_MB_2U_LIB.S9S_MB_2U(SCH_1):PAGE164
  J107   I8     I8 CONN112_10137002101LF-CONN112_A    I38 @S9S_MB_2U_LIB.S9S_MB_2U(SCH_1):PAGE317

P5E_CPU0_PE0_TX_C_DP<10> @S9S_MB_2U_LIB.S9S_MB_2U(SCH_1):P5E_CPU0_PE0_TX_C_DP(10)
  C913    1      1 Q_CAP_DIFFBUS_C0201-DIFF BUS_0A    I57 @S9S_MB_2U_LIB.S9S_MB_2U(SCH_1):PAGE164
  J108   I6     I6 CONN112_10137002101LF-CONN112_A    I76 @S9S_MB_2U_LIB.S9S_MB_2U(SCH_1):PAGE320

P5E_CPU0_PE0_TX_C_DP<11> @S9S_MB_2U_LIB.S9S_MB_2U(SCH_1):P5E_CPU0_PE0_TX_C_DP(11)
  C911    1      1 Q_CAP_DIFFBUS_C0201-DIFF BUS_0A    I59 @S9S_MB_2U_LIB.S9S_MB_2U(SCH_1):PAGE164
  J108   J5     J5 CONN112_10137002101LF-CONN112_A    I76 @S9S_MB_2U_LIB.S9S_MB_2U(SCH_1):PAGE320

P5E_CPU0_PE0_TX_C_DP<12> @S9S_MB_2U_LIB.S9S_MB_2U(SCH_1):P5E_CPU0_PE0_TX_C_DP(12)
  C909    1      1 Q_CAP_DIFFBUS_C0201-DIFF BUS_0A    I61 @S9S_MB_2U_LIB.S9S_MB_2U(SCH_1):PAGE164
  J108   I4     I4 CONN112_10137002101LF-CONN112_A    I57 @S9S_MB_2U_LIB.S9S_MB_2U(SCH_1):PAGE320

P5E_CPU0_PE0_TX_C_DP<13> @S9S_MB_2U_LIB.S9S_MB_2U(SCH_1):P5E_CPU0_PE0_TX_C_DP(13)
  C907    1      1 Q_CAP_DIFFBUS_C0201-DIFF BUS_0A    I64 @S9S_MB_2U_LIB.S9S_MB_2U(SCH_1):PAGE164
  J108   J3     J3 CONN112_10137002101LF-CONN112_A    I57 @S9S_MB_2U_LIB.S9S_MB_2U(SCH_1):PAGE320

P5E_CPU0_PE0_TX_C_DP<14> @S9S_MB_2U_LIB.S9S_MB_2U(SCH_1):P5E_CPU0_PE0_TX_C_DP(14)
  C905    1      1 Q_CAP_DIFFBUS_C0201-DIFF BUS_0A    I65 @S9S_MB_2U_LIB.S9S_MB_2U(SCH_1):PAGE164
  J108   I2     I2 CONN112_10137002101LF-CONN112_A    I57 @S9S_MB_2U_LIB.S9S_MB_2U(SCH_1):PAGE320

P5E_CPU0_PE0_TX_C_DP<15> @S9S_MB_2U_LIB.S9S_MB_2U(SCH_1):P5E_CPU0_PE0_TX_C_DP(15)
  C903    1      1 Q_CAP_DIFFBUS_C0201-DIFF BUS_0A    I67 @S9S_MB_2U_LIB.S9S_MB_2U(SCH_1):PAGE164
  J108   J1     J1 CONN112_10137002101LF-CONN112_A    I57 @S9S_MB_2U_LIB.S9S_MB_2U(SCH_1):PAGE320

P5E_CPU0_PE0_TX_C_DP<1> @S9S_MB_2U_LIB.S9S_MB_2U(SCH_1):P5E_CPU0_PE0_TX_C_DP(1)
  C931    1      1 Q_CAP_DIFFBUS_C0201-DIFF BUS_0A    I23 @S9S_MB_2U_LIB.S9S_MB_2U(SCH_1):PAGE164
  J107   J7     J7 CONN112_10137002101LF-CONN112_A    I38 @S9S_MB_2U_LIB.S9S_MB_2U(SCH_1):PAGE317

P5E_CPU0_PE0_TX_C_DP<2> @S9S_MB_2U_LIB.S9S_MB_2U(SCH_1):P5E_CPU0_PE0_TX_C_DP(2)
  C929    1      1 Q_CAP_DIFFBUS_C0201-DIFF BUS_0A    I26 @S9S_MB_2U_LIB.S9S_MB_2U(SCH_1):PAGE164
  J107   I6     I6 CONN112_10137002101LF-CONN112_A    I38 @S9S_MB_2U_LIB.S9S_MB_2U(SCH_1):PAGE317

P5E_CPU0_PE0_TX_C_DP<3> @S9S_MB_2U_LIB.S9S_MB_2U(SCH_1):P5E_CPU0_PE0_TX_C_DP(3)
  C927    1      1 Q_CAP_DIFFBUS_C0201-DIFF BUS_0A    I27 @S9S_MB_2U_LIB.S9S_MB_2U(SCH_1):PAGE164
  J107   J5     J5 CONN112_10137002101LF-CONN112_A    I38 @S9S_MB_2U_LIB.S9S_MB_2U(SCH_1):PAGE317

P5E_CPU0_PE0_TX_C_DP<4> @S9S_MB_2U_LIB.S9S_MB_2U(SCH_1):P5E_CPU0_PE0_TX_C_DP(4)
  C925    1      1 Q_CAP_DIFFBUS_C0201-DIFF BUS_0A    I29 @S9S_MB_2U_LIB.S9S_MB_2U(SCH_1):PAGE164
  J107   I4     I4 CONN112_10137002101LF-CONN112_A    I58 @S9S_MB_2U_LIB.S9S_MB_2U(SCH_1):PAGE317

P5E_CPU0_PE0_TX_C_DP<5> @S9S_MB_2U_LIB.S9S_MB_2U(SCH_1):P5E_CPU0_PE0_TX_C_DP(5)
  C923    1      1 Q_CAP_DIFFBUS_C0201-DIFF BUS_0A    I31 @S9S_MB_2U_LIB.S9S_MB_2U(SCH_1):PAGE164
  J107   J3     J3 CONN112_10137002101LF-CONN112_A    I58 @S9S_MB_2U_LIB.S9S_MB_2U(SCH_1):PAGE317

P5E_CPU0_PE0_TX_C_DP<6> @S9S_MB_2U_LIB.S9S_MB_2U(SCH_1):P5E_CPU0_PE0_TX_C_DP(6)
  C921    1      1 Q_CAP_DIFFBUS_C0201-DIFF BUS_0A    I33 @S9S_MB_2U_LIB.S9S_MB_2U(SCH_1):PAGE164
  J107   I2     I2 CONN112_10137002101LF-CONN112_A    I58 @S9S_MB_2U_LIB.S9S_MB_2U(SCH_1):PAGE317

P5E_CPU0_PE0_TX_C_DP<7> @S9S_MB_2U_LIB.S9S_MB_2U(SCH_1):P5E_CPU0_PE0_TX_C_DP(7)
  C919    1      1 Q_CAP_DIFFBUS_C0201-DIFF BUS_0A    I36 @S9S_MB_2U_LIB.S9S_MB_2U(SCH_1):PAGE164
  J107   J1     J1 CONN112_10137002101LF-CONN112_A    I58 @S9S_MB_2U_LIB.S9S_MB_2U(SCH_1):PAGE317

P5E_CPU0_PE0_TX_C_DP<8> @S9S_MB_2U_LIB.S9S_MB_2U(SCH_1):P5E_CPU0_PE0_TX_C_DP(8)
  C917    1      1 Q_CAP_DIFFBUS_C0201-DIFF BUS_0A    I54 @S9S_MB_2U_LIB.S9S_MB_2U(SCH_1):PAGE164
  J108   I8     I8 CONN112_10137002101LF-CONN112_A    I76 @S9S_MB_2U_LIB.S9S_MB_2U(SCH_1):PAGE320

P5E_CPU0_PE0_TX_C_DP<9> @S9S_MB_2U_LIB.S9S_MB_2U(SCH_1):P5E_CPU0_PE0_TX_C_DP(9)
  C915    1      1 Q_CAP_DIFFBUS_C0201-DIFF BUS_0A    I55 @S9S_MB_2U_LIB.S9S_MB_2U(SCH_1):PAGE164
  J108   J7     J7 CONN112_10137002101LF-CONN112_A    I76 @S9S_MB_2U_LIB.S9S_MB_2U(SCH_1):PAGE320

P5E_CPU0_PE0_TX_DN<0> @S9S_MB_2U_LIB.S9S_MB_2U(SCH_1):P5E_CPU0_PE0_TX_DN(0)
    U2  N13 PE0_TX_DN0 SOCKET4677_AZIF0045P001C01CS-SA    I37 @S9S_MB_2U_LIB.S9S_MB_2U(SCH_1):PAGE29
  C932    2      2 Q_CAP_DIFFBUS_C0201-DIFF BUS_0A    I21 @S9S_MB_2U_LIB.S9S_MB_2U(SCH_1):PAGE164

P5E_CPU0_PE0_TX_DN<10> @S9S_MB_2U_LIB.S9S_MB_2U(SCH_1):P5E_CPU0_PE0_TX_DN(10)
    U2 AN13 PE0_TX_DN10 SOCKET4677_AZIF0045P001C01CS-SA    I37 @S9S_MB_2U_LIB.S9S_MB_2U(SCH_1):PAGE29
  C912    2      2 Q_CAP_DIFFBUS_C0201-DIFF BUS_0A    I58 @S9S_MB_2U_LIB.S9S_MB_2U(SCH_1):PAGE164

P5E_CPU0_PE0_TX_DN<11> @S9S_MB_2U_LIB.S9S_MB_2U(SCH_1):P5E_CPU0_PE0_TX_DN(11)
    U2 AP14 PE0_TX_DN11 SOCKET4677_AZIF0045P001C01CS-SA    I37 @S9S_MB_2U_LIB.S9S_MB_2U(SCH_1):PAGE29
  C910    2      2 Q_CAP_DIFFBUS_C0201-DIFF BUS_0A    I60 @S9S_MB_2U_LIB.S9S_MB_2U(SCH_1):PAGE164

P5E_CPU0_PE0_TX_DN<12> @S9S_MB_2U_LIB.S9S_MB_2U(SCH_1):P5E_CPU0_PE0_TX_DN(12)
    U2 AU13 PE0_TX_DN12 SOCKET4677_AZIF0045P001C01CS-SA    I37 @S9S_MB_2U_LIB.S9S_MB_2U(SCH_1):PAGE29
  C908    2      2 Q_CAP_DIFFBUS_C0201-DIFF BUS_0A    I62 @S9S_MB_2U_LIB.S9S_MB_2U(SCH_1):PAGE164

P5E_CPU0_PE0_TX_DN<13> @S9S_MB_2U_LIB.S9S_MB_2U(SCH_1):P5E_CPU0_PE0_TX_DN(13)
    U2 AV14 PE0_TX_DN13 SOCKET4677_AZIF0045P001C01CS-SA    I37 @S9S_MB_2U_LIB.S9S_MB_2U(SCH_1):PAGE29
  C906    2      2 Q_CAP_DIFFBUS_C0201-DIFF BUS_0A    I63 @S9S_MB_2U_LIB.S9S_MB_2U(SCH_1):PAGE164

P5E_CPU0_PE0_TX_DN<14> @S9S_MB_2U_LIB.S9S_MB_2U(SCH_1):P5E_CPU0_PE0_TX_DN(14)
    U2 BA13 PE0_TX_DN14 SOCKET4677_AZIF0045P001C01CS-SA    I37 @S9S_MB_2U_LIB.S9S_MB_2U(SCH_1):PAGE29
  C904    2      2 Q_CAP_DIFFBUS_C0201-DIFF BUS_0A    I66 @S9S_MB_2U_LIB.S9S_MB_2U(SCH_1):PAGE164

P5E_CPU0_PE0_TX_DN<15> @S9S_MB_2U_LIB.S9S_MB_2U(SCH_1):P5E_CPU0_PE0_TX_DN(15)
    U2 BB14 PE0_TX_DN15 SOCKET4677_AZIF0045P001C01CS-SA    I37 @S9S_MB_2U_LIB.S9S_MB_2U(SCH_1):PAGE29
  C902    2      2 Q_CAP_DIFFBUS_C0201-DIFF BUS_0A    I68 @S9S_MB_2U_LIB.S9S_MB_2U(SCH_1):PAGE164

P5E_CPU0_PE0_TX_DN<1> @S9S_MB_2U_LIB.S9S_MB_2U(SCH_1):P5E_CPU0_PE0_TX_DN(1)
    U2  P14 PE0_TX_DN1 SOCKET4677_AZIF0045P001C01CS-SA    I37 @S9S_MB_2U_LIB.S9S_MB_2U(SCH_1):PAGE29
  C930    2      2 Q_CAP_DIFFBUS_C0201-DIFF BUS_0A    I24 @S9S_MB_2U_LIB.S9S_MB_2U(SCH_1):PAGE164

P5E_CPU0_PE0_TX_DN<2> @S9S_MB_2U_LIB.S9S_MB_2U(SCH_1):P5E_CPU0_PE0_TX_DN(2)
    U2  U13 PE0_TX_DN2 SOCKET4677_AZIF0045P001C01CS-SA    I37 @S9S_MB_2U_LIB.S9S_MB_2U(SCH_1):PAGE29
  C928    2      2 Q_CAP_DIFFBUS_C0201-DIFF BUS_0A    I25 @S9S_MB_2U_LIB.S9S_MB_2U(SCH_1):PAGE164

P5E_CPU0_PE0_TX_DN<3> @S9S_MB_2U_LIB.S9S_MB_2U(SCH_1):P5E_CPU0_PE0_TX_DN(3)
    U2  V14 PE0_TX_DN3 SOCKET4677_AZIF0045P001C01CS-SA    I37 @S9S_MB_2U_LIB.S9S_MB_2U(SCH_1):PAGE29
  C926    2      2 Q_CAP_DIFFBUS_C0201-DIFF BUS_0A    I28 @S9S_MB_2U_LIB.S9S_MB_2U(SCH_1):PAGE164

P5E_CPU0_PE0_TX_DN<4> @S9S_MB_2U_LIB.S9S_MB_2U(SCH_1):P5E_CPU0_PE0_TX_DN(4)
    U2 AA13 PE0_TX_DN4 SOCKET4677_AZIF0045P001C01CS-SA    I37 @S9S_MB_2U_LIB.S9S_MB_2U(SCH_1):PAGE29
  C924    2      2 Q_CAP_DIFFBUS_C0201-DIFF BUS_0A    I30 @S9S_MB_2U_LIB.S9S_MB_2U(SCH_1):PAGE164

P5E_CPU0_PE0_TX_DN<5> @S9S_MB_2U_LIB.S9S_MB_2U(SCH_1):P5E_CPU0_PE0_TX_DN(5)
    U2 AB14 PE0_TX_DN5 SOCKET4677_AZIF0045P001C01CS-SA    I37 @S9S_MB_2U_LIB.S9S_MB_2U(SCH_1):PAGE29
  C922    2      2 Q_CAP_DIFFBUS_C0201-DIFF BUS_0A    I32 @S9S_MB_2U_LIB.S9S_MB_2U(SCH_1):PAGE164

P5E_CPU0_PE0_TX_DN<6> @S9S_MB_2U_LIB.S9S_MB_2U(SCH_1):P5E_CPU0_PE0_TX_DN(6)
    U2 AE13 PE0_TX_DN6 SOCKET4677_AZIF0045P001C01CS-SA    I37 @S9S_MB_2U_LIB.S9S_MB_2U(SCH_1):PAGE29
  C920    2      2 Q_CAP_DIFFBUS_C0201-DIFF BUS_0A    I34 @S9S_MB_2U_LIB.S9S_MB_2U(SCH_1):PAGE164

P5E_CPU0_PE0_TX_DN<7> @S9S_MB_2U_LIB.S9S_MB_2U(SCH_1):P5E_CPU0_PE0_TX_DN(7)
    U2 AF14 PE0_TX_DN7 SOCKET4677_AZIF0045P001C01CS-SA    I37 @S9S_MB_2U_LIB.S9S_MB_2U(SCH_1):PAGE29
  C918    2      2 Q_CAP_DIFFBUS_C0201-DIFF BUS_0A    I35 @S9S_MB_2U_LIB.S9S_MB_2U(SCH_1):PAGE164

P5E_CPU0_PE0_TX_DN<8> @S9S_MB_2U_LIB.S9S_MB_2U(SCH_1):P5E_CPU0_PE0_TX_DN(8)
    U2 AJ13 PE0_TX_DN8 SOCKET4677_AZIF0045P001C01CS-SA    I37 @S9S_MB_2U_LIB.S9S_MB_2U(SCH_1):PAGE29
  C916    2      2 Q_CAP_DIFFBUS_C0201-DIFF BUS_0A    I53 @S9S_MB_2U_LIB.S9S_MB_2U(SCH_1):PAGE164

P5E_CPU0_PE0_TX_DN<9> @S9S_MB_2U_LIB.S9S_MB_2U(SCH_1):P5E_CPU0_PE0_TX_DN(9)
    U2 AK14 PE0_TX_DN9 SOCKET4677_AZIF0045P001C01CS-SA    I37 @S9S_MB_2U_LIB.S9S_MB_2U(SCH_1):PAGE29
  C914    2      2 Q_CAP_DIFFBUS_C0201-DIFF BUS_0A    I56 @S9S_MB_2U_LIB.S9S_MB_2U(SCH_1):PAGE164

P5E_CPU0_PE0_TX_DP<0> @S9S_MB_2U_LIB.S9S_MB_2U(SCH_1):P5E_CPU0_PE0_TX_DP(0)
    U2  M14 PE0_TX_DP0 SOCKET4677_AZIF0045P001C01CS-SA    I37 @S9S_MB_2U_LIB.S9S_MB_2U(SCH_1):PAGE29
  C933    2      2 Q_CAP_DIFFBUS_C0201-DIFF BUS_0A    I22 @S9S_MB_2U_LIB.S9S_MB_2U(SCH_1):PAGE164

P5E_CPU0_PE0_TX_DP<10> @S9S_MB_2U_LIB.S9S_MB_2U(SCH_1):P5E_CPU0_PE0_TX_DP(10)
    U2 AM14 PE0_TX_DP10 SOCKET4677_AZIF0045P001C01CS-SA    I37 @S9S_MB_2U_LIB.S9S_MB_2U(SCH_1):PAGE29
  C913    2      2 Q_CAP_DIFFBUS_C0201-DIFF BUS_0A    I57 @S9S_MB_2U_LIB.S9S_MB_2U(SCH_1):PAGE164

P5E_CPU0_PE0_TX_DP<11> @S9S_MB_2U_LIB.S9S_MB_2U(SCH_1):P5E_CPU0_PE0_TX_DP(11)
    U2 AR15 PE0_TX_DP11 SOCKET4677_AZIF0045P001C01CS-SA    I37 @S9S_MB_2U_LIB.S9S_MB_2U(SCH_1):PAGE29
  C911    2      2 Q_CAP_DIFFBUS_C0201-DIFF BUS_0A    I59 @S9S_MB_2U_LIB.S9S_MB_2U(SCH_1):PAGE164

P5E_CPU0_PE0_TX_DP<12> @S9S_MB_2U_LIB.S9S_MB_2U(SCH_1):P5E_CPU0_PE0_TX_DP(12)
    U2 AT14 PE0_TX_DP12 SOCKET4677_AZIF0045P001C01CS-SA    I37 @S9S_MB_2U_LIB.S9S_MB_2U(SCH_1):PAGE29
  C909    2      2 Q_CAP_DIFFBUS_C0201-DIFF BUS_0A    I61 @S9S_MB_2U_LIB.S9S_MB_2U(SCH_1):PAGE164

P5E_CPU0_PE0_TX_DP<13> @S9S_MB_2U_LIB.S9S_MB_2U(SCH_1):P5E_CPU0_PE0_TX_DP(13)
    U2 AW15 PE0_TX_DP13 SOCKET4677_AZIF0045P001C01CS-SA    I37 @S9S_MB_2U_LIB.S9S_MB_2U(SCH_1):PAGE29
  C907    2      2 Q_CAP_DIFFBUS_C0201-DIFF BUS_0A    I64 @S9S_MB_2U_LIB.S9S_MB_2U(SCH_1):PAGE164

P5E_CPU0_PE0_TX_DP<14> @S9S_MB_2U_LIB.S9S_MB_2U(SCH_1):P5E_CPU0_PE0_TX_DP(14)
    U2 AY14 PE0_TX_DP14 SOCKET4677_AZIF0045P001C01CS-SA    I37 @S9S_MB_2U_LIB.S9S_MB_2U(SCH_1):PAGE29
  C905    2      2 Q_CAP_DIFFBUS_C0201-DIFF BUS_0A    I65 @S9S_MB_2U_LIB.S9S_MB_2U(SCH_1):PAGE164

P5E_CPU0_PE0_TX_DP<15> @S9S_MB_2U_LIB.S9S_MB_2U(SCH_1):P5E_CPU0_PE0_TX_DP(15)
    U2 BC15 PE0_TX_DP15 SOCKET4677_AZIF0045P001C01CS-SA    I37 @S9S_MB_2U_LIB.S9S_MB_2U(SCH_1):PAGE29
  C903    2      2 Q_CAP_DIFFBUS_C0201-DIFF BUS_0A    I67 @S9S_MB_2U_LIB.S9S_MB_2U(SCH_1):PAGE164

P5E_CPU0_PE0_TX_DP<1> @S9S_MB_2U_LIB.S9S_MB_2U(SCH_1):P5E_CPU0_PE0_TX_DP(1)
    U2  R15 PE0_TX_DP1 SOCKET4677_AZIF0045P001C01CS-SA    I37 @S9S_MB_2U_LIB.S9S_MB_2U(SCH_1):PAGE29
  C931    2      2 Q_CAP_DIFFBUS_C0201-DIFF BUS_0A    I23 @S9S_MB_2U_LIB.S9S_MB_2U(SCH_1):PAGE164

P5E_CPU0_PE0_TX_DP<2> @S9S_MB_2U_LIB.S9S_MB_2U(SCH_1):P5E_CPU0_PE0_TX_DP(2)
    U2  T14 PE0_TX_DP2 SOCKET4677_AZIF0045P001C01CS-SA    I37 @S9S_MB_2U_LIB.S9S_MB_2U(SCH_1):PAGE29
  C929    2      2 Q_CAP_DIFFBUS_C0201-DIFF BUS_0A    I26 @S9S_MB_2U_LIB.S9S_MB_2U(SCH_1):PAGE164

P5E_CPU0_PE0_TX_DP<3> @S9S_MB_2U_LIB.S9S_MB_2U(SCH_1):P5E_CPU0_PE0_TX_DP(3)
    U2  W15 PE0_TX_DP3 SOCKET4677_AZIF0045P001C01CS-SA    I37 @S9S_MB_2U_LIB.S9S_MB_2U(SCH_1):PAGE29
  C927    2      2 Q_CAP_DIFFBUS_C0201-DIFF BUS_0A    I27 @S9S_MB_2U_LIB.S9S_MB_2U(SCH_1):PAGE164

P5E_CPU0_PE0_TX_DP<4> @S9S_MB_2U_LIB.S9S_MB_2U(SCH_1):P5E_CPU0_PE0_TX_DP(4)
    U2  Y14 PE0_TX_DP4 SOCKET4677_AZIF0045P001C01CS-SA    I37 @S9S_MB_2U_LIB.S9S_MB_2U(SCH_1):PAGE29
  C925    2      2 Q_CAP_DIFFBUS_C0201-DIFF BUS_0A    I29 @S9S_MB_2U_LIB.S9S_MB_2U(SCH_1):PAGE164

P5E_CPU0_PE0_TX_DP<5> @S9S_MB_2U_LIB.S9S_MB_2U(SCH_1):P5E_CPU0_PE0_TX_DP(5)
    U2 AC15 PE0_TX_DP5 SOCKET4677_AZIF0045P001C01CS-SA    I37 @S9S_MB_2U_LIB.S9S_MB_2U(SCH_1):PAGE29
  C923    2      2 Q_CAP_DIFFBUS_C0201-DIFF BUS_0A    I31 @S9S_MB_2U_LIB.S9S_MB_2U(SCH_1):PAGE164

P5E_CPU0_PE0_TX_DP<6> @S9S_MB_2U_LIB.S9S_MB_2U(SCH_1):P5E_CPU0_PE0_TX_DP(6)
    U2 AD14 PE0_TX_DP6 SOCKET4677_AZIF0045P001C01CS-SA    I37 @S9S_MB_2U_LIB.S9S_MB_2U(SCH_1):PAGE29
  C921    2      2 Q_CAP_DIFFBUS_C0201-DIFF BUS_0A    I33 @S9S_MB_2U_LIB.S9S_MB_2U(SCH_1):PAGE164

P5E_CPU0_PE0_TX_DP<7> @S9S_MB_2U_LIB.S9S_MB_2U(SCH_1):P5E_CPU0_PE0_TX_DP(7)
    U2 AG15 PE0_TX_DP7 SOCKET4677_AZIF0045P001C01CS-SA    I37 @S9S_MB_2U_LIB.S9S_MB_2U(SCH_1):PAGE29
  C919    2      2 Q_CAP_DIFFBUS_C0201-DIFF BUS_0A    I36 @S9S_MB_2U_LIB.S9S_MB_2U(SCH_1):PAGE164

P5E_CPU0_PE0_TX_DP<8> @S9S_MB_2U_LIB.S9S_MB_2U(SCH_1):P5E_CPU0_PE0_TX_DP(8)
    U2 AH14 PE0_TX_DP8 SOCKET4677_AZIF0045P001C01CS-SA    I37 @S9S_MB_2U_LIB.S9S_MB_2U(SCH_1):PAGE29
  C917    2      2 Q_CAP_DIFFBUS_C0201-DIFF BUS_0A    I54 @S9S_MB_2U_LIB.S9S_MB_2U(SCH_1):PAGE164

P5E_CPU0_PE0_TX_DP<9> @S9S_MB_2U_LIB.S9S_MB_2U(SCH_1):P5E_CPU0_PE0_TX_DP(9)
    U2 AL15 PE0_TX_DP9 SOCKET4677_AZIF0045P001C01CS-SA    I37 @S9S_MB_2U_LIB.S9S_MB_2U(SCH_1):PAGE29
  C915    2      2 Q_CAP_DIFFBUS_C0201-DIFF BUS_0A    I55 @S9S_MB_2U_LIB.S9S_MB_2U(SCH_1):PAGE164

P5E_CPU0_PE1_RX_DN<0> @S9S_MB_2U_LIB.S9S_MB_2U(SCH_1):P5E_CPU0_PE1_RX_DN(0)
    U2 CP10 PE1_RX_DN0 SOCKET4677_AZIF0045P001C01CS-SA   I176 @S9S_MB_2U_LIB.S9S_MB_2U(SCH_1):PAGE29
   J37  A17  PERN0 SCONN168_ME1016810202011-SCONNA   I199 @S9S_MB_2U_LIB.S9S_MB_2U(SCH_1):PAGE150

P5E_CPU0_PE1_RX_DN<10> @S9S_MB_2U_LIB.S9S_MB_2U(SCH_1):P5E_CPU0_PE1_RX_DN(10)
    U2 BP10 PE1_RX_DN10 SOCKET4677_AZIF0045P001C01CS-SA   I176 @S9S_MB_2U_LIB.S9S_MB_2U(SCH_1):PAGE29
   J37  A51 PERP10 SCONN168_ME1016810202011-SCONNA   I199 @S9S_MB_2U_LIB.S9S_MB_2U(SCH_1):PAGE150

P5E_CPU0_PE1_RX_DN<11> @S9S_MB_2U_LIB.S9S_MB_2U(SCH_1):P5E_CPU0_PE1_RX_DN(11)
    U2 BL11 PE1_RX_DN11 SOCKET4677_AZIF0045P001C01CS-SA   I176 @S9S_MB_2U_LIB.S9S_MB_2U(SCH_1):PAGE29
   J37  A54 PERP11 SCONN168_ME1016810202011-SCONNA   I199 @S9S_MB_2U_LIB.S9S_MB_2U(SCH_1):PAGE150

P5E_CPU0_PE1_RX_DN<12> @S9S_MB_2U_LIB.S9S_MB_2U(SCH_1):P5E_CPU0_PE1_RX_DN(12)
    U2 BK10 PE1_RX_DN12 SOCKET4677_AZIF0045P001C01CS-SA   I176 @S9S_MB_2U_LIB.S9S_MB_2U(SCH_1):PAGE29
   J37  A57 PERP12 SCONN168_ME1016810202011-SCONNA   I199 @S9S_MB_2U_LIB.S9S_MB_2U(SCH_1):PAGE150

P5E_CPU0_PE1_RX_DN<13> @S9S_MB_2U_LIB.S9S_MB_2U(SCH_1):P5E_CPU0_PE1_RX_DN(13)
    U2 BG11 PE1_RX_DN13 SOCKET4677_AZIF0045P001C01CS-SA   I176 @S9S_MB_2U_LIB.S9S_MB_2U(SCH_1):PAGE29
   J37  A60 PERP13 SCONN168_ME1016810202011-SCONNA   I199 @S9S_MB_2U_LIB.S9S_MB_2U(SCH_1):PAGE150

P5E_CPU0_PE1_RX_DN<14> @S9S_MB_2U_LIB.S9S_MB_2U(SCH_1):P5E_CPU0_PE1_RX_DN(14)
    U2 BF10 PE1_RX_DN14 SOCKET4677_AZIF0045P001C01CS-SA   I176 @S9S_MB_2U_LIB.S9S_MB_2U(SCH_1):PAGE29
   J37  A63 PERP14 SCONN168_ME1016810202011-SCONNA   I199 @S9S_MB_2U_LIB.S9S_MB_2U(SCH_1):PAGE150

P5E_CPU0_PE1_RX_DN<15> @S9S_MB_2U_LIB.S9S_MB_2U(SCH_1):P5E_CPU0_PE1_RX_DN(15)
    U2 BC11 PE1_RX_DN15 SOCKET4677_AZIF0045P001C01CS-SA   I176 @S9S_MB_2U_LIB.S9S_MB_2U(SCH_1):PAGE29
   J37  A66 PERP15 SCONN168_ME1016810202011-SCONNA   I199 @S9S_MB_2U_LIB.S9S_MB_2U(SCH_1):PAGE150

P5E_CPU0_PE1_RX_DN<1> @S9S_MB_2U_LIB.S9S_MB_2U(SCH_1):P5E_CPU0_PE1_RX_DN(1)
    U2 CL11 PE1_RX_DN1 SOCKET4677_AZIF0045P001C01CS-SA   I176 @S9S_MB_2U_LIB.S9S_MB_2U(SCH_1):PAGE29
   J37  A21  PERP1 SCONN168_ME1016810202011-SCONNA   I199 @S9S_MB_2U_LIB.S9S_MB_2U(SCH_1):PAGE150

P5E_CPU0_PE1_RX_DN<2> @S9S_MB_2U_LIB.S9S_MB_2U(SCH_1):P5E_CPU0_PE1_RX_DN(2)
    U2 CK10 PE1_RX_DN2 SOCKET4677_AZIF0045P001C01CS-SA   I176 @S9S_MB_2U_LIB.S9S_MB_2U(SCH_1):PAGE29
   J37  A24  PERP2 SCONN168_ME1016810202011-SCONNA   I199 @S9S_MB_2U_LIB.S9S_MB_2U(SCH_1):PAGE150

P5E_CPU0_PE1_RX_DN<3> @S9S_MB_2U_LIB.S9S_MB_2U(SCH_1):P5E_CPU0_PE1_RX_DN(3)
    U2 CG11 PE1_RX_DN3 SOCKET4677_AZIF0045P001C01CS-SA   I176 @S9S_MB_2U_LIB.S9S_MB_2U(SCH_1):PAGE29
   J37  A27  PERP3 SCONN168_ME1016810202011-SCONNA   I199 @S9S_MB_2U_LIB.S9S_MB_2U(SCH_1):PAGE150

P5E_CPU0_PE1_RX_DN<4> @S9S_MB_2U_LIB.S9S_MB_2U(SCH_1):P5E_CPU0_PE1_RX_DN(4)
    U2 CF10 PE1_RX_DN4 SOCKET4677_AZIF0045P001C01CS-SA   I176 @S9S_MB_2U_LIB.S9S_MB_2U(SCH_1):PAGE29
   J37  A31  PERP4 SCONN168_ME1016810202011-SCONNA   I199 @S9S_MB_2U_LIB.S9S_MB_2U(SCH_1):PAGE150

P5E_CPU0_PE1_RX_DN<5> @S9S_MB_2U_LIB.S9S_MB_2U(SCH_1):P5E_CPU0_PE1_RX_DN(5)
    U2 CC11 PE1_RX_DN5 SOCKET4677_AZIF0045P001C01CS-SA   I176 @S9S_MB_2U_LIB.S9S_MB_2U(SCH_1):PAGE29
   J37  A34  PERP5 SCONN168_ME1016810202011-SCONNA   I199 @S9S_MB_2U_LIB.S9S_MB_2U(SCH_1):PAGE150

P5E_CPU0_PE1_RX_DN<6> @S9S_MB_2U_LIB.S9S_MB_2U(SCH_1):P5E_CPU0_PE1_RX_DN(6)
    U2 CB10 PE1_RX_DN6 SOCKET4677_AZIF0045P001C01CS-SA   I176 @S9S_MB_2U_LIB.S9S_MB_2U(SCH_1):PAGE29
   J37  A37  PERP6 SCONN168_ME1016810202011-SCONNA   I199 @S9S_MB_2U_LIB.S9S_MB_2U(SCH_1):PAGE150

P5E_CPU0_PE1_RX_DN<7> @S9S_MB_2U_LIB.S9S_MB_2U(SCH_1):P5E_CPU0_PE1_RX_DN(7)
    U2 BW11 PE1_RX_DN7 SOCKET4677_AZIF0045P001C01CS-SA   I176 @S9S_MB_2U_LIB.S9S_MB_2U(SCH_1):PAGE29
   J37  A40  PERP7 SCONN168_ME1016810202011-SCONNA   I199 @S9S_MB_2U_LIB.S9S_MB_2U(SCH_1):PAGE150

P5E_CPU0_PE1_RX_DN<8> @S9S_MB_2U_LIB.S9S_MB_2U(SCH_1):P5E_CPU0_PE1_RX_DN(8)
    U2 BV10 PE1_RX_DN8 SOCKET4677_AZIF0045P001C01CS-SA   I176 @S9S_MB_2U_LIB.S9S_MB_2U(SCH_1):PAGE29
   J37  A45  PERP8 SCONN168_ME1016810202011-SCONNA   I199 @S9S_MB_2U_LIB.S9S_MB_2U(SCH_1):PAGE150

P5E_CPU0_PE1_RX_DN<9> @S9S_MB_2U_LIB.S9S_MB_2U(SCH_1):P5E_CPU0_PE1_RX_DN(9)
    U2 BR11 PE1_RX_DN9 SOCKET4677_AZIF0045P001C01CS-SA   I176 @S9S_MB_2U_LIB.S9S_MB_2U(SCH_1):PAGE29
   J37  A48  PERP9 SCONN168_ME1016810202011-SCONNA   I199 @S9S_MB_2U_LIB.S9S_MB_2U(SCH_1):PAGE150

P5E_CPU0_PE1_RX_DP<0> @S9S_MB_2U_LIB.S9S_MB_2U(SCH_1):P5E_CPU0_PE1_RX_DP(0)
    U2  CN9 PE1_RX_DP0 SOCKET4677_AZIF0045P001C01CS-SA   I176 @S9S_MB_2U_LIB.S9S_MB_2U(SCH_1):PAGE29
   J37  A18  PERP0 SCONN168_ME1016810202011-SCONNA   I199 @S9S_MB_2U_LIB.S9S_MB_2U(SCH_1):PAGE150

P5E_CPU0_PE1_RX_DP<10> @S9S_MB_2U_LIB.S9S_MB_2U(SCH_1):P5E_CPU0_PE1_RX_DP(10)
    U2  BN9 PE1_RX_DP10 SOCKET4677_AZIF0045P001C01CS-SA   I176 @S9S_MB_2U_LIB.S9S_MB_2U(SCH_1):PAGE29
   J37  A50 PERN10 SCONN168_ME1016810202011-SCONNA   I199 @S9S_MB_2U_LIB.S9S_MB_2U(SCH_1):PAGE150

P5E_CPU0_PE1_RX_DP<11> @S9S_MB_2U_LIB.S9S_MB_2U(SCH_1):P5E_CPU0_PE1_RX_DP(11)
    U2 BM10 PE1_RX_DP11 SOCKET4677_AZIF0045P001C01CS-SA   I176 @S9S_MB_2U_LIB.S9S_MB_2U(SCH_1):PAGE29
   J37  A53 PERN11 SCONN168_ME1016810202011-SCONNA   I199 @S9S_MB_2U_LIB.S9S_MB_2U(SCH_1):PAGE150

P5E_CPU0_PE1_RX_DP<12> @S9S_MB_2U_LIB.S9S_MB_2U(SCH_1):P5E_CPU0_PE1_RX_DP(12)
    U2  BJ9 PE1_RX_DP12 SOCKET4677_AZIF0045P001C01CS-SA   I176 @S9S_MB_2U_LIB.S9S_MB_2U(SCH_1):PAGE29
   J37  A56 PERN12 SCONN168_ME1016810202011-SCONNA   I199 @S9S_MB_2U_LIB.S9S_MB_2U(SCH_1):PAGE150

P5E_CPU0_PE1_RX_DP<13> @S9S_MB_2U_LIB.S9S_MB_2U(SCH_1):P5E_CPU0_PE1_RX_DP(13)
    U2 BH10 PE1_RX_DP13 SOCKET4677_AZIF0045P001C01CS-SA   I176 @S9S_MB_2U_LIB.S9S_MB_2U(SCH_1):PAGE29
   J37  A59 PERN13 SCONN168_ME1016810202011-SCONNA   I199 @S9S_MB_2U_LIB.S9S_MB_2U(SCH_1):PAGE150

P5E_CPU0_PE1_RX_DP<14> @S9S_MB_2U_LIB.S9S_MB_2U(SCH_1):P5E_CPU0_PE1_RX_DP(14)
    U2  BE9 PE1_RX_DP14 SOCKET4677_AZIF0045P001C01CS-SA   I176 @S9S_MB_2U_LIB.S9S_MB_2U(SCH_1):PAGE29
   J37  A62 PERN14 SCONN168_ME1016810202011-SCONNA   I199 @S9S_MB_2U_LIB.S9S_MB_2U(SCH_1):PAGE150

P5E_CPU0_PE1_RX_DP<15> @S9S_MB_2U_LIB.S9S_MB_2U(SCH_1):P5E_CPU0_PE1_RX_DP(15)
    U2 BD10 PE1_RX_DP15 SOCKET4677_AZIF0045P001C01CS-SA   I176 @S9S_MB_2U_LIB.S9S_MB_2U(SCH_1):PAGE29
   J37  A65 PERN15 SCONN168_ME1016810202011-SCONNA   I199 @S9S_MB_2U_LIB.S9S_MB_2U(SCH_1):PAGE150

P5E_CPU0_PE1_RX_DP<1> @S9S_MB_2U_LIB.S9S_MB_2U(SCH_1):P5E_CPU0_PE1_RX_DP(1)
    U2 CM10 PE1_RX_DP1 SOCKET4677_AZIF0045P001C01CS-SA   I176 @S9S_MB_2U_LIB.S9S_MB_2U(SCH_1):PAGE29
   J37  A20  PERN1 SCONN168_ME1016810202011-SCONNA   I199 @S9S_MB_2U_LIB.S9S_MB_2U(SCH_1):PAGE150

P5E_CPU0_PE1_RX_DP<2> @S9S_MB_2U_LIB.S9S_MB_2U(SCH_1):P5E_CPU0_PE1_RX_DP(2)
    U2  CJ9 PE1_RX_DP2 SOCKET4677_AZIF0045P001C01CS-SA   I176 @S9S_MB_2U_LIB.S9S_MB_2U(SCH_1):PAGE29
   J37  A23  PERN2 SCONN168_ME1016810202011-SCONNA   I199 @S9S_MB_2U_LIB.S9S_MB_2U(SCH_1):PAGE150

P5E_CPU0_PE1_RX_DP<3> @S9S_MB_2U_LIB.S9S_MB_2U(SCH_1):P5E_CPU0_PE1_RX_DP(3)
    U2 CH10 PE1_RX_DP3 SOCKET4677_AZIF0045P001C01CS-SA   I176 @S9S_MB_2U_LIB.S9S_MB_2U(SCH_1):PAGE29
   J37  A26  PERN3 SCONN168_ME1016810202011-SCONNA   I199 @S9S_MB_2U_LIB.S9S_MB_2U(SCH_1):PAGE150

P5E_CPU0_PE1_RX_DP<4> @S9S_MB_2U_LIB.S9S_MB_2U(SCH_1):P5E_CPU0_PE1_RX_DP(4)
    U2  CE9 PE1_RX_DP4 SOCKET4677_AZIF0045P001C01CS-SA   I176 @S9S_MB_2U_LIB.S9S_MB_2U(SCH_1):PAGE29
   J37  A30  PERN4 SCONN168_ME1016810202011-SCONNA   I199 @S9S_MB_2U_LIB.S9S_MB_2U(SCH_1):PAGE150

P5E_CPU0_PE1_RX_DP<5> @S9S_MB_2U_LIB.S9S_MB_2U(SCH_1):P5E_CPU0_PE1_RX_DP(5)
    U2 CD10 PE1_RX_DP5 SOCKET4677_AZIF0045P001C01CS-SA   I176 @S9S_MB_2U_LIB.S9S_MB_2U(SCH_1):PAGE29
   J37  A33  PERN5 SCONN168_ME1016810202011-SCONNA   I199 @S9S_MB_2U_LIB.S9S_MB_2U(SCH_1):PAGE150

P5E_CPU0_PE1_RX_DP<6> @S9S_MB_2U_LIB.S9S_MB_2U(SCH_1):P5E_CPU0_PE1_RX_DP(6)
    U2  CA9 PE1_RX_DP6 SOCKET4677_AZIF0045P001C01CS-SA   I176 @S9S_MB_2U_LIB.S9S_MB_2U(SCH_1):PAGE29
   J37  A36  PERN6 SCONN168_ME1016810202011-SCONNA   I199 @S9S_MB_2U_LIB.S9S_MB_2U(SCH_1):PAGE150

P5E_CPU0_PE1_RX_DP<7> @S9S_MB_2U_LIB.S9S_MB_2U(SCH_1):P5E_CPU0_PE1_RX_DP(7)
    U2 BY10 PE1_RX_DP7 SOCKET4677_AZIF0045P001C01CS-SA   I176 @S9S_MB_2U_LIB.S9S_MB_2U(SCH_1):PAGE29
   J37  A39  PERN7 SCONN168_ME1016810202011-SCONNA   I199 @S9S_MB_2U_LIB.S9S_MB_2U(SCH_1):PAGE150

P5E_CPU0_PE1_RX_DP<8> @S9S_MB_2U_LIB.S9S_MB_2U(SCH_1):P5E_CPU0_PE1_RX_DP(8)
    U2  BU9 PE1_RX_DP8 SOCKET4677_AZIF0045P001C01CS-SA   I176 @S9S_MB_2U_LIB.S9S_MB_2U(SCH_1):PAGE29
   J37  A44  PERN8 SCONN168_ME1016810202011-SCONNA   I199 @S9S_MB_2U_LIB.S9S_MB_2U(SCH_1):PAGE150

P5E_CPU0_PE1_RX_DP<9> @S9S_MB_2U_LIB.S9S_MB_2U(SCH_1):P5E_CPU0_PE1_RX_DP(9)
    U2 BT10 PE1_RX_DP9 SOCKET4677_AZIF0045P001C01CS-SA   I176 @S9S_MB_2U_LIB.S9S_MB_2U(SCH_1):PAGE29
   J37  A47  PERN9 SCONN168_ME1016810202011-SCONNA   I199 @S9S_MB_2U_LIB.S9S_MB_2U(SCH_1):PAGE150

P5E_CPU0_PE1_TX_C_DN<0> @S9S_MB_2U_LIB.S9S_MB_2U(SCH_1):P5E_CPU0_PE1_TX_C_DN(0)
  C868    1      1 Q_CAP_DIFFBUS_C0201-DIFF BUS_0A    I22 @S9S_MB_2U_LIB.S9S_MB_2U(SCH_1):PAGE165
   J37  B17  PETN0 SCONN168_ME1016810202011-SCONNA   I199 @S9S_MB_2U_LIB.S9S_MB_2U(SCH_1):PAGE150

P5E_CPU0_PE1_TX_C_DN<10> @S9S_MB_2U_LIB.S9S_MB_2U(SCH_1):P5E_CPU0_PE1_TX_C_DN(10)
  C848    1      1 Q_CAP_DIFFBUS_C0201-DIFF BUS_0A    I66 @S9S_MB_2U_LIB.S9S_MB_2U(SCH_1):PAGE165
   J37  B51 PETP10 SCONN168_ME1016810202011-SCONNA   I199 @S9S_MB_2U_LIB.S9S_MB_2U(SCH_1):PAGE150

P5E_CPU0_PE1_TX_C_DN<11> @S9S_MB_2U_LIB.S9S_MB_2U(SCH_1):P5E_CPU0_PE1_TX_C_DN(11)
  C846    1      1 Q_CAP_DIFFBUS_C0201-DIFF BUS_0A    I68 @S9S_MB_2U_LIB.S9S_MB_2U(SCH_1):PAGE165
   J37  B53 PETN11 SCONN168_ME1016810202011-SCONNA   I199 @S9S_MB_2U_LIB.S9S_MB_2U(SCH_1):PAGE150

P5E_CPU0_PE1_TX_C_DN<12> @S9S_MB_2U_LIB.S9S_MB_2U(SCH_1):P5E_CPU0_PE1_TX_C_DN(12)
  C844    1      1 Q_CAP_DIFFBUS_C0201-DIFF BUS_0A    I70 @S9S_MB_2U_LIB.S9S_MB_2U(SCH_1):PAGE165
   J37  B57 PETP12 SCONN168_ME1016810202011-SCONNA   I199 @S9S_MB_2U_LIB.S9S_MB_2U(SCH_1):PAGE150

P5E_CPU0_PE1_TX_C_DN<13> @S9S_MB_2U_LIB.S9S_MB_2U(SCH_1):P5E_CPU0_PE1_TX_C_DN(13)
  C842    1      1 Q_CAP_DIFFBUS_C0201-DIFF BUS_0A    I76 @S9S_MB_2U_LIB.S9S_MB_2U(SCH_1):PAGE165
   J37  B59 PETN13 SCONN168_ME1016810202011-SCONNA   I199 @S9S_MB_2U_LIB.S9S_MB_2U(SCH_1):PAGE150

P5E_CPU0_PE1_TX_C_DN<14> @S9S_MB_2U_LIB.S9S_MB_2U(SCH_1):P5E_CPU0_PE1_TX_C_DN(14)
  C840    1      1 Q_CAP_DIFFBUS_C0201-DIFF BUS_0A    I79 @S9S_MB_2U_LIB.S9S_MB_2U(SCH_1):PAGE165
   J37  B63 PETP14 SCONN168_ME1016810202011-SCONNA   I199 @S9S_MB_2U_LIB.S9S_MB_2U(SCH_1):PAGE150

P5E_CPU0_PE1_TX_C_DN<15> @S9S_MB_2U_LIB.S9S_MB_2U(SCH_1):P5E_CPU0_PE1_TX_C_DN(15)
  C838    1      1 Q_CAP_DIFFBUS_C0201-DIFF BUS_0A    I80 @S9S_MB_2U_LIB.S9S_MB_2U(SCH_1):PAGE165
   J37  B65 PETN15 SCONN168_ME1016810202011-SCONNA   I199 @S9S_MB_2U_LIB.S9S_MB_2U(SCH_1):PAGE150

P5E_CPU0_PE1_TX_C_DN<1> @S9S_MB_2U_LIB.S9S_MB_2U(SCH_1):P5E_CPU0_PE1_TX_C_DN(1)
  C866    1      1 Q_CAP_DIFFBUS_C0201-DIFF BUS_0A    I24 @S9S_MB_2U_LIB.S9S_MB_2U(SCH_1):PAGE165
   J37  B20  PETN1 SCONN168_ME1016810202011-SCONNA   I199 @S9S_MB_2U_LIB.S9S_MB_2U(SCH_1):PAGE150

P5E_CPU0_PE1_TX_C_DN<2> @S9S_MB_2U_LIB.S9S_MB_2U(SCH_1):P5E_CPU0_PE1_TX_C_DN(2)
  C864    1      1 Q_CAP_DIFFBUS_C0201-DIFF BUS_0A    I25 @S9S_MB_2U_LIB.S9S_MB_2U(SCH_1):PAGE165
   J37  B24  PETP2 SCONN168_ME1016810202011-SCONNA   I199 @S9S_MB_2U_LIB.S9S_MB_2U(SCH_1):PAGE150

P5E_CPU0_PE1_TX_C_DN<3> @S9S_MB_2U_LIB.S9S_MB_2U(SCH_1):P5E_CPU0_PE1_TX_C_DN(3)
  C862    1      1 Q_CAP_DIFFBUS_C0201-DIFF BUS_0A    I28 @S9S_MB_2U_LIB.S9S_MB_2U(SCH_1):PAGE165
   J37  B26  PETN3 SCONN168_ME1016810202011-SCONNA   I199 @S9S_MB_2U_LIB.S9S_MB_2U(SCH_1):PAGE150

P5E_CPU0_PE1_TX_C_DN<4> @S9S_MB_2U_LIB.S9S_MB_2U(SCH_1):P5E_CPU0_PE1_TX_C_DN(4)
  C860    1      1 Q_CAP_DIFFBUS_C0201-DIFF BUS_0A    I30 @S9S_MB_2U_LIB.S9S_MB_2U(SCH_1):PAGE165
   J37  B31  PETP4 SCONN168_ME1016810202011-SCONNA   I199 @S9S_MB_2U_LIB.S9S_MB_2U(SCH_1):PAGE150

P5E_CPU0_PE1_TX_C_DN<5> @S9S_MB_2U_LIB.S9S_MB_2U(SCH_1):P5E_CPU0_PE1_TX_C_DN(5)
  C858    1      1 Q_CAP_DIFFBUS_C0201-DIFF BUS_0A    I37 @S9S_MB_2U_LIB.S9S_MB_2U(SCH_1):PAGE165
   J37  B33  PETN5 SCONN168_ME1016810202011-SCONNA   I199 @S9S_MB_2U_LIB.S9S_MB_2U(SCH_1):PAGE150

P5E_CPU0_PE1_TX_C_DN<6> @S9S_MB_2U_LIB.S9S_MB_2U(SCH_1):P5E_CPU0_PE1_TX_C_DN(6)
  C856    1      1 Q_CAP_DIFFBUS_C0201-DIFF BUS_0A    I39 @S9S_MB_2U_LIB.S9S_MB_2U(SCH_1):PAGE165
   J37  B37  PETP6 SCONN168_ME1016810202011-SCONNA   I199 @S9S_MB_2U_LIB.S9S_MB_2U(SCH_1):PAGE150

P5E_CPU0_PE1_TX_C_DN<7> @S9S_MB_2U_LIB.S9S_MB_2U(SCH_1):P5E_CPU0_PE1_TX_C_DN(7)
  C854    1      1 Q_CAP_DIFFBUS_C0201-DIFF BUS_0A    I41 @S9S_MB_2U_LIB.S9S_MB_2U(SCH_1):PAGE165
   J37  B39  PETN7 SCONN168_ME1016810202011-SCONNA   I199 @S9S_MB_2U_LIB.S9S_MB_2U(SCH_1):PAGE150

P5E_CPU0_PE1_TX_C_DN<8> @S9S_MB_2U_LIB.S9S_MB_2U(SCH_1):P5E_CPU0_PE1_TX_C_DN(8)
  C852    1      1 Q_CAP_DIFFBUS_C0201-DIFF BUS_0A    I61 @S9S_MB_2U_LIB.S9S_MB_2U(SCH_1):PAGE165
   J37  B45  PETP8 SCONN168_ME1016810202011-SCONNA   I199 @S9S_MB_2U_LIB.S9S_MB_2U(SCH_1):PAGE150

P5E_CPU0_PE1_TX_C_DN<9> @S9S_MB_2U_LIB.S9S_MB_2U(SCH_1):P5E_CPU0_PE1_TX_C_DN(9)
  C850    1      1 Q_CAP_DIFFBUS_C0201-DIFF BUS_0A    I64 @S9S_MB_2U_LIB.S9S_MB_2U(SCH_1):PAGE165
   J37  B47  PETN9 SCONN168_ME1016810202011-SCONNA   I199 @S9S_MB_2U_LIB.S9S_MB_2U(SCH_1):PAGE150

P5E_CPU0_PE1_TX_C_DP<0> @S9S_MB_2U_LIB.S9S_MB_2U(SCH_1):P5E_CPU0_PE1_TX_C_DP(0)
  C869    1      1 Q_CAP_DIFFBUS_C0201-DIFF BUS_0A    I21 @S9S_MB_2U_LIB.S9S_MB_2U(SCH_1):PAGE165
   J37  B18  PETP0 SCONN168_ME1016810202011-SCONNA   I199 @S9S_MB_2U_LIB.S9S_MB_2U(SCH_1):PAGE150

P5E_CPU0_PE1_TX_C_DP<10> @S9S_MB_2U_LIB.S9S_MB_2U(SCH_1):P5E_CPU0_PE1_TX_C_DP(10)
  C849    1      1 Q_CAP_DIFFBUS_C0201-DIFF BUS_0A    I65 @S9S_MB_2U_LIB.S9S_MB_2U(SCH_1):PAGE165
   J37  B50 PETN10 SCONN168_ME1016810202011-SCONNA   I199 @S9S_MB_2U_LIB.S9S_MB_2U(SCH_1):PAGE150

P5E_CPU0_PE1_TX_C_DP<11> @S9S_MB_2U_LIB.S9S_MB_2U(SCH_1):P5E_CPU0_PE1_TX_C_DP(11)
  C847    1      1 Q_CAP_DIFFBUS_C0201-DIFF BUS_0A    I67 @S9S_MB_2U_LIB.S9S_MB_2U(SCH_1):PAGE165
   J37  B54 PETP11 SCONN168_ME1016810202011-SCONNA   I199 @S9S_MB_2U_LIB.S9S_MB_2U(SCH_1):PAGE150

P5E_CPU0_PE1_TX_C_DP<12> @S9S_MB_2U_LIB.S9S_MB_2U(SCH_1):P5E_CPU0_PE1_TX_C_DP(12)
  C845    1      1 Q_CAP_DIFFBUS_C0201-DIFF BUS_0A    I69 @S9S_MB_2U_LIB.S9S_MB_2U(SCH_1):PAGE165
   J37  B56 PETN12 SCONN168_ME1016810202011-SCONNA   I199 @S9S_MB_2U_LIB.S9S_MB_2U(SCH_1):PAGE150

P5E_CPU0_PE1_TX_C_DP<13> @S9S_MB_2U_LIB.S9S_MB_2U(SCH_1):P5E_CPU0_PE1_TX_C_DP(13)
  C843    1      1 Q_CAP_DIFFBUS_C0201-DIFF BUS_0A    I77 @S9S_MB_2U_LIB.S9S_MB_2U(SCH_1):PAGE165
   J37  B60 PETP13 SCONN168_ME1016810202011-SCONNA   I199 @S9S_MB_2U_LIB.S9S_MB_2U(SCH_1):PAGE150

P5E_CPU0_PE1_TX_C_DP<14> @S9S_MB_2U_LIB.S9S_MB_2U(SCH_1):P5E_CPU0_PE1_TX_C_DP(14)
  C841    1      1 Q_CAP_DIFFBUS_C0201-DIFF BUS_0A    I78 @S9S_MB_2U_LIB.S9S_MB_2U(SCH_1):PAGE165
   J37  B62 PETN14 SCONN168_ME1016810202011-SCONNA   I199 @S9S_MB_2U_LIB.S9S_MB_2U(SCH_1):PAGE150

P5E_CPU0_PE1_TX_C_DP<15> @S9S_MB_2U_LIB.S9S_MB_2U(SCH_1):P5E_CPU0_PE1_TX_C_DP(15)
  C839    1      1 Q_CAP_DIFFBUS_C0201-DIFF BUS_0A    I81 @S9S_MB_2U_LIB.S9S_MB_2U(SCH_1):PAGE165
   J37  B66 PETP15 SCONN168_ME1016810202011-SCONNA   I199 @S9S_MB_2U_LIB.S9S_MB_2U(SCH_1):PAGE150

P5E_CPU0_PE1_TX_C_DP<1> @S9S_MB_2U_LIB.S9S_MB_2U(SCH_1):P5E_CPU0_PE1_TX_C_DP(1)
  C867    1      1 Q_CAP_DIFFBUS_C0201-DIFF BUS_0A    I23 @S9S_MB_2U_LIB.S9S_MB_2U(SCH_1):PAGE165
   J37  B21  PETP1 SCONN168_ME1016810202011-SCONNA   I199 @S9S_MB_2U_LIB.S9S_MB_2U(SCH_1):PAGE150

P5E_CPU0_PE1_TX_C_DP<2> @S9S_MB_2U_LIB.S9S_MB_2U(SCH_1):P5E_CPU0_PE1_TX_C_DP(2)
  C865    1      1 Q_CAP_DIFFBUS_C0201-DIFF BUS_0A    I26 @S9S_MB_2U_LIB.S9S_MB_2U(SCH_1):PAGE165
   J37  B23  PETN2 SCONN168_ME1016810202011-SCONNA   I199 @S9S_MB_2U_LIB.S9S_MB_2U(SCH_1):PAGE150

P5E_CPU0_PE1_TX_C_DP<3> @S9S_MB_2U_LIB.S9S_MB_2U(SCH_1):P5E_CPU0_PE1_TX_C_DP(3)
  C863    1      1 Q_CAP_DIFFBUS_C0201-DIFF BUS_0A    I27 @S9S_MB_2U_LIB.S9S_MB_2U(SCH_1):PAGE165
   J37  B27  PETP3 SCONN168_ME1016810202011-SCONNA   I199 @S9S_MB_2U_LIB.S9S_MB_2U(SCH_1):PAGE150

P5E_CPU0_PE1_TX_C_DP<4> @S9S_MB_2U_LIB.S9S_MB_2U(SCH_1):P5E_CPU0_PE1_TX_C_DP(4)
  C861    1      1 Q_CAP_DIFFBUS_C0201-DIFF BUS_0A    I29 @S9S_MB_2U_LIB.S9S_MB_2U(SCH_1):PAGE165
   J37  B30  PETN4 SCONN168_ME1016810202011-SCONNA   I199 @S9S_MB_2U_LIB.S9S_MB_2U(SCH_1):PAGE150

P5E_CPU0_PE1_TX_C_DP<5> @S9S_MB_2U_LIB.S9S_MB_2U(SCH_1):P5E_CPU0_PE1_TX_C_DP(5)
  C859    1      1 Q_CAP_DIFFBUS_C0201-DIFF BUS_0A    I36 @S9S_MB_2U_LIB.S9S_MB_2U(SCH_1):PAGE165
   J37  B34  PETP5 SCONN168_ME1016810202011-SCONNA   I199 @S9S_MB_2U_LIB.S9S_MB_2U(SCH_1):PAGE150

P5E_CPU0_PE1_TX_C_DP<6> @S9S_MB_2U_LIB.S9S_MB_2U(SCH_1):P5E_CPU0_PE1_TX_C_DP(6)
  C857    1      1 Q_CAP_DIFFBUS_C0201-DIFF BUS_0A    I38 @S9S_MB_2U_LIB.S9S_MB_2U(SCH_1):PAGE165
   J37  B36  PETN6 SCONN168_ME1016810202011-SCONNA   I199 @S9S_MB_2U_LIB.S9S_MB_2U(SCH_1):PAGE150

P5E_CPU0_PE1_TX_C_DP<7> @S9S_MB_2U_LIB.S9S_MB_2U(SCH_1):P5E_CPU0_PE1_TX_C_DP(7)
  C855    1      1 Q_CAP_DIFFBUS_C0201-DIFF BUS_0A    I40 @S9S_MB_2U_LIB.S9S_MB_2U(SCH_1):PAGE165
   J37  B40  PETP7 SCONN168_ME1016810202011-SCONNA   I199 @S9S_MB_2U_LIB.S9S_MB_2U(SCH_1):PAGE150

P5E_CPU0_PE1_TX_C_DP<8> @S9S_MB_2U_LIB.S9S_MB_2U(SCH_1):P5E_CPU0_PE1_TX_C_DP(8)
  C853    1      1 Q_CAP_DIFFBUS_C0201-DIFF BUS_0A    I62 @S9S_MB_2U_LIB.S9S_MB_2U(SCH_1):PAGE165
   J37  B44  PETN8 SCONN168_ME1016810202011-SCONNA   I199 @S9S_MB_2U_LIB.S9S_MB_2U(SCH_1):PAGE150

P5E_CPU0_PE1_TX_C_DP<9> @S9S_MB_2U_LIB.S9S_MB_2U(SCH_1):P5E_CPU0_PE1_TX_C_DP(9)
  C851    1      1 Q_CAP_DIFFBUS_C0201-DIFF BUS_0A    I63 @S9S_MB_2U_LIB.S9S_MB_2U(SCH_1):PAGE165
   J37  B48  PETP9 SCONN168_ME1016810202011-SCONNA   I199 @S9S_MB_2U_LIB.S9S_MB_2U(SCH_1):PAGE150

P5E_CPU0_PE1_TX_DN<0> @S9S_MB_2U_LIB.S9S_MB_2U(SCH_1):P5E_CPU0_PE1_TX_DN(0)
    U2 CP14 PE1_TX_DN0 SOCKET4677_AZIF0045P001C01CS-SA   I176 @S9S_MB_2U_LIB.S9S_MB_2U(SCH_1):PAGE29
  C868    2      2 Q_CAP_DIFFBUS_C0201-DIFF BUS_0A    I22 @S9S_MB_2U_LIB.S9S_MB_2U(SCH_1):PAGE165

P5E_CPU0_PE1_TX_DN<10> @S9S_MB_2U_LIB.S9S_MB_2U(SCH_1):P5E_CPU0_PE1_TX_DN(10)
    U2 BP14 PE1_TX_DN10 SOCKET4677_AZIF0045P001C01CS-SA   I176 @S9S_MB_2U_LIB.S9S_MB_2U(SCH_1):PAGE29
  C848    2      2 Q_CAP_DIFFBUS_C0201-DIFF BUS_0A    I66 @S9S_MB_2U_LIB.S9S_MB_2U(SCH_1):PAGE165

P5E_CPU0_PE1_TX_DN<11> @S9S_MB_2U_LIB.S9S_MB_2U(SCH_1):P5E_CPU0_PE1_TX_DN(11)
    U2 BN13 PE1_TX_DN11 SOCKET4677_AZIF0045P001C01CS-SA   I176 @S9S_MB_2U_LIB.S9S_MB_2U(SCH_1):PAGE29
  C846    2      2 Q_CAP_DIFFBUS_C0201-DIFF BUS_0A    I68 @S9S_MB_2U_LIB.S9S_MB_2U(SCH_1):PAGE165

P5E_CPU0_PE1_TX_DN<12> @S9S_MB_2U_LIB.S9S_MB_2U(SCH_1):P5E_CPU0_PE1_TX_DN(12)
    U2 BK14 PE1_TX_DN12 SOCKET4677_AZIF0045P001C01CS-SA   I176 @S9S_MB_2U_LIB.S9S_MB_2U(SCH_1):PAGE29
  C844    2      2 Q_CAP_DIFFBUS_C0201-DIFF BUS_0A    I70 @S9S_MB_2U_LIB.S9S_MB_2U(SCH_1):PAGE165

P5E_CPU0_PE1_TX_DN<13> @S9S_MB_2U_LIB.S9S_MB_2U(SCH_1):P5E_CPU0_PE1_TX_DN(13)
    U2 BJ13 PE1_TX_DN13 SOCKET4677_AZIF0045P001C01CS-SA   I176 @S9S_MB_2U_LIB.S9S_MB_2U(SCH_1):PAGE29
  C842    2      2 Q_CAP_DIFFBUS_C0201-DIFF BUS_0A    I76 @S9S_MB_2U_LIB.S9S_MB_2U(SCH_1):PAGE165

P5E_CPU0_PE1_TX_DN<14> @S9S_MB_2U_LIB.S9S_MB_2U(SCH_1):P5E_CPU0_PE1_TX_DN(14)
    U2 BF14 PE1_TX_DN14 SOCKET4677_AZIF0045P001C01CS-SA   I176 @S9S_MB_2U_LIB.S9S_MB_2U(SCH_1):PAGE29
  C840    2      2 Q_CAP_DIFFBUS_C0201-DIFF BUS_0A    I79 @S9S_MB_2U_LIB.S9S_MB_2U(SCH_1):PAGE165

P5E_CPU0_PE1_TX_DN<15> @S9S_MB_2U_LIB.S9S_MB_2U(SCH_1):P5E_CPU0_PE1_TX_DN(15)
    U2 BE13 PE1_TX_DN15 SOCKET4677_AZIF0045P001C01CS-SA   I176 @S9S_MB_2U_LIB.S9S_MB_2U(SCH_1):PAGE29
  C838    2      2 Q_CAP_DIFFBUS_C0201-DIFF BUS_0A    I80 @S9S_MB_2U_LIB.S9S_MB_2U(SCH_1):PAGE165

P5E_CPU0_PE1_TX_DN<1> @S9S_MB_2U_LIB.S9S_MB_2U(SCH_1):P5E_CPU0_PE1_TX_DN(1)
    U2 CN13 PE1_TX_DN1 SOCKET4677_AZIF0045P001C01CS-SA   I176 @S9S_MB_2U_LIB.S9S_MB_2U(SCH_1):PAGE29
  C866    2      2 Q_CAP_DIFFBUS_C0201-DIFF BUS_0A    I24 @S9S_MB_2U_LIB.S9S_MB_2U(SCH_1):PAGE165

P5E_CPU0_PE1_TX_DN<2> @S9S_MB_2U_LIB.S9S_MB_2U(SCH_1):P5E_CPU0_PE1_TX_DN(2)
    U2 CK14 PE1_TX_DN2 SOCKET4677_AZIF0045P001C01CS-SA   I176 @S9S_MB_2U_LIB.S9S_MB_2U(SCH_1):PAGE29
  C864    2      2 Q_CAP_DIFFBUS_C0201-DIFF BUS_0A    I25 @S9S_MB_2U_LIB.S9S_MB_2U(SCH_1):PAGE165

P5E_CPU0_PE1_TX_DN<3> @S9S_MB_2U_LIB.S9S_MB_2U(SCH_1):P5E_CPU0_PE1_TX_DN(3)
    U2 CJ13 PE1_TX_DN3 SOCKET4677_AZIF0045P001C01CS-SA   I176 @S9S_MB_2U_LIB.S9S_MB_2U(SCH_1):PAGE29
  C862    2      2 Q_CAP_DIFFBUS_C0201-DIFF BUS_0A    I28 @S9S_MB_2U_LIB.S9S_MB_2U(SCH_1):PAGE165

P5E_CPU0_PE1_TX_DN<4> @S9S_MB_2U_LIB.S9S_MB_2U(SCH_1):P5E_CPU0_PE1_TX_DN(4)
    U2 CF14 PE1_TX_DN4 SOCKET4677_AZIF0045P001C01CS-SA   I176 @S9S_MB_2U_LIB.S9S_MB_2U(SCH_1):PAGE29
  C860    2      2 Q_CAP_DIFFBUS_C0201-DIFF BUS_0A    I30 @S9S_MB_2U_LIB.S9S_MB_2U(SCH_1):PAGE165

P5E_CPU0_PE1_TX_DN<5> @S9S_MB_2U_LIB.S9S_MB_2U(SCH_1):P5E_CPU0_PE1_TX_DN(5)
    U2 CE13 PE1_TX_DN5 SOCKET4677_AZIF0045P001C01CS-SA   I176 @S9S_MB_2U_LIB.S9S_MB_2U(SCH_1):PAGE29
  C858    2      2 Q_CAP_DIFFBUS_C0201-DIFF BUS_0A    I37 @S9S_MB_2U_LIB.S9S_MB_2U(SCH_1):PAGE165

P5E_CPU0_PE1_TX_DN<6> @S9S_MB_2U_LIB.S9S_MB_2U(SCH_1):P5E_CPU0_PE1_TX_DN(6)
    U2 CB14 PE1_TX_DN6 SOCKET4677_AZIF0045P001C01CS-SA   I176 @S9S_MB_2U_LIB.S9S_MB_2U(SCH_1):PAGE29
  C856    2      2 Q_CAP_DIFFBUS_C0201-DIFF BUS_0A    I39 @S9S_MB_2U_LIB.S9S_MB_2U(SCH_1):PAGE165

P5E_CPU0_PE1_TX_DN<7> @S9S_MB_2U_LIB.S9S_MB_2U(SCH_1):P5E_CPU0_PE1_TX_DN(7)
    U2 CA13 PE1_TX_DN7 SOCKET4677_AZIF0045P001C01CS-SA   I176 @S9S_MB_2U_LIB.S9S_MB_2U(SCH_1):PAGE29
  C854    2      2 Q_CAP_DIFFBUS_C0201-DIFF BUS_0A    I41 @S9S_MB_2U_LIB.S9S_MB_2U(SCH_1):PAGE165

P5E_CPU0_PE1_TX_DN<8> @S9S_MB_2U_LIB.S9S_MB_2U(SCH_1):P5E_CPU0_PE1_TX_DN(8)
    U2 BV14 PE1_TX_DN8 SOCKET4677_AZIF0045P001C01CS-SA   I176 @S9S_MB_2U_LIB.S9S_MB_2U(SCH_1):PAGE29
  C852    2      2 Q_CAP_DIFFBUS_C0201-DIFF BUS_0A    I61 @S9S_MB_2U_LIB.S9S_MB_2U(SCH_1):PAGE165

P5E_CPU0_PE1_TX_DN<9> @S9S_MB_2U_LIB.S9S_MB_2U(SCH_1):P5E_CPU0_PE1_TX_DN(9)
    U2 BU13 PE1_TX_DN9 SOCKET4677_AZIF0045P001C01CS-SA   I176 @S9S_MB_2U_LIB.S9S_MB_2U(SCH_1):PAGE29
  C850    2      2 Q_CAP_DIFFBUS_C0201-DIFF BUS_0A    I64 @S9S_MB_2U_LIB.S9S_MB_2U(SCH_1):PAGE165

P5E_CPU0_PE1_TX_DP<0> @S9S_MB_2U_LIB.S9S_MB_2U(SCH_1):P5E_CPU0_PE1_TX_DP(0)
    U2 CR15 PE1_TX_DP0 SOCKET4677_AZIF0045P001C01CS-SA   I176 @S9S_MB_2U_LIB.S9S_MB_2U(SCH_1):PAGE29
  C869    2      2 Q_CAP_DIFFBUS_C0201-DIFF BUS_0A    I21 @S9S_MB_2U_LIB.S9S_MB_2U(SCH_1):PAGE165

P5E_CPU0_PE1_TX_DP<10> @S9S_MB_2U_LIB.S9S_MB_2U(SCH_1):P5E_CPU0_PE1_TX_DP(10)
    U2 BR15 PE1_TX_DP10 SOCKET4677_AZIF0045P001C01CS-SA   I176 @S9S_MB_2U_LIB.S9S_MB_2U(SCH_1):PAGE29
  C849    2      2 Q_CAP_DIFFBUS_C0201-DIFF BUS_0A    I65 @S9S_MB_2U_LIB.S9S_MB_2U(SCH_1):PAGE165

P5E_CPU0_PE1_TX_DP<11> @S9S_MB_2U_LIB.S9S_MB_2U(SCH_1):P5E_CPU0_PE1_TX_DP(11)
    U2 BM14 PE1_TX_DP11 SOCKET4677_AZIF0045P001C01CS-SA   I176 @S9S_MB_2U_LIB.S9S_MB_2U(SCH_1):PAGE29
  C847    2      2 Q_CAP_DIFFBUS_C0201-DIFF BUS_0A    I67 @S9S_MB_2U_LIB.S9S_MB_2U(SCH_1):PAGE165

P5E_CPU0_PE1_TX_DP<12> @S9S_MB_2U_LIB.S9S_MB_2U(SCH_1):P5E_CPU0_PE1_TX_DP(12)
    U2 BL15 PE1_TX_DP12 SOCKET4677_AZIF0045P001C01CS-SA   I176 @S9S_MB_2U_LIB.S9S_MB_2U(SCH_1):PAGE29
  C845    2      2 Q_CAP_DIFFBUS_C0201-DIFF BUS_0A    I69 @S9S_MB_2U_LIB.S9S_MB_2U(SCH_1):PAGE165

P5E_CPU0_PE1_TX_DP<13> @S9S_MB_2U_LIB.S9S_MB_2U(SCH_1):P5E_CPU0_PE1_TX_DP(13)
    U2 BH14 PE1_TX_DP13 SOCKET4677_AZIF0045P001C01CS-SA   I176 @S9S_MB_2U_LIB.S9S_MB_2U(SCH_1):PAGE29
  C843    2      2 Q_CAP_DIFFBUS_C0201-DIFF BUS_0A    I77 @S9S_MB_2U_LIB.S9S_MB_2U(SCH_1):PAGE165

P5E_CPU0_PE1_TX_DP<14> @S9S_MB_2U_LIB.S9S_MB_2U(SCH_1):P5E_CPU0_PE1_TX_DP(14)
    U2 BG15 PE1_TX_DP14 SOCKET4677_AZIF0045P001C01CS-SA   I176 @S9S_MB_2U_LIB.S9S_MB_2U(SCH_1):PAGE29
  C841    2      2 Q_CAP_DIFFBUS_C0201-DIFF BUS_0A    I78 @S9S_MB_2U_LIB.S9S_MB_2U(SCH_1):PAGE165

P5E_CPU0_PE1_TX_DP<15> @S9S_MB_2U_LIB.S9S_MB_2U(SCH_1):P5E_CPU0_PE1_TX_DP(15)
    U2 BD14 PE1_TX_DP15 SOCKET4677_AZIF0045P001C01CS-SA   I176 @S9S_MB_2U_LIB.S9S_MB_2U(SCH_1):PAGE29
  C839    2      2 Q_CAP_DIFFBUS_C0201-DIFF BUS_0A    I81 @S9S_MB_2U_LIB.S9S_MB_2U(SCH_1):PAGE165

P5E_CPU0_PE1_TX_DP<1> @S9S_MB_2U_LIB.S9S_MB_2U(SCH_1):P5E_CPU0_PE1_TX_DP(1)
    U2 CM14 PE1_TX_DP1 SOCKET4677_AZIF0045P001C01CS-SA   I176 @S9S_MB_2U_LIB.S9S_MB_2U(SCH_1):PAGE29
  C867    2      2 Q_CAP_DIFFBUS_C0201-DIFF BUS_0A    I23 @S9S_MB_2U_LIB.S9S_MB_2U(SCH_1):PAGE165

P5E_CPU0_PE1_TX_DP<2> @S9S_MB_2U_LIB.S9S_MB_2U(SCH_1):P5E_CPU0_PE1_TX_DP(2)
    U2 CL15 PE1_TX_DP2 SOCKET4677_AZIF0045P001C01CS-SA   I176 @S9S_MB_2U_LIB.S9S_MB_2U(SCH_1):PAGE29
  C865    2      2 Q_CAP_DIFFBUS_C0201-DIFF BUS_0A    I26 @S9S_MB_2U_LIB.S9S_MB_2U(SCH_1):PAGE165

P5E_CPU0_PE1_TX_DP<3> @S9S_MB_2U_LIB.S9S_MB_2U(SCH_1):P5E_CPU0_PE1_TX_DP(3)
    U2 CH14 PE1_TX_DP3 SOCKET4677_AZIF0045P001C01CS-SA   I176 @S9S_MB_2U_LIB.S9S_MB_2U(SCH_1):PAGE29
  C863    2      2 Q_CAP_DIFFBUS_C0201-DIFF BUS_0A    I27 @S9S_MB_2U_LIB.S9S_MB_2U(SCH_1):PAGE165

P5E_CPU0_PE1_TX_DP<4> @S9S_MB_2U_LIB.S9S_MB_2U(SCH_1):P5E_CPU0_PE1_TX_DP(4)
    U2 CG15 PE1_TX_DP4 SOCKET4677_AZIF0045P001C01CS-SA   I176 @S9S_MB_2U_LIB.S9S_MB_2U(SCH_1):PAGE29
  C861    2      2 Q_CAP_DIFFBUS_C0201-DIFF BUS_0A    I29 @S9S_MB_2U_LIB.S9S_MB_2U(SCH_1):PAGE165

P5E_CPU0_PE1_TX_DP<5> @S9S_MB_2U_LIB.S9S_MB_2U(SCH_1):P5E_CPU0_PE1_TX_DP(5)
    U2 CD14 PE1_TX_DP5 SOCKET4677_AZIF0045P001C01CS-SA   I176 @S9S_MB_2U_LIB.S9S_MB_2U(SCH_1):PAGE29
  C859    2      2 Q_CAP_DIFFBUS_C0201-DIFF BUS_0A    I36 @S9S_MB_2U_LIB.S9S_MB_2U(SCH_1):PAGE165

P5E_CPU0_PE1_TX_DP<6> @S9S_MB_2U_LIB.S9S_MB_2U(SCH_1):P5E_CPU0_PE1_TX_DP(6)
    U2 CC15 PE1_TX_DP6 SOCKET4677_AZIF0045P001C01CS-SA   I176 @S9S_MB_2U_LIB.S9S_MB_2U(SCH_1):PAGE29
  C857    2      2 Q_CAP_DIFFBUS_C0201-DIFF BUS_0A    I38 @S9S_MB_2U_LIB.S9S_MB_2U(SCH_1):PAGE165

P5E_CPU0_PE1_TX_DP<7> @S9S_MB_2U_LIB.S9S_MB_2U(SCH_1):P5E_CPU0_PE1_TX_DP(7)
    U2 BY14 PE1_TX_DP7 SOCKET4677_AZIF0045P001C01CS-SA   I176 @S9S_MB_2U_LIB.S9S_MB_2U(SCH_1):PAGE29
  C855    2      2 Q_CAP_DIFFBUS_C0201-DIFF BUS_0A    I40 @S9S_MB_2U_LIB.S9S_MB_2U(SCH_1):PAGE165

P5E_CPU0_PE1_TX_DP<8> @S9S_MB_2U_LIB.S9S_MB_2U(SCH_1):P5E_CPU0_PE1_TX_DP(8)
    U2 BW15 PE1_TX_DP8 SOCKET4677_AZIF0045P001C01CS-SA   I176 @S9S_MB_2U_LIB.S9S_MB_2U(SCH_1):PAGE29
  C853    2      2 Q_CAP_DIFFBUS_C0201-DIFF BUS_0A    I62 @S9S_MB_2U_LIB.S9S_MB_2U(SCH_1):PAGE165

P5E_CPU0_PE1_TX_DP<9> @S9S_MB_2U_LIB.S9S_MB_2U(SCH_1):P5E_CPU0_PE1_TX_DP(9)
    U2 BT14 PE1_TX_DP9 SOCKET4677_AZIF0045P001C01CS-SA   I176 @S9S_MB_2U_LIB.S9S_MB_2U(SCH_1):PAGE29
  C851    2      2 Q_CAP_DIFFBUS_C0201-DIFF BUS_0A    I63 @S9S_MB_2U_LIB.S9S_MB_2U(SCH_1):PAGE165

P5E_CPU0_PE2_RX_DN<0> @S9S_MB_2U_LIB.S9S_MB_2U(SCH_1):P5E_CPU0_PE2_RX_DN(0)
    U2  CU9 PE2_RX_DN0 SOCKET4677_AZIF0045P001C01CS-SA   I139 @S9S_MB_2U_LIB.S9S_MB_2U(SCH_1):PAGE30
  J105   F8     F8 CONN112_10137002101LF-CONN112_A    I68 @S9S_MB_2U_LIB.S9S_MB_2U(SCH_1):PAGE142

P5E_CPU0_PE2_RX_DN<10> @S9S_MB_2U_LIB.S9S_MB_2U(SCH_1):P5E_CPU0_PE2_RX_DN(10)
    U2  DU9 PE2_RX_DN10 SOCKET4677_AZIF0045P001C01CS-SA   I139 @S9S_MB_2U_LIB.S9S_MB_2U(SCH_1):PAGE30
  J106   F6     F6 CONN112_10137002101LF-CONN112_A    I68 @S9S_MB_2U_LIB.S9S_MB_2U(SCH_1):PAGE144

P5E_CPU0_PE2_RX_DN<11> @S9S_MB_2U_LIB.S9S_MB_2U(SCH_1):P5E_CPU0_PE2_RX_DN(11)
    U2 DY10 PE2_RX_DN11 SOCKET4677_AZIF0045P001C01CS-SA   I139 @S9S_MB_2U_LIB.S9S_MB_2U(SCH_1):PAGE30
  J106   G5     G5 CONN112_10137002101LF-CONN112_A    I68 @S9S_MB_2U_LIB.S9S_MB_2U(SCH_1):PAGE144

P5E_CPU0_PE2_RX_DN<12> @S9S_MB_2U_LIB.S9S_MB_2U(SCH_1):P5E_CPU0_PE2_RX_DN(12)
    U2  EA9 PE2_RX_DN12 SOCKET4677_AZIF0045P001C01CS-SA   I139 @S9S_MB_2U_LIB.S9S_MB_2U(SCH_1):PAGE30
  J106   F4     F4 CONN112_10137002101LF-CONN112_A    I65 @S9S_MB_2U_LIB.S9S_MB_2U(SCH_1):PAGE144

P5E_CPU0_PE2_RX_DN<13> @S9S_MB_2U_LIB.S9S_MB_2U(SCH_1):P5E_CPU0_PE2_RX_DN(13)
    U2 ED10 PE2_RX_DN13 SOCKET4677_AZIF0045P001C01CS-SA   I139 @S9S_MB_2U_LIB.S9S_MB_2U(SCH_1):PAGE30
  J106   G3     G3 CONN112_10137002101LF-CONN112_A    I65 @S9S_MB_2U_LIB.S9S_MB_2U(SCH_1):PAGE144

P5E_CPU0_PE2_RX_DN<14> @S9S_MB_2U_LIB.S9S_MB_2U(SCH_1):P5E_CPU0_PE2_RX_DN(14)
    U2  EE9 PE2_RX_DN14 SOCKET4677_AZIF0045P001C01CS-SA   I139 @S9S_MB_2U_LIB.S9S_MB_2U(SCH_1):PAGE30
  J106   F2     F2 CONN112_10137002101LF-CONN112_A    I65 @S9S_MB_2U_LIB.S9S_MB_2U(SCH_1):PAGE144

P5E_CPU0_PE2_RX_DN<15> @S9S_MB_2U_LIB.S9S_MB_2U(SCH_1):P5E_CPU0_PE2_RX_DN(15)
    U2 EH10 PE2_RX_DN15 SOCKET4677_AZIF0045P001C01CS-SA   I139 @S9S_MB_2U_LIB.S9S_MB_2U(SCH_1):PAGE30
  J106   G1     G1 CONN112_10137002101LF-CONN112_A    I65 @S9S_MB_2U_LIB.S9S_MB_2U(SCH_1):PAGE144

P5E_CPU0_PE2_RX_DN<1> @S9S_MB_2U_LIB.S9S_MB_2U(SCH_1):P5E_CPU0_PE2_RX_DN(1)
    U2 CY10 PE2_RX_DN1 SOCKET4677_AZIF0045P001C01CS-SA   I139 @S9S_MB_2U_LIB.S9S_MB_2U(SCH_1):PAGE30
  J105   G7     G7 CONN112_10137002101LF-CONN112_A    I68 @S9S_MB_2U_LIB.S9S_MB_2U(SCH_1):PAGE142

P5E_CPU0_PE2_RX_DN<2> @S9S_MB_2U_LIB.S9S_MB_2U(SCH_1):P5E_CPU0_PE2_RX_DN(2)
    U2  DA9 PE2_RX_DN2 SOCKET4677_AZIF0045P001C01CS-SA   I139 @S9S_MB_2U_LIB.S9S_MB_2U(SCH_1):PAGE30
  J105   F6     F6 CONN112_10137002101LF-CONN112_A    I68 @S9S_MB_2U_LIB.S9S_MB_2U(SCH_1):PAGE142

P5E_CPU0_PE2_RX_DN<3> @S9S_MB_2U_LIB.S9S_MB_2U(SCH_1):P5E_CPU0_PE2_RX_DN(3)
    U2 DD10 PE2_RX_DN3 SOCKET4677_AZIF0045P001C01CS-SA   I139 @S9S_MB_2U_LIB.S9S_MB_2U(SCH_1):PAGE30
  J105   G5     G5 CONN112_10137002101LF-CONN112_A    I68 @S9S_MB_2U_LIB.S9S_MB_2U(SCH_1):PAGE142

P5E_CPU0_PE2_RX_DN<4> @S9S_MB_2U_LIB.S9S_MB_2U(SCH_1):P5E_CPU0_PE2_RX_DN(4)
    U2  DE9 PE2_RX_DN4 SOCKET4677_AZIF0045P001C01CS-SA   I139 @S9S_MB_2U_LIB.S9S_MB_2U(SCH_1):PAGE30
  J105   F4     F4 CONN112_10137002101LF-CONN112_A    I65 @S9S_MB_2U_LIB.S9S_MB_2U(SCH_1):PAGE142

P5E_CPU0_PE2_RX_DN<5> @S9S_MB_2U_LIB.S9S_MB_2U(SCH_1):P5E_CPU0_PE2_RX_DN(5)
    U2 DH10 PE2_RX_DN5 SOCKET4677_AZIF0045P001C01CS-SA   I139 @S9S_MB_2U_LIB.S9S_MB_2U(SCH_1):PAGE30
  J105   G3     G3 CONN112_10137002101LF-CONN112_A    I65 @S9S_MB_2U_LIB.S9S_MB_2U(SCH_1):PAGE142

P5E_CPU0_PE2_RX_DN<6> @S9S_MB_2U_LIB.S9S_MB_2U(SCH_1):P5E_CPU0_PE2_RX_DN(6)
    U2  DJ9 PE2_RX_DN6 SOCKET4677_AZIF0045P001C01CS-SA   I139 @S9S_MB_2U_LIB.S9S_MB_2U(SCH_1):PAGE30
  J105   F2     F2 CONN112_10137002101LF-CONN112_A    I65 @S9S_MB_2U_LIB.S9S_MB_2U(SCH_1):PAGE142

P5E_CPU0_PE2_RX_DN<7> @S9S_MB_2U_LIB.S9S_MB_2U(SCH_1):P5E_CPU0_PE2_RX_DN(7)
    U2 DM10 PE2_RX_DN7 SOCKET4677_AZIF0045P001C01CS-SA   I139 @S9S_MB_2U_LIB.S9S_MB_2U(SCH_1):PAGE30
  J105   G1     G1 CONN112_10137002101LF-CONN112_A    I65 @S9S_MB_2U_LIB.S9S_MB_2U(SCH_1):PAGE142

P5E_CPU0_PE2_RX_DN<8> @S9S_MB_2U_LIB.S9S_MB_2U(SCH_1):P5E_CPU0_PE2_RX_DN(8)
    U2  DN9 PE2_RX_DN8 SOCKET4677_AZIF0045P001C01CS-SA   I139 @S9S_MB_2U_LIB.S9S_MB_2U(SCH_1):PAGE30
  J106   F8     F8 CONN112_10137002101LF-CONN112_A    I68 @S9S_MB_2U_LIB.S9S_MB_2U(SCH_1):PAGE144

P5E_CPU0_PE2_RX_DN<9> @S9S_MB_2U_LIB.S9S_MB_2U(SCH_1):P5E_CPU0_PE2_RX_DN(9)
    U2 DT10 PE2_RX_DN9 SOCKET4677_AZIF0045P001C01CS-SA   I139 @S9S_MB_2U_LIB.S9S_MB_2U(SCH_1):PAGE30
  J106   G7     G7 CONN112_10137002101LF-CONN112_A    I68 @S9S_MB_2U_LIB.S9S_MB_2U(SCH_1):PAGE144

P5E_CPU0_PE2_RX_DP<0> @S9S_MB_2U_LIB.S9S_MB_2U(SCH_1):P5E_CPU0_PE2_RX_DP(0)
    U2 CV10 PE2_RX_DP0 SOCKET4677_AZIF0045P001C01CS-SA   I139 @S9S_MB_2U_LIB.S9S_MB_2U(SCH_1):PAGE30
  J105   E8     E8 CONN112_10137002101LF-CONN112_A    I68 @S9S_MB_2U_LIB.S9S_MB_2U(SCH_1):PAGE142

P5E_CPU0_PE2_RX_DP<10> @S9S_MB_2U_LIB.S9S_MB_2U(SCH_1):P5E_CPU0_PE2_RX_DP(10)
    U2 DV10 PE2_RX_DP10 SOCKET4677_AZIF0045P001C01CS-SA   I139 @S9S_MB_2U_LIB.S9S_MB_2U(SCH_1):PAGE30
  J106   E6     E6 CONN112_10137002101LF-CONN112_A    I68 @S9S_MB_2U_LIB.S9S_MB_2U(SCH_1):PAGE144

P5E_CPU0_PE2_RX_DP<11> @S9S_MB_2U_LIB.S9S_MB_2U(SCH_1):P5E_CPU0_PE2_RX_DP(11)
    U2 DW11 PE2_RX_DP11 SOCKET4677_AZIF0045P001C01CS-SA   I139 @S9S_MB_2U_LIB.S9S_MB_2U(SCH_1):PAGE30
  J106   F5     F5 CONN112_10137002101LF-CONN112_A    I68 @S9S_MB_2U_LIB.S9S_MB_2U(SCH_1):PAGE144

P5E_CPU0_PE2_RX_DP<12> @S9S_MB_2U_LIB.S9S_MB_2U(SCH_1):P5E_CPU0_PE2_RX_DP(12)
    U2 EB10 PE2_RX_DP12 SOCKET4677_AZIF0045P001C01CS-SA   I139 @S9S_MB_2U_LIB.S9S_MB_2U(SCH_1):PAGE30
  J106   E4     E4 CONN112_10137002101LF-CONN112_A    I65 @S9S_MB_2U_LIB.S9S_MB_2U(SCH_1):PAGE144

P5E_CPU0_PE2_RX_DP<13> @S9S_MB_2U_LIB.S9S_MB_2U(SCH_1):P5E_CPU0_PE2_RX_DP(13)
    U2 EC11 PE2_RX_DP13 SOCKET4677_AZIF0045P001C01CS-SA   I139 @S9S_MB_2U_LIB.S9S_MB_2U(SCH_1):PAGE30
  J106   F3     F3 CONN112_10137002101LF-CONN112_A    I65 @S9S_MB_2U_LIB.S9S_MB_2U(SCH_1):PAGE144

P5E_CPU0_PE2_RX_DP<14> @S9S_MB_2U_LIB.S9S_MB_2U(SCH_1):P5E_CPU0_PE2_RX_DP(14)
    U2 EF10 PE2_RX_DP14 SOCKET4677_AZIF0045P001C01CS-SA   I139 @S9S_MB_2U_LIB.S9S_MB_2U(SCH_1):PAGE30
  J106   E2     E2 CONN112_10137002101LF-CONN112_A    I65 @S9S_MB_2U_LIB.S9S_MB_2U(SCH_1):PAGE144

P5E_CPU0_PE2_RX_DP<15> @S9S_MB_2U_LIB.S9S_MB_2U(SCH_1):P5E_CPU0_PE2_RX_DP(15)
    U2 EG11 PE2_RX_DP15 SOCKET4677_AZIF0045P001C01CS-SA   I139 @S9S_MB_2U_LIB.S9S_MB_2U(SCH_1):PAGE30
  J106   F1     F1 CONN112_10137002101LF-CONN112_A    I65 @S9S_MB_2U_LIB.S9S_MB_2U(SCH_1):PAGE144

P5E_CPU0_PE2_RX_DP<1> @S9S_MB_2U_LIB.S9S_MB_2U(SCH_1):P5E_CPU0_PE2_RX_DP(1)
    U2 CW11 PE2_RX_DP1 SOCKET4677_AZIF0045P001C01CS-SA   I139 @S9S_MB_2U_LIB.S9S_MB_2U(SCH_1):PAGE30
  J105   F7     F7 CONN112_10137002101LF-CONN112_A    I68 @S9S_MB_2U_LIB.S9S_MB_2U(SCH_1):PAGE142

P5E_CPU0_PE2_RX_DP<2> @S9S_MB_2U_LIB.S9S_MB_2U(SCH_1):P5E_CPU0_PE2_RX_DP(2)
    U2 DB10 PE2_RX_DP2 SOCKET4677_AZIF0045P001C01CS-SA   I139 @S9S_MB_2U_LIB.S9S_MB_2U(SCH_1):PAGE30
  J105   E6     E6 CONN112_10137002101LF-CONN112_A    I68 @S9S_MB_2U_LIB.S9S_MB_2U(SCH_1):PAGE142

P5E_CPU0_PE2_RX_DP<3> @S9S_MB_2U_LIB.S9S_MB_2U(SCH_1):P5E_CPU0_PE2_RX_DP(3)
    U2 DC11 PE2_RX_DP3 SOCKET4677_AZIF0045P001C01CS-SA   I139 @S9S_MB_2U_LIB.S9S_MB_2U(SCH_1):PAGE30
  J105   F5     F5 CONN112_10137002101LF-CONN112_A    I68 @S9S_MB_2U_LIB.S9S_MB_2U(SCH_1):PAGE142

P5E_CPU0_PE2_RX_DP<4> @S9S_MB_2U_LIB.S9S_MB_2U(SCH_1):P5E_CPU0_PE2_RX_DP(4)
    U2 DF10 PE2_RX_DP4 SOCKET4677_AZIF0045P001C01CS-SA   I139 @S9S_MB_2U_LIB.S9S_MB_2U(SCH_1):PAGE30
  J105   E4     E4 CONN112_10137002101LF-CONN112_A    I65 @S9S_MB_2U_LIB.S9S_MB_2U(SCH_1):PAGE142

P5E_CPU0_PE2_RX_DP<5> @S9S_MB_2U_LIB.S9S_MB_2U(SCH_1):P5E_CPU0_PE2_RX_DP(5)
    U2 DG11 PE2_RX_DP5 SOCKET4677_AZIF0045P001C01CS-SA   I139 @S9S_MB_2U_LIB.S9S_MB_2U(SCH_1):PAGE30
  J105   F3     F3 CONN112_10137002101LF-CONN112_A    I65 @S9S_MB_2U_LIB.S9S_MB_2U(SCH_1):PAGE142

P5E_CPU0_PE2_RX_DP<6> @S9S_MB_2U_LIB.S9S_MB_2U(SCH_1):P5E_CPU0_PE2_RX_DP(6)
    U2 DK10 PE2_RX_DP6 SOCKET4677_AZIF0045P001C01CS-SA   I139 @S9S_MB_2U_LIB.S9S_MB_2U(SCH_1):PAGE30
  J105   E2     E2 CONN112_10137002101LF-CONN112_A    I65 @S9S_MB_2U_LIB.S9S_MB_2U(SCH_1):PAGE142

P5E_CPU0_PE2_RX_DP<7> @S9S_MB_2U_LIB.S9S_MB_2U(SCH_1):P5E_CPU0_PE2_RX_DP(7)
    U2 DL11 PE2_RX_DP7 SOCKET4677_AZIF0045P001C01CS-SA   I139 @S9S_MB_2U_LIB.S9S_MB_2U(SCH_1):PAGE30
  J105   F1     F1 CONN112_10137002101LF-CONN112_A    I65 @S9S_MB_2U_LIB.S9S_MB_2U(SCH_1):PAGE142

P5E_CPU0_PE2_RX_DP<8> @S9S_MB_2U_LIB.S9S_MB_2U(SCH_1):P5E_CPU0_PE2_RX_DP(8)
    U2 DP10 PE2_RX_DP8 SOCKET4677_AZIF0045P001C01CS-SA   I139 @S9S_MB_2U_LIB.S9S_MB_2U(SCH_1):PAGE30
  J106   E8     E8 CONN112_10137002101LF-CONN112_A    I68 @S9S_MB_2U_LIB.S9S_MB_2U(SCH_1):PAGE144

P5E_CPU0_PE2_RX_DP<9> @S9S_MB_2U_LIB.S9S_MB_2U(SCH_1):P5E_CPU0_PE2_RX_DP(9)
    U2 DR11 PE2_RX_DP9 SOCKET4677_AZIF0045P001C01CS-SA   I139 @S9S_MB_2U_LIB.S9S_MB_2U(SCH_1):PAGE30
  J106   F7     F7 CONN112_10137002101LF-CONN112_A    I68 @S9S_MB_2U_LIB.S9S_MB_2U(SCH_1):PAGE144

P5E_CPU0_PE2_TX_C_DN<0> @S9S_MB_2U_LIB.S9S_MB_2U(SCH_1):P5E_CPU0_PE2_TX_C_DN(0)
  C964    1      1 Q_CAP_DIFFBUS_C0201-DIFF BUS_0A   I122 @S9S_MB_2U_LIB.S9S_MB_2U(SCH_1):PAGE164
  J105   L8     L8 CONN112_10137002101LF-CONN112_A    I68 @S9S_MB_2U_LIB.S9S_MB_2U(SCH_1):PAGE142

P5E_CPU0_PE2_TX_C_DN<10> @S9S_MB_2U_LIB.S9S_MB_2U(SCH_1):P5E_CPU0_PE2_TX_C_DN(10)
  C944    1      1 Q_CAP_DIFFBUS_C0201-DIFF BUS_0A   I156 @S9S_MB_2U_LIB.S9S_MB_2U(SCH_1):PAGE164
  J106   L6     L6 CONN112_10137002101LF-CONN112_A    I68 @S9S_MB_2U_LIB.S9S_MB_2U(SCH_1):PAGE144

P5E_CPU0_PE2_TX_C_DN<11> @S9S_MB_2U_LIB.S9S_MB_2U(SCH_1):P5E_CPU0_PE2_TX_C_DN(11)
  C942    1      1 Q_CAP_DIFFBUS_C0201-DIFF BUS_0A   I158 @S9S_MB_2U_LIB.S9S_MB_2U(SCH_1):PAGE164
  J106   M5     M5 CONN112_10137002101LF-CONN112_A    I68 @S9S_MB_2U_LIB.S9S_MB_2U(SCH_1):PAGE144

P5E_CPU0_PE2_TX_C_DN<12> @S9S_MB_2U_LIB.S9S_MB_2U(SCH_1):P5E_CPU0_PE2_TX_C_DN(12)
  C940    1      1 Q_CAP_DIFFBUS_C0201-DIFF BUS_0A   I160 @S9S_MB_2U_LIB.S9S_MB_2U(SCH_1):PAGE164
  J106   L4     L4 CONN112_10137002101LF-CONN112_A    I65 @S9S_MB_2U_LIB.S9S_MB_2U(SCH_1):PAGE144

P5E_CPU0_PE2_TX_C_DN<13> @S9S_MB_2U_LIB.S9S_MB_2U(SCH_1):P5E_CPU0_PE2_TX_C_DN(13)
  C938    1      1 Q_CAP_DIFFBUS_C0201-DIFF BUS_0A   I165 @S9S_MB_2U_LIB.S9S_MB_2U(SCH_1):PAGE164
  J106   M3     M3 CONN112_10137002101LF-CONN112_A    I65 @S9S_MB_2U_LIB.S9S_MB_2U(SCH_1):PAGE144

P5E_CPU0_PE2_TX_C_DN<14> @S9S_MB_2U_LIB.S9S_MB_2U(SCH_1):P5E_CPU0_PE2_TX_C_DN(14)
  C936    1      1 Q_CAP_DIFFBUS_C0201-DIFF BUS_0A   I167 @S9S_MB_2U_LIB.S9S_MB_2U(SCH_1):PAGE164
  J106   L2     L2 CONN112_10137002101LF-CONN112_A    I65 @S9S_MB_2U_LIB.S9S_MB_2U(SCH_1):PAGE144

P5E_CPU0_PE2_TX_C_DN<15> @S9S_MB_2U_LIB.S9S_MB_2U(SCH_1):P5E_CPU0_PE2_TX_C_DN(15)
  C934    1      1 Q_CAP_DIFFBUS_C0201-DIFF BUS_0A   I169 @S9S_MB_2U_LIB.S9S_MB_2U(SCH_1):PAGE164
  J106   L1     L1 CONN112_10137002101LF-CONN112_A    I65 @S9S_MB_2U_LIB.S9S_MB_2U(SCH_1):PAGE144

P5E_CPU0_PE2_TX_C_DN<1> @S9S_MB_2U_LIB.S9S_MB_2U(SCH_1):P5E_CPU0_PE2_TX_C_DN(1)
  C962    1      1 Q_CAP_DIFFBUS_C0201-DIFF BUS_0A   I124 @S9S_MB_2U_LIB.S9S_MB_2U(SCH_1):PAGE164
  J105   M7     M7 CONN112_10137002101LF-CONN112_A    I68 @S9S_MB_2U_LIB.S9S_MB_2U(SCH_1):PAGE142

P5E_CPU0_PE2_TX_C_DN<2> @S9S_MB_2U_LIB.S9S_MB_2U(SCH_1):P5E_CPU0_PE2_TX_C_DN(2)
  C960    1      1 Q_CAP_DIFFBUS_C0201-DIFF BUS_0A   I126 @S9S_MB_2U_LIB.S9S_MB_2U(SCH_1):PAGE164
  J105   L6     L6 CONN112_10137002101LF-CONN112_A    I68 @S9S_MB_2U_LIB.S9S_MB_2U(SCH_1):PAGE142

P5E_CPU0_PE2_TX_C_DN<3> @S9S_MB_2U_LIB.S9S_MB_2U(SCH_1):P5E_CPU0_PE2_TX_C_DN(3)
  C958    1      1 Q_CAP_DIFFBUS_C0201-DIFF BUS_0A   I128 @S9S_MB_2U_LIB.S9S_MB_2U(SCH_1):PAGE164
  J105   M5     M5 CONN112_10137002101LF-CONN112_A    I68 @S9S_MB_2U_LIB.S9S_MB_2U(SCH_1):PAGE142

P5E_CPU0_PE2_TX_C_DN<4> @S9S_MB_2U_LIB.S9S_MB_2U(SCH_1):P5E_CPU0_PE2_TX_C_DN(4)
  C956    1      1 Q_CAP_DIFFBUS_C0201-DIFF BUS_0A   I207 @S9S_MB_2U_LIB.S9S_MB_2U(SCH_1):PAGE164
  J105   L4     L4 CONN112_10137002101LF-CONN112_A    I65 @S9S_MB_2U_LIB.S9S_MB_2U(SCH_1):PAGE142

P5E_CPU0_PE2_TX_C_DN<5> @S9S_MB_2U_LIB.S9S_MB_2U(SCH_1):P5E_CPU0_PE2_TX_C_DN(5)
  C954    1      1 Q_CAP_DIFFBUS_C0201-DIFF BUS_0A   I133 @S9S_MB_2U_LIB.S9S_MB_2U(SCH_1):PAGE164
  J105   M3     M3 CONN112_10137002101LF-CONN112_A    I65 @S9S_MB_2U_LIB.S9S_MB_2U(SCH_1):PAGE142

P5E_CPU0_PE2_TX_C_DN<6> @S9S_MB_2U_LIB.S9S_MB_2U(SCH_1):P5E_CPU0_PE2_TX_C_DN(6)
  C952    1      1 Q_CAP_DIFFBUS_C0201-DIFF BUS_0A   I135 @S9S_MB_2U_LIB.S9S_MB_2U(SCH_1):PAGE164
  J105   L2     L2 CONN112_10137002101LF-CONN112_A    I65 @S9S_MB_2U_LIB.S9S_MB_2U(SCH_1):PAGE142

P5E_CPU0_PE2_TX_C_DN<7> @S9S_MB_2U_LIB.S9S_MB_2U(SCH_1):P5E_CPU0_PE2_TX_C_DN(7)
  C950    1      1 Q_CAP_DIFFBUS_C0201-DIFF BUS_0A   I137 @S9S_MB_2U_LIB.S9S_MB_2U(SCH_1):PAGE164
  J105   M1     M1 CONN112_10137002101LF-CONN112_A    I65 @S9S_MB_2U_LIB.S9S_MB_2U(SCH_1):PAGE142

P5E_CPU0_PE2_TX_C_DN<8> @S9S_MB_2U_LIB.S9S_MB_2U(SCH_1):P5E_CPU0_PE2_TX_C_DN(8)
  C948    1      1 Q_CAP_DIFFBUS_C0201-DIFF BUS_0A   I152 @S9S_MB_2U_LIB.S9S_MB_2U(SCH_1):PAGE164
  J106   L8     L8 CONN112_10137002101LF-CONN112_A    I68 @S9S_MB_2U_LIB.S9S_MB_2U(SCH_1):PAGE144

P5E_CPU0_PE2_TX_C_DN<9> @S9S_MB_2U_LIB.S9S_MB_2U(SCH_1):P5E_CPU0_PE2_TX_C_DN(9)
  C946    1      1 Q_CAP_DIFFBUS_C0201-DIFF BUS_0A   I154 @S9S_MB_2U_LIB.S9S_MB_2U(SCH_1):PAGE164
  J106   M7     M7 CONN112_10137002101LF-CONN112_A    I68 @S9S_MB_2U_LIB.S9S_MB_2U(SCH_1):PAGE144

P5E_CPU0_PE2_TX_C_DP<0> @S9S_MB_2U_LIB.S9S_MB_2U(SCH_1):P5E_CPU0_PE2_TX_C_DP(0)
  C965    1      1 Q_CAP_DIFFBUS_C0201-DIFF BUS_0A   I121 @S9S_MB_2U_LIB.S9S_MB_2U(SCH_1):PAGE164
  J105   K8     K8 CONN112_10137002101LF-CONN112_A    I68 @S9S_MB_2U_LIB.S9S_MB_2U(SCH_1):PAGE142

P5E_CPU0_PE2_TX_C_DP<10> @S9S_MB_2U_LIB.S9S_MB_2U(SCH_1):P5E_CPU0_PE2_TX_C_DP(10)
  C945    1      1 Q_CAP_DIFFBUS_C0201-DIFF BUS_0A   I155 @S9S_MB_2U_LIB.S9S_MB_2U(SCH_1):PAGE164
  J106   K6     K6 CONN112_10137002101LF-CONN112_A    I68 @S9S_MB_2U_LIB.S9S_MB_2U(SCH_1):PAGE144

P5E_CPU0_PE2_TX_C_DP<11> @S9S_MB_2U_LIB.S9S_MB_2U(SCH_1):P5E_CPU0_PE2_TX_C_DP(11)
  C943    1      1 Q_CAP_DIFFBUS_C0201-DIFF BUS_0A   I157 @S9S_MB_2U_LIB.S9S_MB_2U(SCH_1):PAGE164
  J106   L5     L5 CONN112_10137002101LF-CONN112_A    I68 @S9S_MB_2U_LIB.S9S_MB_2U(SCH_1):PAGE144

P5E_CPU0_PE2_TX_C_DP<12> @S9S_MB_2U_LIB.S9S_MB_2U(SCH_1):P5E_CPU0_PE2_TX_C_DP(12)
  C941    1      1 Q_CAP_DIFFBUS_C0201-DIFF BUS_0A   I159 @S9S_MB_2U_LIB.S9S_MB_2U(SCH_1):PAGE164
  J106   K4     K4 CONN112_10137002101LF-CONN112_A    I65 @S9S_MB_2U_LIB.S9S_MB_2U(SCH_1):PAGE144

P5E_CPU0_PE2_TX_C_DP<13> @S9S_MB_2U_LIB.S9S_MB_2U(SCH_1):P5E_CPU0_PE2_TX_C_DP(13)
  C939    1      1 Q_CAP_DIFFBUS_C0201-DIFF BUS_0A   I164 @S9S_MB_2U_LIB.S9S_MB_2U(SCH_1):PAGE164
  J106   L3     L3 CONN112_10137002101LF-CONN112_A    I65 @S9S_MB_2U_LIB.S9S_MB_2U(SCH_1):PAGE144

P5E_CPU0_PE2_TX_C_DP<14> @S9S_MB_2U_LIB.S9S_MB_2U(SCH_1):P5E_CPU0_PE2_TX_C_DP(14)
  C937    1      1 Q_CAP_DIFFBUS_C0201-DIFF BUS_0A   I166 @S9S_MB_2U_LIB.S9S_MB_2U(SCH_1):PAGE164
  J106   K2     K2 CONN112_10137002101LF-CONN112_A    I65 @S9S_MB_2U_LIB.S9S_MB_2U(SCH_1):PAGE144

P5E_CPU0_PE2_TX_C_DP<15> @S9S_MB_2U_LIB.S9S_MB_2U(SCH_1):P5E_CPU0_PE2_TX_C_DP(15)
  C935    1      1 Q_CAP_DIFFBUS_C0201-DIFF BUS_0A   I168 @S9S_MB_2U_LIB.S9S_MB_2U(SCH_1):PAGE164
  J106   M1     M1 CONN112_10137002101LF-CONN112_A    I65 @S9S_MB_2U_LIB.S9S_MB_2U(SCH_1):PAGE144

P5E_CPU0_PE2_TX_C_DP<1> @S9S_MB_2U_LIB.S9S_MB_2U(SCH_1):P5E_CPU0_PE2_TX_C_DP(1)
  C963    1      1 Q_CAP_DIFFBUS_C0201-DIFF BUS_0A   I123 @S9S_MB_2U_LIB.S9S_MB_2U(SCH_1):PAGE164
  J105   L7     L7 CONN112_10137002101LF-CONN112_A    I68 @S9S_MB_2U_LIB.S9S_MB_2U(SCH_1):PAGE142

P5E_CPU0_PE2_TX_C_DP<2> @S9S_MB_2U_LIB.S9S_MB_2U(SCH_1):P5E_CPU0_PE2_TX_C_DP(2)
  C961    1      1 Q_CAP_DIFFBUS_C0201-DIFF BUS_0A   I125 @S9S_MB_2U_LIB.S9S_MB_2U(SCH_1):PAGE164
  J105   K6     K6 CONN112_10137002101LF-CONN112_A    I68 @S9S_MB_2U_LIB.S9S_MB_2U(SCH_1):PAGE142

P5E_CPU0_PE2_TX_C_DP<3> @S9S_MB_2U_LIB.S9S_MB_2U(SCH_1):P5E_CPU0_PE2_TX_C_DP(3)
  C959    1      1 Q_CAP_DIFFBUS_C0201-DIFF BUS_0A   I127 @S9S_MB_2U_LIB.S9S_MB_2U(SCH_1):PAGE164
  J105   L5     L5 CONN112_10137002101LF-CONN112_A    I68 @S9S_MB_2U_LIB.S9S_MB_2U(SCH_1):PAGE142

P5E_CPU0_PE2_TX_C_DP<4> @S9S_MB_2U_LIB.S9S_MB_2U(SCH_1):P5E_CPU0_PE2_TX_C_DP(4)
  C957    1      1 Q_CAP_DIFFBUS_C0201-DIFF BUS_0A   I206 @S9S_MB_2U_LIB.S9S_MB_2U(SCH_1):PAGE164
  J105   K4     K4 CONN112_10137002101LF-CONN112_A    I65 @S9S_MB_2U_LIB.S9S_MB_2U(SCH_1):PAGE142

P5E_CPU0_PE2_TX_C_DP<5> @S9S_MB_2U_LIB.S9S_MB_2U(SCH_1):P5E_CPU0_PE2_TX_C_DP(5)
  C955    1      1 Q_CAP_DIFFBUS_C0201-DIFF BUS_0A   I208 @S9S_MB_2U_LIB.S9S_MB_2U(SCH_1):PAGE164
  J105   L3     L3 CONN112_10137002101LF-CONN112_A    I65 @S9S_MB_2U_LIB.S9S_MB_2U(SCH_1):PAGE142

P5E_CPU0_PE2_TX_C_DP<6> @S9S_MB_2U_LIB.S9S_MB_2U(SCH_1):P5E_CPU0_PE2_TX_C_DP(6)
  C953    1      1 Q_CAP_DIFFBUS_C0201-DIFF BUS_0A   I134 @S9S_MB_2U_LIB.S9S_MB_2U(SCH_1):PAGE164
  J105   K2     K2 CONN112_10137002101LF-CONN112_A    I65 @S9S_MB_2U_LIB.S9S_MB_2U(SCH_1):PAGE142

P5E_CPU0_PE2_TX_C_DP<7> @S9S_MB_2U_LIB.S9S_MB_2U(SCH_1):P5E_CPU0_PE2_TX_C_DP(7)
  C951    1      1 Q_CAP_DIFFBUS_C0201-DIFF BUS_0A   I136 @S9S_MB_2U_LIB.S9S_MB_2U(SCH_1):PAGE164
  J105   L1     L1 CONN112_10137002101LF-CONN112_A    I65 @S9S_MB_2U_LIB.S9S_MB_2U(SCH_1):PAGE142

P5E_CPU0_PE2_TX_C_DP<8> @S9S_MB_2U_LIB.S9S_MB_2U(SCH_1):P5E_CPU0_PE2_TX_C_DP(8)
  C949    1      1 Q_CAP_DIFFBUS_C0201-DIFF BUS_0A   I151 @S9S_MB_2U_LIB.S9S_MB_2U(SCH_1):PAGE164
  J106   K8     K8 CONN112_10137002101LF-CONN112_A    I68 @S9S_MB_2U_LIB.S9S_MB_2U(SCH_1):PAGE144

P5E_CPU0_PE2_TX_C_DP<9> @S9S_MB_2U_LIB.S9S_MB_2U(SCH_1):P5E_CPU0_PE2_TX_C_DP(9)
  C947    1      1 Q_CAP_DIFFBUS_C0201-DIFF BUS_0A   I153 @S9S_MB_2U_LIB.S9S_MB_2U(SCH_1):PAGE164
  J106   L7     L7 CONN112_10137002101LF-CONN112_A    I68 @S9S_MB_2U_LIB.S9S_MB_2U(SCH_1):PAGE144

P5E_CPU0_PE2_TX_DN<0> @S9S_MB_2U_LIB.S9S_MB_2U(SCH_1):P5E_CPU0_PE2_TX_DN(0)
    U2 CU13 PE2_TX_DN0 SOCKET4677_AZIF0045P001C01CS-SA   I139 @S9S_MB_2U_LIB.S9S_MB_2U(SCH_1):PAGE30
  C964    2      2 Q_CAP_DIFFBUS_C0201-DIFF BUS_0A   I122 @S9S_MB_2U_LIB.S9S_MB_2U(SCH_1):PAGE164

P5E_CPU0_PE2_TX_DN<10> @S9S_MB_2U_LIB.S9S_MB_2U(SCH_1):P5E_CPU0_PE2_TX_DN(10)
    U2 DU13 PE2_TX_DN10 SOCKET4677_AZIF0045P001C01CS-SA   I139 @S9S_MB_2U_LIB.S9S_MB_2U(SCH_1):PAGE30
  C944    2      2 Q_CAP_DIFFBUS_C0201-DIFF BUS_0A   I156 @S9S_MB_2U_LIB.S9S_MB_2U(SCH_1):PAGE164

P5E_CPU0_PE2_TX_DN<11> @S9S_MB_2U_LIB.S9S_MB_2U(SCH_1):P5E_CPU0_PE2_TX_DN(11)
    U2 DV14 PE2_TX_DN11 SOCKET4677_AZIF0045P001C01CS-SA   I139 @S9S_MB_2U_LIB.S9S_MB_2U(SCH_1):PAGE30
  C942    2      2 Q_CAP_DIFFBUS_C0201-DIFF BUS_0A   I158 @S9S_MB_2U_LIB.S9S_MB_2U(SCH_1):PAGE164

P5E_CPU0_PE2_TX_DN<12> @S9S_MB_2U_LIB.S9S_MB_2U(SCH_1):P5E_CPU0_PE2_TX_DN(12)
    U2 EA13 PE2_TX_DN12 SOCKET4677_AZIF0045P001C01CS-SA   I139 @S9S_MB_2U_LIB.S9S_MB_2U(SCH_1):PAGE30
  C940    2      2 Q_CAP_DIFFBUS_C0201-DIFF BUS_0A   I160 @S9S_MB_2U_LIB.S9S_MB_2U(SCH_1):PAGE164

P5E_CPU0_PE2_TX_DN<13> @S9S_MB_2U_LIB.S9S_MB_2U(SCH_1):P5E_CPU0_PE2_TX_DN(13)
    U2 EB14 PE2_TX_DN13 SOCKET4677_AZIF0045P001C01CS-SA   I139 @S9S_MB_2U_LIB.S9S_MB_2U(SCH_1):PAGE30
  C938    2      2 Q_CAP_DIFFBUS_C0201-DIFF BUS_0A   I165 @S9S_MB_2U_LIB.S9S_MB_2U(SCH_1):PAGE164

P5E_CPU0_PE2_TX_DN<14> @S9S_MB_2U_LIB.S9S_MB_2U(SCH_1):P5E_CPU0_PE2_TX_DN(14)
    U2 EE13 PE2_TX_DN14 SOCKET4677_AZIF0045P001C01CS-SA   I139 @S9S_MB_2U_LIB.S9S_MB_2U(SCH_1):PAGE30
  C936    2      2 Q_CAP_DIFFBUS_C0201-DIFF BUS_0A   I167 @S9S_MB_2U_LIB.S9S_MB_2U(SCH_1):PAGE164

P5E_CPU0_PE2_TX_DN<15> @S9S_MB_2U_LIB.S9S_MB_2U(SCH_1):P5E_CPU0_PE2_TX_DN(15)
    U2 EF14 PE2_TX_DN15 SOCKET4677_AZIF0045P001C01CS-SA   I139 @S9S_MB_2U_LIB.S9S_MB_2U(SCH_1):PAGE30
  C934    2      2 Q_CAP_DIFFBUS_C0201-DIFF BUS_0A   I169 @S9S_MB_2U_LIB.S9S_MB_2U(SCH_1):PAGE164

P5E_CPU0_PE2_TX_DN<1> @S9S_MB_2U_LIB.S9S_MB_2U(SCH_1):P5E_CPU0_PE2_TX_DN(1)
    U2 CV14 PE2_TX_DN1 SOCKET4677_AZIF0045P001C01CS-SA   I139 @S9S_MB_2U_LIB.S9S_MB_2U(SCH_1):PAGE30
  C962    2      2 Q_CAP_DIFFBUS_C0201-DIFF BUS_0A   I124 @S9S_MB_2U_LIB.S9S_MB_2U(SCH_1):PAGE164

P5E_CPU0_PE2_TX_DN<2> @S9S_MB_2U_LIB.S9S_MB_2U(SCH_1):P5E_CPU0_PE2_TX_DN(2)
    U2 DA13 PE2_TX_DN2 SOCKET4677_AZIF0045P001C01CS-SA   I139 @S9S_MB_2U_LIB.S9S_MB_2U(SCH_1):PAGE30
  C960    2      2 Q_CAP_DIFFBUS_C0201-DIFF BUS_0A   I126 @S9S_MB_2U_LIB.S9S_MB_2U(SCH_1):PAGE164

P5E_CPU0_PE2_TX_DN<3> @S9S_MB_2U_LIB.S9S_MB_2U(SCH_1):P5E_CPU0_PE2_TX_DN(3)
    U2 DB14 PE2_TX_DN3 SOCKET4677_AZIF0045P001C01CS-SA   I139 @S9S_MB_2U_LIB.S9S_MB_2U(SCH_1):PAGE30
  C958    2      2 Q_CAP_DIFFBUS_C0201-DIFF BUS_0A   I128 @S9S_MB_2U_LIB.S9S_MB_2U(SCH_1):PAGE164

P5E_CPU0_PE2_TX_DN<4> @S9S_MB_2U_LIB.S9S_MB_2U(SCH_1):P5E_CPU0_PE2_TX_DN(4)
    U2 DE13 PE2_TX_DN4 SOCKET4677_AZIF0045P001C01CS-SA   I139 @S9S_MB_2U_LIB.S9S_MB_2U(SCH_1):PAGE30
  C956    2      2 Q_CAP_DIFFBUS_C0201-DIFF BUS_0A   I207 @S9S_MB_2U_LIB.S9S_MB_2U(SCH_1):PAGE164

P5E_CPU0_PE2_TX_DN<5> @S9S_MB_2U_LIB.S9S_MB_2U(SCH_1):P5E_CPU0_PE2_TX_DN(5)
    U2 DF14 PE2_TX_DN5 SOCKET4677_AZIF0045P001C01CS-SA   I139 @S9S_MB_2U_LIB.S9S_MB_2U(SCH_1):PAGE30
  C954    2      2 Q_CAP_DIFFBUS_C0201-DIFF BUS_0A   I133 @S9S_MB_2U_LIB.S9S_MB_2U(SCH_1):PAGE164

P5E_CPU0_PE2_TX_DN<6> @S9S_MB_2U_LIB.S9S_MB_2U(SCH_1):P5E_CPU0_PE2_TX_DN(6)
    U2 DJ13 PE2_TX_DN6 SOCKET4677_AZIF0045P001C01CS-SA   I139 @S9S_MB_2U_LIB.S9S_MB_2U(SCH_1):PAGE30
  C952    2      2 Q_CAP_DIFFBUS_C0201-DIFF BUS_0A   I135 @S9S_MB_2U_LIB.S9S_MB_2U(SCH_1):PAGE164

P5E_CPU0_PE2_TX_DN<7> @S9S_MB_2U_LIB.S9S_MB_2U(SCH_1):P5E_CPU0_PE2_TX_DN(7)
    U2 DK14 PE2_TX_DN7 SOCKET4677_AZIF0045P001C01CS-SA   I139 @S9S_MB_2U_LIB.S9S_MB_2U(SCH_1):PAGE30
  C950    2      2 Q_CAP_DIFFBUS_C0201-DIFF BUS_0A   I137 @S9S_MB_2U_LIB.S9S_MB_2U(SCH_1):PAGE164

P5E_CPU0_PE2_TX_DN<8> @S9S_MB_2U_LIB.S9S_MB_2U(SCH_1):P5E_CPU0_PE2_TX_DN(8)
    U2 DN13 PE2_TX_DN8 SOCKET4677_AZIF0045P001C01CS-SA   I139 @S9S_MB_2U_LIB.S9S_MB_2U(SCH_1):PAGE30
  C948    2      2 Q_CAP_DIFFBUS_C0201-DIFF BUS_0A   I152 @S9S_MB_2U_LIB.S9S_MB_2U(SCH_1):PAGE164

P5E_CPU0_PE2_TX_DN<9> @S9S_MB_2U_LIB.S9S_MB_2U(SCH_1):P5E_CPU0_PE2_TX_DN(9)
    U2 DP14 PE2_TX_DN9 SOCKET4677_AZIF0045P001C01CS-SA   I139 @S9S_MB_2U_LIB.S9S_MB_2U(SCH_1):PAGE30
  C946    2      2 Q_CAP_DIFFBUS_C0201-DIFF BUS_0A   I154 @S9S_MB_2U_LIB.S9S_MB_2U(SCH_1):PAGE164

P5E_CPU0_PE2_TX_DP<0> @S9S_MB_2U_LIB.S9S_MB_2U(SCH_1):P5E_CPU0_PE2_TX_DP(0)
    U2 CT14 PE2_TX_DP0 SOCKET4677_AZIF0045P001C01CS-SA   I139 @S9S_MB_2U_LIB.S9S_MB_2U(SCH_1):PAGE30
  C965    2      2 Q_CAP_DIFFBUS_C0201-DIFF BUS_0A   I121 @S9S_MB_2U_LIB.S9S_MB_2U(SCH_1):PAGE164

P5E_CPU0_PE2_TX_DP<10> @S9S_MB_2U_LIB.S9S_MB_2U(SCH_1):P5E_CPU0_PE2_TX_DP(10)
    U2 DT14 PE2_TX_DP10 SOCKET4677_AZIF0045P001C01CS-SA   I139 @S9S_MB_2U_LIB.S9S_MB_2U(SCH_1):PAGE30
  C945    2      2 Q_CAP_DIFFBUS_C0201-DIFF BUS_0A   I155 @S9S_MB_2U_LIB.S9S_MB_2U(SCH_1):PAGE164

P5E_CPU0_PE2_TX_DP<11> @S9S_MB_2U_LIB.S9S_MB_2U(SCH_1):P5E_CPU0_PE2_TX_DP(11)
    U2 DW15 PE2_TX_DP11 SOCKET4677_AZIF0045P001C01CS-SA   I139 @S9S_MB_2U_LIB.S9S_MB_2U(SCH_1):PAGE30
  C943    2      2 Q_CAP_DIFFBUS_C0201-DIFF BUS_0A   I157 @S9S_MB_2U_LIB.S9S_MB_2U(SCH_1):PAGE164

P5E_CPU0_PE2_TX_DP<12> @S9S_MB_2U_LIB.S9S_MB_2U(SCH_1):P5E_CPU0_PE2_TX_DP(12)
    U2 DY14 PE2_TX_DP12 SOCKET4677_AZIF0045P001C01CS-SA   I139 @S9S_MB_2U_LIB.S9S_MB_2U(SCH_1):PAGE30
  C941    2      2 Q_CAP_DIFFBUS_C0201-DIFF BUS_0A   I159 @S9S_MB_2U_LIB.S9S_MB_2U(SCH_1):PAGE164

P5E_CPU0_PE2_TX_DP<13> @S9S_MB_2U_LIB.S9S_MB_2U(SCH_1):P5E_CPU0_PE2_TX_DP(13)
    U2 EC15 PE2_TX_DP13 SOCKET4677_AZIF0045P001C01CS-SA   I139 @S9S_MB_2U_LIB.S9S_MB_2U(SCH_1):PAGE30
  C939    2      2 Q_CAP_DIFFBUS_C0201-DIFF BUS_0A   I164 @S9S_MB_2U_LIB.S9S_MB_2U(SCH_1):PAGE164

P5E_CPU0_PE2_TX_DP<14> @S9S_MB_2U_LIB.S9S_MB_2U(SCH_1):P5E_CPU0_PE2_TX_DP(14)
    U2 ED14 PE2_TX_DP14 SOCKET4677_AZIF0045P001C01CS-SA   I139 @S9S_MB_2U_LIB.S9S_MB_2U(SCH_1):PAGE30
  C937    2      2 Q_CAP_DIFFBUS_C0201-DIFF BUS_0A   I166 @S9S_MB_2U_LIB.S9S_MB_2U(SCH_1):PAGE164

P5E_CPU0_PE2_TX_DP<15> @S9S_MB_2U_LIB.S9S_MB_2U(SCH_1):P5E_CPU0_PE2_TX_DP(15)
    U2 EG15 PE2_TX_DP15 SOCKET4677_AZIF0045P001C01CS-SA   I139 @S9S_MB_2U_LIB.S9S_MB_2U(SCH_1):PAGE30
  C935    2      2 Q_CAP_DIFFBUS_C0201-DIFF BUS_0A   I168 @S9S_MB_2U_LIB.S9S_MB_2U(SCH_1):PAGE164

P5E_CPU0_PE2_TX_DP<1> @S9S_MB_2U_LIB.S9S_MB_2U(SCH_1):P5E_CPU0_PE2_TX_DP(1)
    U2 CW15 PE2_TX_DP1 SOCKET4677_AZIF0045P001C01CS-SA   I139 @S9S_MB_2U_LIB.S9S_MB_2U(SCH_1):PAGE30
  C963    2      2 Q_CAP_DIFFBUS_C0201-DIFF BUS_0A   I123 @S9S_MB_2U_LIB.S9S_MB_2U(SCH_1):PAGE164

P5E_CPU0_PE2_TX_DP<2> @S9S_MB_2U_LIB.S9S_MB_2U(SCH_1):P5E_CPU0_PE2_TX_DP(2)
    U2 CY14 PE2_TX_DP2 SOCKET4677_AZIF0045P001C01CS-SA   I139 @S9S_MB_2U_LIB.S9S_MB_2U(SCH_1):PAGE30
  C961    2      2 Q_CAP_DIFFBUS_C0201-DIFF BUS_0A   I125 @S9S_MB_2U_LIB.S9S_MB_2U(SCH_1):PAGE164

P5E_CPU0_PE2_TX_DP<3> @S9S_MB_2U_LIB.S9S_MB_2U(SCH_1):P5E_CPU0_PE2_TX_DP(3)
    U2 DC15 PE2_TX_DP3 SOCKET4677_AZIF0045P001C01CS-SA   I139 @S9S_MB_2U_LIB.S9S_MB_2U(SCH_1):PAGE30
  C959    2      2 Q_CAP_DIFFBUS_C0201-DIFF BUS_0A   I127 @S9S_MB_2U_LIB.S9S_MB_2U(SCH_1):PAGE164

P5E_CPU0_PE2_TX_DP<4> @S9S_MB_2U_LIB.S9S_MB_2U(SCH_1):P5E_CPU0_PE2_TX_DP(4)
    U2 DD14 PE2_TX_DP4 SOCKET4677_AZIF0045P001C01CS-SA   I139 @S9S_MB_2U_LIB.S9S_MB_2U(SCH_1):PAGE30
  C957    2      2 Q_CAP_DIFFBUS_C0201-DIFF BUS_0A   I206 @S9S_MB_2U_LIB.S9S_MB_2U(SCH_1):PAGE164

P5E_CPU0_PE2_TX_DP<5> @S9S_MB_2U_LIB.S9S_MB_2U(SCH_1):P5E_CPU0_PE2_TX_DP(5)
    U2 DG15 PE2_TX_DP5 SOCKET4677_AZIF0045P001C01CS-SA   I139 @S9S_MB_2U_LIB.S9S_MB_2U(SCH_1):PAGE30
  C955    2      2 Q_CAP_DIFFBUS_C0201-DIFF BUS_0A   I208 @S9S_MB_2U_LIB.S9S_MB_2U(SCH_1):PAGE164

P5E_CPU0_PE2_TX_DP<6> @S9S_MB_2U_LIB.S9S_MB_2U(SCH_1):P5E_CPU0_PE2_TX_DP(6)
    U2 DH14 PE2_TX_DP6 SOCKET4677_AZIF0045P001C01CS-SA   I139 @S9S_MB_2U_LIB.S9S_MB_2U(SCH_1):PAGE30
  C953    2      2 Q_CAP_DIFFBUS_C0201-DIFF BUS_0A   I134 @S9S_MB_2U_LIB.S9S_MB_2U(SCH_1):PAGE164

P5E_CPU0_PE2_TX_DP<7> @S9S_MB_2U_LIB.S9S_MB_2U(SCH_1):P5E_CPU0_PE2_TX_DP(7)
    U2 DL15 PE2_TX_DP7 SOCKET4677_AZIF0045P001C01CS-SA   I139 @S9S_MB_2U_LIB.S9S_MB_2U(SCH_1):PAGE30
  C951    2      2 Q_CAP_DIFFBUS_C0201-DIFF BUS_0A   I136 @S9S_MB_2U_LIB.S9S_MB_2U(SCH_1):PAGE164

P5E_CPU0_PE2_TX_DP<8> @S9S_MB_2U_LIB.S9S_MB_2U(SCH_1):P5E_CPU0_PE2_TX_DP(8)
    U2 DM14 PE2_TX_DP8 SOCKET4677_AZIF0045P001C01CS-SA   I139 @S9S_MB_2U_LIB.S9S_MB_2U(SCH_1):PAGE30
  C949    2      2 Q_CAP_DIFFBUS_C0201-DIFF BUS_0A   I151 @S9S_MB_2U_LIB.S9S_MB_2U(SCH_1):PAGE164

P5E_CPU0_PE2_TX_DP<9> @S9S_MB_2U_LIB.S9S_MB_2U(SCH_1):P5E_CPU0_PE2_TX_DP(9)
    U2 DR15 PE2_TX_DP9 SOCKET4677_AZIF0045P001C01CS-SA   I139 @S9S_MB_2U_LIB.S9S_MB_2U(SCH_1):PAGE30
  C947    2      2 Q_CAP_DIFFBUS_C0201-DIFF BUS_0A   I153 @S9S_MB_2U_LIB.S9S_MB_2U(SCH_1):PAGE164

P5E_CPU0_PE3_RX_DN<0> @S9S_MB_2U_LIB.S9S_MB_2U(SCH_1):P5E_CPU0_PE3_RX_DN(0)
    U2 EH89 PE3_RX_DN0 SOCKET4677_AZIF0045P001C01CS-SA   I140 @S9S_MB_2U_LIB.S9S_MB_2U(SCH_1):PAGE30
  J105   C8     C8 CONN112_10137002101LF-CONN112_A    I68 @S9S_MB_2U_LIB.S9S_MB_2U(SCH_1):PAGE142

P5E_CPU0_PE3_RX_DN<10> @S9S_MB_2U_LIB.S9S_MB_2U(SCH_1):P5E_CPU0_PE3_RX_DN(10)
    U2 DG90 PE3_RX_DN10 SOCKET4677_AZIF0045P001C01CS-SA   I140 @S9S_MB_2U_LIB.S9S_MB_2U(SCH_1):PAGE30
  J106   B6     B6 CONN112_10137002101LF-CONN112_A    I68 @S9S_MB_2U_LIB.S9S_MB_2U(SCH_1):PAGE144

P5E_CPU0_PE3_RX_DN<11> @S9S_MB_2U_LIB.S9S_MB_2U(SCH_1):P5E_CPU0_PE3_RX_DN(11)
    U2 DD91 PE3_RX_DN11 SOCKET4677_AZIF0045P001C01CS-SA   I140 @S9S_MB_2U_LIB.S9S_MB_2U(SCH_1):PAGE30
  J106   C5     C5 CONN112_10137002101LF-CONN112_A    I68 @S9S_MB_2U_LIB.S9S_MB_2U(SCH_1):PAGE144

P5E_CPU0_PE3_RX_DN<12> @S9S_MB_2U_LIB.S9S_MB_2U(SCH_1):P5E_CPU0_PE3_RX_DN(12)
    U2 DB89 PE3_RX_DN12 SOCKET4677_AZIF0045P001C01CS-SA   I140 @S9S_MB_2U_LIB.S9S_MB_2U(SCH_1):PAGE30
  J106   C4     C4 CONN112_10137002101LF-CONN112_A    I65 @S9S_MB_2U_LIB.S9S_MB_2U(SCH_1):PAGE144

P5E_CPU0_PE3_RX_DN<13> @S9S_MB_2U_LIB.S9S_MB_2U(SCH_1):P5E_CPU0_PE3_RX_DN(13)
    U2 DA90 PE3_RX_DN13 SOCKET4677_AZIF0045P001C01CS-SA   I140 @S9S_MB_2U_LIB.S9S_MB_2U(SCH_1):PAGE30
  J106   D3     D3 CONN112_10137002101LF-CONN112_A    I65 @S9S_MB_2U_LIB.S9S_MB_2U(SCH_1):PAGE144

P5E_CPU0_PE3_RX_DN<14> @S9S_MB_2U_LIB.S9S_MB_2U(SCH_1):P5E_CPU0_PE3_RX_DN(14)
    U2 CV89 PE3_RX_DN14 SOCKET4677_AZIF0045P001C01CS-SA   I140 @S9S_MB_2U_LIB.S9S_MB_2U(SCH_1):PAGE30
  J106   C2     C2 CONN112_10137002101LF-CONN112_A    I65 @S9S_MB_2U_LIB.S9S_MB_2U(SCH_1):PAGE144

P5E_CPU0_PE3_RX_DN<15> @S9S_MB_2U_LIB.S9S_MB_2U(SCH_1):P5E_CPU0_PE3_RX_DN(15)
    U2 CU90 PE3_RX_DN15 SOCKET4677_AZIF0045P001C01CS-SA   I140 @S9S_MB_2U_LIB.S9S_MB_2U(SCH_1):PAGE30
  J106   D1     D1 CONN112_10137002101LF-CONN112_A    I65 @S9S_MB_2U_LIB.S9S_MB_2U(SCH_1):PAGE144

P5E_CPU0_PE3_RX_DN<1> @S9S_MB_2U_LIB.S9S_MB_2U(SCH_1):P5E_CPU0_PE3_RX_DN(1)
    U2 ED91 PE3_RX_DN1 SOCKET4677_AZIF0045P001C01CS-SA   I140 @S9S_MB_2U_LIB.S9S_MB_2U(SCH_1):PAGE30
  J105   C7     C7 CONN112_10137002101LF-CONN112_A    I68 @S9S_MB_2U_LIB.S9S_MB_2U(SCH_1):PAGE142

P5E_CPU0_PE3_RX_DN<2> @S9S_MB_2U_LIB.S9S_MB_2U(SCH_1):P5E_CPU0_PE3_RX_DN(2)
    U2 EC90 PE3_RX_DN2 SOCKET4677_AZIF0045P001C01CS-SA   I140 @S9S_MB_2U_LIB.S9S_MB_2U(SCH_1):PAGE30
  J105   B6     B6 CONN112_10137002101LF-CONN112_A    I68 @S9S_MB_2U_LIB.S9S_MB_2U(SCH_1):PAGE142

P5E_CPU0_PE3_RX_DN<3> @S9S_MB_2U_LIB.S9S_MB_2U(SCH_1):P5E_CPU0_PE3_RX_DN(3)
    U2 DY91 PE3_RX_DN3 SOCKET4677_AZIF0045P001C01CS-SA   I140 @S9S_MB_2U_LIB.S9S_MB_2U(SCH_1):PAGE30
  J105   C5     C5 CONN112_10137002101LF-CONN112_A    I68 @S9S_MB_2U_LIB.S9S_MB_2U(SCH_1):PAGE142

P5E_CPU0_PE3_RX_DN<4> @S9S_MB_2U_LIB.S9S_MB_2U(SCH_1):P5E_CPU0_PE3_RX_DN(4)
    U2 DV89 PE3_RX_DN4 SOCKET4677_AZIF0045P001C01CS-SA   I140 @S9S_MB_2U_LIB.S9S_MB_2U(SCH_1):PAGE30
  J105   C4     C4 CONN112_10137002101LF-CONN112_A    I65 @S9S_MB_2U_LIB.S9S_MB_2U(SCH_1):PAGE142

P5E_CPU0_PE3_RX_DN<5> @S9S_MB_2U_LIB.S9S_MB_2U(SCH_1):P5E_CPU0_PE3_RX_DN(5)
    U2 DU90 PE3_RX_DN5 SOCKET4677_AZIF0045P001C01CS-SA   I140 @S9S_MB_2U_LIB.S9S_MB_2U(SCH_1):PAGE30
  J105   D3     D3 CONN112_10137002101LF-CONN112_A    I65 @S9S_MB_2U_LIB.S9S_MB_2U(SCH_1):PAGE142

P5E_CPU0_PE3_RX_DN<6> @S9S_MB_2U_LIB.S9S_MB_2U(SCH_1):P5E_CPU0_PE3_RX_DN(6)
    U2 DP89 PE3_RX_DN6 SOCKET4677_AZIF0045P001C01CS-SA   I140 @S9S_MB_2U_LIB.S9S_MB_2U(SCH_1):PAGE30
  J105   C2     C2 CONN112_10137002101LF-CONN112_A    I65 @S9S_MB_2U_LIB.S9S_MB_2U(SCH_1):PAGE142

P5E_CPU0_PE3_RX_DN<7> @S9S_MB_2U_LIB.S9S_MB_2U(SCH_1):P5E_CPU0_PE3_RX_DN(7)
    U2 DN90 PE3_RX_DN7 SOCKET4677_AZIF0045P001C01CS-SA   I140 @S9S_MB_2U_LIB.S9S_MB_2U(SCH_1):PAGE30
  J105   D1     D1 CONN112_10137002101LF-CONN112_A    I65 @S9S_MB_2U_LIB.S9S_MB_2U(SCH_1):PAGE142

P5E_CPU0_PE3_RX_DN<8> @S9S_MB_2U_LIB.S9S_MB_2U(SCH_1):P5E_CPU0_PE3_RX_DN(8)
    U2 DL90 PE3_RX_DN8 SOCKET4677_AZIF0045P001C01CS-SA   I140 @S9S_MB_2U_LIB.S9S_MB_2U(SCH_1):PAGE30
  J106   B8     B8 CONN112_10137002101LF-CONN112_A    I68 @S9S_MB_2U_LIB.S9S_MB_2U(SCH_1):PAGE144

P5E_CPU0_PE3_RX_DN<9> @S9S_MB_2U_LIB.S9S_MB_2U(SCH_1):P5E_CPU0_PE3_RX_DN(9)
    U2 DH91 PE3_RX_DN9 SOCKET4677_AZIF0045P001C01CS-SA   I140 @S9S_MB_2U_LIB.S9S_MB_2U(SCH_1):PAGE30
  J106   C7     C7 CONN112_10137002101LF-CONN112_A    I68 @S9S_MB_2U_LIB.S9S_MB_2U(SCH_1):PAGE144

P5E_CPU0_PE3_RX_DP<0> @S9S_MB_2U_LIB.S9S_MB_2U(SCH_1):P5E_CPU0_PE3_RX_DP(0)
    U2 EJ90 PE3_RX_DP0 SOCKET4677_AZIF0045P001C01CS-SA   I140 @S9S_MB_2U_LIB.S9S_MB_2U(SCH_1):PAGE30
  J105   B8     B8 CONN112_10137002101LF-CONN112_A    I68 @S9S_MB_2U_LIB.S9S_MB_2U(SCH_1):PAGE142

P5E_CPU0_PE3_RX_DP<10> @S9S_MB_2U_LIB.S9S_MB_2U(SCH_1):P5E_CPU0_PE3_RX_DP(10)
    U2 DF89 PE3_RX_DP10 SOCKET4677_AZIF0045P001C01CS-SA   I140 @S9S_MB_2U_LIB.S9S_MB_2U(SCH_1):PAGE30
  J106   C6     C6 CONN112_10137002101LF-CONN112_A    I68 @S9S_MB_2U_LIB.S9S_MB_2U(SCH_1):PAGE144

P5E_CPU0_PE3_RX_DP<11> @S9S_MB_2U_LIB.S9S_MB_2U(SCH_1):P5E_CPU0_PE3_RX_DP(11)
    U2 DE90 PE3_RX_DP11 SOCKET4677_AZIF0045P001C01CS-SA   I140 @S9S_MB_2U_LIB.S9S_MB_2U(SCH_1):PAGE30
  J106   D5     D5 CONN112_10137002101LF-CONN112_A    I68 @S9S_MB_2U_LIB.S9S_MB_2U(SCH_1):PAGE144

P5E_CPU0_PE3_RX_DP<12> @S9S_MB_2U_LIB.S9S_MB_2U(SCH_1):P5E_CPU0_PE3_RX_DP(12)
    U2 DC90 PE3_RX_DP12 SOCKET4677_AZIF0045P001C01CS-SA   I140 @S9S_MB_2U_LIB.S9S_MB_2U(SCH_1):PAGE30
  J106   B4     B4 CONN112_10137002101LF-CONN112_A    I65 @S9S_MB_2U_LIB.S9S_MB_2U(SCH_1):PAGE144

P5E_CPU0_PE3_RX_DP<13> @S9S_MB_2U_LIB.S9S_MB_2U(SCH_1):P5E_CPU0_PE3_RX_DP(13)
    U2 CY91 PE3_RX_DP13 SOCKET4677_AZIF0045P001C01CS-SA   I140 @S9S_MB_2U_LIB.S9S_MB_2U(SCH_1):PAGE30
  J106   C3     C3 CONN112_10137002101LF-CONN112_A    I65 @S9S_MB_2U_LIB.S9S_MB_2U(SCH_1):PAGE144

P5E_CPU0_PE3_RX_DP<14> @S9S_MB_2U_LIB.S9S_MB_2U(SCH_1):P5E_CPU0_PE3_RX_DP(14)
    U2 CW90 PE3_RX_DP14 SOCKET4677_AZIF0045P001C01CS-SA   I140 @S9S_MB_2U_LIB.S9S_MB_2U(SCH_1):PAGE30
  J106   B2     B2 CONN112_10137002101LF-CONN112_A    I65 @S9S_MB_2U_LIB.S9S_MB_2U(SCH_1):PAGE144

P5E_CPU0_PE3_RX_DP<15> @S9S_MB_2U_LIB.S9S_MB_2U(SCH_1):P5E_CPU0_PE3_RX_DP(15)
    U2 CT91 PE3_RX_DP15 SOCKET4677_AZIF0045P001C01CS-SA   I140 @S9S_MB_2U_LIB.S9S_MB_2U(SCH_1):PAGE30
  J106   C1     C1 CONN112_10137002101LF-CONN112_A    I65 @S9S_MB_2U_LIB.S9S_MB_2U(SCH_1):PAGE144

P5E_CPU0_PE3_RX_DP<1> @S9S_MB_2U_LIB.S9S_MB_2U(SCH_1):P5E_CPU0_PE3_RX_DP(1)
    U2 EE90 PE3_RX_DP1 SOCKET4677_AZIF0045P001C01CS-SA   I140 @S9S_MB_2U_LIB.S9S_MB_2U(SCH_1):PAGE30
  J105   D7     D7 CONN112_10137002101LF-CONN112_A    I68 @S9S_MB_2U_LIB.S9S_MB_2U(SCH_1):PAGE142

P5E_CPU0_PE3_RX_DP<2> @S9S_MB_2U_LIB.S9S_MB_2U(SCH_1):P5E_CPU0_PE3_RX_DP(2)
    U2 EB89 PE3_RX_DP2 SOCKET4677_AZIF0045P001C01CS-SA   I140 @S9S_MB_2U_LIB.S9S_MB_2U(SCH_1):PAGE30
  J105   C6     C6 CONN112_10137002101LF-CONN112_A    I68 @S9S_MB_2U_LIB.S9S_MB_2U(SCH_1):PAGE142

P5E_CPU0_PE3_RX_DP<3> @S9S_MB_2U_LIB.S9S_MB_2U(SCH_1):P5E_CPU0_PE3_RX_DP(3)
    U2 EA90 PE3_RX_DP3 SOCKET4677_AZIF0045P001C01CS-SA   I140 @S9S_MB_2U_LIB.S9S_MB_2U(SCH_1):PAGE30
  J105   D5     D5 CONN112_10137002101LF-CONN112_A    I68 @S9S_MB_2U_LIB.S9S_MB_2U(SCH_1):PAGE142

P5E_CPU0_PE3_RX_DP<4> @S9S_MB_2U_LIB.S9S_MB_2U(SCH_1):P5E_CPU0_PE3_RX_DP(4)
    U2 DW90 PE3_RX_DP4 SOCKET4677_AZIF0045P001C01CS-SA   I140 @S9S_MB_2U_LIB.S9S_MB_2U(SCH_1):PAGE30
  J105   B4     B4 CONN112_10137002101LF-CONN112_A    I65 @S9S_MB_2U_LIB.S9S_MB_2U(SCH_1):PAGE142

P5E_CPU0_PE3_RX_DP<5> @S9S_MB_2U_LIB.S9S_MB_2U(SCH_1):P5E_CPU0_PE3_RX_DP(5)
    U2 DT91 PE3_RX_DP5 SOCKET4677_AZIF0045P001C01CS-SA   I140 @S9S_MB_2U_LIB.S9S_MB_2U(SCH_1):PAGE30
  J105   C3     C3 CONN112_10137002101LF-CONN112_A    I65 @S9S_MB_2U_LIB.S9S_MB_2U(SCH_1):PAGE142

P5E_CPU0_PE3_RX_DP<6> @S9S_MB_2U_LIB.S9S_MB_2U(SCH_1):P5E_CPU0_PE3_RX_DP(6)
    U2 DR90 PE3_RX_DP6 SOCKET4677_AZIF0045P001C01CS-SA   I140 @S9S_MB_2U_LIB.S9S_MB_2U(SCH_1):PAGE30
  J105   B2     B2 CONN112_10137002101LF-CONN112_A    I65 @S9S_MB_2U_LIB.S9S_MB_2U(SCH_1):PAGE142

P5E_CPU0_PE3_RX_DP<7> @S9S_MB_2U_LIB.S9S_MB_2U(SCH_1):P5E_CPU0_PE3_RX_DP(7)
    U2 DM91 PE3_RX_DP7 SOCKET4677_AZIF0045P001C01CS-SA   I140 @S9S_MB_2U_LIB.S9S_MB_2U(SCH_1):PAGE30
  J105   C1     C1 CONN112_10137002101LF-CONN112_A    I65 @S9S_MB_2U_LIB.S9S_MB_2U(SCH_1):PAGE142

P5E_CPU0_PE3_RX_DP<8> @S9S_MB_2U_LIB.S9S_MB_2U(SCH_1):P5E_CPU0_PE3_RX_DP(8)
    U2 DK89 PE3_RX_DP8 SOCKET4677_AZIF0045P001C01CS-SA   I140 @S9S_MB_2U_LIB.S9S_MB_2U(SCH_1):PAGE30
  J106   C8     C8 CONN112_10137002101LF-CONN112_A    I68 @S9S_MB_2U_LIB.S9S_MB_2U(SCH_1):PAGE144

P5E_CPU0_PE3_RX_DP<9> @S9S_MB_2U_LIB.S9S_MB_2U(SCH_1):P5E_CPU0_PE3_RX_DP(9)
    U2 DJ90 PE3_RX_DP9 SOCKET4677_AZIF0045P001C01CS-SA   I140 @S9S_MB_2U_LIB.S9S_MB_2U(SCH_1):PAGE30
  J106   D7     D7 CONN112_10137002101LF-CONN112_A    I68 @S9S_MB_2U_LIB.S9S_MB_2U(SCH_1):PAGE144

P5E_CPU0_PE3_TX_C_DN<0> @S9S_MB_2U_LIB.S9S_MB_2U(SCH_1):P5E_CPU0_PE3_TX_C_DN(0)
  C900    1      1 Q_CAP_DIFFBUS_C0201-DIFF BUS_0A   I121 @S9S_MB_2U_LIB.S9S_MB_2U(SCH_1):PAGE165
  J105   I8     I8 CONN112_10137002101LF-CONN112_A    I68 @S9S_MB_2U_LIB.S9S_MB_2U(SCH_1):PAGE142

P5E_CPU0_PE3_TX_C_DN<10> @S9S_MB_2U_LIB.S9S_MB_2U(SCH_1):P5E_CPU0_PE3_TX_C_DN(10)
  C880    1      1 Q_CAP_DIFFBUS_C0201-DIFF BUS_0A   I156 @S9S_MB_2U_LIB.S9S_MB_2U(SCH_1):PAGE165
  J106   H6     H6 CONN112_10137002101LF-CONN112_A    I68 @S9S_MB_2U_LIB.S9S_MB_2U(SCH_1):PAGE144

P5E_CPU0_PE3_TX_C_DN<11> @S9S_MB_2U_LIB.S9S_MB_2U(SCH_1):P5E_CPU0_PE3_TX_C_DN(11)
  C878    1      1 Q_CAP_DIFFBUS_C0201-DIFF BUS_0A   I157 @S9S_MB_2U_LIB.S9S_MB_2U(SCH_1):PAGE165
  J106   I5     I5 CONN112_10137002101LF-CONN112_A    I68 @S9S_MB_2U_LIB.S9S_MB_2U(SCH_1):PAGE144

P5E_CPU0_PE3_TX_C_DN<12> @S9S_MB_2U_LIB.S9S_MB_2U(SCH_1):P5E_CPU0_PE3_TX_C_DN(12)
  C876    1      1 Q_CAP_DIFFBUS_C0201-DIFF BUS_0A   I160 @S9S_MB_2U_LIB.S9S_MB_2U(SCH_1):PAGE165
  J106   H4     H4 CONN112_10137002101LF-CONN112_A    I65 @S9S_MB_2U_LIB.S9S_MB_2U(SCH_1):PAGE144

P5E_CPU0_PE3_TX_C_DN<13> @S9S_MB_2U_LIB.S9S_MB_2U(SCH_1):P5E_CPU0_PE3_TX_C_DN(13)
  C874    1      1 Q_CAP_DIFFBUS_C0201-DIFF BUS_0A   I165 @S9S_MB_2U_LIB.S9S_MB_2U(SCH_1):PAGE165
  J106   I3     I3 CONN112_10137002101LF-CONN112_A    I65 @S9S_MB_2U_LIB.S9S_MB_2U(SCH_1):PAGE144

P5E_CPU0_PE3_TX_C_DN<14> @S9S_MB_2U_LIB.S9S_MB_2U(SCH_1):P5E_CPU0_PE3_TX_C_DN(14)
  C872    1      1 Q_CAP_DIFFBUS_C0201-DIFF BUS_0A   I167 @S9S_MB_2U_LIB.S9S_MB_2U(SCH_1):PAGE165
  J106   H2     H2 CONN112_10137002101LF-CONN112_A    I65 @S9S_MB_2U_LIB.S9S_MB_2U(SCH_1):PAGE144

P5E_CPU0_PE3_TX_C_DN<15> @S9S_MB_2U_LIB.S9S_MB_2U(SCH_1):P5E_CPU0_PE3_TX_C_DN(15)
  C870    1      1 Q_CAP_DIFFBUS_C0201-DIFF BUS_0A   I169 @S9S_MB_2U_LIB.S9S_MB_2U(SCH_1):PAGE165
  J106   I1     I1 CONN112_10137002101LF-CONN112_A    I65 @S9S_MB_2U_LIB.S9S_MB_2U(SCH_1):PAGE144

P5E_CPU0_PE3_TX_C_DN<1> @S9S_MB_2U_LIB.S9S_MB_2U(SCH_1):P5E_CPU0_PE3_TX_C_DN(1)
  C898    1      1 Q_CAP_DIFFBUS_C0201-DIFF BUS_0A   I206 @S9S_MB_2U_LIB.S9S_MB_2U(SCH_1):PAGE165
  J105   I7     I7 CONN112_10137002101LF-CONN112_A    I68 @S9S_MB_2U_LIB.S9S_MB_2U(SCH_1):PAGE142

P5E_CPU0_PE3_TX_C_DN<2> @S9S_MB_2U_LIB.S9S_MB_2U(SCH_1):P5E_CPU0_PE3_TX_C_DN(2)
  C896    1      1 Q_CAP_DIFFBUS_C0201-DIFF BUS_0A   I124 @S9S_MB_2U_LIB.S9S_MB_2U(SCH_1):PAGE165
  J105   H6     H6 CONN112_10137002101LF-CONN112_A    I68 @S9S_MB_2U_LIB.S9S_MB_2U(SCH_1):PAGE142

P5E_CPU0_PE3_TX_C_DN<3> @S9S_MB_2U_LIB.S9S_MB_2U(SCH_1):P5E_CPU0_PE3_TX_C_DN(3)
  C894    1      1 Q_CAP_DIFFBUS_C0201-DIFF BUS_0A   I126 @S9S_MB_2U_LIB.S9S_MB_2U(SCH_1):PAGE165
  J105   I5     I5 CONN112_10137002101LF-CONN112_A    I68 @S9S_MB_2U_LIB.S9S_MB_2U(SCH_1):PAGE142

P5E_CPU0_PE3_TX_C_DN<4> @S9S_MB_2U_LIB.S9S_MB_2U(SCH_1):P5E_CPU0_PE3_TX_C_DN(4)
  C892    1      1 Q_CAP_DIFFBUS_C0201-DIFF BUS_0A   I127 @S9S_MB_2U_LIB.S9S_MB_2U(SCH_1):PAGE165
  J105   H4     H4 CONN112_10137002101LF-CONN112_A    I65 @S9S_MB_2U_LIB.S9S_MB_2U(SCH_1):PAGE142

P5E_CPU0_PE3_TX_C_DN<5> @S9S_MB_2U_LIB.S9S_MB_2U(SCH_1):P5E_CPU0_PE3_TX_C_DN(5)
  C890    1      1 Q_CAP_DIFFBUS_C0201-DIFF BUS_0A   I133 @S9S_MB_2U_LIB.S9S_MB_2U(SCH_1):PAGE165
  J105   I3     I3 CONN112_10137002101LF-CONN112_A    I65 @S9S_MB_2U_LIB.S9S_MB_2U(SCH_1):PAGE142

P5E_CPU0_PE3_TX_C_DN<6> @S9S_MB_2U_LIB.S9S_MB_2U(SCH_1):P5E_CPU0_PE3_TX_C_DN(6)
  C888    1      1 Q_CAP_DIFFBUS_C0201-DIFF BUS_0A   I135 @S9S_MB_2U_LIB.S9S_MB_2U(SCH_1):PAGE165
  J105   H2     H2 CONN112_10137002101LF-CONN112_A    I65 @S9S_MB_2U_LIB.S9S_MB_2U(SCH_1):PAGE142

P5E_CPU0_PE3_TX_C_DN<7> @S9S_MB_2U_LIB.S9S_MB_2U(SCH_1):P5E_CPU0_PE3_TX_C_DN(7)
  C886    1      1 Q_CAP_DIFFBUS_C0201-DIFF BUS_0A   I137 @S9S_MB_2U_LIB.S9S_MB_2U(SCH_1):PAGE165
  J105   I1     I1 CONN112_10137002101LF-CONN112_A    I65 @S9S_MB_2U_LIB.S9S_MB_2U(SCH_1):PAGE142

P5E_CPU0_PE3_TX_C_DN<8> @S9S_MB_2U_LIB.S9S_MB_2U(SCH_1):P5E_CPU0_PE3_TX_C_DN(8)
  C884    1      1 Q_CAP_DIFFBUS_C0201-DIFF BUS_0A   I151 @S9S_MB_2U_LIB.S9S_MB_2U(SCH_1):PAGE165
  J106   H8     H8 CONN112_10137002101LF-CONN112_A    I68 @S9S_MB_2U_LIB.S9S_MB_2U(SCH_1):PAGE144

P5E_CPU0_PE3_TX_C_DN<9> @S9S_MB_2U_LIB.S9S_MB_2U(SCH_1):P5E_CPU0_PE3_TX_C_DN(9)
  C882    1      1 Q_CAP_DIFFBUS_C0201-DIFF BUS_0A   I154 @S9S_MB_2U_LIB.S9S_MB_2U(SCH_1):PAGE165
  J106   I7     I7 CONN112_10137002101LF-CONN112_A    I68 @S9S_MB_2U_LIB.S9S_MB_2U(SCH_1):PAGE144

P5E_CPU0_PE3_TX_C_DP<0> @S9S_MB_2U_LIB.S9S_MB_2U(SCH_1):P5E_CPU0_PE3_TX_C_DP(0)
  C901    1      1 Q_CAP_DIFFBUS_C0201-DIFF BUS_0A   I120 @S9S_MB_2U_LIB.S9S_MB_2U(SCH_1):PAGE165
  J105   H8     H8 CONN112_10137002101LF-CONN112_A    I68 @S9S_MB_2U_LIB.S9S_MB_2U(SCH_1):PAGE142

P5E_CPU0_PE3_TX_C_DP<10> @S9S_MB_2U_LIB.S9S_MB_2U(SCH_1):P5E_CPU0_PE3_TX_C_DP(10)
  C881    1      1 Q_CAP_DIFFBUS_C0201-DIFF BUS_0A   I155 @S9S_MB_2U_LIB.S9S_MB_2U(SCH_1):PAGE165
  J106   I6     I6 CONN112_10137002101LF-CONN112_A    I68 @S9S_MB_2U_LIB.S9S_MB_2U(SCH_1):PAGE144

P5E_CPU0_PE3_TX_C_DP<11> @S9S_MB_2U_LIB.S9S_MB_2U(SCH_1):P5E_CPU0_PE3_TX_C_DP(11)
  C879    1      1 Q_CAP_DIFFBUS_C0201-DIFF BUS_0A   I158 @S9S_MB_2U_LIB.S9S_MB_2U(SCH_1):PAGE165
  J106   J5     J5 CONN112_10137002101LF-CONN112_A    I68 @S9S_MB_2U_LIB.S9S_MB_2U(SCH_1):PAGE144

P5E_CPU0_PE3_TX_C_DP<12> @S9S_MB_2U_LIB.S9S_MB_2U(SCH_1):P5E_CPU0_PE3_TX_C_DP(12)
  C877    1      1 Q_CAP_DIFFBUS_C0201-DIFF BUS_0A   I159 @S9S_MB_2U_LIB.S9S_MB_2U(SCH_1):PAGE165
  J106   I4     I4 CONN112_10137002101LF-CONN112_A    I65 @S9S_MB_2U_LIB.S9S_MB_2U(SCH_1):PAGE144

P5E_CPU0_PE3_TX_C_DP<13> @S9S_MB_2U_LIB.S9S_MB_2U(SCH_1):P5E_CPU0_PE3_TX_C_DP(13)
  C875    1      1 Q_CAP_DIFFBUS_C0201-DIFF BUS_0A   I164 @S9S_MB_2U_LIB.S9S_MB_2U(SCH_1):PAGE165
  J106   J3     J3 CONN112_10137002101LF-CONN112_A    I65 @S9S_MB_2U_LIB.S9S_MB_2U(SCH_1):PAGE144

P5E_CPU0_PE3_TX_C_DP<14> @S9S_MB_2U_LIB.S9S_MB_2U(SCH_1):P5E_CPU0_PE3_TX_C_DP(14)
  C873    1      1 Q_CAP_DIFFBUS_C0201-DIFF BUS_0A   I166 @S9S_MB_2U_LIB.S9S_MB_2U(SCH_1):PAGE165
  J106   I2     I2 CONN112_10137002101LF-CONN112_A    I65 @S9S_MB_2U_LIB.S9S_MB_2U(SCH_1):PAGE144

P5E_CPU0_PE3_TX_C_DP<15> @S9S_MB_2U_LIB.S9S_MB_2U(SCH_1):P5E_CPU0_PE3_TX_C_DP(15)
  C871    1      1 Q_CAP_DIFFBUS_C0201-DIFF BUS_0A   I168 @S9S_MB_2U_LIB.S9S_MB_2U(SCH_1):PAGE165
  J106   J1     J1 CONN112_10137002101LF-CONN112_A    I65 @S9S_MB_2U_LIB.S9S_MB_2U(SCH_1):PAGE144

P5E_CPU0_PE3_TX_C_DP<1> @S9S_MB_2U_LIB.S9S_MB_2U(SCH_1):P5E_CPU0_PE3_TX_C_DP(1)
  C899    1      1 Q_CAP_DIFFBUS_C0201-DIFF BUS_0A   I122 @S9S_MB_2U_LIB.S9S_MB_2U(SCH_1):PAGE165
  J105   J7     J7 CONN112_10137002101LF-CONN112_A    I68 @S9S_MB_2U_LIB.S9S_MB_2U(SCH_1):PAGE142

P5E_CPU0_PE3_TX_C_DP<2> @S9S_MB_2U_LIB.S9S_MB_2U(SCH_1):P5E_CPU0_PE3_TX_C_DP(2)
  C897    1      1 Q_CAP_DIFFBUS_C0201-DIFF BUS_0A   I123 @S9S_MB_2U_LIB.S9S_MB_2U(SCH_1):PAGE165
  J105   I6     I6 CONN112_10137002101LF-CONN112_A    I68 @S9S_MB_2U_LIB.S9S_MB_2U(SCH_1):PAGE142

P5E_CPU0_PE3_TX_C_DP<3> @S9S_MB_2U_LIB.S9S_MB_2U(SCH_1):P5E_CPU0_PE3_TX_C_DP(3)
  C895    1      1 Q_CAP_DIFFBUS_C0201-DIFF BUS_0A   I125 @S9S_MB_2U_LIB.S9S_MB_2U(SCH_1):PAGE165
  J105   J5     J5 CONN112_10137002101LF-CONN112_A    I68 @S9S_MB_2U_LIB.S9S_MB_2U(SCH_1):PAGE142

P5E_CPU0_PE3_TX_C_DP<4> @S9S_MB_2U_LIB.S9S_MB_2U(SCH_1):P5E_CPU0_PE3_TX_C_DP(4)
  C893    1      1 Q_CAP_DIFFBUS_C0201-DIFF BUS_0A   I128 @S9S_MB_2U_LIB.S9S_MB_2U(SCH_1):PAGE165
  J105   I4     I4 CONN112_10137002101LF-CONN112_A    I65 @S9S_MB_2U_LIB.S9S_MB_2U(SCH_1):PAGE142

P5E_CPU0_PE3_TX_C_DP<5> @S9S_MB_2U_LIB.S9S_MB_2U(SCH_1):P5E_CPU0_PE3_TX_C_DP(5)
  C891    1      1 Q_CAP_DIFFBUS_C0201-DIFF BUS_0A   I132 @S9S_MB_2U_LIB.S9S_MB_2U(SCH_1):PAGE165
  J105   J3     J3 CONN112_10137002101LF-CONN112_A    I65 @S9S_MB_2U_LIB.S9S_MB_2U(SCH_1):PAGE142

P5E_CPU0_PE3_TX_C_DP<6> @S9S_MB_2U_LIB.S9S_MB_2U(SCH_1):P5E_CPU0_PE3_TX_C_DP(6)
  C889    1      1 Q_CAP_DIFFBUS_C0201-DIFF BUS_0A   I134 @S9S_MB_2U_LIB.S9S_MB_2U(SCH_1):PAGE165
  J105   I2     I2 CONN112_10137002101LF-CONN112_A    I65 @S9S_MB_2U_LIB.S9S_MB_2U(SCH_1):PAGE142

P5E_CPU0_PE3_TX_C_DP<7> @S9S_MB_2U_LIB.S9S_MB_2U(SCH_1):P5E_CPU0_PE3_TX_C_DP(7)
  C887    1      1 Q_CAP_DIFFBUS_C0201-DIFF BUS_0A   I136 @S9S_MB_2U_LIB.S9S_MB_2U(SCH_1):PAGE165
  J105   J1     J1 CONN112_10137002101LF-CONN112_A    I65 @S9S_MB_2U_LIB.S9S_MB_2U(SCH_1):PAGE142

P5E_CPU0_PE3_TX_C_DP<8> @S9S_MB_2U_LIB.S9S_MB_2U(SCH_1):P5E_CPU0_PE3_TX_C_DP(8)
  C885    1      1 Q_CAP_DIFFBUS_C0201-DIFF BUS_0A   I152 @S9S_MB_2U_LIB.S9S_MB_2U(SCH_1):PAGE165
  J106   I8     I8 CONN112_10137002101LF-CONN112_A    I68 @S9S_MB_2U_LIB.S9S_MB_2U(SCH_1):PAGE144

P5E_CPU0_PE3_TX_C_DP<9> @S9S_MB_2U_LIB.S9S_MB_2U(SCH_1):P5E_CPU0_PE3_TX_C_DP(9)
  C883    1      1 Q_CAP_DIFFBUS_C0201-DIFF BUS_0A   I153 @S9S_MB_2U_LIB.S9S_MB_2U(SCH_1):PAGE165
  J106   J7     J7 CONN112_10137002101LF-CONN112_A    I68 @S9S_MB_2U_LIB.S9S_MB_2U(SCH_1):PAGE144

P5E_CPU0_PE3_TX_DN<0> @S9S_MB_2U_LIB.S9S_MB_2U(SCH_1):P5E_CPU0_PE3_TX_DN(0)
    U2 EE86 PE3_TX_DN0 SOCKET4677_AZIF0045P001C01CS-SA   I140 @S9S_MB_2U_LIB.S9S_MB_2U(SCH_1):PAGE30
  C900    2      2 Q_CAP_DIFFBUS_C0201-DIFF BUS_0A   I121 @S9S_MB_2U_LIB.S9S_MB_2U(SCH_1):PAGE165

P5E_CPU0_PE3_TX_DN<10> @S9S_MB_2U_LIB.S9S_MB_2U(SCH_1):P5E_CPU0_PE3_TX_DN(10)
    U2 DD87 PE3_TX_DN10 SOCKET4677_AZIF0045P001C01CS-SA   I140 @S9S_MB_2U_LIB.S9S_MB_2U(SCH_1):PAGE30
  C880    2      2 Q_CAP_DIFFBUS_C0201-DIFF BUS_0A   I156 @S9S_MB_2U_LIB.S9S_MB_2U(SCH_1):PAGE165

P5E_CPU0_PE3_TX_DN<11> @S9S_MB_2U_LIB.S9S_MB_2U(SCH_1):P5E_CPU0_PE3_TX_DN(11)
    U2 DB85 PE3_TX_DN11 SOCKET4677_AZIF0045P001C01CS-SA   I140 @S9S_MB_2U_LIB.S9S_MB_2U(SCH_1):PAGE30
  C878    2      2 Q_CAP_DIFFBUS_C0201-DIFF BUS_0A   I157 @S9S_MB_2U_LIB.S9S_MB_2U(SCH_1):PAGE165

P5E_CPU0_PE3_TX_DN<12> @S9S_MB_2U_LIB.S9S_MB_2U(SCH_1):P5E_CPU0_PE3_TX_DN(12)
    U2 CY87 PE3_TX_DN12 SOCKET4677_AZIF0045P001C01CS-SA   I140 @S9S_MB_2U_LIB.S9S_MB_2U(SCH_1):PAGE30
  C876    2      2 Q_CAP_DIFFBUS_C0201-DIFF BUS_0A   I160 @S9S_MB_2U_LIB.S9S_MB_2U(SCH_1):PAGE165

P5E_CPU0_PE3_TX_DN<13> @S9S_MB_2U_LIB.S9S_MB_2U(SCH_1):P5E_CPU0_PE3_TX_DN(13)
    U2 CV85 PE3_TX_DN13 SOCKET4677_AZIF0045P001C01CS-SA   I140 @S9S_MB_2U_LIB.S9S_MB_2U(SCH_1):PAGE30
  C874    2      2 Q_CAP_DIFFBUS_C0201-DIFF BUS_0A   I165 @S9S_MB_2U_LIB.S9S_MB_2U(SCH_1):PAGE165

P5E_CPU0_PE3_TX_DN<14> @S9S_MB_2U_LIB.S9S_MB_2U(SCH_1):P5E_CPU0_PE3_TX_DN(14)
    U2 CT87 PE3_TX_DN14 SOCKET4677_AZIF0045P001C01CS-SA   I140 @S9S_MB_2U_LIB.S9S_MB_2U(SCH_1):PAGE30
  C872    2      2 Q_CAP_DIFFBUS_C0201-DIFF BUS_0A   I167 @S9S_MB_2U_LIB.S9S_MB_2U(SCH_1):PAGE165

P5E_CPU0_PE3_TX_DN<15> @S9S_MB_2U_LIB.S9S_MB_2U(SCH_1):P5E_CPU0_PE3_TX_DN(15)
    U2 CP85 PE3_TX_DN15 SOCKET4677_AZIF0045P001C01CS-SA   I140 @S9S_MB_2U_LIB.S9S_MB_2U(SCH_1):PAGE30
  C870    2      2 Q_CAP_DIFFBUS_C0201-DIFF BUS_0A   I169 @S9S_MB_2U_LIB.S9S_MB_2U(SCH_1):PAGE165

P5E_CPU0_PE3_TX_DN<1> @S9S_MB_2U_LIB.S9S_MB_2U(SCH_1):P5E_CPU0_PE3_TX_DN(1)
    U2 EB85 PE3_TX_DN1 SOCKET4677_AZIF0045P001C01CS-SA   I140 @S9S_MB_2U_LIB.S9S_MB_2U(SCH_1):PAGE30
  C898    2      2 Q_CAP_DIFFBUS_C0201-DIFF BUS_0A   I206 @S9S_MB_2U_LIB.S9S_MB_2U(SCH_1):PAGE165

P5E_CPU0_PE3_TX_DN<2> @S9S_MB_2U_LIB.S9S_MB_2U(SCH_1):P5E_CPU0_PE3_TX_DN(2)
    U2 DY87 PE3_TX_DN2 SOCKET4677_AZIF0045P001C01CS-SA   I140 @S9S_MB_2U_LIB.S9S_MB_2U(SCH_1):PAGE30
  C896    2      2 Q_CAP_DIFFBUS_C0201-DIFF BUS_0A   I124 @S9S_MB_2U_LIB.S9S_MB_2U(SCH_1):PAGE165

P5E_CPU0_PE3_TX_DN<3> @S9S_MB_2U_LIB.S9S_MB_2U(SCH_1):P5E_CPU0_PE3_TX_DN(3)
    U2 DV85 PE3_TX_DN3 SOCKET4677_AZIF0045P001C01CS-SA   I140 @S9S_MB_2U_LIB.S9S_MB_2U(SCH_1):PAGE30
  C894    2      2 Q_CAP_DIFFBUS_C0201-DIFF BUS_0A   I126 @S9S_MB_2U_LIB.S9S_MB_2U(SCH_1):PAGE165

P5E_CPU0_PE3_TX_DN<4> @S9S_MB_2U_LIB.S9S_MB_2U(SCH_1):P5E_CPU0_PE3_TX_DN(4)
    U2 DT87 PE3_TX_DN4 SOCKET4677_AZIF0045P001C01CS-SA   I140 @S9S_MB_2U_LIB.S9S_MB_2U(SCH_1):PAGE30
  C892    2      2 Q_CAP_DIFFBUS_C0201-DIFF BUS_0A   I127 @S9S_MB_2U_LIB.S9S_MB_2U(SCH_1):PAGE165

P5E_CPU0_PE3_TX_DN<5> @S9S_MB_2U_LIB.S9S_MB_2U(SCH_1):P5E_CPU0_PE3_TX_DN(5)
    U2 DP85 PE3_TX_DN5 SOCKET4677_AZIF0045P001C01CS-SA   I140 @S9S_MB_2U_LIB.S9S_MB_2U(SCH_1):PAGE30
  C890    2      2 Q_CAP_DIFFBUS_C0201-DIFF BUS_0A   I133 @S9S_MB_2U_LIB.S9S_MB_2U(SCH_1):PAGE165

P5E_CPU0_PE3_TX_DN<6> @S9S_MB_2U_LIB.S9S_MB_2U(SCH_1):P5E_CPU0_PE3_TX_DN(6)
    U2 DM87 PE3_TX_DN6 SOCKET4677_AZIF0045P001C01CS-SA   I140 @S9S_MB_2U_LIB.S9S_MB_2U(SCH_1):PAGE30
  C888    2      2 Q_CAP_DIFFBUS_C0201-DIFF BUS_0A   I135 @S9S_MB_2U_LIB.S9S_MB_2U(SCH_1):PAGE165

P5E_CPU0_PE3_TX_DN<7> @S9S_MB_2U_LIB.S9S_MB_2U(SCH_1):P5E_CPU0_PE3_TX_DN(7)
    U2 DK85 PE3_TX_DN7 SOCKET4677_AZIF0045P001C01CS-SA   I140 @S9S_MB_2U_LIB.S9S_MB_2U(SCH_1):PAGE30
  C886    2      2 Q_CAP_DIFFBUS_C0201-DIFF BUS_0A   I137 @S9S_MB_2U_LIB.S9S_MB_2U(SCH_1):PAGE165

P5E_CPU0_PE3_TX_DN<8> @S9S_MB_2U_LIB.S9S_MB_2U(SCH_1):P5E_CPU0_PE3_TX_DN(8)
    U2 DH87 PE3_TX_DN8 SOCKET4677_AZIF0045P001C01CS-SA   I140 @S9S_MB_2U_LIB.S9S_MB_2U(SCH_1):PAGE30
  C884    2      2 Q_CAP_DIFFBUS_C0201-DIFF BUS_0A   I151 @S9S_MB_2U_LIB.S9S_MB_2U(SCH_1):PAGE165

P5E_CPU0_PE3_TX_DN<9> @S9S_MB_2U_LIB.S9S_MB_2U(SCH_1):P5E_CPU0_PE3_TX_DN(9)
    U2 DF85 PE3_TX_DN9 SOCKET4677_AZIF0045P001C01CS-SA   I140 @S9S_MB_2U_LIB.S9S_MB_2U(SCH_1):PAGE30
  C882    2      2 Q_CAP_DIFFBUS_C0201-DIFF BUS_0A   I154 @S9S_MB_2U_LIB.S9S_MB_2U(SCH_1):PAGE165

P5E_CPU0_PE3_TX_DP<0> @S9S_MB_2U_LIB.S9S_MB_2U(SCH_1):P5E_CPU0_PE3_TX_DP(0)
    U2 ED87 PE3_TX_DP0 SOCKET4677_AZIF0045P001C01CS-SA   I140 @S9S_MB_2U_LIB.S9S_MB_2U(SCH_1):PAGE30
  C901    2      2 Q_CAP_DIFFBUS_C0201-DIFF BUS_0A   I120 @S9S_MB_2U_LIB.S9S_MB_2U(SCH_1):PAGE165

P5E_CPU0_PE3_TX_DP<10> @S9S_MB_2U_LIB.S9S_MB_2U(SCH_1):P5E_CPU0_PE3_TX_DP(10)
    U2 DE86 PE3_TX_DP10 SOCKET4677_AZIF0045P001C01CS-SA   I140 @S9S_MB_2U_LIB.S9S_MB_2U(SCH_1):PAGE30
  C881    2      2 Q_CAP_DIFFBUS_C0201-DIFF BUS_0A   I155 @S9S_MB_2U_LIB.S9S_MB_2U(SCH_1):PAGE165

P5E_CPU0_PE3_TX_DP<11> @S9S_MB_2U_LIB.S9S_MB_2U(SCH_1):P5E_CPU0_PE3_TX_DP(11)
    U2 DC86 PE3_TX_DP11 SOCKET4677_AZIF0045P001C01CS-SA   I140 @S9S_MB_2U_LIB.S9S_MB_2U(SCH_1):PAGE30
  C879    2      2 Q_CAP_DIFFBUS_C0201-DIFF BUS_0A   I158 @S9S_MB_2U_LIB.S9S_MB_2U(SCH_1):PAGE165

P5E_CPU0_PE3_TX_DP<12> @S9S_MB_2U_LIB.S9S_MB_2U(SCH_1):P5E_CPU0_PE3_TX_DP(12)
    U2 DA86 PE3_TX_DP12 SOCKET4677_AZIF0045P001C01CS-SA   I140 @S9S_MB_2U_LIB.S9S_MB_2U(SCH_1):PAGE30
  C877    2      2 Q_CAP_DIFFBUS_C0201-DIFF BUS_0A   I159 @S9S_MB_2U_LIB.S9S_MB_2U(SCH_1):PAGE165

P5E_CPU0_PE3_TX_DP<13> @S9S_MB_2U_LIB.S9S_MB_2U(SCH_1):P5E_CPU0_PE3_TX_DP(13)
    U2 CW86 PE3_TX_DP13 SOCKET4677_AZIF0045P001C01CS-SA   I140 @S9S_MB_2U_LIB.S9S_MB_2U(SCH_1):PAGE30
  C875    2      2 Q_CAP_DIFFBUS_C0201-DIFF BUS_0A   I164 @S9S_MB_2U_LIB.S9S_MB_2U(SCH_1):PAGE165

P5E_CPU0_PE3_TX_DP<14> @S9S_MB_2U_LIB.S9S_MB_2U(SCH_1):P5E_CPU0_PE3_TX_DP(14)
    U2 CU86 PE3_TX_DP14 SOCKET4677_AZIF0045P001C01CS-SA   I140 @S9S_MB_2U_LIB.S9S_MB_2U(SCH_1):PAGE30
  C873    2      2 Q_CAP_DIFFBUS_C0201-DIFF BUS_0A   I166 @S9S_MB_2U_LIB.S9S_MB_2U(SCH_1):PAGE165

P5E_CPU0_PE3_TX_DP<15> @S9S_MB_2U_LIB.S9S_MB_2U(SCH_1):P5E_CPU0_PE3_TX_DP(15)
    U2 CR86 PE3_TX_DP15 SOCKET4677_AZIF0045P001C01CS-SA   I140 @S9S_MB_2U_LIB.S9S_MB_2U(SCH_1):PAGE30
  C871    2      2 Q_CAP_DIFFBUS_C0201-DIFF BUS_0A   I168 @S9S_MB_2U_LIB.S9S_MB_2U(SCH_1):PAGE165

P5E_CPU0_PE3_TX_DP<1> @S9S_MB_2U_LIB.S9S_MB_2U(SCH_1):P5E_CPU0_PE3_TX_DP(1)
    U2 EC86 PE3_TX_DP1 SOCKET4677_AZIF0045P001C01CS-SA   I140 @S9S_MB_2U_LIB.S9S_MB_2U(SCH_1):PAGE30
  C899    2      2 Q_CAP_DIFFBUS_C0201-DIFF BUS_0A   I122 @S9S_MB_2U_LIB.S9S_MB_2U(SCH_1):PAGE165

P5E_CPU0_PE3_TX_DP<2> @S9S_MB_2U_LIB.S9S_MB_2U(SCH_1):P5E_CPU0_PE3_TX_DP(2)
    U2 EA86 PE3_TX_DP2 SOCKET4677_AZIF0045P001C01CS-SA   I140 @S9S_MB_2U_LIB.S9S_MB_2U(SCH_1):PAGE30
  C897    2      2 Q_CAP_DIFFBUS_C0201-DIFF BUS_0A   I123 @S9S_MB_2U_LIB.S9S_MB_2U(SCH_1):PAGE165

P5E_CPU0_PE3_TX_DP<3> @S9S_MB_2U_LIB.S9S_MB_2U(SCH_1):P5E_CPU0_PE3_TX_DP(3)
    U2 DW86 PE3_TX_DP3 SOCKET4677_AZIF0045P001C01CS-SA   I140 @S9S_MB_2U_LIB.S9S_MB_2U(SCH_1):PAGE30
  C895    2      2 Q_CAP_DIFFBUS_C0201-DIFF BUS_0A   I125 @S9S_MB_2U_LIB.S9S_MB_2U(SCH_1):PAGE165

P5E_CPU0_PE3_TX_DP<4> @S9S_MB_2U_LIB.S9S_MB_2U(SCH_1):P5E_CPU0_PE3_TX_DP(4)
    U2 DU86 PE3_TX_DP4 SOCKET4677_AZIF0045P001C01CS-SA   I140 @S9S_MB_2U_LIB.S9S_MB_2U(SCH_1):PAGE30
  C893    2      2 Q_CAP_DIFFBUS_C0201-DIFF BUS_0A   I128 @S9S_MB_2U_LIB.S9S_MB_2U(SCH_1):PAGE165

P5E_CPU0_PE3_TX_DP<5> @S9S_MB_2U_LIB.S9S_MB_2U(SCH_1):P5E_CPU0_PE3_TX_DP(5)
    U2 DR86 PE3_TX_DP5 SOCKET4677_AZIF0045P001C01CS-SA   I140 @S9S_MB_2U_LIB.S9S_MB_2U(SCH_1):PAGE30
  C891    2      2 Q_CAP_DIFFBUS_C0201-DIFF BUS_0A   I132 @S9S_MB_2U_LIB.S9S_MB_2U(SCH_1):PAGE165

P5E_CPU0_PE3_TX_DP<6> @S9S_MB_2U_LIB.S9S_MB_2U(SCH_1):P5E_CPU0_PE3_TX_DP(6)
    U2 DN86 PE3_TX_DP6 SOCKET4677_AZIF0045P001C01CS-SA   I140 @S9S_MB_2U_LIB.S9S_MB_2U(SCH_1):PAGE30
  C889    2      2 Q_CAP_DIFFBUS_C0201-DIFF BUS_0A   I134 @S9S_MB_2U_LIB.S9S_MB_2U(SCH_1):PAGE165

P5E_CPU0_PE3_TX_DP<7> @S9S_MB_2U_LIB.S9S_MB_2U(SCH_1):P5E_CPU0_PE3_TX_DP(7)
    U2 DL86 PE3_TX_DP7 SOCKET4677_AZIF0045P001C01CS-SA   I140 @S9S_MB_2U_LIB.S9S_MB_2U(SCH_1):PAGE30
  C887    2      2 Q_CAP_DIFFBUS_C0201-DIFF BUS_0A   I136 @S9S_MB_2U_LIB.S9S_MB_2U(SCH_1):PAGE165

P5E_CPU0_PE3_TX_DP<8> @S9S_MB_2U_LIB.S9S_MB_2U(SCH_1):P5E_CPU0_PE3_TX_DP(8)
    U2 DJ86 PE3_TX_DP8 SOCKET4677_AZIF0045P001C01CS-SA   I140 @S9S_MB_2U_LIB.S9S_MB_2U(SCH_1):PAGE30
  C885    2      2 Q_CAP_DIFFBUS_C0201-DIFF BUS_0A   I152 @S9S_MB_2U_LIB.S9S_MB_2U(SCH_1):PAGE165

P5E_CPU0_PE3_TX_DP<9> @S9S_MB_2U_LIB.S9S_MB_2U(SCH_1):P5E_CPU0_PE3_TX_DP(9)
    U2 DG86 PE3_TX_DP9 SOCKET4677_AZIF0045P001C01CS-SA   I140 @S9S_MB_2U_LIB.S9S_MB_2U(SCH_1):PAGE30
  C883    2      2 Q_CAP_DIFFBUS_C0201-DIFF BUS_0A   I153 @S9S_MB_2U_LIB.S9S_MB_2U(SCH_1):PAGE165

P5E_CPU0_PE4_RX_DN<0> @S9S_MB_2U_LIB.S9S_MB_2U(SCH_1):P5E_CPU0_PE4_RX_DN(0)
    U2  J90 PE4_RX_DN0 SOCKET4677_AZIF0045P001C01CS-SA   I139 @S9S_MB_2U_LIB.S9S_MB_2U(SCH_1):PAGE31
  J108   F1     F1 CONN112_10137002101LF-CONN112_A    I57 @S9S_MB_2U_LIB.S9S_MB_2U(SCH_1):PAGE320

P5E_CPU0_PE4_RX_DN<10> @S9S_MB_2U_LIB.S9S_MB_2U(SCH_1):P5E_CPU0_PE4_RX_DN(10)
    U2 AM91 PE4_RX_DN10 SOCKET4677_AZIF0045P001C01CS-SA   I139 @S9S_MB_2U_LIB.S9S_MB_2U(SCH_1):PAGE31
  J107   F3     F3 CONN112_10137002101LF-CONN112_A    I58 @S9S_MB_2U_LIB.S9S_MB_2U(SCH_1):PAGE317

P5E_CPU0_PE4_RX_DN<11> @S9S_MB_2U_LIB.S9S_MB_2U(SCH_1):P5E_CPU0_PE4_RX_DN(11)
    U2 AP89 PE4_RX_DN11 SOCKET4677_AZIF0045P001C01CS-SA   I139 @S9S_MB_2U_LIB.S9S_MB_2U(SCH_1):PAGE31
  J107   F4     F4 CONN112_10137002101LF-CONN112_A    I58 @S9S_MB_2U_LIB.S9S_MB_2U(SCH_1):PAGE317

P5E_CPU0_PE4_RX_DN<12> @S9S_MB_2U_LIB.S9S_MB_2U(SCH_1):P5E_CPU0_PE4_RX_DN(12)
    U2 AT91 PE4_RX_DN12 SOCKET4677_AZIF0045P001C01CS-SA   I139 @S9S_MB_2U_LIB.S9S_MB_2U(SCH_1):PAGE31
  J107   F5     F5 CONN112_10137002101LF-CONN112_A    I38 @S9S_MB_2U_LIB.S9S_MB_2U(SCH_1):PAGE317

P5E_CPU0_PE4_RX_DN<13> @S9S_MB_2U_LIB.S9S_MB_2U(SCH_1):P5E_CPU0_PE4_RX_DN(13)
    U2 AV89 PE4_RX_DN13 SOCKET4677_AZIF0045P001C01CS-SA   I139 @S9S_MB_2U_LIB.S9S_MB_2U(SCH_1):PAGE31
  J107   F6     F6 CONN112_10137002101LF-CONN112_A    I38 @S9S_MB_2U_LIB.S9S_MB_2U(SCH_1):PAGE317

P5E_CPU0_PE4_RX_DN<14> @S9S_MB_2U_LIB.S9S_MB_2U(SCH_1):P5E_CPU0_PE4_RX_DN(14)
    U2 AY91 PE4_RX_DN14 SOCKET4677_AZIF0045P001C01CS-SA   I139 @S9S_MB_2U_LIB.S9S_MB_2U(SCH_1):PAGE31
  J107   F7     F7 CONN112_10137002101LF-CONN112_A    I38 @S9S_MB_2U_LIB.S9S_MB_2U(SCH_1):PAGE317

P5E_CPU0_PE4_RX_DN<15> @S9S_MB_2U_LIB.S9S_MB_2U(SCH_1):P5E_CPU0_PE4_RX_DN(15)
    U2 BB89 PE4_RX_DN15 SOCKET4677_AZIF0045P001C01CS-SA   I139 @S9S_MB_2U_LIB.S9S_MB_2U(SCH_1):PAGE31
  J107   F8     F8 CONN112_10137002101LF-CONN112_A    I38 @S9S_MB_2U_LIB.S9S_MB_2U(SCH_1):PAGE317

P5E_CPU0_PE4_RX_DN<1> @S9S_MB_2U_LIB.S9S_MB_2U(SCH_1):P5E_CPU0_PE4_RX_DN(1)
    U2  P89 PE4_RX_DN1 SOCKET4677_AZIF0045P001C01CS-SA   I139 @S9S_MB_2U_LIB.S9S_MB_2U(SCH_1):PAGE31
  J108   F2     F2 CONN112_10137002101LF-CONN112_A    I57 @S9S_MB_2U_LIB.S9S_MB_2U(SCH_1):PAGE320

P5E_CPU0_PE4_RX_DN<2> @S9S_MB_2U_LIB.S9S_MB_2U(SCH_1):P5E_CPU0_PE4_RX_DN(2)
    U2  T91 PE4_RX_DN2 SOCKET4677_AZIF0045P001C01CS-SA   I139 @S9S_MB_2U_LIB.S9S_MB_2U(SCH_1):PAGE31
  J108   F3     F3 CONN112_10137002101LF-CONN112_A    I57 @S9S_MB_2U_LIB.S9S_MB_2U(SCH_1):PAGE320

P5E_CPU0_PE4_RX_DN<3> @S9S_MB_2U_LIB.S9S_MB_2U(SCH_1):P5E_CPU0_PE4_RX_DN(3)
    U2  V89 PE4_RX_DN3 SOCKET4677_AZIF0045P001C01CS-SA   I139 @S9S_MB_2U_LIB.S9S_MB_2U(SCH_1):PAGE31
  J108   F4     F4 CONN112_10137002101LF-CONN112_A    I57 @S9S_MB_2U_LIB.S9S_MB_2U(SCH_1):PAGE320

P5E_CPU0_PE4_RX_DN<4> @S9S_MB_2U_LIB.S9S_MB_2U(SCH_1):P5E_CPU0_PE4_RX_DN(4)
    U2  Y91 PE4_RX_DN4 SOCKET4677_AZIF0045P001C01CS-SA   I139 @S9S_MB_2U_LIB.S9S_MB_2U(SCH_1):PAGE31
  J108   F5     F5 CONN112_10137002101LF-CONN112_A    I76 @S9S_MB_2U_LIB.S9S_MB_2U(SCH_1):PAGE320

P5E_CPU0_PE4_RX_DN<5> @S9S_MB_2U_LIB.S9S_MB_2U(SCH_1):P5E_CPU0_PE4_RX_DN(5)
    U2 AB89 PE4_RX_DN5 SOCKET4677_AZIF0045P001C01CS-SA   I139 @S9S_MB_2U_LIB.S9S_MB_2U(SCH_1):PAGE31
  J108   F6     F6 CONN112_10137002101LF-CONN112_A    I76 @S9S_MB_2U_LIB.S9S_MB_2U(SCH_1):PAGE320

P5E_CPU0_PE4_RX_DN<6> @S9S_MB_2U_LIB.S9S_MB_2U(SCH_1):P5E_CPU0_PE4_RX_DN(6)
    U2 AD91 PE4_RX_DN6 SOCKET4677_AZIF0045P001C01CS-SA   I139 @S9S_MB_2U_LIB.S9S_MB_2U(SCH_1):PAGE31
  J108   F7     F7 CONN112_10137002101LF-CONN112_A    I76 @S9S_MB_2U_LIB.S9S_MB_2U(SCH_1):PAGE320

P5E_CPU0_PE4_RX_DN<7> @S9S_MB_2U_LIB.S9S_MB_2U(SCH_1):P5E_CPU0_PE4_RX_DN(7)
    U2 AF89 PE4_RX_DN7 SOCKET4677_AZIF0045P001C01CS-SA   I139 @S9S_MB_2U_LIB.S9S_MB_2U(SCH_1):PAGE31
  J108   F8     F8 CONN112_10137002101LF-CONN112_A    I76 @S9S_MB_2U_LIB.S9S_MB_2U(SCH_1):PAGE320

P5E_CPU0_PE4_RX_DN<8> @S9S_MB_2U_LIB.S9S_MB_2U(SCH_1):P5E_CPU0_PE4_RX_DN(8)
    U2 AH91 PE4_RX_DN8 SOCKET4677_AZIF0045P001C01CS-SA   I139 @S9S_MB_2U_LIB.S9S_MB_2U(SCH_1):PAGE31
  J107   F1     F1 CONN112_10137002101LF-CONN112_A    I58 @S9S_MB_2U_LIB.S9S_MB_2U(SCH_1):PAGE317

P5E_CPU0_PE4_RX_DN<9> @S9S_MB_2U_LIB.S9S_MB_2U(SCH_1):P5E_CPU0_PE4_RX_DN(9)
    U2 AK89 PE4_RX_DN9 SOCKET4677_AZIF0045P001C01CS-SA   I139 @S9S_MB_2U_LIB.S9S_MB_2U(SCH_1):PAGE31
  J107   F2     F2 CONN112_10137002101LF-CONN112_A    I58 @S9S_MB_2U_LIB.S9S_MB_2U(SCH_1):PAGE317

P5E_CPU0_PE4_RX_DP<0> @S9S_MB_2U_LIB.S9S_MB_2U(SCH_1):P5E_CPU0_PE4_RX_DP(0)
    U2  K89 PE4_RX_DP0 SOCKET4677_AZIF0045P001C01CS-SA   I139 @S9S_MB_2U_LIB.S9S_MB_2U(SCH_1):PAGE31
  J108   G1     G1 CONN112_10137002101LF-CONN112_A    I57 @S9S_MB_2U_LIB.S9S_MB_2U(SCH_1):PAGE320

P5E_CPU0_PE4_RX_DP<10> @S9S_MB_2U_LIB.S9S_MB_2U(SCH_1):P5E_CPU0_PE4_RX_DP(10)
    U2 AL90 PE4_RX_DP10 SOCKET4677_AZIF0045P001C01CS-SA   I139 @S9S_MB_2U_LIB.S9S_MB_2U(SCH_1):PAGE31
  J107   G3     G3 CONN112_10137002101LF-CONN112_A    I58 @S9S_MB_2U_LIB.S9S_MB_2U(SCH_1):PAGE317

P5E_CPU0_PE4_RX_DP<11> @S9S_MB_2U_LIB.S9S_MB_2U(SCH_1):P5E_CPU0_PE4_RX_DP(11)
    U2 AN90 PE4_RX_DP11 SOCKET4677_AZIF0045P001C01CS-SA   I139 @S9S_MB_2U_LIB.S9S_MB_2U(SCH_1):PAGE31
  J107   E4     E4 CONN112_10137002101LF-CONN112_A    I58 @S9S_MB_2U_LIB.S9S_MB_2U(SCH_1):PAGE317

P5E_CPU0_PE4_RX_DP<12> @S9S_MB_2U_LIB.S9S_MB_2U(SCH_1):P5E_CPU0_PE4_RX_DP(12)
    U2 AR90 PE4_RX_DP12 SOCKET4677_AZIF0045P001C01CS-SA   I139 @S9S_MB_2U_LIB.S9S_MB_2U(SCH_1):PAGE31
  J107   G5     G5 CONN112_10137002101LF-CONN112_A    I38 @S9S_MB_2U_LIB.S9S_MB_2U(SCH_1):PAGE317

P5E_CPU0_PE4_RX_DP<13> @S9S_MB_2U_LIB.S9S_MB_2U(SCH_1):P5E_CPU0_PE4_RX_DP(13)
    U2 AU90 PE4_RX_DP13 SOCKET4677_AZIF0045P001C01CS-SA   I139 @S9S_MB_2U_LIB.S9S_MB_2U(SCH_1):PAGE31
  J107   E6     E6 CONN112_10137002101LF-CONN112_A    I38 @S9S_MB_2U_LIB.S9S_MB_2U(SCH_1):PAGE317

P5E_CPU0_PE4_RX_DP<14> @S9S_MB_2U_LIB.S9S_MB_2U(SCH_1):P5E_CPU0_PE4_RX_DP(14)
    U2 AW90 PE4_RX_DP14 SOCKET4677_AZIF0045P001C01CS-SA   I139 @S9S_MB_2U_LIB.S9S_MB_2U(SCH_1):PAGE31
  J107   G7     G7 CONN112_10137002101LF-CONN112_A    I38 @S9S_MB_2U_LIB.S9S_MB_2U(SCH_1):PAGE317

P5E_CPU0_PE4_RX_DP<15> @S9S_MB_2U_LIB.S9S_MB_2U(SCH_1):P5E_CPU0_PE4_RX_DP(15)
    U2 BA90 PE4_RX_DP15 SOCKET4677_AZIF0045P001C01CS-SA   I139 @S9S_MB_2U_LIB.S9S_MB_2U(SCH_1):PAGE31
  J107   E8     E8 CONN112_10137002101LF-CONN112_A    I38 @S9S_MB_2U_LIB.S9S_MB_2U(SCH_1):PAGE317

P5E_CPU0_PE4_RX_DP<1> @S9S_MB_2U_LIB.S9S_MB_2U(SCH_1):P5E_CPU0_PE4_RX_DP(1)
    U2  N90 PE4_RX_DP1 SOCKET4677_AZIF0045P001C01CS-SA   I139 @S9S_MB_2U_LIB.S9S_MB_2U(SCH_1):PAGE31
  J108   E2     E2 CONN112_10137002101LF-CONN112_A    I57 @S9S_MB_2U_LIB.S9S_MB_2U(SCH_1):PAGE320

P5E_CPU0_PE4_RX_DP<2> @S9S_MB_2U_LIB.S9S_MB_2U(SCH_1):P5E_CPU0_PE4_RX_DP(2)
    U2  R90 PE4_RX_DP2 SOCKET4677_AZIF0045P001C01CS-SA   I139 @S9S_MB_2U_LIB.S9S_MB_2U(SCH_1):PAGE31
  J108   G3     G3 CONN112_10137002101LF-CONN112_A    I57 @S9S_MB_2U_LIB.S9S_MB_2U(SCH_1):PAGE320

P5E_CPU0_PE4_RX_DP<3> @S9S_MB_2U_LIB.S9S_MB_2U(SCH_1):P5E_CPU0_PE4_RX_DP(3)
    U2  U90 PE4_RX_DP3 SOCKET4677_AZIF0045P001C01CS-SA   I139 @S9S_MB_2U_LIB.S9S_MB_2U(SCH_1):PAGE31
  J108   E4     E4 CONN112_10137002101LF-CONN112_A    I57 @S9S_MB_2U_LIB.S9S_MB_2U(SCH_1):PAGE320

P5E_CPU0_PE4_RX_DP<4> @S9S_MB_2U_LIB.S9S_MB_2U(SCH_1):P5E_CPU0_PE4_RX_DP(4)
    U2  W90 PE4_RX_DP4 SOCKET4677_AZIF0045P001C01CS-SA   I139 @S9S_MB_2U_LIB.S9S_MB_2U(SCH_1):PAGE31
  J108   G5     G5 CONN112_10137002101LF-CONN112_A    I76 @S9S_MB_2U_LIB.S9S_MB_2U(SCH_1):PAGE320

P5E_CPU0_PE4_RX_DP<5> @S9S_MB_2U_LIB.S9S_MB_2U(SCH_1):P5E_CPU0_PE4_RX_DP(5)
    U2 AA90 PE4_RX_DP5 SOCKET4677_AZIF0045P001C01CS-SA   I139 @S9S_MB_2U_LIB.S9S_MB_2U(SCH_1):PAGE31
  J108   E6     E6 CONN112_10137002101LF-CONN112_A    I76 @S9S_MB_2U_LIB.S9S_MB_2U(SCH_1):PAGE320

P5E_CPU0_PE4_RX_DP<6> @S9S_MB_2U_LIB.S9S_MB_2U(SCH_1):P5E_CPU0_PE4_RX_DP(6)
    U2 AC90 PE4_RX_DP6 SOCKET4677_AZIF0045P001C01CS-SA   I139 @S9S_MB_2U_LIB.S9S_MB_2U(SCH_1):PAGE31
  J108   G7     G7 CONN112_10137002101LF-CONN112_A    I76 @S9S_MB_2U_LIB.S9S_MB_2U(SCH_1):PAGE320

P5E_CPU0_PE4_RX_DP<7> @S9S_MB_2U_LIB.S9S_MB_2U(SCH_1):P5E_CPU0_PE4_RX_DP(7)
    U2 AE90 PE4_RX_DP7 SOCKET4677_AZIF0045P001C01CS-SA   I139 @S9S_MB_2U_LIB.S9S_MB_2U(SCH_1):PAGE31
  J108   E8     E8 CONN112_10137002101LF-CONN112_A    I76 @S9S_MB_2U_LIB.S9S_MB_2U(SCH_1):PAGE320

P5E_CPU0_PE4_RX_DP<8> @S9S_MB_2U_LIB.S9S_MB_2U(SCH_1):P5E_CPU0_PE4_RX_DP(8)
    U2 AG90 PE4_RX_DP8 SOCKET4677_AZIF0045P001C01CS-SA   I139 @S9S_MB_2U_LIB.S9S_MB_2U(SCH_1):PAGE31
  J107   G1     G1 CONN112_10137002101LF-CONN112_A    I58 @S9S_MB_2U_LIB.S9S_MB_2U(SCH_1):PAGE317

P5E_CPU0_PE4_RX_DP<9> @S9S_MB_2U_LIB.S9S_MB_2U(SCH_1):P5E_CPU0_PE4_RX_DP(9)
    U2 AJ90 PE4_RX_DP9 SOCKET4677_AZIF0045P001C01CS-SA   I139 @S9S_MB_2U_LIB.S9S_MB_2U(SCH_1):PAGE31
  J107   E2     E2 CONN112_10137002101LF-CONN112_A    I58 @S9S_MB_2U_LIB.S9S_MB_2U(SCH_1):PAGE317

P5E_CPU0_PE4_TX_C_DN<0> @S9S_MB_2U_LIB.S9S_MB_2U(SCH_1):P5E_CPU0_PE4_TX_C_DN(0)
 C1578    1      1 Q_CAP_DIFFBUS_C0201-DIFF BUS_0A   I230 @S9S_MB_2U_LIB.S9S_MB_2U(SCH_1):PAGE166
  J108   L1     L1 CONN112_10137002101LF-CONN112_A    I57 @S9S_MB_2U_LIB.S9S_MB_2U(SCH_1):PAGE320

P5E_CPU0_PE4_TX_C_DN<10> @S9S_MB_2U_LIB.S9S_MB_2U(SCH_1):P5E_CPU0_PE4_TX_C_DN(10)
 C1558    1      1 Q_CAP_DIFFBUS_C0201-DIFF BUS_0A   I264 @S9S_MB_2U_LIB.S9S_MB_2U(SCH_1):PAGE166
  J107   L3     L3 CONN112_10137002101LF-CONN112_A    I58 @S9S_MB_2U_LIB.S9S_MB_2U(SCH_1):PAGE317

P5E_CPU0_PE4_TX_C_DN<11> @S9S_MB_2U_LIB.S9S_MB_2U(SCH_1):P5E_CPU0_PE4_TX_C_DN(11)
 C1556    1      1 Q_CAP_DIFFBUS_C0201-DIFF BUS_0A   I265 @S9S_MB_2U_LIB.S9S_MB_2U(SCH_1):PAGE166
  J107   L4     L4 CONN112_10137002101LF-CONN112_A    I58 @S9S_MB_2U_LIB.S9S_MB_2U(SCH_1):PAGE317

P5E_CPU0_PE4_TX_C_DN<12> @S9S_MB_2U_LIB.S9S_MB_2U(SCH_1):P5E_CPU0_PE4_TX_C_DN(12)
 C1554    1      1 Q_CAP_DIFFBUS_C0201-DIFF BUS_0A   I268 @S9S_MB_2U_LIB.S9S_MB_2U(SCH_1):PAGE166
  J107   L5     L5 CONN112_10137002101LF-CONN112_A    I38 @S9S_MB_2U_LIB.S9S_MB_2U(SCH_1):PAGE317

P5E_CPU0_PE4_TX_C_DN<13> @S9S_MB_2U_LIB.S9S_MB_2U(SCH_1):P5E_CPU0_PE4_TX_C_DN(13)
 C1552    1      1 Q_CAP_DIFFBUS_C0201-DIFF BUS_0A   I270 @S9S_MB_2U_LIB.S9S_MB_2U(SCH_1):PAGE166
  J107   K6     K6 CONN112_10137002101LF-CONN112_A    I38 @S9S_MB_2U_LIB.S9S_MB_2U(SCH_1):PAGE317

P5E_CPU0_PE4_TX_C_DN<14> @S9S_MB_2U_LIB.S9S_MB_2U(SCH_1):P5E_CPU0_PE4_TX_C_DN(14)
 C1550    1      1 Q_CAP_DIFFBUS_C0201-DIFF BUS_0A   I272 @S9S_MB_2U_LIB.S9S_MB_2U(SCH_1):PAGE166
  J107   L7     L7 CONN112_10137002101LF-CONN112_A    I38 @S9S_MB_2U_LIB.S9S_MB_2U(SCH_1):PAGE317

P5E_CPU0_PE4_TX_C_DN<15> @S9S_MB_2U_LIB.S9S_MB_2U(SCH_1):P5E_CPU0_PE4_TX_C_DN(15)
 C1548    1      1 Q_CAP_DIFFBUS_C0201-DIFF BUS_0A   I273 @S9S_MB_2U_LIB.S9S_MB_2U(SCH_1):PAGE166
  J107   K8     K8 CONN112_10137002101LF-CONN112_A    I38 @S9S_MB_2U_LIB.S9S_MB_2U(SCH_1):PAGE317

P5E_CPU0_PE4_TX_C_DN<1> @S9S_MB_2U_LIB.S9S_MB_2U(SCH_1):P5E_CPU0_PE4_TX_C_DN(1)
 C1576    1      1 Q_CAP_DIFFBUS_C0201-DIFF BUS_0A   I312 @S9S_MB_2U_LIB.S9S_MB_2U(SCH_1):PAGE166
  J108   L2     L2 CONN112_10137002101LF-CONN112_A    I57 @S9S_MB_2U_LIB.S9S_MB_2U(SCH_1):PAGE320

P5E_CPU0_PE4_TX_C_DN<2> @S9S_MB_2U_LIB.S9S_MB_2U(SCH_1):P5E_CPU0_PE4_TX_C_DN(2)
 C1574    1      1 Q_CAP_DIFFBUS_C0201-DIFF BUS_0A   I232 @S9S_MB_2U_LIB.S9S_MB_2U(SCH_1):PAGE166
  J108   L3     L3 CONN112_10137002101LF-CONN112_A    I57 @S9S_MB_2U_LIB.S9S_MB_2U(SCH_1):PAGE320

P5E_CPU0_PE4_TX_C_DN<3> @S9S_MB_2U_LIB.S9S_MB_2U(SCH_1):P5E_CPU0_PE4_TX_C_DN(3)
 C1572    1      1 Q_CAP_DIFFBUS_C0201-DIFF BUS_0A   I234 @S9S_MB_2U_LIB.S9S_MB_2U(SCH_1):PAGE166
  J108   K4     K4 CONN112_10137002101LF-CONN112_A    I57 @S9S_MB_2U_LIB.S9S_MB_2U(SCH_1):PAGE320

P5E_CPU0_PE4_TX_C_DN<4> @S9S_MB_2U_LIB.S9S_MB_2U(SCH_1):P5E_CPU0_PE4_TX_C_DN(4)
 C1570    1      1 Q_CAP_DIFFBUS_C0201-DIFF BUS_0A   I235 @S9S_MB_2U_LIB.S9S_MB_2U(SCH_1):PAGE166
  J108   L5     L5 CONN112_10137002101LF-CONN112_A    I76 @S9S_MB_2U_LIB.S9S_MB_2U(SCH_1):PAGE320

P5E_CPU0_PE4_TX_C_DN<5> @S9S_MB_2U_LIB.S9S_MB_2U(SCH_1):P5E_CPU0_PE4_TX_C_DN(5)
 C1568    1      1 Q_CAP_DIFFBUS_C0201-DIFF BUS_0A   I238 @S9S_MB_2U_LIB.S9S_MB_2U(SCH_1):PAGE166
  J108   K6     K6 CONN112_10137002101LF-CONN112_A    I76 @S9S_MB_2U_LIB.S9S_MB_2U(SCH_1):PAGE320

P5E_CPU0_PE4_TX_C_DN<6> @S9S_MB_2U_LIB.S9S_MB_2U(SCH_1):P5E_CPU0_PE4_TX_C_DN(6)
 C1566    1      1 Q_CAP_DIFFBUS_C0201-DIFF BUS_0A   I240 @S9S_MB_2U_LIB.S9S_MB_2U(SCH_1):PAGE166
  J108   L7     L7 CONN112_10137002101LF-CONN112_A    I76 @S9S_MB_2U_LIB.S9S_MB_2U(SCH_1):PAGE320

P5E_CPU0_PE4_TX_C_DN<7> @S9S_MB_2U_LIB.S9S_MB_2U(SCH_1):P5E_CPU0_PE4_TX_C_DN(7)
 C1564    1      1 Q_CAP_DIFFBUS_C0201-DIFF BUS_0A   I242 @S9S_MB_2U_LIB.S9S_MB_2U(SCH_1):PAGE166
  J108   K8     K8 CONN112_10137002101LF-CONN112_A    I76 @S9S_MB_2U_LIB.S9S_MB_2U(SCH_1):PAGE320

P5E_CPU0_PE4_TX_C_DN<8> @S9S_MB_2U_LIB.S9S_MB_2U(SCH_1):P5E_CPU0_PE4_TX_C_DN(8)
 C1794    1      1 Q_CAP_DIFFBUS_C0201-DIFF BUS_0A   I260 @S9S_MB_2U_LIB.S9S_MB_2U(SCH_1):PAGE166
  J107   L1     L1 CONN112_10137002101LF-CONN112_A    I58 @S9S_MB_2U_LIB.S9S_MB_2U(SCH_1):PAGE317

P5E_CPU0_PE4_TX_C_DN<9> @S9S_MB_2U_LIB.S9S_MB_2U(SCH_1):P5E_CPU0_PE4_TX_C_DN(9)
 C1560    1      1 Q_CAP_DIFFBUS_C0201-DIFF BUS_0A   I262 @S9S_MB_2U_LIB.S9S_MB_2U(SCH_1):PAGE166
  J107   K2     K2 CONN112_10137002101LF-CONN112_A    I58 @S9S_MB_2U_LIB.S9S_MB_2U(SCH_1):PAGE317

P5E_CPU0_PE4_TX_C_DP<0> @S9S_MB_2U_LIB.S9S_MB_2U(SCH_1):P5E_CPU0_PE4_TX_C_DP(0)
 C1579    1      1 Q_CAP_DIFFBUS_C0201-DIFF BUS_0A   I229 @S9S_MB_2U_LIB.S9S_MB_2U(SCH_1):PAGE166
  J108   M1     M1 CONN112_10137002101LF-CONN112_A    I57 @S9S_MB_2U_LIB.S9S_MB_2U(SCH_1):PAGE320

P5E_CPU0_PE4_TX_C_DP<10> @S9S_MB_2U_LIB.S9S_MB_2U(SCH_1):P5E_CPU0_PE4_TX_C_DP(10)
 C1559    1      1 Q_CAP_DIFFBUS_C0201-DIFF BUS_0A   I263 @S9S_MB_2U_LIB.S9S_MB_2U(SCH_1):PAGE166
  J107   M3     M3 CONN112_10137002101LF-CONN112_A    I58 @S9S_MB_2U_LIB.S9S_MB_2U(SCH_1):PAGE317

P5E_CPU0_PE4_TX_C_DP<11> @S9S_MB_2U_LIB.S9S_MB_2U(SCH_1):P5E_CPU0_PE4_TX_C_DP(11)
 C1557    1      1 Q_CAP_DIFFBUS_C0201-DIFF BUS_0A   I266 @S9S_MB_2U_LIB.S9S_MB_2U(SCH_1):PAGE166
  J107   K4     K4 CONN112_10137002101LF-CONN112_A    I58 @S9S_MB_2U_LIB.S9S_MB_2U(SCH_1):PAGE317

P5E_CPU0_PE4_TX_C_DP<12> @S9S_MB_2U_LIB.S9S_MB_2U(SCH_1):P5E_CPU0_PE4_TX_C_DP(12)
 C1555    1      1 Q_CAP_DIFFBUS_C0201-DIFF BUS_0A   I267 @S9S_MB_2U_LIB.S9S_MB_2U(SCH_1):PAGE166
  J107   M5     M5 CONN112_10137002101LF-CONN112_A    I38 @S9S_MB_2U_LIB.S9S_MB_2U(SCH_1):PAGE317

P5E_CPU0_PE4_TX_C_DP<13> @S9S_MB_2U_LIB.S9S_MB_2U(SCH_1):P5E_CPU0_PE4_TX_C_DP(13)
 C1553    1      1 Q_CAP_DIFFBUS_C0201-DIFF BUS_0A   I269 @S9S_MB_2U_LIB.S9S_MB_2U(SCH_1):PAGE166
  J107   L6     L6 CONN112_10137002101LF-CONN112_A    I38 @S9S_MB_2U_LIB.S9S_MB_2U(SCH_1):PAGE317

P5E_CPU0_PE4_TX_C_DP<14> @S9S_MB_2U_LIB.S9S_MB_2U(SCH_1):P5E_CPU0_PE4_TX_C_DP(14)
 C1792    1      1 Q_CAP_DIFFBUS_C0201-DIFF BUS_0A   I271 @S9S_MB_2U_LIB.S9S_MB_2U(SCH_1):PAGE166
  J107   M7     M7 CONN112_10137002101LF-CONN112_A    I38 @S9S_MB_2U_LIB.S9S_MB_2U(SCH_1):PAGE317

P5E_CPU0_PE4_TX_C_DP<15> @S9S_MB_2U_LIB.S9S_MB_2U(SCH_1):P5E_CPU0_PE4_TX_C_DP(15)
 C1549    1      1 Q_CAP_DIFFBUS_C0201-DIFF BUS_0A   I274 @S9S_MB_2U_LIB.S9S_MB_2U(SCH_1):PAGE166
  J107   L8     L8 CONN112_10137002101LF-CONN112_A    I38 @S9S_MB_2U_LIB.S9S_MB_2U(SCH_1):PAGE317

P5E_CPU0_PE4_TX_C_DP<1> @S9S_MB_2U_LIB.S9S_MB_2U(SCH_1):P5E_CPU0_PE4_TX_C_DP(1)
 C1577    1      1 Q_CAP_DIFFBUS_C0201-DIFF BUS_0A   I311 @S9S_MB_2U_LIB.S9S_MB_2U(SCH_1):PAGE166
  J108   K2     K2 CONN112_10137002101LF-CONN112_A    I57 @S9S_MB_2U_LIB.S9S_MB_2U(SCH_1):PAGE320

P5E_CPU0_PE4_TX_C_DP<2> @S9S_MB_2U_LIB.S9S_MB_2U(SCH_1):P5E_CPU0_PE4_TX_C_DP(2)
 C1575    1      1 Q_CAP_DIFFBUS_C0201-DIFF BUS_0A   I231 @S9S_MB_2U_LIB.S9S_MB_2U(SCH_1):PAGE166
  J108   M3     M3 CONN112_10137002101LF-CONN112_A    I57 @S9S_MB_2U_LIB.S9S_MB_2U(SCH_1):PAGE320

P5E_CPU0_PE4_TX_C_DP<3> @S9S_MB_2U_LIB.S9S_MB_2U(SCH_1):P5E_CPU0_PE4_TX_C_DP(3)
 C1573    1      1 Q_CAP_DIFFBUS_C0201-DIFF BUS_0A   I233 @S9S_MB_2U_LIB.S9S_MB_2U(SCH_1):PAGE166
  J108   L4     L4 CONN112_10137002101LF-CONN112_A    I57 @S9S_MB_2U_LIB.S9S_MB_2U(SCH_1):PAGE320

P5E_CPU0_PE4_TX_C_DP<4> @S9S_MB_2U_LIB.S9S_MB_2U(SCH_1):P5E_CPU0_PE4_TX_C_DP(4)
 C1571    1      1 Q_CAP_DIFFBUS_C0201-DIFF BUS_0A   I236 @S9S_MB_2U_LIB.S9S_MB_2U(SCH_1):PAGE166
  J108   M5     M5 CONN112_10137002101LF-CONN112_A    I76 @S9S_MB_2U_LIB.S9S_MB_2U(SCH_1):PAGE320

P5E_CPU0_PE4_TX_C_DP<5> @S9S_MB_2U_LIB.S9S_MB_2U(SCH_1):P5E_CPU0_PE4_TX_C_DP(5)
 C1569    1      1 Q_CAP_DIFFBUS_C0201-DIFF BUS_0A   I237 @S9S_MB_2U_LIB.S9S_MB_2U(SCH_1):PAGE166
  J108   L6     L6 CONN112_10137002101LF-CONN112_A    I76 @S9S_MB_2U_LIB.S9S_MB_2U(SCH_1):PAGE320

P5E_CPU0_PE4_TX_C_DP<6> @S9S_MB_2U_LIB.S9S_MB_2U(SCH_1):P5E_CPU0_PE4_TX_C_DP(6)
 C1567    1      1 Q_CAP_DIFFBUS_C0201-DIFF BUS_0A   I239 @S9S_MB_2U_LIB.S9S_MB_2U(SCH_1):PAGE166
  J108   M7     M7 CONN112_10137002101LF-CONN112_A    I76 @S9S_MB_2U_LIB.S9S_MB_2U(SCH_1):PAGE320

P5E_CPU0_PE4_TX_C_DP<7> @S9S_MB_2U_LIB.S9S_MB_2U(SCH_1):P5E_CPU0_PE4_TX_C_DP(7)
 C1565    1      1 Q_CAP_DIFFBUS_C0201-DIFF BUS_0A   I241 @S9S_MB_2U_LIB.S9S_MB_2U(SCH_1):PAGE166
  J108   L8     L8 CONN112_10137002101LF-CONN112_A    I76 @S9S_MB_2U_LIB.S9S_MB_2U(SCH_1):PAGE320

P5E_CPU0_PE4_TX_C_DP<8> @S9S_MB_2U_LIB.S9S_MB_2U(SCH_1):P5E_CPU0_PE4_TX_C_DP(8)
 C1563    1      1 Q_CAP_DIFFBUS_C0201-DIFF BUS_0A   I259 @S9S_MB_2U_LIB.S9S_MB_2U(SCH_1):PAGE166
  J107   M1     M1 CONN112_10137002101LF-CONN112_A    I58 @S9S_MB_2U_LIB.S9S_MB_2U(SCH_1):PAGE317

P5E_CPU0_PE4_TX_C_DP<9> @S9S_MB_2U_LIB.S9S_MB_2U(SCH_1):P5E_CPU0_PE4_TX_C_DP(9)
 C1793    1      1 Q_CAP_DIFFBUS_C0201-DIFF BUS_0A   I261 @S9S_MB_2U_LIB.S9S_MB_2U(SCH_1):PAGE166
  J107   L2     L2 CONN112_10137002101LF-CONN112_A    I58 @S9S_MB_2U_LIB.S9S_MB_2U(SCH_1):PAGE317

P5E_CPU0_PE4_TX_DN<0> @S9S_MB_2U_LIB.S9S_MB_2U(SCH_1):P5E_CPU0_PE4_TX_DN(0)
    U2  L86 PE4_TX_DN0 SOCKET4677_AZIF0045P001C01CS-SA   I139 @S9S_MB_2U_LIB.S9S_MB_2U(SCH_1):PAGE31
 C1578    2      2 Q_CAP_DIFFBUS_C0201-DIFF BUS_0A   I230 @S9S_MB_2U_LIB.S9S_MB_2U(SCH_1):PAGE166

P5E_CPU0_PE4_TX_DN<10> @S9S_MB_2U_LIB.S9S_MB_2U(SCH_1):P5E_CPU0_PE4_TX_DN(10)
    U2 AL86 PE4_TX_DN10 SOCKET4677_AZIF0045P001C01CS-SA   I139 @S9S_MB_2U_LIB.S9S_MB_2U(SCH_1):PAGE31
 C1558    2      2 Q_CAP_DIFFBUS_C0201-DIFF BUS_0A   I264 @S9S_MB_2U_LIB.S9S_MB_2U(SCH_1):PAGE166

P5E_CPU0_PE4_TX_DN<11> @S9S_MB_2U_LIB.S9S_MB_2U(SCH_1):P5E_CPU0_PE4_TX_DN(11)
    U2 AP85 PE4_TX_DN11 SOCKET4677_AZIF0045P001C01CS-SA   I139 @S9S_MB_2U_LIB.S9S_MB_2U(SCH_1):PAGE31
 C1556    2      2 Q_CAP_DIFFBUS_C0201-DIFF BUS_0A   I265 @S9S_MB_2U_LIB.S9S_MB_2U(SCH_1):PAGE166

P5E_CPU0_PE4_TX_DN<12> @S9S_MB_2U_LIB.S9S_MB_2U(SCH_1):P5E_CPU0_PE4_TX_DN(12)
    U2 AR86 PE4_TX_DN12 SOCKET4677_AZIF0045P001C01CS-SA   I139 @S9S_MB_2U_LIB.S9S_MB_2U(SCH_1):PAGE31
 C1554    2      2 Q_CAP_DIFFBUS_C0201-DIFF BUS_0A   I268 @S9S_MB_2U_LIB.S9S_MB_2U(SCH_1):PAGE166

P5E_CPU0_PE4_TX_DN<13> @S9S_MB_2U_LIB.S9S_MB_2U(SCH_1):P5E_CPU0_PE4_TX_DN(13)
    U2 AU86 PE4_TX_DN13 SOCKET4677_AZIF0045P001C01CS-SA   I139 @S9S_MB_2U_LIB.S9S_MB_2U(SCH_1):PAGE31
 C1552    2      2 Q_CAP_DIFFBUS_C0201-DIFF BUS_0A   I270 @S9S_MB_2U_LIB.S9S_MB_2U(SCH_1):PAGE166

P5E_CPU0_PE4_TX_DN<14> @S9S_MB_2U_LIB.S9S_MB_2U(SCH_1):P5E_CPU0_PE4_TX_DN(14)
    U2 AW86 PE4_TX_DN14 SOCKET4677_AZIF0045P001C01CS-SA   I139 @S9S_MB_2U_LIB.S9S_MB_2U(SCH_1):PAGE31
 C1550    2      2 Q_CAP_DIFFBUS_C0201-DIFF BUS_0A   I272 @S9S_MB_2U_LIB.S9S_MB_2U(SCH_1):PAGE166

P5E_CPU0_PE4_TX_DN<15> @S9S_MB_2U_LIB.S9S_MB_2U(SCH_1):P5E_CPU0_PE4_TX_DN(15)
    U2 BA86 PE4_TX_DN15 SOCKET4677_AZIF0045P001C01CS-SA   I139 @S9S_MB_2U_LIB.S9S_MB_2U(SCH_1):PAGE31
 C1548    2      2 Q_CAP_DIFFBUS_C0201-DIFF BUS_0A   I273 @S9S_MB_2U_LIB.S9S_MB_2U(SCH_1):PAGE166

P5E_CPU0_PE4_TX_DN<1> @S9S_MB_2U_LIB.S9S_MB_2U(SCH_1):P5E_CPU0_PE4_TX_DN(1)
    U2  P85 PE4_TX_DN1 SOCKET4677_AZIF0045P001C01CS-SA   I139 @S9S_MB_2U_LIB.S9S_MB_2U(SCH_1):PAGE31
 C1576    2      2 Q_CAP_DIFFBUS_C0201-DIFF BUS_0A   I312 @S9S_MB_2U_LIB.S9S_MB_2U(SCH_1):PAGE166

P5E_CPU0_PE4_TX_DN<2> @S9S_MB_2U_LIB.S9S_MB_2U(SCH_1):P5E_CPU0_PE4_TX_DN(2)
    U2  R86 PE4_TX_DN2 SOCKET4677_AZIF0045P001C01CS-SA   I139 @S9S_MB_2U_LIB.S9S_MB_2U(SCH_1):PAGE31
 C1574    2      2 Q_CAP_DIFFBUS_C0201-DIFF BUS_0A   I232 @S9S_MB_2U_LIB.S9S_MB_2U(SCH_1):PAGE166

P5E_CPU0_PE4_TX_DN<3> @S9S_MB_2U_LIB.S9S_MB_2U(SCH_1):P5E_CPU0_PE4_TX_DN(3)
    U2  U86 PE4_TX_DN3 SOCKET4677_AZIF0045P001C01CS-SA   I139 @S9S_MB_2U_LIB.S9S_MB_2U(SCH_1):PAGE31
 C1572    2      2 Q_CAP_DIFFBUS_C0201-DIFF BUS_0A   I234 @S9S_MB_2U_LIB.S9S_MB_2U(SCH_1):PAGE166

P5E_CPU0_PE4_TX_DN<4> @S9S_MB_2U_LIB.S9S_MB_2U(SCH_1):P5E_CPU0_PE4_TX_DN(4)
    U2  W86 PE4_TX_DN4 SOCKET4677_AZIF0045P001C01CS-SA   I139 @S9S_MB_2U_LIB.S9S_MB_2U(SCH_1):PAGE31
 C1570    2      2 Q_CAP_DIFFBUS_C0201-DIFF BUS_0A   I235 @S9S_MB_2U_LIB.S9S_MB_2U(SCH_1):PAGE166

P5E_CPU0_PE4_TX_DN<5> @S9S_MB_2U_LIB.S9S_MB_2U(SCH_1):P5E_CPU0_PE4_TX_DN(5)
    U2 AA86 PE4_TX_DN5 SOCKET4677_AZIF0045P001C01CS-SA   I139 @S9S_MB_2U_LIB.S9S_MB_2U(SCH_1):PAGE31
 C1568    2      2 Q_CAP_DIFFBUS_C0201-DIFF BUS_0A   I238 @S9S_MB_2U_LIB.S9S_MB_2U(SCH_1):PAGE166

P5E_CPU0_PE4_TX_DN<6> @S9S_MB_2U_LIB.S9S_MB_2U(SCH_1):P5E_CPU0_PE4_TX_DN(6)
    U2 AC86 PE4_TX_DN6 SOCKET4677_AZIF0045P001C01CS-SA   I139 @S9S_MB_2U_LIB.S9S_MB_2U(SCH_1):PAGE31
 C1566    2      2 Q_CAP_DIFFBUS_C0201-DIFF BUS_0A   I240 @S9S_MB_2U_LIB.S9S_MB_2U(SCH_1):PAGE166

P5E_CPU0_PE4_TX_DN<7> @S9S_MB_2U_LIB.S9S_MB_2U(SCH_1):P5E_CPU0_PE4_TX_DN(7)
    U2 AE86 PE4_TX_DN7 SOCKET4677_AZIF0045P001C01CS-SA   I139 @S9S_MB_2U_LIB.S9S_MB_2U(SCH_1):PAGE31
 C1564    2      2 Q_CAP_DIFFBUS_C0201-DIFF BUS_0A   I242 @S9S_MB_2U_LIB.S9S_MB_2U(SCH_1):PAGE166

P5E_CPU0_PE4_TX_DN<8> @S9S_MB_2U_LIB.S9S_MB_2U(SCH_1):P5E_CPU0_PE4_TX_DN(8)
    U2 AG86 PE4_TX_DN8 SOCKET4677_AZIF0045P001C01CS-SA   I139 @S9S_MB_2U_LIB.S9S_MB_2U(SCH_1):PAGE31
 C1794    2      2 Q_CAP_DIFFBUS_C0201-DIFF BUS_0A   I260 @S9S_MB_2U_LIB.S9S_MB_2U(SCH_1):PAGE166

P5E_CPU0_PE4_TX_DN<9> @S9S_MB_2U_LIB.S9S_MB_2U(SCH_1):P5E_CPU0_PE4_TX_DN(9)
    U2 AJ86 PE4_TX_DN9 SOCKET4677_AZIF0045P001C01CS-SA   I139 @S9S_MB_2U_LIB.S9S_MB_2U(SCH_1):PAGE31
 C1560    2      2 Q_CAP_DIFFBUS_C0201-DIFF BUS_0A   I262 @S9S_MB_2U_LIB.S9S_MB_2U(SCH_1):PAGE166

P5E_CPU0_PE4_TX_DP<0> @S9S_MB_2U_LIB.S9S_MB_2U(SCH_1):P5E_CPU0_PE4_TX_DP(0)
    U2  M87 PE4_TX_DP0 SOCKET4677_AZIF0045P001C01CS-SA   I139 @S9S_MB_2U_LIB.S9S_MB_2U(SCH_1):PAGE31
 C1579    2      2 Q_CAP_DIFFBUS_C0201-DIFF BUS_0A   I229 @S9S_MB_2U_LIB.S9S_MB_2U(SCH_1):PAGE166

P5E_CPU0_PE4_TX_DP<10> @S9S_MB_2U_LIB.S9S_MB_2U(SCH_1):P5E_CPU0_PE4_TX_DP(10)
    U2 AM87 PE4_TX_DP10 SOCKET4677_AZIF0045P001C01CS-SA   I139 @S9S_MB_2U_LIB.S9S_MB_2U(SCH_1):PAGE31
 C1559    2      2 Q_CAP_DIFFBUS_C0201-DIFF BUS_0A   I263 @S9S_MB_2U_LIB.S9S_MB_2U(SCH_1):PAGE166

P5E_CPU0_PE4_TX_DP<11> @S9S_MB_2U_LIB.S9S_MB_2U(SCH_1):P5E_CPU0_PE4_TX_DP(11)
    U2 AN86 PE4_TX_DP11 SOCKET4677_AZIF0045P001C01CS-SA   I139 @S9S_MB_2U_LIB.S9S_MB_2U(SCH_1):PAGE31
 C1557    2      2 Q_CAP_DIFFBUS_C0201-DIFF BUS_0A   I266 @S9S_MB_2U_LIB.S9S_MB_2U(SCH_1):PAGE166

P5E_CPU0_PE4_TX_DP<12> @S9S_MB_2U_LIB.S9S_MB_2U(SCH_1):P5E_CPU0_PE4_TX_DP(12)
    U2 AT87 PE4_TX_DP12 SOCKET4677_AZIF0045P001C01CS-SA   I139 @S9S_MB_2U_LIB.S9S_MB_2U(SCH_1):PAGE31
 C1555    2      2 Q_CAP_DIFFBUS_C0201-DIFF BUS_0A   I267 @S9S_MB_2U_LIB.S9S_MB_2U(SCH_1):PAGE166

P5E_CPU0_PE4_TX_DP<13> @S9S_MB_2U_LIB.S9S_MB_2U(SCH_1):P5E_CPU0_PE4_TX_DP(13)
    U2 AV85 PE4_TX_DP13 SOCKET4677_AZIF0045P001C01CS-SA   I139 @S9S_MB_2U_LIB.S9S_MB_2U(SCH_1):PAGE31
 C1553    2      2 Q_CAP_DIFFBUS_C0201-DIFF BUS_0A   I269 @S9S_MB_2U_LIB.S9S_MB_2U(SCH_1):PAGE166

P5E_CPU0_PE4_TX_DP<14> @S9S_MB_2U_LIB.S9S_MB_2U(SCH_1):P5E_CPU0_PE4_TX_DP(14)
    U2 AY87 PE4_TX_DP14 SOCKET4677_AZIF0045P001C01CS-SA   I139 @S9S_MB_2U_LIB.S9S_MB_2U(SCH_1):PAGE31
 C1792    2      2 Q_CAP_DIFFBUS_C0201-DIFF BUS_0A   I271 @S9S_MB_2U_LIB.S9S_MB_2U(SCH_1):PAGE166

P5E_CPU0_PE4_TX_DP<15> @S9S_MB_2U_LIB.S9S_MB_2U(SCH_1):P5E_CPU0_PE4_TX_DP(15)
    U2 BB85 PE4_TX_DP15 SOCKET4677_AZIF0045P001C01CS-SA   I139 @S9S_MB_2U_LIB.S9S_MB_2U(SCH_1):PAGE31
 C1549    2      2 Q_CAP_DIFFBUS_C0201-DIFF BUS_0A   I274 @S9S_MB_2U_LIB.S9S_MB_2U(SCH_1):PAGE166

P5E_CPU0_PE4_TX_DP<1> @S9S_MB_2U_LIB.S9S_MB_2U(SCH_1):P5E_CPU0_PE4_TX_DP(1)
    U2  N86 PE4_TX_DP1 SOCKET4677_AZIF0045P001C01CS-SA   I139 @S9S_MB_2U_LIB.S9S_MB_2U(SCH_1):PAGE31
 C1577    2      2 Q_CAP_DIFFBUS_C0201-DIFF BUS_0A   I311 @S9S_MB_2U_LIB.S9S_MB_2U(SCH_1):PAGE166

P5E_CPU0_PE4_TX_DP<2> @S9S_MB_2U_LIB.S9S_MB_2U(SCH_1):P5E_CPU0_PE4_TX_DP(2)
    U2  T87 PE4_TX_DP2 SOCKET4677_AZIF0045P001C01CS-SA   I139 @S9S_MB_2U_LIB.S9S_MB_2U(SCH_1):PAGE31
 C1575    2      2 Q_CAP_DIFFBUS_C0201-DIFF BUS_0A   I231 @S9S_MB_2U_LIB.S9S_MB_2U(SCH_1):PAGE166

P5E_CPU0_PE4_TX_DP<3> @S9S_MB_2U_LIB.S9S_MB_2U(SCH_1):P5E_CPU0_PE4_TX_DP(3)
    U2  V85 PE4_TX_DP3 SOCKET4677_AZIF0045P001C01CS-SA   I139 @S9S_MB_2U_LIB.S9S_MB_2U(SCH_1):PAGE31
 C1573    2      2 Q_CAP_DIFFBUS_C0201-DIFF BUS_0A   I233 @S9S_MB_2U_LIB.S9S_MB_2U(SCH_1):PAGE166

P5E_CPU0_PE4_TX_DP<4> @S9S_MB_2U_LIB.S9S_MB_2U(SCH_1):P5E_CPU0_PE4_TX_DP(4)
    U2  Y87 PE4_TX_DP4 SOCKET4677_AZIF0045P001C01CS-SA   I139 @S9S_MB_2U_LIB.S9S_MB_2U(SCH_1):PAGE31
 C1571    2      2 Q_CAP_DIFFBUS_C0201-DIFF BUS_0A   I236 @S9S_MB_2U_LIB.S9S_MB_2U(SCH_1):PAGE166

P5E_CPU0_PE4_TX_DP<5> @S9S_MB_2U_LIB.S9S_MB_2U(SCH_1):P5E_CPU0_PE4_TX_DP(5)
    U2 AB85 PE4_TX_DP5 SOCKET4677_AZIF0045P001C01CS-SA   I139 @S9S_MB_2U_LIB.S9S_MB_2U(SCH_1):PAGE31
 C1569    2      2 Q_CAP_DIFFBUS_C0201-DIFF BUS_0A   I237 @S9S_MB_2U_LIB.S9S_MB_2U(SCH_1):PAGE166

P5E_CPU0_PE4_TX_DP<6> @S9S_MB_2U_LIB.S9S_MB_2U(SCH_1):P5E_CPU0_PE4_TX_DP(6)
    U2 AD87 PE4_TX_DP6 SOCKET4677_AZIF0045P001C01CS-SA   I139 @S9S_MB_2U_LIB.S9S_MB_2U(SCH_1):PAGE31
 C1567    2      2 Q_CAP_DIFFBUS_C0201-DIFF BUS_0A   I239 @S9S_MB_2U_LIB.S9S_MB_2U(SCH_1):PAGE166

P5E_CPU0_PE4_TX_DP<7> @S9S_MB_2U_LIB.S9S_MB_2U(SCH_1):P5E_CPU0_PE4_TX_DP(7)
    U2 AF85 PE4_TX_DP7 SOCKET4677_AZIF0045P001C01CS-SA   I139 @S9S_MB_2U_LIB.S9S_MB_2U(SCH_1):PAGE31
 C1565    2      2 Q_CAP_DIFFBUS_C0201-DIFF BUS_0A   I241 @S9S_MB_2U_LIB.S9S_MB_2U(SCH_1):PAGE166

P5E_CPU0_PE4_TX_DP<8> @S9S_MB_2U_LIB.S9S_MB_2U(SCH_1):P5E_CPU0_PE4_TX_DP(8)
    U2 AH87 PE4_TX_DP8 SOCKET4677_AZIF0045P001C01CS-SA   I139 @S9S_MB_2U_LIB.S9S_MB_2U(SCH_1):PAGE31
 C1563    2      2 Q_CAP_DIFFBUS_C0201-DIFF BUS_0A   I259 @S9S_MB_2U_LIB.S9S_MB_2U(SCH_1):PAGE166

P5E_CPU0_PE4_TX_DP<9> @S9S_MB_2U_LIB.S9S_MB_2U(SCH_1):P5E_CPU0_PE4_TX_DP(9)
    U2 AK85 PE4_TX_DP9 SOCKET4677_AZIF0045P001C01CS-SA   I139 @S9S_MB_2U_LIB.S9S_MB_2U(SCH_1):PAGE31
 C1793    2      2 Q_CAP_DIFFBUS_C0201-DIFF BUS_0A   I261 @S9S_MB_2U_LIB.S9S_MB_2U(SCH_1):PAGE166

P5E_CPU1_PE0_RX_DN<0> @S9S_MB_2U_LIB.S9S_MB_2U(SCH_1):P5E_CPU1_PE0_RX_DN(0)
    U1  K10 PE0_RX_DN0 SOCKET4677_AZIF0045P001C01CS-SA    I80 @S9S_MB_2U_LIB.S9S_MB_2U(SCH_1):PAGE60
  J111   B8     B8 CONN112_10137002101LF-CONN112_A    I74 @S9S_MB_2U_LIB.S9S_MB_2U(SCH_1):PAGE148

P5E_CPU1_PE0_RX_DN<10> @S9S_MB_2U_LIB.S9S_MB_2U(SCH_1):P5E_CPU1_PE0_RX_DN(10)
    U1 AK10 PE0_RX_DN10 SOCKET4677_AZIF0045P001C01CS-SA    I80 @S9S_MB_2U_LIB.S9S_MB_2U(SCH_1):PAGE60
  J112   B6     B6 CONN160_10131762101LF-CONN160_A    I75 @S9S_MB_2U_LIB.S9S_MB_2U(SCH_1):PAGE149

P5E_CPU1_PE0_RX_DN<11> @S9S_MB_2U_LIB.S9S_MB_2U(SCH_1):P5E_CPU1_PE0_RX_DN(11)
    U1 AM10 PE0_RX_DN11 SOCKET4677_AZIF0045P001C01CS-SA    I80 @S9S_MB_2U_LIB.S9S_MB_2U(SCH_1):PAGE60
  J112   D5     D5 CONN160_10131762101LF-CONN160_A    I75 @S9S_MB_2U_LIB.S9S_MB_2U(SCH_1):PAGE149

P5E_CPU1_PE0_RX_DN<12> @S9S_MB_2U_LIB.S9S_MB_2U(SCH_1):P5E_CPU1_PE0_RX_DN(12)
    U1 AP10 PE0_RX_DN12 SOCKET4677_AZIF0045P001C01CS-SA    I80 @S9S_MB_2U_LIB.S9S_MB_2U(SCH_1):PAGE60
  J112   B4     B4 CONN160_10131762101LF-CONN160_A    I76 @S9S_MB_2U_LIB.S9S_MB_2U(SCH_1):PAGE149

P5E_CPU1_PE0_RX_DN<13> @S9S_MB_2U_LIB.S9S_MB_2U(SCH_1):P5E_CPU1_PE0_RX_DN(13)
    U1  AU9 PE0_RX_DN13 SOCKET4677_AZIF0045P001C01CS-SA    I80 @S9S_MB_2U_LIB.S9S_MB_2U(SCH_1):PAGE60
  J112   C3     C3 CONN160_10131762101LF-CONN160_A    I76 @S9S_MB_2U_LIB.S9S_MB_2U(SCH_1):PAGE149

P5E_CPU1_PE0_RX_DN<14> @S9S_MB_2U_LIB.S9S_MB_2U(SCH_1):P5E_CPU1_PE0_RX_DN(14)
    U1 AV10 PE0_RX_DN14 SOCKET4677_AZIF0045P001C01CS-SA    I80 @S9S_MB_2U_LIB.S9S_MB_2U(SCH_1):PAGE60
  J112   B2     B2 CONN160_10131762101LF-CONN160_A    I76 @S9S_MB_2U_LIB.S9S_MB_2U(SCH_1):PAGE149

P5E_CPU1_PE0_RX_DN<15> @S9S_MB_2U_LIB.S9S_MB_2U(SCH_1):P5E_CPU1_PE0_RX_DN(15)
    U1  BA9 PE0_RX_DN15 SOCKET4677_AZIF0045P001C01CS-SA    I80 @S9S_MB_2U_LIB.S9S_MB_2U(SCH_1):PAGE60
  J112   C1     C1 CONN160_10131762101LF-CONN160_A    I76 @S9S_MB_2U_LIB.S9S_MB_2U(SCH_1):PAGE149

P5E_CPU1_PE0_RX_DN<1> @S9S_MB_2U_LIB.S9S_MB_2U(SCH_1):P5E_CPU1_PE0_RX_DN(1)
    U1  M10 PE0_RX_DN1 SOCKET4677_AZIF0045P001C01CS-SA    I80 @S9S_MB_2U_LIB.S9S_MB_2U(SCH_1):PAGE60
  J111   D7     D7 CONN112_10137002101LF-CONN112_A    I74 @S9S_MB_2U_LIB.S9S_MB_2U(SCH_1):PAGE148

P5E_CPU1_PE0_RX_DN<2> @S9S_MB_2U_LIB.S9S_MB_2U(SCH_1):P5E_CPU1_PE0_RX_DN(2)
    U1  P10 PE0_RX_DN2 SOCKET4677_AZIF0045P001C01CS-SA    I80 @S9S_MB_2U_LIB.S9S_MB_2U(SCH_1):PAGE60
  J111   B6     B6 CONN112_10137002101LF-CONN112_A    I74 @S9S_MB_2U_LIB.S9S_MB_2U(SCH_1):PAGE148

P5E_CPU1_PE0_RX_DN<3> @S9S_MB_2U_LIB.S9S_MB_2U(SCH_1):P5E_CPU1_PE0_RX_DN(3)
    U1  T10 PE0_RX_DN3 SOCKET4677_AZIF0045P001C01CS-SA    I80 @S9S_MB_2U_LIB.S9S_MB_2U(SCH_1):PAGE60
  J111   D5     D5 CONN112_10137002101LF-CONN112_A    I74 @S9S_MB_2U_LIB.S9S_MB_2U(SCH_1):PAGE148

P5E_CPU1_PE0_RX_DN<4> @S9S_MB_2U_LIB.S9S_MB_2U(SCH_1):P5E_CPU1_PE0_RX_DN(4)
    U1  V10 PE0_RX_DN4 SOCKET4677_AZIF0045P001C01CS-SA    I80 @S9S_MB_2U_LIB.S9S_MB_2U(SCH_1):PAGE60
  J111   B4     B4 CONN112_10137002101LF-CONN112_A    I75 @S9S_MB_2U_LIB.S9S_MB_2U(SCH_1):PAGE148

P5E_CPU1_PE0_RX_DN<5> @S9S_MB_2U_LIB.S9S_MB_2U(SCH_1):P5E_CPU1_PE0_RX_DN(5)
    U1  AA9 PE0_RX_DN5 SOCKET4677_AZIF0045P001C01CS-SA    I80 @S9S_MB_2U_LIB.S9S_MB_2U(SCH_1):PAGE60
  J111   C3     C3 CONN112_10137002101LF-CONN112_A    I75 @S9S_MB_2U_LIB.S9S_MB_2U(SCH_1):PAGE148

P5E_CPU1_PE0_RX_DN<6> @S9S_MB_2U_LIB.S9S_MB_2U(SCH_1):P5E_CPU1_PE0_RX_DN(6)
    U1 AB10 PE0_RX_DN6 SOCKET4677_AZIF0045P001C01CS-SA    I80 @S9S_MB_2U_LIB.S9S_MB_2U(SCH_1):PAGE60
  J111   B2     B2 CONN112_10137002101LF-CONN112_A    I75 @S9S_MB_2U_LIB.S9S_MB_2U(SCH_1):PAGE148

P5E_CPU1_PE0_RX_DN<7> @S9S_MB_2U_LIB.S9S_MB_2U(SCH_1):P5E_CPU1_PE0_RX_DN(7)
    U1  AE9 PE0_RX_DN7 SOCKET4677_AZIF0045P001C01CS-SA    I80 @S9S_MB_2U_LIB.S9S_MB_2U(SCH_1):PAGE60
  J111   C1     C1 CONN112_10137002101LF-CONN112_A    I75 @S9S_MB_2U_LIB.S9S_MB_2U(SCH_1):PAGE148

P5E_CPU1_PE0_RX_DN<8> @S9S_MB_2U_LIB.S9S_MB_2U(SCH_1):P5E_CPU1_PE0_RX_DN(8)
    U1 AF10 PE0_RX_DN8 SOCKET4677_AZIF0045P001C01CS-SA    I80 @S9S_MB_2U_LIB.S9S_MB_2U(SCH_1):PAGE60
  J112   B8     B8 CONN160_10131762101LF-CONN160_A    I75 @S9S_MB_2U_LIB.S9S_MB_2U(SCH_1):PAGE149

P5E_CPU1_PE0_RX_DN<9> @S9S_MB_2U_LIB.S9S_MB_2U(SCH_1):P5E_CPU1_PE0_RX_DN(9)
    U1  AJ9 PE0_RX_DN9 SOCKET4677_AZIF0045P001C01CS-SA    I80 @S9S_MB_2U_LIB.S9S_MB_2U(SCH_1):PAGE60
  J112   C7     C7 CONN160_10131762101LF-CONN160_A    I75 @S9S_MB_2U_LIB.S9S_MB_2U(SCH_1):PAGE149

P5E_CPU1_PE0_RX_DP<0> @S9S_MB_2U_LIB.S9S_MB_2U(SCH_1):P5E_CPU1_PE0_RX_DP(0)
    U1  L11 PE0_RX_DP0 SOCKET4677_AZIF0045P001C01CS-SA    I80 @S9S_MB_2U_LIB.S9S_MB_2U(SCH_1):PAGE60
  J111   C8     C8 CONN112_10137002101LF-CONN112_A    I74 @S9S_MB_2U_LIB.S9S_MB_2U(SCH_1):PAGE148

P5E_CPU1_PE0_RX_DP<10> @S9S_MB_2U_LIB.S9S_MB_2U(SCH_1):P5E_CPU1_PE0_RX_DP(10)
    U1 AL11 PE0_RX_DP10 SOCKET4677_AZIF0045P001C01CS-SA    I80 @S9S_MB_2U_LIB.S9S_MB_2U(SCH_1):PAGE60
  J112   C6     C6 CONN160_10131762101LF-CONN160_A    I75 @S9S_MB_2U_LIB.S9S_MB_2U(SCH_1):PAGE149

P5E_CPU1_PE0_RX_DP<11> @S9S_MB_2U_LIB.S9S_MB_2U(SCH_1):P5E_CPU1_PE0_RX_DP(11)
    U1  AN9 PE0_RX_DP11 SOCKET4677_AZIF0045P001C01CS-SA    I80 @S9S_MB_2U_LIB.S9S_MB_2U(SCH_1):PAGE60
  J112   C5     C5 CONN160_10131762101LF-CONN160_A    I75 @S9S_MB_2U_LIB.S9S_MB_2U(SCH_1):PAGE149

P5E_CPU1_PE0_RX_DP<12> @S9S_MB_2U_LIB.S9S_MB_2U(SCH_1):P5E_CPU1_PE0_RX_DP(12)
    U1 AR11 PE0_RX_DP12 SOCKET4677_AZIF0045P001C01CS-SA    I80 @S9S_MB_2U_LIB.S9S_MB_2U(SCH_1):PAGE60
  J112   C4     C4 CONN160_10131762101LF-CONN160_A    I76 @S9S_MB_2U_LIB.S9S_MB_2U(SCH_1):PAGE149

P5E_CPU1_PE0_RX_DP<13> @S9S_MB_2U_LIB.S9S_MB_2U(SCH_1):P5E_CPU1_PE0_RX_DP(13)
    U1 AT10 PE0_RX_DP13 SOCKET4677_AZIF0045P001C01CS-SA    I80 @S9S_MB_2U_LIB.S9S_MB_2U(SCH_1):PAGE60
  J112   D3     D3 CONN160_10131762101LF-CONN160_A    I76 @S9S_MB_2U_LIB.S9S_MB_2U(SCH_1):PAGE149

P5E_CPU1_PE0_RX_DP<14> @S9S_MB_2U_LIB.S9S_MB_2U(SCH_1):P5E_CPU1_PE0_RX_DP(14)
    U1 AW11 PE0_RX_DP14 SOCKET4677_AZIF0045P001C01CS-SA    I80 @S9S_MB_2U_LIB.S9S_MB_2U(SCH_1):PAGE60
  J112   C2     C2 CONN160_10131762101LF-CONN160_A    I76 @S9S_MB_2U_LIB.S9S_MB_2U(SCH_1):PAGE149

P5E_CPU1_PE0_RX_DP<15> @S9S_MB_2U_LIB.S9S_MB_2U(SCH_1):P5E_CPU1_PE0_RX_DP(15)
    U1 AY10 PE0_RX_DP15 SOCKET4677_AZIF0045P001C01CS-SA    I80 @S9S_MB_2U_LIB.S9S_MB_2U(SCH_1):PAGE60
  J112   D1     D1 CONN160_10131762101LF-CONN160_A    I76 @S9S_MB_2U_LIB.S9S_MB_2U(SCH_1):PAGE149

P5E_CPU1_PE0_RX_DP<1> @S9S_MB_2U_LIB.S9S_MB_2U(SCH_1):P5E_CPU1_PE0_RX_DP(1)
    U1   N9 PE0_RX_DP1 SOCKET4677_AZIF0045P001C01CS-SA    I80 @S9S_MB_2U_LIB.S9S_MB_2U(SCH_1):PAGE60
  J111   C7     C7 CONN112_10137002101LF-CONN112_A    I74 @S9S_MB_2U_LIB.S9S_MB_2U(SCH_1):PAGE148

P5E_CPU1_PE0_RX_DP<2> @S9S_MB_2U_LIB.S9S_MB_2U(SCH_1):P5E_CPU1_PE0_RX_DP(2)
    U1  R11 PE0_RX_DP2 SOCKET4677_AZIF0045P001C01CS-SA    I80 @S9S_MB_2U_LIB.S9S_MB_2U(SCH_1):PAGE60
  J111   C6     C6 CONN112_10137002101LF-CONN112_A    I74 @S9S_MB_2U_LIB.S9S_MB_2U(SCH_1):PAGE148

P5E_CPU1_PE0_RX_DP<3> @S9S_MB_2U_LIB.S9S_MB_2U(SCH_1):P5E_CPU1_PE0_RX_DP(3)
    U1   U9 PE0_RX_DP3 SOCKET4677_AZIF0045P001C01CS-SA    I80 @S9S_MB_2U_LIB.S9S_MB_2U(SCH_1):PAGE60
  J111   C5     C5 CONN112_10137002101LF-CONN112_A    I74 @S9S_MB_2U_LIB.S9S_MB_2U(SCH_1):PAGE148

P5E_CPU1_PE0_RX_DP<4> @S9S_MB_2U_LIB.S9S_MB_2U(SCH_1):P5E_CPU1_PE0_RX_DP(4)
    U1  W11 PE0_RX_DP4 SOCKET4677_AZIF0045P001C01CS-SA    I80 @S9S_MB_2U_LIB.S9S_MB_2U(SCH_1):PAGE60
  J111   C4     C4 CONN112_10137002101LF-CONN112_A    I75 @S9S_MB_2U_LIB.S9S_MB_2U(SCH_1):PAGE148

P5E_CPU1_PE0_RX_DP<5> @S9S_MB_2U_LIB.S9S_MB_2U(SCH_1):P5E_CPU1_PE0_RX_DP(5)
    U1  Y10 PE0_RX_DP5 SOCKET4677_AZIF0045P001C01CS-SA    I80 @S9S_MB_2U_LIB.S9S_MB_2U(SCH_1):PAGE60
  J111   D3     D3 CONN112_10137002101LF-CONN112_A    I75 @S9S_MB_2U_LIB.S9S_MB_2U(SCH_1):PAGE148

P5E_CPU1_PE0_RX_DP<6> @S9S_MB_2U_LIB.S9S_MB_2U(SCH_1):P5E_CPU1_PE0_RX_DP(6)
    U1 AC11 PE0_RX_DP6 SOCKET4677_AZIF0045P001C01CS-SA    I80 @S9S_MB_2U_LIB.S9S_MB_2U(SCH_1):PAGE60
  J111   C2     C2 CONN112_10137002101LF-CONN112_A    I75 @S9S_MB_2U_LIB.S9S_MB_2U(SCH_1):PAGE148

P5E_CPU1_PE0_RX_DP<7> @S9S_MB_2U_LIB.S9S_MB_2U(SCH_1):P5E_CPU1_PE0_RX_DP(7)
    U1 AD10 PE0_RX_DP7 SOCKET4677_AZIF0045P001C01CS-SA    I80 @S9S_MB_2U_LIB.S9S_MB_2U(SCH_1):PAGE60
  J111   D1     D1 CONN112_10137002101LF-CONN112_A    I75 @S9S_MB_2U_LIB.S9S_MB_2U(SCH_1):PAGE148

P5E_CPU1_PE0_RX_DP<8> @S9S_MB_2U_LIB.S9S_MB_2U(SCH_1):P5E_CPU1_PE0_RX_DP(8)
    U1 AG11 PE0_RX_DP8 SOCKET4677_AZIF0045P001C01CS-SA    I80 @S9S_MB_2U_LIB.S9S_MB_2U(SCH_1):PAGE60
  J112   C8     C8 CONN160_10131762101LF-CONN160_A    I75 @S9S_MB_2U_LIB.S9S_MB_2U(SCH_1):PAGE149

P5E_CPU1_PE0_RX_DP<9> @S9S_MB_2U_LIB.S9S_MB_2U(SCH_1):P5E_CPU1_PE0_RX_DP(9)
    U1 AH10 PE0_RX_DP9 SOCKET4677_AZIF0045P001C01CS-SA    I80 @S9S_MB_2U_LIB.S9S_MB_2U(SCH_1):PAGE60
  J112   D7     D7 CONN160_10131762101LF-CONN160_A    I75 @S9S_MB_2U_LIB.S9S_MB_2U(SCH_1):PAGE149

P5E_CPU1_PE0_TX_C_DN<0> @S9S_MB_2U_LIB.S9S_MB_2U(SCH_1):P5E_CPU1_PE0_TX_C_DN(0)
  J111   H8     H8 CONN112_10137002101LF-CONN112_A    I74 @S9S_MB_2U_LIB.S9S_MB_2U(SCH_1):PAGE148
  C740    1      1 Q_CAP_DIFFBUS_C0201-DIFF BUS_0A   I229 @S9S_MB_2U_LIB.S9S_MB_2U(SCH_1):PAGE167

P5E_CPU1_PE0_TX_C_DN<10> @S9S_MB_2U_LIB.S9S_MB_2U(SCH_1):P5E_CPU1_PE0_TX_C_DN(10)
  C720    1      1 Q_CAP_DIFFBUS_C0201-DIFF BUS_0A   I279 @S9S_MB_2U_LIB.S9S_MB_2U(SCH_1):PAGE167
  J112   H6     H6 CONN160_10131762101LF-CONN160_A    I75 @S9S_MB_2U_LIB.S9S_MB_2U(SCH_1):PAGE149

P5E_CPU1_PE0_TX_C_DN<11> @S9S_MB_2U_LIB.S9S_MB_2U(SCH_1):P5E_CPU1_PE0_TX_C_DN(11)
  C718    1      1 Q_CAP_DIFFBUS_C0201-DIFF BUS_0A   I281 @S9S_MB_2U_LIB.S9S_MB_2U(SCH_1):PAGE167
  J112   I5     I5 CONN160_10131762101LF-CONN160_A    I75 @S9S_MB_2U_LIB.S9S_MB_2U(SCH_1):PAGE149

P5E_CPU1_PE0_TX_C_DN<12> @S9S_MB_2U_LIB.S9S_MB_2U(SCH_1):P5E_CPU1_PE0_TX_C_DN(12)
  C716    1      1 Q_CAP_DIFFBUS_C0201-DIFF BUS_0A   I283 @S9S_MB_2U_LIB.S9S_MB_2U(SCH_1):PAGE167
  J112   H4     H4 CONN160_10131762101LF-CONN160_A    I76 @S9S_MB_2U_LIB.S9S_MB_2U(SCH_1):PAGE149

P5E_CPU1_PE0_TX_C_DN<13> @S9S_MB_2U_LIB.S9S_MB_2U(SCH_1):P5E_CPU1_PE0_TX_C_DN(13)
  C714    1      1 Q_CAP_DIFFBUS_C0201-DIFF BUS_0A   I295 @S9S_MB_2U_LIB.S9S_MB_2U(SCH_1):PAGE167
  J112   I3     I3 CONN160_10131762101LF-CONN160_A    I76 @S9S_MB_2U_LIB.S9S_MB_2U(SCH_1):PAGE149

P5E_CPU1_PE0_TX_C_DN<14> @S9S_MB_2U_LIB.S9S_MB_2U(SCH_1):P5E_CPU1_PE0_TX_C_DN(14)
  C712    1      1 Q_CAP_DIFFBUS_C0201-DIFF BUS_0A   I296 @S9S_MB_2U_LIB.S9S_MB_2U(SCH_1):PAGE167
  J112   H2     H2 CONN160_10131762101LF-CONN160_A    I76 @S9S_MB_2U_LIB.S9S_MB_2U(SCH_1):PAGE149

P5E_CPU1_PE0_TX_C_DN<15> @S9S_MB_2U_LIB.S9S_MB_2U(SCH_1):P5E_CPU1_PE0_TX_C_DN(15)
  C710    1      1 Q_CAP_DIFFBUS_C0201-DIFF BUS_0A   I299 @S9S_MB_2U_LIB.S9S_MB_2U(SCH_1):PAGE167
  J112   I1     I1 CONN160_10131762101LF-CONN160_A    I76 @S9S_MB_2U_LIB.S9S_MB_2U(SCH_1):PAGE149

P5E_CPU1_PE0_TX_C_DN<1> @S9S_MB_2U_LIB.S9S_MB_2U(SCH_1):P5E_CPU1_PE0_TX_C_DN(1)
  J111   I7     I7 CONN112_10137002101LF-CONN112_A    I74 @S9S_MB_2U_LIB.S9S_MB_2U(SCH_1):PAGE148
  C738    1      1 Q_CAP_DIFFBUS_C0201-DIFF BUS_0A   I232 @S9S_MB_2U_LIB.S9S_MB_2U(SCH_1):PAGE167

P5E_CPU1_PE0_TX_C_DN<2> @S9S_MB_2U_LIB.S9S_MB_2U(SCH_1):P5E_CPU1_PE0_TX_C_DN(2)
  J111   H6     H6 CONN112_10137002101LF-CONN112_A    I74 @S9S_MB_2U_LIB.S9S_MB_2U(SCH_1):PAGE148
  C736    1      1 Q_CAP_DIFFBUS_C0201-DIFF BUS_0A   I234 @S9S_MB_2U_LIB.S9S_MB_2U(SCH_1):PAGE167

P5E_CPU1_PE0_TX_C_DN<3> @S9S_MB_2U_LIB.S9S_MB_2U(SCH_1):P5E_CPU1_PE0_TX_C_DN(3)
  J111   I5     I5 CONN112_10137002101LF-CONN112_A    I74 @S9S_MB_2U_LIB.S9S_MB_2U(SCH_1):PAGE148
  C734    1      1 Q_CAP_DIFFBUS_C0201-DIFF BUS_0A   I235 @S9S_MB_2U_LIB.S9S_MB_2U(SCH_1):PAGE167

P5E_CPU1_PE0_TX_C_DN<4> @S9S_MB_2U_LIB.S9S_MB_2U(SCH_1):P5E_CPU1_PE0_TX_C_DN(4)
  C732    1      1 Q_CAP_DIFFBUS_C0201-DIFF BUS_0A   I246 @S9S_MB_2U_LIB.S9S_MB_2U(SCH_1):PAGE167
  J111   H4     H4 CONN112_10137002101LF-CONN112_A    I75 @S9S_MB_2U_LIB.S9S_MB_2U(SCH_1):PAGE148

P5E_CPU1_PE0_TX_C_DN<5> @S9S_MB_2U_LIB.S9S_MB_2U(SCH_1):P5E_CPU1_PE0_TX_C_DN(5)
  C730    1      1 Q_CAP_DIFFBUS_C0201-DIFF BUS_0A   I248 @S9S_MB_2U_LIB.S9S_MB_2U(SCH_1):PAGE167
  J111   I3     I3 CONN112_10137002101LF-CONN112_A    I75 @S9S_MB_2U_LIB.S9S_MB_2U(SCH_1):PAGE148

P5E_CPU1_PE0_TX_C_DN<6> @S9S_MB_2U_LIB.S9S_MB_2U(SCH_1):P5E_CPU1_PE0_TX_C_DN(6)
  C728    1      1 Q_CAP_DIFFBUS_C0201-DIFF BUS_0A   I250 @S9S_MB_2U_LIB.S9S_MB_2U(SCH_1):PAGE167
  J111   H2     H2 CONN112_10137002101LF-CONN112_A    I75 @S9S_MB_2U_LIB.S9S_MB_2U(SCH_1):PAGE148

P5E_CPU1_PE0_TX_C_DN<7> @S9S_MB_2U_LIB.S9S_MB_2U(SCH_1):P5E_CPU1_PE0_TX_C_DN(7)
  C726    1      1 Q_CAP_DIFFBUS_C0201-DIFF BUS_0A   I312 @S9S_MB_2U_LIB.S9S_MB_2U(SCH_1):PAGE167
  J111   I1     I1 CONN112_10137002101LF-CONN112_A    I75 @S9S_MB_2U_LIB.S9S_MB_2U(SCH_1):PAGE148

P5E_CPU1_PE0_TX_C_DN<8> @S9S_MB_2U_LIB.S9S_MB_2U(SCH_1):P5E_CPU1_PE0_TX_C_DN(8)
  C724    1      1 Q_CAP_DIFFBUS_C0201-DIFF BUS_0A   I275 @S9S_MB_2U_LIB.S9S_MB_2U(SCH_1):PAGE167
  J112   H8     H8 CONN160_10131762101LF-CONN160_A    I75 @S9S_MB_2U_LIB.S9S_MB_2U(SCH_1):PAGE149

P5E_CPU1_PE0_TX_C_DN<9> @S9S_MB_2U_LIB.S9S_MB_2U(SCH_1):P5E_CPU1_PE0_TX_C_DN(9)
  C722    1      1 Q_CAP_DIFFBUS_C0201-DIFF BUS_0A   I276 @S9S_MB_2U_LIB.S9S_MB_2U(SCH_1):PAGE167
  J112   I7     I7 CONN160_10131762101LF-CONN160_A    I75 @S9S_MB_2U_LIB.S9S_MB_2U(SCH_1):PAGE149

P5E_CPU1_PE0_TX_C_DP<0> @S9S_MB_2U_LIB.S9S_MB_2U(SCH_1):P5E_CPU1_PE0_TX_C_DP(0)
  J111   I8     I8 CONN112_10137002101LF-CONN112_A    I74 @S9S_MB_2U_LIB.S9S_MB_2U(SCH_1):PAGE148
  C741    1      1 Q_CAP_DIFFBUS_C0201-DIFF BUS_0A   I230 @S9S_MB_2U_LIB.S9S_MB_2U(SCH_1):PAGE167

P5E_CPU1_PE0_TX_C_DP<10> @S9S_MB_2U_LIB.S9S_MB_2U(SCH_1):P5E_CPU1_PE0_TX_C_DP(10)
  C721    1      1 Q_CAP_DIFFBUS_C0201-DIFF BUS_0A   I278 @S9S_MB_2U_LIB.S9S_MB_2U(SCH_1):PAGE167
  J112   I6     I6 CONN160_10131762101LF-CONN160_A    I75 @S9S_MB_2U_LIB.S9S_MB_2U(SCH_1):PAGE149

P5E_CPU1_PE0_TX_C_DP<11> @S9S_MB_2U_LIB.S9S_MB_2U(SCH_1):P5E_CPU1_PE0_TX_C_DP(11)
  C719    1      1 Q_CAP_DIFFBUS_C0201-DIFF BUS_0A   I280 @S9S_MB_2U_LIB.S9S_MB_2U(SCH_1):PAGE167
  J112   J5     J5 CONN160_10131762101LF-CONN160_A    I75 @S9S_MB_2U_LIB.S9S_MB_2U(SCH_1):PAGE149

P5E_CPU1_PE0_TX_C_DP<12> @S9S_MB_2U_LIB.S9S_MB_2U(SCH_1):P5E_CPU1_PE0_TX_C_DP(12)
  C717    1      1 Q_CAP_DIFFBUS_C0201-DIFF BUS_0A   I282 @S9S_MB_2U_LIB.S9S_MB_2U(SCH_1):PAGE167
  J112   I4     I4 CONN160_10131762101LF-CONN160_A    I76 @S9S_MB_2U_LIB.S9S_MB_2U(SCH_1):PAGE149

P5E_CPU1_PE0_TX_C_DP<13> @S9S_MB_2U_LIB.S9S_MB_2U(SCH_1):P5E_CPU1_PE0_TX_C_DP(13)
  C715    1      1 Q_CAP_DIFFBUS_C0201-DIFF BUS_0A   I294 @S9S_MB_2U_LIB.S9S_MB_2U(SCH_1):PAGE167
  J112   J3     J3 CONN160_10131762101LF-CONN160_A    I76 @S9S_MB_2U_LIB.S9S_MB_2U(SCH_1):PAGE149

P5E_CPU1_PE0_TX_C_DP<14> @S9S_MB_2U_LIB.S9S_MB_2U(SCH_1):P5E_CPU1_PE0_TX_C_DP(14)
  C713    1      1 Q_CAP_DIFFBUS_C0201-DIFF BUS_0A   I297 @S9S_MB_2U_LIB.S9S_MB_2U(SCH_1):PAGE167
  J112   I2     I2 CONN160_10131762101LF-CONN160_A    I76 @S9S_MB_2U_LIB.S9S_MB_2U(SCH_1):PAGE149

P5E_CPU1_PE0_TX_C_DP<15> @S9S_MB_2U_LIB.S9S_MB_2U(SCH_1):P5E_CPU1_PE0_TX_C_DP(15)
  C711    1      1 Q_CAP_DIFFBUS_C0201-DIFF BUS_0A   I298 @S9S_MB_2U_LIB.S9S_MB_2U(SCH_1):PAGE167
  J112   J1     J1 CONN160_10131762101LF-CONN160_A    I76 @S9S_MB_2U_LIB.S9S_MB_2U(SCH_1):PAGE149

P5E_CPU1_PE0_TX_C_DP<1> @S9S_MB_2U_LIB.S9S_MB_2U(SCH_1):P5E_CPU1_PE0_TX_C_DP(1)
  J111   J7     J7 CONN112_10137002101LF-CONN112_A    I74 @S9S_MB_2U_LIB.S9S_MB_2U(SCH_1):PAGE148
  C739    1      1 Q_CAP_DIFFBUS_C0201-DIFF BUS_0A   I231 @S9S_MB_2U_LIB.S9S_MB_2U(SCH_1):PAGE167

P5E_CPU1_PE0_TX_C_DP<2> @S9S_MB_2U_LIB.S9S_MB_2U(SCH_1):P5E_CPU1_PE0_TX_C_DP(2)
  J111   I6     I6 CONN112_10137002101LF-CONN112_A    I74 @S9S_MB_2U_LIB.S9S_MB_2U(SCH_1):PAGE148
  C737    1      1 Q_CAP_DIFFBUS_C0201-DIFF BUS_0A   I233 @S9S_MB_2U_LIB.S9S_MB_2U(SCH_1):PAGE167

P5E_CPU1_PE0_TX_C_DP<3> @S9S_MB_2U_LIB.S9S_MB_2U(SCH_1):P5E_CPU1_PE0_TX_C_DP(3)
  J111   J5     J5 CONN112_10137002101LF-CONN112_A    I74 @S9S_MB_2U_LIB.S9S_MB_2U(SCH_1):PAGE148
  C735    1      1 Q_CAP_DIFFBUS_C0201-DIFF BUS_0A   I236 @S9S_MB_2U_LIB.S9S_MB_2U(SCH_1):PAGE167

P5E_CPU1_PE0_TX_C_DP<4> @S9S_MB_2U_LIB.S9S_MB_2U(SCH_1):P5E_CPU1_PE0_TX_C_DP(4)
  C733    1      1 Q_CAP_DIFFBUS_C0201-DIFF BUS_0A   I237 @S9S_MB_2U_LIB.S9S_MB_2U(SCH_1):PAGE167
  J111   I4     I4 CONN112_10137002101LF-CONN112_A    I75 @S9S_MB_2U_LIB.S9S_MB_2U(SCH_1):PAGE148

P5E_CPU1_PE0_TX_C_DP<5> @S9S_MB_2U_LIB.S9S_MB_2U(SCH_1):P5E_CPU1_PE0_TX_C_DP(5)
  C731    1      1 Q_CAP_DIFFBUS_C0201-DIFF BUS_0A   I247 @S9S_MB_2U_LIB.S9S_MB_2U(SCH_1):PAGE167
  J111   J3     J3 CONN112_10137002101LF-CONN112_A    I75 @S9S_MB_2U_LIB.S9S_MB_2U(SCH_1):PAGE148

P5E_CPU1_PE0_TX_C_DP<6> @S9S_MB_2U_LIB.S9S_MB_2U(SCH_1):P5E_CPU1_PE0_TX_C_DP(6)
  C729    1      1 Q_CAP_DIFFBUS_C0201-DIFF BUS_0A   I249 @S9S_MB_2U_LIB.S9S_MB_2U(SCH_1):PAGE167
  J111   I2     I2 CONN112_10137002101LF-CONN112_A    I75 @S9S_MB_2U_LIB.S9S_MB_2U(SCH_1):PAGE148

P5E_CPU1_PE0_TX_C_DP<7> @S9S_MB_2U_LIB.S9S_MB_2U(SCH_1):P5E_CPU1_PE0_TX_C_DP(7)
  C727    1      1 Q_CAP_DIFFBUS_C0201-DIFF BUS_0A   I251 @S9S_MB_2U_LIB.S9S_MB_2U(SCH_1):PAGE167
  J111   J1     J1 CONN112_10137002101LF-CONN112_A    I75 @S9S_MB_2U_LIB.S9S_MB_2U(SCH_1):PAGE148

P5E_CPU1_PE0_TX_C_DP<8> @S9S_MB_2U_LIB.S9S_MB_2U(SCH_1):P5E_CPU1_PE0_TX_C_DP(8)
  C725    1      1 Q_CAP_DIFFBUS_C0201-DIFF BUS_0A   I274 @S9S_MB_2U_LIB.S9S_MB_2U(SCH_1):PAGE167
  J112   I8     I8 CONN160_10131762101LF-CONN160_A    I75 @S9S_MB_2U_LIB.S9S_MB_2U(SCH_1):PAGE149

P5E_CPU1_PE0_TX_C_DP<9> @S9S_MB_2U_LIB.S9S_MB_2U(SCH_1):P5E_CPU1_PE0_TX_C_DP(9)
  C723    1      1 Q_CAP_DIFFBUS_C0201-DIFF BUS_0A   I277 @S9S_MB_2U_LIB.S9S_MB_2U(SCH_1):PAGE167
  J112   J7     J7 CONN160_10131762101LF-CONN160_A    I75 @S9S_MB_2U_LIB.S9S_MB_2U(SCH_1):PAGE149

P5E_CPU1_PE0_TX_DN<0> @S9S_MB_2U_LIB.S9S_MB_2U(SCH_1):P5E_CPU1_PE0_TX_DN(0)
    U1  N13 PE0_TX_DN0 SOCKET4677_AZIF0045P001C01CS-SA    I80 @S9S_MB_2U_LIB.S9S_MB_2U(SCH_1):PAGE60
  C740    2      2 Q_CAP_DIFFBUS_C0201-DIFF BUS_0A   I229 @S9S_MB_2U_LIB.S9S_MB_2U(SCH_1):PAGE167

P5E_CPU1_PE0_TX_DN<10> @S9S_MB_2U_LIB.S9S_MB_2U(SCH_1):P5E_CPU1_PE0_TX_DN(10)
    U1 AN13 PE0_TX_DN10 SOCKET4677_AZIF0045P001C01CS-SA    I80 @S9S_MB_2U_LIB.S9S_MB_2U(SCH_1):PAGE60
  C720    2      2 Q_CAP_DIFFBUS_C0201-DIFF BUS_0A   I279 @S9S_MB_2U_LIB.S9S_MB_2U(SCH_1):PAGE167

P5E_CPU1_PE0_TX_DN<11> @S9S_MB_2U_LIB.S9S_MB_2U(SCH_1):P5E_CPU1_PE0_TX_DN(11)
    U1 AP14 PE0_TX_DN11 SOCKET4677_AZIF0045P001C01CS-SA    I80 @S9S_MB_2U_LIB.S9S_MB_2U(SCH_1):PAGE60
  C718    2      2 Q_CAP_DIFFBUS_C0201-DIFF BUS_0A   I281 @S9S_MB_2U_LIB.S9S_MB_2U(SCH_1):PAGE167

P5E_CPU1_PE0_TX_DN<12> @S9S_MB_2U_LIB.S9S_MB_2U(SCH_1):P5E_CPU1_PE0_TX_DN(12)
    U1 AU13 PE0_TX_DN12 SOCKET4677_AZIF0045P001C01CS-SA    I80 @S9S_MB_2U_LIB.S9S_MB_2U(SCH_1):PAGE60
  C716    2      2 Q_CAP_DIFFBUS_C0201-DIFF BUS_0A   I283 @S9S_MB_2U_LIB.S9S_MB_2U(SCH_1):PAGE167

P5E_CPU1_PE0_TX_DN<13> @S9S_MB_2U_LIB.S9S_MB_2U(SCH_1):P5E_CPU1_PE0_TX_DN(13)
    U1 AV14 PE0_TX_DN13 SOCKET4677_AZIF0045P001C01CS-SA    I80 @S9S_MB_2U_LIB.S9S_MB_2U(SCH_1):PAGE60
  C714    2      2 Q_CAP_DIFFBUS_C0201-DIFF BUS_0A   I295 @S9S_MB_2U_LIB.S9S_MB_2U(SCH_1):PAGE167

P5E_CPU1_PE0_TX_DN<14> @S9S_MB_2U_LIB.S9S_MB_2U(SCH_1):P5E_CPU1_PE0_TX_DN(14)
    U1 BA13 PE0_TX_DN14 SOCKET4677_AZIF0045P001C01CS-SA    I80 @S9S_MB_2U_LIB.S9S_MB_2U(SCH_1):PAGE60
  C712    2      2 Q_CAP_DIFFBUS_C0201-DIFF BUS_0A   I296 @S9S_MB_2U_LIB.S9S_MB_2U(SCH_1):PAGE167

P5E_CPU1_PE0_TX_DN<15> @S9S_MB_2U_LIB.S9S_MB_2U(SCH_1):P5E_CPU1_PE0_TX_DN(15)
    U1 BB14 PE0_TX_DN15 SOCKET4677_AZIF0045P001C01CS-SA    I80 @S9S_MB_2U_LIB.S9S_MB_2U(SCH_1):PAGE60
  C710    2      2 Q_CAP_DIFFBUS_C0201-DIFF BUS_0A   I299 @S9S_MB_2U_LIB.S9S_MB_2U(SCH_1):PAGE167

P5E_CPU1_PE0_TX_DN<1> @S9S_MB_2U_LIB.S9S_MB_2U(SCH_1):P5E_CPU1_PE0_TX_DN(1)
    U1  P14 PE0_TX_DN1 SOCKET4677_AZIF0045P001C01CS-SA    I80 @S9S_MB_2U_LIB.S9S_MB_2U(SCH_1):PAGE60
  C738    2      2 Q_CAP_DIFFBUS_C0201-DIFF BUS_0A   I232 @S9S_MB_2U_LIB.S9S_MB_2U(SCH_1):PAGE167

P5E_CPU1_PE0_TX_DN<2> @S9S_MB_2U_LIB.S9S_MB_2U(SCH_1):P5E_CPU1_PE0_TX_DN(2)
    U1  U13 PE0_TX_DN2 SOCKET4677_AZIF0045P001C01CS-SA    I80 @S9S_MB_2U_LIB.S9S_MB_2U(SCH_1):PAGE60
  C736    2      2 Q_CAP_DIFFBUS_C0201-DIFF BUS_0A   I234 @S9S_MB_2U_LIB.S9S_MB_2U(SCH_1):PAGE167

P5E_CPU1_PE0_TX_DN<3> @S9S_MB_2U_LIB.S9S_MB_2U(SCH_1):P5E_CPU1_PE0_TX_DN(3)
    U1  V14 PE0_TX_DN3 SOCKET4677_AZIF0045P001C01CS-SA    I80 @S9S_MB_2U_LIB.S9S_MB_2U(SCH_1):PAGE60
  C734    2      2 Q_CAP_DIFFBUS_C0201-DIFF BUS_0A   I235 @S9S_MB_2U_LIB.S9S_MB_2U(SCH_1):PAGE167

P5E_CPU1_PE0_TX_DN<4> @S9S_MB_2U_LIB.S9S_MB_2U(SCH_1):P5E_CPU1_PE0_TX_DN(4)
    U1 AA13 PE0_TX_DN4 SOCKET4677_AZIF0045P001C01CS-SA    I80 @S9S_MB_2U_LIB.S9S_MB_2U(SCH_1):PAGE60
  C732    2      2 Q_CAP_DIFFBUS_C0201-DIFF BUS_0A   I246 @S9S_MB_2U_LIB.S9S_MB_2U(SCH_1):PAGE167

P5E_CPU1_PE0_TX_DN<5> @S9S_MB_2U_LIB.S9S_MB_2U(SCH_1):P5E_CPU1_PE0_TX_DN(5)
    U1 AB14 PE0_TX_DN5 SOCKET4677_AZIF0045P001C01CS-SA    I80 @S9S_MB_2U_LIB.S9S_MB_2U(SCH_1):PAGE60
  C730    2      2 Q_CAP_DIFFBUS_C0201-DIFF BUS_0A   I248 @S9S_MB_2U_LIB.S9S_MB_2U(SCH_1):PAGE167

P5E_CPU1_PE0_TX_DN<6> @S9S_MB_2U_LIB.S9S_MB_2U(SCH_1):P5E_CPU1_PE0_TX_DN(6)
    U1 AE13 PE0_TX_DN6 SOCKET4677_AZIF0045P001C01CS-SA    I80 @S9S_MB_2U_LIB.S9S_MB_2U(SCH_1):PAGE60
  C728    2      2 Q_CAP_DIFFBUS_C0201-DIFF BUS_0A   I250 @S9S_MB_2U_LIB.S9S_MB_2U(SCH_1):PAGE167

P5E_CPU1_PE0_TX_DN<7> @S9S_MB_2U_LIB.S9S_MB_2U(SCH_1):P5E_CPU1_PE0_TX_DN(7)
    U1 AF14 PE0_TX_DN7 SOCKET4677_AZIF0045P001C01CS-SA    I80 @S9S_MB_2U_LIB.S9S_MB_2U(SCH_1):PAGE60
  C726    2      2 Q_CAP_DIFFBUS_C0201-DIFF BUS_0A   I312 @S9S_MB_2U_LIB.S9S_MB_2U(SCH_1):PAGE167

P5E_CPU1_PE0_TX_DN<8> @S9S_MB_2U_LIB.S9S_MB_2U(SCH_1):P5E_CPU1_PE0_TX_DN(8)
    U1 AJ13 PE0_TX_DN8 SOCKET4677_AZIF0045P001C01CS-SA    I80 @S9S_MB_2U_LIB.S9S_MB_2U(SCH_1):PAGE60
  C724    2      2 Q_CAP_DIFFBUS_C0201-DIFF BUS_0A   I275 @S9S_MB_2U_LIB.S9S_MB_2U(SCH_1):PAGE167

P5E_CPU1_PE0_TX_DN<9> @S9S_MB_2U_LIB.S9S_MB_2U(SCH_1):P5E_CPU1_PE0_TX_DN(9)
    U1 AK14 PE0_TX_DN9 SOCKET4677_AZIF0045P001C01CS-SA    I80 @S9S_MB_2U_LIB.S9S_MB_2U(SCH_1):PAGE60
  C722    2      2 Q_CAP_DIFFBUS_C0201-DIFF BUS_0A   I276 @S9S_MB_2U_LIB.S9S_MB_2U(SCH_1):PAGE167

P5E_CPU1_PE0_TX_DP<0> @S9S_MB_2U_LIB.S9S_MB_2U(SCH_1):P5E_CPU1_PE0_TX_DP(0)
    U1  M14 PE0_TX_DP0 SOCKET4677_AZIF0045P001C01CS-SA    I80 @S9S_MB_2U_LIB.S9S_MB_2U(SCH_1):PAGE60
  C741    2      2 Q_CAP_DIFFBUS_C0201-DIFF BUS_0A   I230 @S9S_MB_2U_LIB.S9S_MB_2U(SCH_1):PAGE167

P5E_CPU1_PE0_TX_DP<10> @S9S_MB_2U_LIB.S9S_MB_2U(SCH_1):P5E_CPU1_PE0_TX_DP(10)
    U1 AM14 PE0_TX_DP10 SOCKET4677_AZIF0045P001C01CS-SA    I80 @S9S_MB_2U_LIB.S9S_MB_2U(SCH_1):PAGE60
  C721    2      2 Q_CAP_DIFFBUS_C0201-DIFF BUS_0A   I278 @S9S_MB_2U_LIB.S9S_MB_2U(SCH_1):PAGE167

P5E_CPU1_PE0_TX_DP<11> @S9S_MB_2U_LIB.S9S_MB_2U(SCH_1):P5E_CPU1_PE0_TX_DP(11)
    U1 AR15 PE0_TX_DP11 SOCKET4677_AZIF0045P001C01CS-SA    I80 @S9S_MB_2U_LIB.S9S_MB_2U(SCH_1):PAGE60
  C719    2      2 Q_CAP_DIFFBUS_C0201-DIFF BUS_0A   I280 @S9S_MB_2U_LIB.S9S_MB_2U(SCH_1):PAGE167

P5E_CPU1_PE0_TX_DP<12> @S9S_MB_2U_LIB.S9S_MB_2U(SCH_1):P5E_CPU1_PE0_TX_DP(12)
    U1 AT14 PE0_TX_DP12 SOCKET4677_AZIF0045P001C01CS-SA    I80 @S9S_MB_2U_LIB.S9S_MB_2U(SCH_1):PAGE60
  C717    2      2 Q_CAP_DIFFBUS_C0201-DIFF BUS_0A   I282 @S9S_MB_2U_LIB.S9S_MB_2U(SCH_1):PAGE167

P5E_CPU1_PE0_TX_DP<13> @S9S_MB_2U_LIB.S9S_MB_2U(SCH_1):P5E_CPU1_PE0_TX_DP(13)
    U1 AW15 PE0_TX_DP13 SOCKET4677_AZIF0045P001C01CS-SA    I80 @S9S_MB_2U_LIB.S9S_MB_2U(SCH_1):PAGE60
  C715    2      2 Q_CAP_DIFFBUS_C0201-DIFF BUS_0A   I294 @S9S_MB_2U_LIB.S9S_MB_2U(SCH_1):PAGE167

P5E_CPU1_PE0_TX_DP<14> @S9S_MB_2U_LIB.S9S_MB_2U(SCH_1):P5E_CPU1_PE0_TX_DP(14)
    U1 AY14 PE0_TX_DP14 SOCKET4677_AZIF0045P001C01CS-SA    I80 @S9S_MB_2U_LIB.S9S_MB_2U(SCH_1):PAGE60
  C713    2      2 Q_CAP_DIFFBUS_C0201-DIFF BUS_0A   I297 @S9S_MB_2U_LIB.S9S_MB_2U(SCH_1):PAGE167

P5E_CPU1_PE0_TX_DP<15> @S9S_MB_2U_LIB.S9S_MB_2U(SCH_1):P5E_CPU1_PE0_TX_DP(15)
    U1 BC15 PE0_TX_DP15 SOCKET4677_AZIF0045P001C01CS-SA    I80 @S9S_MB_2U_LIB.S9S_MB_2U(SCH_1):PAGE60
  C711    2      2 Q_CAP_DIFFBUS_C0201-DIFF BUS_0A   I298 @S9S_MB_2U_LIB.S9S_MB_2U(SCH_1):PAGE167

P5E_CPU1_PE0_TX_DP<1> @S9S_MB_2U_LIB.S9S_MB_2U(SCH_1):P5E_CPU1_PE0_TX_DP(1)
    U1  R15 PE0_TX_DP1 SOCKET4677_AZIF0045P001C01CS-SA    I80 @S9S_MB_2U_LIB.S9S_MB_2U(SCH_1):PAGE60
  C739    2      2 Q_CAP_DIFFBUS_C0201-DIFF BUS_0A   I231 @S9S_MB_2U_LIB.S9S_MB_2U(SCH_1):PAGE167

P5E_CPU1_PE0_TX_DP<2> @S9S_MB_2U_LIB.S9S_MB_2U(SCH_1):P5E_CPU1_PE0_TX_DP(2)
    U1  T14 PE0_TX_DP2 SOCKET4677_AZIF0045P001C01CS-SA    I80 @S9S_MB_2U_LIB.S9S_MB_2U(SCH_1):PAGE60
  C737    2      2 Q_CAP_DIFFBUS_C0201-DIFF BUS_0A   I233 @S9S_MB_2U_LIB.S9S_MB_2U(SCH_1):PAGE167

P5E_CPU1_PE0_TX_DP<3> @S9S_MB_2U_LIB.S9S_MB_2U(SCH_1):P5E_CPU1_PE0_TX_DP(3)
    U1  W15 PE0_TX_DP3 SOCKET4677_AZIF0045P001C01CS-SA    I80 @S9S_MB_2U_LIB.S9S_MB_2U(SCH_1):PAGE60
  C735    2      2 Q_CAP_DIFFBUS_C0201-DIFF BUS_0A   I236 @S9S_MB_2U_LIB.S9S_MB_2U(SCH_1):PAGE167

P5E_CPU1_PE0_TX_DP<4> @S9S_MB_2U_LIB.S9S_MB_2U(SCH_1):P5E_CPU1_PE0_TX_DP(4)
    U1  Y14 PE0_TX_DP4 SOCKET4677_AZIF0045P001C01CS-SA    I80 @S9S_MB_2U_LIB.S9S_MB_2U(SCH_1):PAGE60
  C733    2      2 Q_CAP_DIFFBUS_C0201-DIFF BUS_0A   I237 @S9S_MB_2U_LIB.S9S_MB_2U(SCH_1):PAGE167

P5E_CPU1_PE0_TX_DP<5> @S9S_MB_2U_LIB.S9S_MB_2U(SCH_1):P5E_CPU1_PE0_TX_DP(5)
    U1 AC15 PE0_TX_DP5 SOCKET4677_AZIF0045P001C01CS-SA    I80 @S9S_MB_2U_LIB.S9S_MB_2U(SCH_1):PAGE60
  C731    2      2 Q_CAP_DIFFBUS_C0201-DIFF BUS_0A   I247 @S9S_MB_2U_LIB.S9S_MB_2U(SCH_1):PAGE167

P5E_CPU1_PE0_TX_DP<6> @S9S_MB_2U_LIB.S9S_MB_2U(SCH_1):P5E_CPU1_PE0_TX_DP(6)
    U1 AD14 PE0_TX_DP6 SOCKET4677_AZIF0045P001C01CS-SA    I80 @S9S_MB_2U_LIB.S9S_MB_2U(SCH_1):PAGE60
  C729    2      2 Q_CAP_DIFFBUS_C0201-DIFF BUS_0A   I249 @S9S_MB_2U_LIB.S9S_MB_2U(SCH_1):PAGE167

P5E_CPU1_PE0_TX_DP<7> @S9S_MB_2U_LIB.S9S_MB_2U(SCH_1):P5E_CPU1_PE0_TX_DP(7)
    U1 AG15 PE0_TX_DP7 SOCKET4677_AZIF0045P001C01CS-SA    I80 @S9S_MB_2U_LIB.S9S_MB_2U(SCH_1):PAGE60
  C727    2      2 Q_CAP_DIFFBUS_C0201-DIFF BUS_0A   I251 @S9S_MB_2U_LIB.S9S_MB_2U(SCH_1):PAGE167

P5E_CPU1_PE0_TX_DP<8> @S9S_MB_2U_LIB.S9S_MB_2U(SCH_1):P5E_CPU1_PE0_TX_DP(8)
    U1 AH14 PE0_TX_DP8 SOCKET4677_AZIF0045P001C01CS-SA    I80 @S9S_MB_2U_LIB.S9S_MB_2U(SCH_1):PAGE60
  C725    2      2 Q_CAP_DIFFBUS_C0201-DIFF BUS_0A   I274 @S9S_MB_2U_LIB.S9S_MB_2U(SCH_1):PAGE167

P5E_CPU1_PE0_TX_DP<9> @S9S_MB_2U_LIB.S9S_MB_2U(SCH_1):P5E_CPU1_PE0_TX_DP(9)
    U1 AL15 PE0_TX_DP9 SOCKET4677_AZIF0045P001C01CS-SA    I80 @S9S_MB_2U_LIB.S9S_MB_2U(SCH_1):PAGE60
  C723    2      2 Q_CAP_DIFFBUS_C0201-DIFF BUS_0A   I277 @S9S_MB_2U_LIB.S9S_MB_2U(SCH_1):PAGE167

P5E_CPU1_PE1_RX_DN<0> @S9S_MB_2U_LIB.S9S_MB_2U(SCH_1):P5E_CPU1_PE1_RX_DN(0)
    U1 CP10 PE1_RX_DN0 SOCKET4677_AZIF0045P001C01CS-SA    I69 @S9S_MB_2U_LIB.S9S_MB_2U(SCH_1):PAGE60
   J35  A17  PERN0 SCONN168_ME1016810202011-SCONNA   I303 @S9S_MB_2U_LIB.S9S_MB_2U(SCH_1):PAGE146

P5E_CPU1_PE1_RX_DN<10> @S9S_MB_2U_LIB.S9S_MB_2U(SCH_1):P5E_CPU1_PE1_RX_DN(10)
    U1 BP10 PE1_RX_DN10 SOCKET4677_AZIF0045P001C01CS-SA    I69 @S9S_MB_2U_LIB.S9S_MB_2U(SCH_1):PAGE60
   J35  A50 PERN10 SCONN168_ME1016810202011-SCONNA   I303 @S9S_MB_2U_LIB.S9S_MB_2U(SCH_1):PAGE146

P5E_CPU1_PE1_RX_DN<11> @S9S_MB_2U_LIB.S9S_MB_2U(SCH_1):P5E_CPU1_PE1_RX_DN(11)
    U1 BL11 PE1_RX_DN11 SOCKET4677_AZIF0045P001C01CS-SA    I69 @S9S_MB_2U_LIB.S9S_MB_2U(SCH_1):PAGE60
   J35  A53 PERN11 SCONN168_ME1016810202011-SCONNA   I303 @S9S_MB_2U_LIB.S9S_MB_2U(SCH_1):PAGE146

P5E_CPU1_PE1_RX_DN<12> @S9S_MB_2U_LIB.S9S_MB_2U(SCH_1):P5E_CPU1_PE1_RX_DN(12)
    U1 BK10 PE1_RX_DN12 SOCKET4677_AZIF0045P001C01CS-SA    I69 @S9S_MB_2U_LIB.S9S_MB_2U(SCH_1):PAGE60
   J35  A56 PERN12 SCONN168_ME1016810202011-SCONNA   I303 @S9S_MB_2U_LIB.S9S_MB_2U(SCH_1):PAGE146

P5E_CPU1_PE1_RX_DN<13> @S9S_MB_2U_LIB.S9S_MB_2U(SCH_1):P5E_CPU1_PE1_RX_DN(13)
    U1 BG11 PE1_RX_DN13 SOCKET4677_AZIF0045P001C01CS-SA    I69 @S9S_MB_2U_LIB.S9S_MB_2U(SCH_1):PAGE60
   J35  A59 PERN13 SCONN168_ME1016810202011-SCONNA   I303 @S9S_MB_2U_LIB.S9S_MB_2U(SCH_1):PAGE146

P5E_CPU1_PE1_RX_DN<14> @S9S_MB_2U_LIB.S9S_MB_2U(SCH_1):P5E_CPU1_PE1_RX_DN(14)
    U1 BF10 PE1_RX_DN14 SOCKET4677_AZIF0045P001C01CS-SA    I69 @S9S_MB_2U_LIB.S9S_MB_2U(SCH_1):PAGE60
   J35  A62 PERN14 SCONN168_ME1016810202011-SCONNA   I303 @S9S_MB_2U_LIB.S9S_MB_2U(SCH_1):PAGE146

P5E_CPU1_PE1_RX_DN<15> @S9S_MB_2U_LIB.S9S_MB_2U(SCH_1):P5E_CPU1_PE1_RX_DN(15)
    U1 BC11 PE1_RX_DN15 SOCKET4677_AZIF0045P001C01CS-SA    I69 @S9S_MB_2U_LIB.S9S_MB_2U(SCH_1):PAGE60
   J35  A65 PERN15 SCONN168_ME1016810202011-SCONNA   I303 @S9S_MB_2U_LIB.S9S_MB_2U(SCH_1):PAGE146

P5E_CPU1_PE1_RX_DN<1> @S9S_MB_2U_LIB.S9S_MB_2U(SCH_1):P5E_CPU1_PE1_RX_DN(1)
    U1 CL11 PE1_RX_DN1 SOCKET4677_AZIF0045P001C01CS-SA    I69 @S9S_MB_2U_LIB.S9S_MB_2U(SCH_1):PAGE60
   J35  A20  PERN1 SCONN168_ME1016810202011-SCONNA   I303 @S9S_MB_2U_LIB.S9S_MB_2U(SCH_1):PAGE146

P5E_CPU1_PE1_RX_DN<2> @S9S_MB_2U_LIB.S9S_MB_2U(SCH_1):P5E_CPU1_PE1_RX_DN(2)
    U1 CK10 PE1_RX_DN2 SOCKET4677_AZIF0045P001C01CS-SA    I69 @S9S_MB_2U_LIB.S9S_MB_2U(SCH_1):PAGE60
   J35  A23  PERN2 SCONN168_ME1016810202011-SCONNA   I303 @S9S_MB_2U_LIB.S9S_MB_2U(SCH_1):PAGE146

P5E_CPU1_PE1_RX_DN<3> @S9S_MB_2U_LIB.S9S_MB_2U(SCH_1):P5E_CPU1_PE1_RX_DN(3)
    U1 CG11 PE1_RX_DN3 SOCKET4677_AZIF0045P001C01CS-SA    I69 @S9S_MB_2U_LIB.S9S_MB_2U(SCH_1):PAGE60
   J35  A26  PERN3 SCONN168_ME1016810202011-SCONNA   I303 @S9S_MB_2U_LIB.S9S_MB_2U(SCH_1):PAGE146

P5E_CPU1_PE1_RX_DN<4> @S9S_MB_2U_LIB.S9S_MB_2U(SCH_1):P5E_CPU1_PE1_RX_DN(4)
    U1 CF10 PE1_RX_DN4 SOCKET4677_AZIF0045P001C01CS-SA    I69 @S9S_MB_2U_LIB.S9S_MB_2U(SCH_1):PAGE60
   J35  A30  PERN4 SCONN168_ME1016810202011-SCONNA   I303 @S9S_MB_2U_LIB.S9S_MB_2U(SCH_1):PAGE146

P5E_CPU1_PE1_RX_DN<5> @S9S_MB_2U_LIB.S9S_MB_2U(SCH_1):P5E_CPU1_PE1_RX_DN(5)
    U1 CC11 PE1_RX_DN5 SOCKET4677_AZIF0045P001C01CS-SA    I69 @S9S_MB_2U_LIB.S9S_MB_2U(SCH_1):PAGE60
   J35  A33  PERN5 SCONN168_ME1016810202011-SCONNA   I303 @S9S_MB_2U_LIB.S9S_MB_2U(SCH_1):PAGE146

P5E_CPU1_PE1_RX_DN<6> @S9S_MB_2U_LIB.S9S_MB_2U(SCH_1):P5E_CPU1_PE1_RX_DN(6)
    U1 CB10 PE1_RX_DN6 SOCKET4677_AZIF0045P001C01CS-SA    I69 @S9S_MB_2U_LIB.S9S_MB_2U(SCH_1):PAGE60
   J35  A36  PERN6 SCONN168_ME1016810202011-SCONNA   I303 @S9S_MB_2U_LIB.S9S_MB_2U(SCH_1):PAGE146

P5E_CPU1_PE1_RX_DN<7> @S9S_MB_2U_LIB.S9S_MB_2U(SCH_1):P5E_CPU1_PE1_RX_DN(7)
    U1 BW11 PE1_RX_DN7 SOCKET4677_AZIF0045P001C01CS-SA    I69 @S9S_MB_2U_LIB.S9S_MB_2U(SCH_1):PAGE60
   J35  A39  PERN7 SCONN168_ME1016810202011-SCONNA   I303 @S9S_MB_2U_LIB.S9S_MB_2U(SCH_1):PAGE146

P5E_CPU1_PE1_RX_DN<8> @S9S_MB_2U_LIB.S9S_MB_2U(SCH_1):P5E_CPU1_PE1_RX_DN(8)
    U1 BV10 PE1_RX_DN8 SOCKET4677_AZIF0045P001C01CS-SA    I69 @S9S_MB_2U_LIB.S9S_MB_2U(SCH_1):PAGE60
   J35  A44  PERN8 SCONN168_ME1016810202011-SCONNA   I303 @S9S_MB_2U_LIB.S9S_MB_2U(SCH_1):PAGE146

P5E_CPU1_PE1_RX_DN<9> @S9S_MB_2U_LIB.S9S_MB_2U(SCH_1):P5E_CPU1_PE1_RX_DN(9)
    U1 BR11 PE1_RX_DN9 SOCKET4677_AZIF0045P001C01CS-SA    I69 @S9S_MB_2U_LIB.S9S_MB_2U(SCH_1):PAGE60
   J35  A47  PERN9 SCONN168_ME1016810202011-SCONNA   I303 @S9S_MB_2U_LIB.S9S_MB_2U(SCH_1):PAGE146

P5E_CPU1_PE1_RX_DP<0> @S9S_MB_2U_LIB.S9S_MB_2U(SCH_1):P5E_CPU1_PE1_RX_DP(0)
    U1  CN9 PE1_RX_DP0 SOCKET4677_AZIF0045P001C01CS-SA    I69 @S9S_MB_2U_LIB.S9S_MB_2U(SCH_1):PAGE60
   J35  A18  PERP0 SCONN168_ME1016810202011-SCONNA   I303 @S9S_MB_2U_LIB.S9S_MB_2U(SCH_1):PAGE146

P5E_CPU1_PE1_RX_DP<10> @S9S_MB_2U_LIB.S9S_MB_2U(SCH_1):P5E_CPU1_PE1_RX_DP(10)
    U1  BN9 PE1_RX_DP10 SOCKET4677_AZIF0045P001C01CS-SA    I69 @S9S_MB_2U_LIB.S9S_MB_2U(SCH_1):PAGE60
   J35  A51 PERP10 SCONN168_ME1016810202011-SCONNA   I303 @S9S_MB_2U_LIB.S9S_MB_2U(SCH_1):PAGE146

P5E_CPU1_PE1_RX_DP<11> @S9S_MB_2U_LIB.S9S_MB_2U(SCH_1):P5E_CPU1_PE1_RX_DP(11)
    U1 BM10 PE1_RX_DP11 SOCKET4677_AZIF0045P001C01CS-SA    I69 @S9S_MB_2U_LIB.S9S_MB_2U(SCH_1):PAGE60
   J35  A54 PERP11 SCONN168_ME1016810202011-SCONNA   I303 @S9S_MB_2U_LIB.S9S_MB_2U(SCH_1):PAGE146

P5E_CPU1_PE1_RX_DP<12> @S9S_MB_2U_LIB.S9S_MB_2U(SCH_1):P5E_CPU1_PE1_RX_DP(12)
    U1  BJ9 PE1_RX_DP12 SOCKET4677_AZIF0045P001C01CS-SA    I69 @S9S_MB_2U_LIB.S9S_MB_2U(SCH_1):PAGE60
   J35  A57 PERP12 SCONN168_ME1016810202011-SCONNA   I303 @S9S_MB_2U_LIB.S9S_MB_2U(SCH_1):PAGE146

P5E_CPU1_PE1_RX_DP<13> @S9S_MB_2U_LIB.S9S_MB_2U(SCH_1):P5E_CPU1_PE1_RX_DP(13)
    U1 BH10 PE1_RX_DP13 SOCKET4677_AZIF0045P001C01CS-SA    I69 @S9S_MB_2U_LIB.S9S_MB_2U(SCH_1):PAGE60
   J35  A60 PERP13 SCONN168_ME1016810202011-SCONNA   I303 @S9S_MB_2U_LIB.S9S_MB_2U(SCH_1):PAGE146

P5E_CPU1_PE1_RX_DP<14> @S9S_MB_2U_LIB.S9S_MB_2U(SCH_1):P5E_CPU1_PE1_RX_DP(14)
    U1  BE9 PE1_RX_DP14 SOCKET4677_AZIF0045P001C01CS-SA    I69 @S9S_MB_2U_LIB.S9S_MB_2U(SCH_1):PAGE60
   J35  A63 PERP14 SCONN168_ME1016810202011-SCONNA   I303 @S9S_MB_2U_LIB.S9S_MB_2U(SCH_1):PAGE146

P5E_CPU1_PE1_RX_DP<15> @S9S_MB_2U_LIB.S9S_MB_2U(SCH_1):P5E_CPU1_PE1_RX_DP(15)
    U1 BD10 PE1_RX_DP15 SOCKET4677_AZIF0045P001C01CS-SA    I69 @S9S_MB_2U_LIB.S9S_MB_2U(SCH_1):PAGE60
   J35  A66 PERP15 SCONN168_ME1016810202011-SCONNA   I303 @S9S_MB_2U_LIB.S9S_MB_2U(SCH_1):PAGE146

P5E_CPU1_PE1_RX_DP<1> @S9S_MB_2U_LIB.S9S_MB_2U(SCH_1):P5E_CPU1_PE1_RX_DP(1)
    U1 CM10 PE1_RX_DP1 SOCKET4677_AZIF0045P001C01CS-SA    I69 @S9S_MB_2U_LIB.S9S_MB_2U(SCH_1):PAGE60
   J35  A21  PERP1 SCONN168_ME1016810202011-SCONNA   I303 @S9S_MB_2U_LIB.S9S_MB_2U(SCH_1):PAGE146

P5E_CPU1_PE1_RX_DP<2> @S9S_MB_2U_LIB.S9S_MB_2U(SCH_1):P5E_CPU1_PE1_RX_DP(2)
    U1  CJ9 PE1_RX_DP2 SOCKET4677_AZIF0045P001C01CS-SA    I69 @S9S_MB_2U_LIB.S9S_MB_2U(SCH_1):PAGE60
   J35  A24  PERP2 SCONN168_ME1016810202011-SCONNA   I303 @S9S_MB_2U_LIB.S9S_MB_2U(SCH_1):PAGE146

P5E_CPU1_PE1_RX_DP<3> @S9S_MB_2U_LIB.S9S_MB_2U(SCH_1):P5E_CPU1_PE1_RX_DP(3)
    U1 CH10 PE1_RX_DP3 SOCKET4677_AZIF0045P001C01CS-SA    I69 @S9S_MB_2U_LIB.S9S_MB_2U(SCH_1):PAGE60
   J35  A27  PERP3 SCONN168_ME1016810202011-SCONNA   I303 @S9S_MB_2U_LIB.S9S_MB_2U(SCH_1):PAGE146

P5E_CPU1_PE1_RX_DP<4> @S9S_MB_2U_LIB.S9S_MB_2U(SCH_1):P5E_CPU1_PE1_RX_DP(4)
    U1  CE9 PE1_RX_DP4 SOCKET4677_AZIF0045P001C01CS-SA    I69 @S9S_MB_2U_LIB.S9S_MB_2U(SCH_1):PAGE60
   J35  A31  PERP4 SCONN168_ME1016810202011-SCONNA   I303 @S9S_MB_2U_LIB.S9S_MB_2U(SCH_1):PAGE146

P5E_CPU1_PE1_RX_DP<5> @S9S_MB_2U_LIB.S9S_MB_2U(SCH_1):P5E_CPU1_PE1_RX_DP(5)
    U1 CD10 PE1_RX_DP5 SOCKET4677_AZIF0045P001C01CS-SA    I69 @S9S_MB_2U_LIB.S9S_MB_2U(SCH_1):PAGE60
   J35  A34  PERP5 SCONN168_ME1016810202011-SCONNA   I303 @S9S_MB_2U_LIB.S9S_MB_2U(SCH_1):PAGE146

P5E_CPU1_PE1_RX_DP<6> @S9S_MB_2U_LIB.S9S_MB_2U(SCH_1):P5E_CPU1_PE1_RX_DP(6)
    U1  CA9 PE1_RX_DP6 SOCKET4677_AZIF0045P001C01CS-SA    I69 @S9S_MB_2U_LIB.S9S_MB_2U(SCH_1):PAGE60
   J35  A37  PERP6 SCONN168_ME1016810202011-SCONNA   I303 @S9S_MB_2U_LIB.S9S_MB_2U(SCH_1):PAGE146

P5E_CPU1_PE1_RX_DP<7> @S9S_MB_2U_LIB.S9S_MB_2U(SCH_1):P5E_CPU1_PE1_RX_DP(7)
    U1 BY10 PE1_RX_DP7 SOCKET4677_AZIF0045P001C01CS-SA    I69 @S9S_MB_2U_LIB.S9S_MB_2U(SCH_1):PAGE60
   J35  A40  PERP7 SCONN168_ME1016810202011-SCONNA   I303 @S9S_MB_2U_LIB.S9S_MB_2U(SCH_1):PAGE146

P5E_CPU1_PE1_RX_DP<8> @S9S_MB_2U_LIB.S9S_MB_2U(SCH_1):P5E_CPU1_PE1_RX_DP(8)
    U1  BU9 PE1_RX_DP8 SOCKET4677_AZIF0045P001C01CS-SA    I69 @S9S_MB_2U_LIB.S9S_MB_2U(SCH_1):PAGE60
   J35  A45  PERP8 SCONN168_ME1016810202011-SCONNA   I303 @S9S_MB_2U_LIB.S9S_MB_2U(SCH_1):PAGE146

P5E_CPU1_PE1_RX_DP<9> @S9S_MB_2U_LIB.S9S_MB_2U(SCH_1):P5E_CPU1_PE1_RX_DP(9)
    U1 BT10 PE1_RX_DP9 SOCKET4677_AZIF0045P001C01CS-SA    I69 @S9S_MB_2U_LIB.S9S_MB_2U(SCH_1):PAGE60
   J35  A48  PERP9 SCONN168_ME1016810202011-SCONNA   I303 @S9S_MB_2U_LIB.S9S_MB_2U(SCH_1):PAGE146

P5E_CPU1_PE1_TX_C_DN<0> @S9S_MB_2U_LIB.S9S_MB_2U(SCH_1):P5E_CPU1_PE1_TX_C_DN(0)
  C836    1      1 Q_CAP_DIFFBUS_C0201-DIFF BUS_0A   I333 @S9S_MB_2U_LIB.S9S_MB_2U(SCH_1):PAGE166
   J35  B18  PETP0 SCONN168_ME1016810202011-SCONNA   I303 @S9S_MB_2U_LIB.S9S_MB_2U(SCH_1):PAGE146

P5E_CPU1_PE1_TX_C_DN<10> @S9S_MB_2U_LIB.S9S_MB_2U(SCH_1):P5E_CPU1_PE1_TX_C_DN(10)
  C816    1      1 Q_CAP_DIFFBUS_C0201-DIFF BUS_0A   I368 @S9S_MB_2U_LIB.S9S_MB_2U(SCH_1):PAGE166
   J35  B51 PETP10 SCONN168_ME1016810202011-SCONNA   I303 @S9S_MB_2U_LIB.S9S_MB_2U(SCH_1):PAGE146

P5E_CPU1_PE1_TX_C_DN<11> @S9S_MB_2U_LIB.S9S_MB_2U(SCH_1):P5E_CPU1_PE1_TX_C_DN(11)
  C814    1      1 Q_CAP_DIFFBUS_C0201-DIFF BUS_0A   I370 @S9S_MB_2U_LIB.S9S_MB_2U(SCH_1):PAGE166
   J35  B53 PETN11 SCONN168_ME1016810202011-SCONNA   I303 @S9S_MB_2U_LIB.S9S_MB_2U(SCH_1):PAGE146

P5E_CPU1_PE1_TX_C_DN<12> @S9S_MB_2U_LIB.S9S_MB_2U(SCH_1):P5E_CPU1_PE1_TX_C_DN(12)
  C812    1      1 Q_CAP_DIFFBUS_C0201-DIFF BUS_0A   I371 @S9S_MB_2U_LIB.S9S_MB_2U(SCH_1):PAGE166
   J35  B57 PETP12 SCONN168_ME1016810202011-SCONNA   I303 @S9S_MB_2U_LIB.S9S_MB_2U(SCH_1):PAGE146

P5E_CPU1_PE1_TX_C_DN<13> @S9S_MB_2U_LIB.S9S_MB_2U(SCH_1):P5E_CPU1_PE1_TX_C_DN(13)
  C810    1      1 Q_CAP_DIFFBUS_C0201-DIFF BUS_0A   I374 @S9S_MB_2U_LIB.S9S_MB_2U(SCH_1):PAGE166
   J35  B59 PETN13 SCONN168_ME1016810202011-SCONNA   I303 @S9S_MB_2U_LIB.S9S_MB_2U(SCH_1):PAGE146

P5E_CPU1_PE1_TX_C_DN<14> @S9S_MB_2U_LIB.S9S_MB_2U(SCH_1):P5E_CPU1_PE1_TX_C_DN(14)
  C808    1      1 Q_CAP_DIFFBUS_C0201-DIFF BUS_0A   I376 @S9S_MB_2U_LIB.S9S_MB_2U(SCH_1):PAGE166
   J35  B63 PETP14 SCONN168_ME1016810202011-SCONNA   I303 @S9S_MB_2U_LIB.S9S_MB_2U(SCH_1):PAGE146

P5E_CPU1_PE1_TX_C_DN<15> @S9S_MB_2U_LIB.S9S_MB_2U(SCH_1):P5E_CPU1_PE1_TX_C_DN(15)
  C806    1      1 Q_CAP_DIFFBUS_C0201-DIFF BUS_0A   I377 @S9S_MB_2U_LIB.S9S_MB_2U(SCH_1):PAGE166
   J35  B65 PETN15 SCONN168_ME1016810202011-SCONNA   I303 @S9S_MB_2U_LIB.S9S_MB_2U(SCH_1):PAGE146

P5E_CPU1_PE1_TX_C_DN<1> @S9S_MB_2U_LIB.S9S_MB_2U(SCH_1):P5E_CPU1_PE1_TX_C_DN(1)
  C834    1      1 Q_CAP_DIFFBUS_C0201-DIFF BUS_0A   I335 @S9S_MB_2U_LIB.S9S_MB_2U(SCH_1):PAGE166
   J35  B20  PETN1 SCONN168_ME1016810202011-SCONNA   I303 @S9S_MB_2U_LIB.S9S_MB_2U(SCH_1):PAGE146

P5E_CPU1_PE1_TX_C_DN<2> @S9S_MB_2U_LIB.S9S_MB_2U(SCH_1):P5E_CPU1_PE1_TX_C_DN(2)
  C832    1      1 Q_CAP_DIFFBUS_C0201-DIFF BUS_0A   I338 @S9S_MB_2U_LIB.S9S_MB_2U(SCH_1):PAGE166
   J35  B24  PETP2 SCONN168_ME1016810202011-SCONNA   I303 @S9S_MB_2U_LIB.S9S_MB_2U(SCH_1):PAGE146

P5E_CPU1_PE1_TX_C_DN<3> @S9S_MB_2U_LIB.S9S_MB_2U(SCH_1):P5E_CPU1_PE1_TX_C_DN(3)
  C830    1      1 Q_CAP_DIFFBUS_C0201-DIFF BUS_0A   I341 @S9S_MB_2U_LIB.S9S_MB_2U(SCH_1):PAGE166
   J35  B26  PETN3 SCONN168_ME1016810202011-SCONNA   I303 @S9S_MB_2U_LIB.S9S_MB_2U(SCH_1):PAGE146

P5E_CPU1_PE1_TX_C_DN<4> @S9S_MB_2U_LIB.S9S_MB_2U(SCH_1):P5E_CPU1_PE1_TX_C_DN(4)
  C828    1      1 Q_CAP_DIFFBUS_C0201-DIFF BUS_0A   I340 @S9S_MB_2U_LIB.S9S_MB_2U(SCH_1):PAGE166
   J35  B31  PETP4 SCONN168_ME1016810202011-SCONNA   I303 @S9S_MB_2U_LIB.S9S_MB_2U(SCH_1):PAGE146

P5E_CPU1_PE1_TX_C_DN<5> @S9S_MB_2U_LIB.S9S_MB_2U(SCH_1):P5E_CPU1_PE1_TX_C_DN(5)
  C826    1      1 Q_CAP_DIFFBUS_C0201-DIFF BUS_0A   I344 @S9S_MB_2U_LIB.S9S_MB_2U(SCH_1):PAGE166
   J35  B33  PETN5 SCONN168_ME1016810202011-SCONNA   I303 @S9S_MB_2U_LIB.S9S_MB_2U(SCH_1):PAGE146

P5E_CPU1_PE1_TX_C_DN<6> @S9S_MB_2U_LIB.S9S_MB_2U(SCH_1):P5E_CPU1_PE1_TX_C_DN(6)
  C824    1      1 Q_CAP_DIFFBUS_C0201-DIFF BUS_0A   I416 @S9S_MB_2U_LIB.S9S_MB_2U(SCH_1):PAGE166
   J35  B37  PETP6 SCONN168_ME1016810202011-SCONNA   I303 @S9S_MB_2U_LIB.S9S_MB_2U(SCH_1):PAGE146

P5E_CPU1_PE1_TX_C_DN<7> @S9S_MB_2U_LIB.S9S_MB_2U(SCH_1):P5E_CPU1_PE1_TX_C_DN(7)
  C822    1      1 Q_CAP_DIFFBUS_C0201-DIFF BUS_0A   I345 @S9S_MB_2U_LIB.S9S_MB_2U(SCH_1):PAGE166
   J35  B39  PETN7 SCONN168_ME1016810202011-SCONNA   I303 @S9S_MB_2U_LIB.S9S_MB_2U(SCH_1):PAGE146

P5E_CPU1_PE1_TX_C_DN<8> @S9S_MB_2U_LIB.S9S_MB_2U(SCH_1):P5E_CPU1_PE1_TX_C_DN(8)
  C820    1      1 Q_CAP_DIFFBUS_C0201-DIFF BUS_0A   I363 @S9S_MB_2U_LIB.S9S_MB_2U(SCH_1):PAGE166
   J35  B45  PETP8 SCONN168_ME1016810202011-SCONNA   I303 @S9S_MB_2U_LIB.S9S_MB_2U(SCH_1):PAGE146

P5E_CPU1_PE1_TX_C_DN<9> @S9S_MB_2U_LIB.S9S_MB_2U(SCH_1):P5E_CPU1_PE1_TX_C_DN(9)
  C818    1      1 Q_CAP_DIFFBUS_C0201-DIFF BUS_0A   I365 @S9S_MB_2U_LIB.S9S_MB_2U(SCH_1):PAGE166
   J35  B47  PETN9 SCONN168_ME1016810202011-SCONNA   I303 @S9S_MB_2U_LIB.S9S_MB_2U(SCH_1):PAGE146

P5E_CPU1_PE1_TX_C_DP<0> @S9S_MB_2U_LIB.S9S_MB_2U(SCH_1):P5E_CPU1_PE1_TX_C_DP(0)
  C837    1      1 Q_CAP_DIFFBUS_C0201-DIFF BUS_0A   I334 @S9S_MB_2U_LIB.S9S_MB_2U(SCH_1):PAGE166
   J35  B17  PETN0 SCONN168_ME1016810202011-SCONNA   I303 @S9S_MB_2U_LIB.S9S_MB_2U(SCH_1):PAGE146

P5E_CPU1_PE1_TX_C_DP<10> @S9S_MB_2U_LIB.S9S_MB_2U(SCH_1):P5E_CPU1_PE1_TX_C_DP(10)
  C817    1      1 Q_CAP_DIFFBUS_C0201-DIFF BUS_0A   I367 @S9S_MB_2U_LIB.S9S_MB_2U(SCH_1):PAGE166
   J35  B50 PETN10 SCONN168_ME1016810202011-SCONNA   I303 @S9S_MB_2U_LIB.S9S_MB_2U(SCH_1):PAGE146

P5E_CPU1_PE1_TX_C_DP<11> @S9S_MB_2U_LIB.S9S_MB_2U(SCH_1):P5E_CPU1_PE1_TX_C_DP(11)
  C815    1      1 Q_CAP_DIFFBUS_C0201-DIFF BUS_0A   I369 @S9S_MB_2U_LIB.S9S_MB_2U(SCH_1):PAGE166
   J35  B54 PETP11 SCONN168_ME1016810202011-SCONNA   I303 @S9S_MB_2U_LIB.S9S_MB_2U(SCH_1):PAGE146

P5E_CPU1_PE1_TX_C_DP<12> @S9S_MB_2U_LIB.S9S_MB_2U(SCH_1):P5E_CPU1_PE1_TX_C_DP(12)
  C813    1      1 Q_CAP_DIFFBUS_C0201-DIFF BUS_0A   I372 @S9S_MB_2U_LIB.S9S_MB_2U(SCH_1):PAGE166
   J35  B56 PETN12 SCONN168_ME1016810202011-SCONNA   I303 @S9S_MB_2U_LIB.S9S_MB_2U(SCH_1):PAGE146

P5E_CPU1_PE1_TX_C_DP<13> @S9S_MB_2U_LIB.S9S_MB_2U(SCH_1):P5E_CPU1_PE1_TX_C_DP(13)
  C811    1      1 Q_CAP_DIFFBUS_C0201-DIFF BUS_0A   I373 @S9S_MB_2U_LIB.S9S_MB_2U(SCH_1):PAGE166
   J35  B60 PETP13 SCONN168_ME1016810202011-SCONNA   I303 @S9S_MB_2U_LIB.S9S_MB_2U(SCH_1):PAGE146

P5E_CPU1_PE1_TX_C_DP<14> @S9S_MB_2U_LIB.S9S_MB_2U(SCH_1):P5E_CPU1_PE1_TX_C_DP(14)
  C809    1      1 Q_CAP_DIFFBUS_C0201-DIFF BUS_0A   I375 @S9S_MB_2U_LIB.S9S_MB_2U(SCH_1):PAGE166
   J35  B62 PETN14 SCONN168_ME1016810202011-SCONNA   I303 @S9S_MB_2U_LIB.S9S_MB_2U(SCH_1):PAGE146

P5E_CPU1_PE1_TX_C_DP<15> @S9S_MB_2U_LIB.S9S_MB_2U(SCH_1):P5E_CPU1_PE1_TX_C_DP(15)
  C807    1      1 Q_CAP_DIFFBUS_C0201-DIFF BUS_0A   I378 @S9S_MB_2U_LIB.S9S_MB_2U(SCH_1):PAGE166
   J35  B66 PETP15 SCONN168_ME1016810202011-SCONNA   I303 @S9S_MB_2U_LIB.S9S_MB_2U(SCH_1):PAGE146

P5E_CPU1_PE1_TX_C_DP<1> @S9S_MB_2U_LIB.S9S_MB_2U(SCH_1):P5E_CPU1_PE1_TX_C_DP(1)
  C835    1      1 Q_CAP_DIFFBUS_C0201-DIFF BUS_0A   I336 @S9S_MB_2U_LIB.S9S_MB_2U(SCH_1):PAGE166
   J35  B21  PETP1 SCONN168_ME1016810202011-SCONNA   I303 @S9S_MB_2U_LIB.S9S_MB_2U(SCH_1):PAGE146

P5E_CPU1_PE1_TX_C_DP<2> @S9S_MB_2U_LIB.S9S_MB_2U(SCH_1):P5E_CPU1_PE1_TX_C_DP(2)
  C833    1      1 Q_CAP_DIFFBUS_C0201-DIFF BUS_0A   I339 @S9S_MB_2U_LIB.S9S_MB_2U(SCH_1):PAGE166
   J35  B23  PETN2 SCONN168_ME1016810202011-SCONNA   I303 @S9S_MB_2U_LIB.S9S_MB_2U(SCH_1):PAGE146

P5E_CPU1_PE1_TX_C_DP<3> @S9S_MB_2U_LIB.S9S_MB_2U(SCH_1):P5E_CPU1_PE1_TX_C_DP(3)
  C831    1      1 Q_CAP_DIFFBUS_C0201-DIFF BUS_0A   I337 @S9S_MB_2U_LIB.S9S_MB_2U(SCH_1):PAGE166
   J35  B27  PETP3 SCONN168_ME1016810202011-SCONNA   I303 @S9S_MB_2U_LIB.S9S_MB_2U(SCH_1):PAGE146

P5E_CPU1_PE1_TX_C_DP<4> @S9S_MB_2U_LIB.S9S_MB_2U(SCH_1):P5E_CPU1_PE1_TX_C_DP(4)
  C829    1      1 Q_CAP_DIFFBUS_C0201-DIFF BUS_0A   I342 @S9S_MB_2U_LIB.S9S_MB_2U(SCH_1):PAGE166
   J35  B30  PETN4 SCONN168_ME1016810202011-SCONNA   I303 @S9S_MB_2U_LIB.S9S_MB_2U(SCH_1):PAGE146

P5E_CPU1_PE1_TX_C_DP<5> @S9S_MB_2U_LIB.S9S_MB_2U(SCH_1):P5E_CPU1_PE1_TX_C_DP(5)
  C827    1      1 Q_CAP_DIFFBUS_C0201-DIFF BUS_0A   I343 @S9S_MB_2U_LIB.S9S_MB_2U(SCH_1):PAGE166
   J35  B34  PETP5 SCONN168_ME1016810202011-SCONNA   I303 @S9S_MB_2U_LIB.S9S_MB_2U(SCH_1):PAGE146

P5E_CPU1_PE1_TX_C_DP<6> @S9S_MB_2U_LIB.S9S_MB_2U(SCH_1):P5E_CPU1_PE1_TX_C_DP(6)
  C825    1      1 Q_CAP_DIFFBUS_C0201-DIFF BUS_0A   I415 @S9S_MB_2U_LIB.S9S_MB_2U(SCH_1):PAGE166
   J35  B36  PETN6 SCONN168_ME1016810202011-SCONNA   I303 @S9S_MB_2U_LIB.S9S_MB_2U(SCH_1):PAGE146

P5E_CPU1_PE1_TX_C_DP<7> @S9S_MB_2U_LIB.S9S_MB_2U(SCH_1):P5E_CPU1_PE1_TX_C_DP(7)
  C823    1      1 Q_CAP_DIFFBUS_C0201-DIFF BUS_0A   I346 @S9S_MB_2U_LIB.S9S_MB_2U(SCH_1):PAGE166
   J35  B40  PETP7 SCONN168_ME1016810202011-SCONNA   I303 @S9S_MB_2U_LIB.S9S_MB_2U(SCH_1):PAGE146

P5E_CPU1_PE1_TX_C_DP<8> @S9S_MB_2U_LIB.S9S_MB_2U(SCH_1):P5E_CPU1_PE1_TX_C_DP(8)
  C821    1      1 Q_CAP_DIFFBUS_C0201-DIFF BUS_0A   I364 @S9S_MB_2U_LIB.S9S_MB_2U(SCH_1):PAGE166
   J35  B44  PETN8 SCONN168_ME1016810202011-SCONNA   I303 @S9S_MB_2U_LIB.S9S_MB_2U(SCH_1):PAGE146

P5E_CPU1_PE1_TX_C_DP<9> @S9S_MB_2U_LIB.S9S_MB_2U(SCH_1):P5E_CPU1_PE1_TX_C_DP(9)
  C819    1      1 Q_CAP_DIFFBUS_C0201-DIFF BUS_0A   I366 @S9S_MB_2U_LIB.S9S_MB_2U(SCH_1):PAGE166
   J35  B48  PETP9 SCONN168_ME1016810202011-SCONNA   I303 @S9S_MB_2U_LIB.S9S_MB_2U(SCH_1):PAGE146

P5E_CPU1_PE1_TX_DN<0> @S9S_MB_2U_LIB.S9S_MB_2U(SCH_1):P5E_CPU1_PE1_TX_DN(0)
    U1 CP14 PE1_TX_DN0 SOCKET4677_AZIF0045P001C01CS-SA    I69 @S9S_MB_2U_LIB.S9S_MB_2U(SCH_1):PAGE60
  C836    2      2 Q_CAP_DIFFBUS_C0201-DIFF BUS_0A   I333 @S9S_MB_2U_LIB.S9S_MB_2U(SCH_1):PAGE166

P5E_CPU1_PE1_TX_DN<10> @S9S_MB_2U_LIB.S9S_MB_2U(SCH_1):P5E_CPU1_PE1_TX_DN(10)
    U1 BP14 PE1_TX_DN10 SOCKET4677_AZIF0045P001C01CS-SA    I69 @S9S_MB_2U_LIB.S9S_MB_2U(SCH_1):PAGE60
  C816    2      2 Q_CAP_DIFFBUS_C0201-DIFF BUS_0A   I368 @S9S_MB_2U_LIB.S9S_MB_2U(SCH_1):PAGE166

P5E_CPU1_PE1_TX_DN<11> @S9S_MB_2U_LIB.S9S_MB_2U(SCH_1):P5E_CPU1_PE1_TX_DN(11)
    U1 BN13 PE1_TX_DN11 SOCKET4677_AZIF0045P001C01CS-SA    I69 @S9S_MB_2U_LIB.S9S_MB_2U(SCH_1):PAGE60
  C814    2      2 Q_CAP_DIFFBUS_C0201-DIFF BUS_0A   I370 @S9S_MB_2U_LIB.S9S_MB_2U(SCH_1):PAGE166

P5E_CPU1_PE1_TX_DN<12> @S9S_MB_2U_LIB.S9S_MB_2U(SCH_1):P5E_CPU1_PE1_TX_DN(12)
    U1 BK14 PE1_TX_DN12 SOCKET4677_AZIF0045P001C01CS-SA    I69 @S9S_MB_2U_LIB.S9S_MB_2U(SCH_1):PAGE60
  C812    2      2 Q_CAP_DIFFBUS_C0201-DIFF BUS_0A   I371 @S9S_MB_2U_LIB.S9S_MB_2U(SCH_1):PAGE166

P5E_CPU1_PE1_TX_DN<13> @S9S_MB_2U_LIB.S9S_MB_2U(SCH_1):P5E_CPU1_PE1_TX_DN(13)
    U1 BJ13 PE1_TX_DN13 SOCKET4677_AZIF0045P001C01CS-SA    I69 @S9S_MB_2U_LIB.S9S_MB_2U(SCH_1):PAGE60
  C810    2      2 Q_CAP_DIFFBUS_C0201-DIFF BUS_0A   I374 @S9S_MB_2U_LIB.S9S_MB_2U(SCH_1):PAGE166

P5E_CPU1_PE1_TX_DN<14> @S9S_MB_2U_LIB.S9S_MB_2U(SCH_1):P5E_CPU1_PE1_TX_DN(14)
    U1 BF14 PE1_TX_DN14 SOCKET4677_AZIF0045P001C01CS-SA    I69 @S9S_MB_2U_LIB.S9S_MB_2U(SCH_1):PAGE60
  C808    2      2 Q_CAP_DIFFBUS_C0201-DIFF BUS_0A   I376 @S9S_MB_2U_LIB.S9S_MB_2U(SCH_1):PAGE166

P5E_CPU1_PE1_TX_DN<15> @S9S_MB_2U_LIB.S9S_MB_2U(SCH_1):P5E_CPU1_PE1_TX_DN(15)
    U1 BE13 PE1_TX_DN15 SOCKET4677_AZIF0045P001C01CS-SA    I69 @S9S_MB_2U_LIB.S9S_MB_2U(SCH_1):PAGE60
  C806    2      2 Q_CAP_DIFFBUS_C0201-DIFF BUS_0A   I377 @S9S_MB_2U_LIB.S9S_MB_2U(SCH_1):PAGE166

P5E_CPU1_PE1_TX_DN<1> @S9S_MB_2U_LIB.S9S_MB_2U(SCH_1):P5E_CPU1_PE1_TX_DN(1)
    U1 CN13 PE1_TX_DN1 SOCKET4677_AZIF0045P001C01CS-SA    I69 @S9S_MB_2U_LIB.S9S_MB_2U(SCH_1):PAGE60
  C834    2      2 Q_CAP_DIFFBUS_C0201-DIFF BUS_0A   I335 @S9S_MB_2U_LIB.S9S_MB_2U(SCH_1):PAGE166

P5E_CPU1_PE1_TX_DN<2> @S9S_MB_2U_LIB.S9S_MB_2U(SCH_1):P5E_CPU1_PE1_TX_DN(2)
    U1 CK14 PE1_TX_DN2 SOCKET4677_AZIF0045P001C01CS-SA    I69 @S9S_MB_2U_LIB.S9S_MB_2U(SCH_1):PAGE60
  C832    2      2 Q_CAP_DIFFBUS_C0201-DIFF BUS_0A   I338 @S9S_MB_2U_LIB.S9S_MB_2U(SCH_1):PAGE166

P5E_CPU1_PE1_TX_DN<3> @S9S_MB_2U_LIB.S9S_MB_2U(SCH_1):P5E_CPU1_PE1_TX_DN(3)
    U1 CJ13 PE1_TX_DN3 SOCKET4677_AZIF0045P001C01CS-SA    I69 @S9S_MB_2U_LIB.S9S_MB_2U(SCH_1):PAGE60
  C830    2      2 Q_CAP_DIFFBUS_C0201-DIFF BUS_0A   I341 @S9S_MB_2U_LIB.S9S_MB_2U(SCH_1):PAGE166

P5E_CPU1_PE1_TX_DN<4> @S9S_MB_2U_LIB.S9S_MB_2U(SCH_1):P5E_CPU1_PE1_TX_DN(4)
    U1 CF14 PE1_TX_DN4 SOCKET4677_AZIF0045P001C01CS-SA    I69 @S9S_MB_2U_LIB.S9S_MB_2U(SCH_1):PAGE60
  C828    2      2 Q_CAP_DIFFBUS_C0201-DIFF BUS_0A   I340 @S9S_MB_2U_LIB.S9S_MB_2U(SCH_1):PAGE166

P5E_CPU1_PE1_TX_DN<5> @S9S_MB_2U_LIB.S9S_MB_2U(SCH_1):P5E_CPU1_PE1_TX_DN(5)
    U1 CE13 PE1_TX_DN5 SOCKET4677_AZIF0045P001C01CS-SA    I69 @S9S_MB_2U_LIB.S9S_MB_2U(SCH_1):PAGE60
  C826    2      2 Q_CAP_DIFFBUS_C0201-DIFF BUS_0A   I344 @S9S_MB_2U_LIB.S9S_MB_2U(SCH_1):PAGE166

P5E_CPU1_PE1_TX_DN<6> @S9S_MB_2U_LIB.S9S_MB_2U(SCH_1):P5E_CPU1_PE1_TX_DN(6)
    U1 CB14 PE1_TX_DN6 SOCKET4677_AZIF0045P001C01CS-SA    I69 @S9S_MB_2U_LIB.S9S_MB_2U(SCH_1):PAGE60
  C824    2      2 Q_CAP_DIFFBUS_C0201-DIFF BUS_0A   I416 @S9S_MB_2U_LIB.S9S_MB_2U(SCH_1):PAGE166

P5E_CPU1_PE1_TX_DN<7> @S9S_MB_2U_LIB.S9S_MB_2U(SCH_1):P5E_CPU1_PE1_TX_DN(7)
    U1 CA13 PE1_TX_DN7 SOCKET4677_AZIF0045P001C01CS-SA    I69 @S9S_MB_2U_LIB.S9S_MB_2U(SCH_1):PAGE60
  C822    2      2 Q_CAP_DIFFBUS_C0201-DIFF BUS_0A   I345 @S9S_MB_2U_LIB.S9S_MB_2U(SCH_1):PAGE166

P5E_CPU1_PE1_TX_DN<8> @S9S_MB_2U_LIB.S9S_MB_2U(SCH_1):P5E_CPU1_PE1_TX_DN(8)
    U1 BV14 PE1_TX_DN8 SOCKET4677_AZIF0045P001C01CS-SA    I69 @S9S_MB_2U_LIB.S9S_MB_2U(SCH_1):PAGE60
  C820    2      2 Q_CAP_DIFFBUS_C0201-DIFF BUS_0A   I363 @S9S_MB_2U_LIB.S9S_MB_2U(SCH_1):PAGE166

P5E_CPU1_PE1_TX_DN<9> @S9S_MB_2U_LIB.S9S_MB_2U(SCH_1):P5E_CPU1_PE1_TX_DN(9)
    U1 BU13 PE1_TX_DN9 SOCKET4677_AZIF0045P001C01CS-SA    I69 @S9S_MB_2U_LIB.S9S_MB_2U(SCH_1):PAGE60
  C818    2      2 Q_CAP_DIFFBUS_C0201-DIFF BUS_0A   I365 @S9S_MB_2U_LIB.S9S_MB_2U(SCH_1):PAGE166

P5E_CPU1_PE1_TX_DP<0> @S9S_MB_2U_LIB.S9S_MB_2U(SCH_1):P5E_CPU1_PE1_TX_DP(0)
    U1 CR15 PE1_TX_DP0 SOCKET4677_AZIF0045P001C01CS-SA    I69 @S9S_MB_2U_LIB.S9S_MB_2U(SCH_1):PAGE60
  C837    2      2 Q_CAP_DIFFBUS_C0201-DIFF BUS_0A   I334 @S9S_MB_2U_LIB.S9S_MB_2U(SCH_1):PAGE166

P5E_CPU1_PE1_TX_DP<10> @S9S_MB_2U_LIB.S9S_MB_2U(SCH_1):P5E_CPU1_PE1_TX_DP(10)
    U1 BR15 PE1_TX_DP10 SOCKET4677_AZIF0045P001C01CS-SA    I69 @S9S_MB_2U_LIB.S9S_MB_2U(SCH_1):PAGE60
  C817    2      2 Q_CAP_DIFFBUS_C0201-DIFF BUS_0A   I367 @S9S_MB_2U_LIB.S9S_MB_2U(SCH_1):PAGE166

P5E_CPU1_PE1_TX_DP<11> @S9S_MB_2U_LIB.S9S_MB_2U(SCH_1):P5E_CPU1_PE1_TX_DP(11)
    U1 BM14 PE1_TX_DP11 SOCKET4677_AZIF0045P001C01CS-SA    I69 @S9S_MB_2U_LIB.S9S_MB_2U(SCH_1):PAGE60
  C815    2      2 Q_CAP_DIFFBUS_C0201-DIFF BUS_0A   I369 @S9S_MB_2U_LIB.S9S_MB_2U(SCH_1):PAGE166

P5E_CPU1_PE1_TX_DP<12> @S9S_MB_2U_LIB.S9S_MB_2U(SCH_1):P5E_CPU1_PE1_TX_DP(12)
    U1 BL15 PE1_TX_DP12 SOCKET4677_AZIF0045P001C01CS-SA    I69 @S9S_MB_2U_LIB.S9S_MB_2U(SCH_1):PAGE60
  C813    2      2 Q_CAP_DIFFBUS_C0201-DIFF BUS_0A   I372 @S9S_MB_2U_LIB.S9S_MB_2U(SCH_1):PAGE166

P5E_CPU1_PE1_TX_DP<13> @S9S_MB_2U_LIB.S9S_MB_2U(SCH_1):P5E_CPU1_PE1_TX_DP(13)
    U1 BH14 PE1_TX_DP13 SOCKET4677_AZIF0045P001C01CS-SA    I69 @S9S_MB_2U_LIB.S9S_MB_2U(SCH_1):PAGE60
  C811    2      2 Q_CAP_DIFFBUS_C0201-DIFF BUS_0A   I373 @S9S_MB_2U_LIB.S9S_MB_2U(SCH_1):PAGE166

P5E_CPU1_PE1_TX_DP<14> @S9S_MB_2U_LIB.S9S_MB_2U(SCH_1):P5E_CPU1_PE1_TX_DP(14)
    U1 BG15 PE1_TX_DP14 SOCKET4677_AZIF0045P001C01CS-SA    I69 @S9S_MB_2U_LIB.S9S_MB_2U(SCH_1):PAGE60
  C809    2      2 Q_CAP_DIFFBUS_C0201-DIFF BUS_0A   I375 @S9S_MB_2U_LIB.S9S_MB_2U(SCH_1):PAGE166

P5E_CPU1_PE1_TX_DP<15> @S9S_MB_2U_LIB.S9S_MB_2U(SCH_1):P5E_CPU1_PE1_TX_DP(15)
    U1 BD14 PE1_TX_DP15 SOCKET4677_AZIF0045P001C01CS-SA    I69 @S9S_MB_2U_LIB.S9S_MB_2U(SCH_1):PAGE60
  C807    2      2 Q_CAP_DIFFBUS_C0201-DIFF BUS_0A   I378 @S9S_MB_2U_LIB.S9S_MB_2U(SCH_1):PAGE166

P5E_CPU1_PE1_TX_DP<1> @S9S_MB_2U_LIB.S9S_MB_2U(SCH_1):P5E_CPU1_PE1_TX_DP(1)
    U1 CM14 PE1_TX_DP1 SOCKET4677_AZIF0045P001C01CS-SA    I69 @S9S_MB_2U_LIB.S9S_MB_2U(SCH_1):PAGE60
  C835    2      2 Q_CAP_DIFFBUS_C0201-DIFF BUS_0A   I336 @S9S_MB_2U_LIB.S9S_MB_2U(SCH_1):PAGE166

P5E_CPU1_PE1_TX_DP<2> @S9S_MB_2U_LIB.S9S_MB_2U(SCH_1):P5E_CPU1_PE1_TX_DP(2)
    U1 CL15 PE1_TX_DP2 SOCKET4677_AZIF0045P001C01CS-SA    I69 @S9S_MB_2U_LIB.S9S_MB_2U(SCH_1):PAGE60
  C833    2      2 Q_CAP_DIFFBUS_C0201-DIFF BUS_0A   I339 @S9S_MB_2U_LIB.S9S_MB_2U(SCH_1):PAGE166

P5E_CPU1_PE1_TX_DP<3> @S9S_MB_2U_LIB.S9S_MB_2U(SCH_1):P5E_CPU1_PE1_TX_DP(3)
    U1 CH14 PE1_TX_DP3 SOCKET4677_AZIF0045P001C01CS-SA    I69 @S9S_MB_2U_LIB.S9S_MB_2U(SCH_1):PAGE60
  C831    2      2 Q_CAP_DIFFBUS_C0201-DIFF BUS_0A   I337 @S9S_MB_2U_LIB.S9S_MB_2U(SCH_1):PAGE166

P5E_CPU1_PE1_TX_DP<4> @S9S_MB_2U_LIB.S9S_MB_2U(SCH_1):P5E_CPU1_PE1_TX_DP(4)
    U1 CG15 PE1_TX_DP4 SOCKET4677_AZIF0045P001C01CS-SA    I69 @S9S_MB_2U_LIB.S9S_MB_2U(SCH_1):PAGE60
  C829    2      2 Q_CAP_DIFFBUS_C0201-DIFF BUS_0A   I342 @S9S_MB_2U_LIB.S9S_MB_2U(SCH_1):PAGE166

P5E_CPU1_PE1_TX_DP<5> @S9S_MB_2U_LIB.S9S_MB_2U(SCH_1):P5E_CPU1_PE1_TX_DP(5)
    U1 CD14 PE1_TX_DP5 SOCKET4677_AZIF0045P001C01CS-SA    I69 @S9S_MB_2U_LIB.S9S_MB_2U(SCH_1):PAGE60
  C827    2      2 Q_CAP_DIFFBUS_C0201-DIFF BUS_0A   I343 @S9S_MB_2U_LIB.S9S_MB_2U(SCH_1):PAGE166

P5E_CPU1_PE1_TX_DP<6> @S9S_MB_2U_LIB.S9S_MB_2U(SCH_1):P5E_CPU1_PE1_TX_DP(6)
    U1 CC15 PE1_TX_DP6 SOCKET4677_AZIF0045P001C01CS-SA    I69 @S9S_MB_2U_LIB.S9S_MB_2U(SCH_1):PAGE60
  C825    2      2 Q_CAP_DIFFBUS_C0201-DIFF BUS_0A   I415 @S9S_MB_2U_LIB.S9S_MB_2U(SCH_1):PAGE166

P5E_CPU1_PE1_TX_DP<7> @S9S_MB_2U_LIB.S9S_MB_2U(SCH_1):P5E_CPU1_PE1_TX_DP(7)
    U1 BY14 PE1_TX_DP7 SOCKET4677_AZIF0045P001C01CS-SA    I69 @S9S_MB_2U_LIB.S9S_MB_2U(SCH_1):PAGE60
  C823    2      2 Q_CAP_DIFFBUS_C0201-DIFF BUS_0A   I346 @S9S_MB_2U_LIB.S9S_MB_2U(SCH_1):PAGE166

P5E_CPU1_PE1_TX_DP<8> @S9S_MB_2U_LIB.S9S_MB_2U(SCH_1):P5E_CPU1_PE1_TX_DP(8)
    U1 BW15 PE1_TX_DP8 SOCKET4677_AZIF0045P001C01CS-SA    I69 @S9S_MB_2U_LIB.S9S_MB_2U(SCH_1):PAGE60
  C821    2      2 Q_CAP_DIFFBUS_C0201-DIFF BUS_0A   I364 @S9S_MB_2U_LIB.S9S_MB_2U(SCH_1):PAGE166

P5E_CPU1_PE1_TX_DP<9> @S9S_MB_2U_LIB.S9S_MB_2U(SCH_1):P5E_CPU1_PE1_TX_DP(9)
    U1 BT14 PE1_TX_DP9 SOCKET4677_AZIF0045P001C01CS-SA    I69 @S9S_MB_2U_LIB.S9S_MB_2U(SCH_1):PAGE60
  C819    2      2 Q_CAP_DIFFBUS_C0201-DIFF BUS_0A   I366 @S9S_MB_2U_LIB.S9S_MB_2U(SCH_1):PAGE166

P5E_CPU1_PE2_RX_DN<0> @S9S_MB_2U_LIB.S9S_MB_2U(SCH_1):P5E_CPU1_PE2_RX_DN(0)
    U1  CU9 PE2_RX_DN0 SOCKET4677_AZIF0045P001C01CS-SA    I54 @S9S_MB_2U_LIB.S9S_MB_2U(SCH_1):PAGE61
  J109   F8     F8 CONN112_10137002101LF-CONN112_A    I76 @S9S_MB_2U_LIB.S9S_MB_2U(SCH_1):PAGE319

P5E_CPU1_PE2_RX_DN<10> @S9S_MB_2U_LIB.S9S_MB_2U(SCH_1):P5E_CPU1_PE2_RX_DN(10)
    U1  DU9 PE2_RX_DN10 SOCKET4677_AZIF0045P001C01CS-SA    I54 @S9S_MB_2U_LIB.S9S_MB_2U(SCH_1):PAGE61
  J110   F6     F6 CONN112_10137002101LF-CONN112_A    I16 @S9S_MB_2U_LIB.S9S_MB_2U(SCH_1):PAGE318

P5E_CPU1_PE2_RX_DN<11> @S9S_MB_2U_LIB.S9S_MB_2U(SCH_1):P5E_CPU1_PE2_RX_DN(11)
    U1 DY10 PE2_RX_DN11 SOCKET4677_AZIF0045P001C01CS-SA    I54 @S9S_MB_2U_LIB.S9S_MB_2U(SCH_1):PAGE61
  J110   G5     G5 CONN112_10137002101LF-CONN112_A    I16 @S9S_MB_2U_LIB.S9S_MB_2U(SCH_1):PAGE318

P5E_CPU1_PE2_RX_DN<12> @S9S_MB_2U_LIB.S9S_MB_2U(SCH_1):P5E_CPU1_PE2_RX_DN(12)
    U1  EA9 PE2_RX_DN12 SOCKET4677_AZIF0045P001C01CS-SA    I54 @S9S_MB_2U_LIB.S9S_MB_2U(SCH_1):PAGE61
  J110   F4     F4 CONN112_10137002101LF-CONN112_A    I54 @S9S_MB_2U_LIB.S9S_MB_2U(SCH_1):PAGE318

P5E_CPU1_PE2_RX_DN<13> @S9S_MB_2U_LIB.S9S_MB_2U(SCH_1):P5E_CPU1_PE2_RX_DN(13)
    U1 ED10 PE2_RX_DN13 SOCKET4677_AZIF0045P001C01CS-SA    I54 @S9S_MB_2U_LIB.S9S_MB_2U(SCH_1):PAGE61
  J110   G3     G3 CONN112_10137002101LF-CONN112_A    I54 @S9S_MB_2U_LIB.S9S_MB_2U(SCH_1):PAGE318

P5E_CPU1_PE2_RX_DN<14> @S9S_MB_2U_LIB.S9S_MB_2U(SCH_1):P5E_CPU1_PE2_RX_DN(14)
    U1  EE9 PE2_RX_DN14 SOCKET4677_AZIF0045P001C01CS-SA    I54 @S9S_MB_2U_LIB.S9S_MB_2U(SCH_1):PAGE61
  J110   F2     F2 CONN112_10137002101LF-CONN112_A    I54 @S9S_MB_2U_LIB.S9S_MB_2U(SCH_1):PAGE318

P5E_CPU1_PE2_RX_DN<15> @S9S_MB_2U_LIB.S9S_MB_2U(SCH_1):P5E_CPU1_PE2_RX_DN(15)
    U1 EH10 PE2_RX_DN15 SOCKET4677_AZIF0045P001C01CS-SA    I54 @S9S_MB_2U_LIB.S9S_MB_2U(SCH_1):PAGE61
  J110   G1     G1 CONN112_10137002101LF-CONN112_A    I54 @S9S_MB_2U_LIB.S9S_MB_2U(SCH_1):PAGE318

P5E_CPU1_PE2_RX_DN<1> @S9S_MB_2U_LIB.S9S_MB_2U(SCH_1):P5E_CPU1_PE2_RX_DN(1)
    U1 CY10 PE2_RX_DN1 SOCKET4677_AZIF0045P001C01CS-SA    I54 @S9S_MB_2U_LIB.S9S_MB_2U(SCH_1):PAGE61
  J109   G7     G7 CONN112_10137002101LF-CONN112_A    I76 @S9S_MB_2U_LIB.S9S_MB_2U(SCH_1):PAGE319

P5E_CPU1_PE2_RX_DN<2> @S9S_MB_2U_LIB.S9S_MB_2U(SCH_1):P5E_CPU1_PE2_RX_DN(2)
    U1  DA9 PE2_RX_DN2 SOCKET4677_AZIF0045P001C01CS-SA    I54 @S9S_MB_2U_LIB.S9S_MB_2U(SCH_1):PAGE61
  J109   F6     F6 CONN112_10137002101LF-CONN112_A    I76 @S9S_MB_2U_LIB.S9S_MB_2U(SCH_1):PAGE319

P5E_CPU1_PE2_RX_DN<3> @S9S_MB_2U_LIB.S9S_MB_2U(SCH_1):P5E_CPU1_PE2_RX_DN(3)
    U1 DD10 PE2_RX_DN3 SOCKET4677_AZIF0045P001C01CS-SA    I54 @S9S_MB_2U_LIB.S9S_MB_2U(SCH_1):PAGE61
  J109   G5     G5 CONN112_10137002101LF-CONN112_A    I76 @S9S_MB_2U_LIB.S9S_MB_2U(SCH_1):PAGE319

P5E_CPU1_PE2_RX_DN<4> @S9S_MB_2U_LIB.S9S_MB_2U(SCH_1):P5E_CPU1_PE2_RX_DN(4)
    U1  DE9 PE2_RX_DN4 SOCKET4677_AZIF0045P001C01CS-SA    I54 @S9S_MB_2U_LIB.S9S_MB_2U(SCH_1):PAGE61
  J109   F4     F4 CONN112_10137002101LF-CONN112_A    I53 @S9S_MB_2U_LIB.S9S_MB_2U(SCH_1):PAGE319

P5E_CPU1_PE2_RX_DN<5> @S9S_MB_2U_LIB.S9S_MB_2U(SCH_1):P5E_CPU1_PE2_RX_DN(5)
    U1 DH10 PE2_RX_DN5 SOCKET4677_AZIF0045P001C01CS-SA    I54 @S9S_MB_2U_LIB.S9S_MB_2U(SCH_1):PAGE61
  J109   G3     G3 CONN112_10137002101LF-CONN112_A    I53 @S9S_MB_2U_LIB.S9S_MB_2U(SCH_1):PAGE319

P5E_CPU1_PE2_RX_DN<6> @S9S_MB_2U_LIB.S9S_MB_2U(SCH_1):P5E_CPU1_PE2_RX_DN(6)
    U1  DJ9 PE2_RX_DN6 SOCKET4677_AZIF0045P001C01CS-SA    I54 @S9S_MB_2U_LIB.S9S_MB_2U(SCH_1):PAGE61
  J109   F2     F2 CONN112_10137002101LF-CONN112_A    I53 @S9S_MB_2U_LIB.S9S_MB_2U(SCH_1):PAGE319

P5E_CPU1_PE2_RX_DN<7> @S9S_MB_2U_LIB.S9S_MB_2U(SCH_1):P5E_CPU1_PE2_RX_DN(7)
    U1 DM10 PE2_RX_DN7 SOCKET4677_AZIF0045P001C01CS-SA    I54 @S9S_MB_2U_LIB.S9S_MB_2U(SCH_1):PAGE61
  J109   G1     G1 CONN112_10137002101LF-CONN112_A    I53 @S9S_MB_2U_LIB.S9S_MB_2U(SCH_1):PAGE319

P5E_CPU1_PE2_RX_DN<8> @S9S_MB_2U_LIB.S9S_MB_2U(SCH_1):P5E_CPU1_PE2_RX_DN(8)
    U1  DN9 PE2_RX_DN8 SOCKET4677_AZIF0045P001C01CS-SA    I54 @S9S_MB_2U_LIB.S9S_MB_2U(SCH_1):PAGE61
  J110   F8     F8 CONN112_10137002101LF-CONN112_A    I16 @S9S_MB_2U_LIB.S9S_MB_2U(SCH_1):PAGE318

P5E_CPU1_PE2_RX_DN<9> @S9S_MB_2U_LIB.S9S_MB_2U(SCH_1):P5E_CPU1_PE2_RX_DN(9)
    U1 DT10 PE2_RX_DN9 SOCKET4677_AZIF0045P001C01CS-SA    I54 @S9S_MB_2U_LIB.S9S_MB_2U(SCH_1):PAGE61
  J110   G7     G7 CONN112_10137002101LF-CONN112_A    I16 @S9S_MB_2U_LIB.S9S_MB_2U(SCH_1):PAGE318

P5E_CPU1_PE2_RX_DP<0> @S9S_MB_2U_LIB.S9S_MB_2U(SCH_1):P5E_CPU1_PE2_RX_DP(0)
    U1 CV10 PE2_RX_DP0 SOCKET4677_AZIF0045P001C01CS-SA    I54 @S9S_MB_2U_LIB.S9S_MB_2U(SCH_1):PAGE61
  J109   E8     E8 CONN112_10137002101LF-CONN112_A    I76 @S9S_MB_2U_LIB.S9S_MB_2U(SCH_1):PAGE319

P5E_CPU1_PE2_RX_DP<10> @S9S_MB_2U_LIB.S9S_MB_2U(SCH_1):P5E_CPU1_PE2_RX_DP(10)
    U1 DV10 PE2_RX_DP10 SOCKET4677_AZIF0045P001C01CS-SA    I54 @S9S_MB_2U_LIB.S9S_MB_2U(SCH_1):PAGE61
  J110   E6     E6 CONN112_10137002101LF-CONN112_A    I16 @S9S_MB_2U_LIB.S9S_MB_2U(SCH_1):PAGE318

P5E_CPU1_PE2_RX_DP<11> @S9S_MB_2U_LIB.S9S_MB_2U(SCH_1):P5E_CPU1_PE2_RX_DP(11)
    U1 DW11 PE2_RX_DP11 SOCKET4677_AZIF0045P001C01CS-SA    I54 @S9S_MB_2U_LIB.S9S_MB_2U(SCH_1):PAGE61
  J110   F5     F5 CONN112_10137002101LF-CONN112_A    I16 @S9S_MB_2U_LIB.S9S_MB_2U(SCH_1):PAGE318

P5E_CPU1_PE2_RX_DP<12> @S9S_MB_2U_LIB.S9S_MB_2U(SCH_1):P5E_CPU1_PE2_RX_DP(12)
    U1 EB10 PE2_RX_DP12 SOCKET4677_AZIF0045P001C01CS-SA    I54 @S9S_MB_2U_LIB.S9S_MB_2U(SCH_1):PAGE61
  J110   E4     E4 CONN112_10137002101LF-CONN112_A    I54 @S9S_MB_2U_LIB.S9S_MB_2U(SCH_1):PAGE318

P5E_CPU1_PE2_RX_DP<13> @S9S_MB_2U_LIB.S9S_MB_2U(SCH_1):P5E_CPU1_PE2_RX_DP(13)
    U1 EC11 PE2_RX_DP13 SOCKET4677_AZIF0045P001C01CS-SA    I54 @S9S_MB_2U_LIB.S9S_MB_2U(SCH_1):PAGE61
  J110   F3     F3 CONN112_10137002101LF-CONN112_A    I54 @S9S_MB_2U_LIB.S9S_MB_2U(SCH_1):PAGE318

P5E_CPU1_PE2_RX_DP<14> @S9S_MB_2U_LIB.S9S_MB_2U(SCH_1):P5E_CPU1_PE2_RX_DP(14)
    U1 EF10 PE2_RX_DP14 SOCKET4677_AZIF0045P001C01CS-SA    I54 @S9S_MB_2U_LIB.S9S_MB_2U(SCH_1):PAGE61
  J110   E2     E2 CONN112_10137002101LF-CONN112_A    I54 @S9S_MB_2U_LIB.S9S_MB_2U(SCH_1):PAGE318

P5E_CPU1_PE2_RX_DP<15> @S9S_MB_2U_LIB.S9S_MB_2U(SCH_1):P5E_CPU1_PE2_RX_DP(15)
    U1 EG11 PE2_RX_DP15 SOCKET4677_AZIF0045P001C01CS-SA    I54 @S9S_MB_2U_LIB.S9S_MB_2U(SCH_1):PAGE61
  J110   F1     F1 CONN112_10137002101LF-CONN112_A    I54 @S9S_MB_2U_LIB.S9S_MB_2U(SCH_1):PAGE318

P5E_CPU1_PE2_RX_DP<1> @S9S_MB_2U_LIB.S9S_MB_2U(SCH_1):P5E_CPU1_PE2_RX_DP(1)
    U1 CW11 PE2_RX_DP1 SOCKET4677_AZIF0045P001C01CS-SA    I54 @S9S_MB_2U_LIB.S9S_MB_2U(SCH_1):PAGE61
  J109   F7     F7 CONN112_10137002101LF-CONN112_A    I76 @S9S_MB_2U_LIB.S9S_MB_2U(SCH_1):PAGE319

P5E_CPU1_PE2_RX_DP<2> @S9S_MB_2U_LIB.S9S_MB_2U(SCH_1):P5E_CPU1_PE2_RX_DP(2)
    U1 DB10 PE2_RX_DP2 SOCKET4677_AZIF0045P001C01CS-SA    I54 @S9S_MB_2U_LIB.S9S_MB_2U(SCH_1):PAGE61
  J109   E6     E6 CONN112_10137002101LF-CONN112_A    I76 @S9S_MB_2U_LIB.S9S_MB_2U(SCH_1):PAGE319

P5E_CPU1_PE2_RX_DP<3> @S9S_MB_2U_LIB.S9S_MB_2U(SCH_1):P5E_CPU1_PE2_RX_DP(3)
    U1 DC11 PE2_RX_DP3 SOCKET4677_AZIF0045P001C01CS-SA    I54 @S9S_MB_2U_LIB.S9S_MB_2U(SCH_1):PAGE61
  J109   F5     F5 CONN112_10137002101LF-CONN112_A    I76 @S9S_MB_2U_LIB.S9S_MB_2U(SCH_1):PAGE319

P5E_CPU1_PE2_RX_DP<4> @S9S_MB_2U_LIB.S9S_MB_2U(SCH_1):P5E_CPU1_PE2_RX_DP(4)
    U1 DF10 PE2_RX_DP4 SOCKET4677_AZIF0045P001C01CS-SA    I54 @S9S_MB_2U_LIB.S9S_MB_2U(SCH_1):PAGE61
  J109   E4     E4 CONN112_10137002101LF-CONN112_A    I53 @S9S_MB_2U_LIB.S9S_MB_2U(SCH_1):PAGE319

P5E_CPU1_PE2_RX_DP<5> @S9S_MB_2U_LIB.S9S_MB_2U(SCH_1):P5E_CPU1_PE2_RX_DP(5)
    U1 DG11 PE2_RX_DP5 SOCKET4677_AZIF0045P001C01CS-SA    I54 @S9S_MB_2U_LIB.S9S_MB_2U(SCH_1):PAGE61
  J109   F3     F3 CONN112_10137002101LF-CONN112_A    I53 @S9S_MB_2U_LIB.S9S_MB_2U(SCH_1):PAGE319

P5E_CPU1_PE2_RX_DP<6> @S9S_MB_2U_LIB.S9S_MB_2U(SCH_1):P5E_CPU1_PE2_RX_DP(6)
    U1 DK10 PE2_RX_DP6 SOCKET4677_AZIF0045P001C01CS-SA    I54 @S9S_MB_2U_LIB.S9S_MB_2U(SCH_1):PAGE61
  J109   E2     E2 CONN112_10137002101LF-CONN112_A    I53 @S9S_MB_2U_LIB.S9S_MB_2U(SCH_1):PAGE319

P5E_CPU1_PE2_RX_DP<7> @S9S_MB_2U_LIB.S9S_MB_2U(SCH_1):P5E_CPU1_PE2_RX_DP(7)
    U1 DL11 PE2_RX_DP7 SOCKET4677_AZIF0045P001C01CS-SA    I54 @S9S_MB_2U_LIB.S9S_MB_2U(SCH_1):PAGE61
  J109   F1     F1 CONN112_10137002101LF-CONN112_A    I53 @S9S_MB_2U_LIB.S9S_MB_2U(SCH_1):PAGE319

P5E_CPU1_PE2_RX_DP<8> @S9S_MB_2U_LIB.S9S_MB_2U(SCH_1):P5E_CPU1_PE2_RX_DP(8)
    U1 DP10 PE2_RX_DP8 SOCKET4677_AZIF0045P001C01CS-SA    I54 @S9S_MB_2U_LIB.S9S_MB_2U(SCH_1):PAGE61
  J110   E8     E8 CONN112_10137002101LF-CONN112_A    I16 @S9S_MB_2U_LIB.S9S_MB_2U(SCH_1):PAGE318

P5E_CPU1_PE2_RX_DP<9> @S9S_MB_2U_LIB.S9S_MB_2U(SCH_1):P5E_CPU1_PE2_RX_DP(9)
    U1 DR11 PE2_RX_DP9 SOCKET4677_AZIF0045P001C01CS-SA    I54 @S9S_MB_2U_LIB.S9S_MB_2U(SCH_1):PAGE61
  J110   F7     F7 CONN112_10137002101LF-CONN112_A    I16 @S9S_MB_2U_LIB.S9S_MB_2U(SCH_1):PAGE318

P5E_CPU1_PE2_TX_C_DN<0> @S9S_MB_2U_LIB.S9S_MB_2U(SCH_1):P5E_CPU1_PE2_TX_C_DN(0)
  C772    1      1 Q_CAP_DIFFBUS_C0201-DIFF BUS_0A   I123 @S9S_MB_2U_LIB.S9S_MB_2U(SCH_1):PAGE167
  J109   L8     L8 CONN112_10137002101LF-CONN112_A    I76 @S9S_MB_2U_LIB.S9S_MB_2U(SCH_1):PAGE319

P5E_CPU1_PE2_TX_C_DN<10> @S9S_MB_2U_LIB.S9S_MB_2U(SCH_1):P5E_CPU1_PE2_TX_C_DN(10)
  C752    1      1 Q_CAP_DIFFBUS_C0201-DIFF BUS_0A   I159 @S9S_MB_2U_LIB.S9S_MB_2U(SCH_1):PAGE167
  J110   L6     L6 CONN112_10137002101LF-CONN112_A    I16 @S9S_MB_2U_LIB.S9S_MB_2U(SCH_1):PAGE318

P5E_CPU1_PE2_TX_C_DN<11> @S9S_MB_2U_LIB.S9S_MB_2U(SCH_1):P5E_CPU1_PE2_TX_C_DN(11)
  C750    1      1 Q_CAP_DIFFBUS_C0201-DIFF BUS_0A   I160 @S9S_MB_2U_LIB.S9S_MB_2U(SCH_1):PAGE167
  J110   M5     M5 CONN112_10137002101LF-CONN112_A    I16 @S9S_MB_2U_LIB.S9S_MB_2U(SCH_1):PAGE318

P5E_CPU1_PE2_TX_C_DN<12> @S9S_MB_2U_LIB.S9S_MB_2U(SCH_1):P5E_CPU1_PE2_TX_C_DN(12)
  C748    1      1 Q_CAP_DIFFBUS_C0201-DIFF BUS_0A   I163 @S9S_MB_2U_LIB.S9S_MB_2U(SCH_1):PAGE167
  J110   L4     L4 CONN112_10137002101LF-CONN112_A    I54 @S9S_MB_2U_LIB.S9S_MB_2U(SCH_1):PAGE318

P5E_CPU1_PE2_TX_C_DN<13> @S9S_MB_2U_LIB.S9S_MB_2U(SCH_1):P5E_CPU1_PE2_TX_C_DN(13)
  C746    1      1 Q_CAP_DIFFBUS_C0201-DIFF BUS_0A   I168 @S9S_MB_2U_LIB.S9S_MB_2U(SCH_1):PAGE167
  J110   M3     M3 CONN112_10137002101LF-CONN112_A    I54 @S9S_MB_2U_LIB.S9S_MB_2U(SCH_1):PAGE318

P5E_CPU1_PE2_TX_C_DN<14> @S9S_MB_2U_LIB.S9S_MB_2U(SCH_1):P5E_CPU1_PE2_TX_C_DN(14)
  C744    1      1 Q_CAP_DIFFBUS_C0201-DIFF BUS_0A   I170 @S9S_MB_2U_LIB.S9S_MB_2U(SCH_1):PAGE167
  J110   L2     L2 CONN112_10137002101LF-CONN112_A    I54 @S9S_MB_2U_LIB.S9S_MB_2U(SCH_1):PAGE318

P5E_CPU1_PE2_TX_C_DN<15> @S9S_MB_2U_LIB.S9S_MB_2U(SCH_1):P5E_CPU1_PE2_TX_C_DN(15)
  C742    1      1 Q_CAP_DIFFBUS_C0201-DIFF BUS_0A   I172 @S9S_MB_2U_LIB.S9S_MB_2U(SCH_1):PAGE167
  J110   M1     M1 CONN112_10137002101LF-CONN112_A    I54 @S9S_MB_2U_LIB.S9S_MB_2U(SCH_1):PAGE318

P5E_CPU1_PE2_TX_C_DN<1> @S9S_MB_2U_LIB.S9S_MB_2U(SCH_1):P5E_CPU1_PE2_TX_C_DN(1)
  C770    1      1 Q_CAP_DIFFBUS_C0201-DIFF BUS_0A   I125 @S9S_MB_2U_LIB.S9S_MB_2U(SCH_1):PAGE167
  J109   M7     M7 CONN112_10137002101LF-CONN112_A    I76 @S9S_MB_2U_LIB.S9S_MB_2U(SCH_1):PAGE319

P5E_CPU1_PE2_TX_C_DN<2> @S9S_MB_2U_LIB.S9S_MB_2U(SCH_1):P5E_CPU1_PE2_TX_C_DN(2)
  C768    1      1 Q_CAP_DIFFBUS_C0201-DIFF BUS_0A   I127 @S9S_MB_2U_LIB.S9S_MB_2U(SCH_1):PAGE167
  J109   L6     L6 CONN112_10137002101LF-CONN112_A    I76 @S9S_MB_2U_LIB.S9S_MB_2U(SCH_1):PAGE319

P5E_CPU1_PE2_TX_C_DN<3> @S9S_MB_2U_LIB.S9S_MB_2U(SCH_1):P5E_CPU1_PE2_TX_C_DN(3)
  C766    1      1 Q_CAP_DIFFBUS_C0201-DIFF BUS_0A   I129 @S9S_MB_2U_LIB.S9S_MB_2U(SCH_1):PAGE167
  J109   M5     M5 CONN112_10137002101LF-CONN112_A    I76 @S9S_MB_2U_LIB.S9S_MB_2U(SCH_1):PAGE319

P5E_CPU1_PE2_TX_C_DN<4> @S9S_MB_2U_LIB.S9S_MB_2U(SCH_1):P5E_CPU1_PE2_TX_C_DN(4)
  C764    1      1 Q_CAP_DIFFBUS_C0201-DIFF BUS_0A   I130 @S9S_MB_2U_LIB.S9S_MB_2U(SCH_1):PAGE167
  J109   L4     L4 CONN112_10137002101LF-CONN112_A    I53 @S9S_MB_2U_LIB.S9S_MB_2U(SCH_1):PAGE319

P5E_CPU1_PE2_TX_C_DN<5> @S9S_MB_2U_LIB.S9S_MB_2U(SCH_1):P5E_CPU1_PE2_TX_C_DN(5)
  C762    1      1 Q_CAP_DIFFBUS_C0201-DIFF BUS_0A   I136 @S9S_MB_2U_LIB.S9S_MB_2U(SCH_1):PAGE167
  J109   M3     M3 CONN112_10137002101LF-CONN112_A    I53 @S9S_MB_2U_LIB.S9S_MB_2U(SCH_1):PAGE319

P5E_CPU1_PE2_TX_C_DN<6> @S9S_MB_2U_LIB.S9S_MB_2U(SCH_1):P5E_CPU1_PE2_TX_C_DN(6)
  C760    1      1 Q_CAP_DIFFBUS_C0201-DIFF BUS_0A   I138 @S9S_MB_2U_LIB.S9S_MB_2U(SCH_1):PAGE167
  J109   L2     L2 CONN112_10137002101LF-CONN112_A    I53 @S9S_MB_2U_LIB.S9S_MB_2U(SCH_1):PAGE319

P5E_CPU1_PE2_TX_C_DN<7> @S9S_MB_2U_LIB.S9S_MB_2U(SCH_1):P5E_CPU1_PE2_TX_C_DN(7)
  C758    1      1 Q_CAP_DIFFBUS_C0201-DIFF BUS_0A   I140 @S9S_MB_2U_LIB.S9S_MB_2U(SCH_1):PAGE167
  J109   M1     M1 CONN112_10137002101LF-CONN112_A    I53 @S9S_MB_2U_LIB.S9S_MB_2U(SCH_1):PAGE319

P5E_CPU1_PE2_TX_C_DN<8> @S9S_MB_2U_LIB.S9S_MB_2U(SCH_1):P5E_CPU1_PE2_TX_C_DN(8)
  C756    1      1 Q_CAP_DIFFBUS_C0201-DIFF BUS_0A   I154 @S9S_MB_2U_LIB.S9S_MB_2U(SCH_1):PAGE167
  J110   L8     L8 CONN112_10137002101LF-CONN112_A    I16 @S9S_MB_2U_LIB.S9S_MB_2U(SCH_1):PAGE318

P5E_CPU1_PE2_TX_C_DN<9> @S9S_MB_2U_LIB.S9S_MB_2U(SCH_1):P5E_CPU1_PE2_TX_C_DN(9)
  C754    1      1 Q_CAP_DIFFBUS_C0201-DIFF BUS_0A   I157 @S9S_MB_2U_LIB.S9S_MB_2U(SCH_1):PAGE167
  J110   M7     M7 CONN112_10137002101LF-CONN112_A    I16 @S9S_MB_2U_LIB.S9S_MB_2U(SCH_1):PAGE318

P5E_CPU1_PE2_TX_C_DP<0> @S9S_MB_2U_LIB.S9S_MB_2U(SCH_1):P5E_CPU1_PE2_TX_C_DP(0)
  C773    1      1 Q_CAP_DIFFBUS_C0201-DIFF BUS_0A   I122 @S9S_MB_2U_LIB.S9S_MB_2U(SCH_1):PAGE167
  J109   K8     K8 CONN112_10137002101LF-CONN112_A    I76 @S9S_MB_2U_LIB.S9S_MB_2U(SCH_1):PAGE319

P5E_CPU1_PE2_TX_C_DP<10> @S9S_MB_2U_LIB.S9S_MB_2U(SCH_1):P5E_CPU1_PE2_TX_C_DP(10)
  C753    1      1 Q_CAP_DIFFBUS_C0201-DIFF BUS_0A   I158 @S9S_MB_2U_LIB.S9S_MB_2U(SCH_1):PAGE167
  J110   K6     K6 CONN112_10137002101LF-CONN112_A    I16 @S9S_MB_2U_LIB.S9S_MB_2U(SCH_1):PAGE318

P5E_CPU1_PE2_TX_C_DP<11> @S9S_MB_2U_LIB.S9S_MB_2U(SCH_1):P5E_CPU1_PE2_TX_C_DP(11)
  C751    1      1 Q_CAP_DIFFBUS_C0201-DIFF BUS_0A   I161 @S9S_MB_2U_LIB.S9S_MB_2U(SCH_1):PAGE167
  J110   L5     L5 CONN112_10137002101LF-CONN112_A    I16 @S9S_MB_2U_LIB.S9S_MB_2U(SCH_1):PAGE318

P5E_CPU1_PE2_TX_C_DP<12> @S9S_MB_2U_LIB.S9S_MB_2U(SCH_1):P5E_CPU1_PE2_TX_C_DP(12)
  C749    1      1 Q_CAP_DIFFBUS_C0201-DIFF BUS_0A   I162 @S9S_MB_2U_LIB.S9S_MB_2U(SCH_1):PAGE167
  J110   K4     K4 CONN112_10137002101LF-CONN112_A    I54 @S9S_MB_2U_LIB.S9S_MB_2U(SCH_1):PAGE318

P5E_CPU1_PE2_TX_C_DP<13> @S9S_MB_2U_LIB.S9S_MB_2U(SCH_1):P5E_CPU1_PE2_TX_C_DP(13)
  C747    1      1 Q_CAP_DIFFBUS_C0201-DIFF BUS_0A   I167 @S9S_MB_2U_LIB.S9S_MB_2U(SCH_1):PAGE167
  J110   L3     L3 CONN112_10137002101LF-CONN112_A    I54 @S9S_MB_2U_LIB.S9S_MB_2U(SCH_1):PAGE318

P5E_CPU1_PE2_TX_C_DP<14> @S9S_MB_2U_LIB.S9S_MB_2U(SCH_1):P5E_CPU1_PE2_TX_C_DP(14)
  C745    1      1 Q_CAP_DIFFBUS_C0201-DIFF BUS_0A   I169 @S9S_MB_2U_LIB.S9S_MB_2U(SCH_1):PAGE167
  J110   K2     K2 CONN112_10137002101LF-CONN112_A    I54 @S9S_MB_2U_LIB.S9S_MB_2U(SCH_1):PAGE318

P5E_CPU1_PE2_TX_C_DP<15> @S9S_MB_2U_LIB.S9S_MB_2U(SCH_1):P5E_CPU1_PE2_TX_C_DP(15)
  C743    1      1 Q_CAP_DIFFBUS_C0201-DIFF BUS_0A   I171 @S9S_MB_2U_LIB.S9S_MB_2U(SCH_1):PAGE167
  J110   L1     L1 CONN112_10137002101LF-CONN112_A    I54 @S9S_MB_2U_LIB.S9S_MB_2U(SCH_1):PAGE318

P5E_CPU1_PE2_TX_C_DP<1> @S9S_MB_2U_LIB.S9S_MB_2U(SCH_1):P5E_CPU1_PE2_TX_C_DP(1)
  C771    1      1 Q_CAP_DIFFBUS_C0201-DIFF BUS_0A   I124 @S9S_MB_2U_LIB.S9S_MB_2U(SCH_1):PAGE167
  J109   L7     L7 CONN112_10137002101LF-CONN112_A    I76 @S9S_MB_2U_LIB.S9S_MB_2U(SCH_1):PAGE319

P5E_CPU1_PE2_TX_C_DP<2> @S9S_MB_2U_LIB.S9S_MB_2U(SCH_1):P5E_CPU1_PE2_TX_C_DP(2)
  C769    1      1 Q_CAP_DIFFBUS_C0201-DIFF BUS_0A   I126 @S9S_MB_2U_LIB.S9S_MB_2U(SCH_1):PAGE167
  J109   K6     K6 CONN112_10137002101LF-CONN112_A    I76 @S9S_MB_2U_LIB.S9S_MB_2U(SCH_1):PAGE319

P5E_CPU1_PE2_TX_C_DP<3> @S9S_MB_2U_LIB.S9S_MB_2U(SCH_1):P5E_CPU1_PE2_TX_C_DP(3)
  C767    1      1 Q_CAP_DIFFBUS_C0201-DIFF BUS_0A   I128 @S9S_MB_2U_LIB.S9S_MB_2U(SCH_1):PAGE167
  J109   L5     L5 CONN112_10137002101LF-CONN112_A    I76 @S9S_MB_2U_LIB.S9S_MB_2U(SCH_1):PAGE319

P5E_CPU1_PE2_TX_C_DP<4> @S9S_MB_2U_LIB.S9S_MB_2U(SCH_1):P5E_CPU1_PE2_TX_C_DP(4)
  C765    1      1 Q_CAP_DIFFBUS_C0201-DIFF BUS_0A   I131 @S9S_MB_2U_LIB.S9S_MB_2U(SCH_1):PAGE167
  J109   K4     K4 CONN112_10137002101LF-CONN112_A    I53 @S9S_MB_2U_LIB.S9S_MB_2U(SCH_1):PAGE319

P5E_CPU1_PE2_TX_C_DP<5> @S9S_MB_2U_LIB.S9S_MB_2U(SCH_1):P5E_CPU1_PE2_TX_C_DP(5)
  C763    1      1 Q_CAP_DIFFBUS_C0201-DIFF BUS_0A   I135 @S9S_MB_2U_LIB.S9S_MB_2U(SCH_1):PAGE167
  J109   L3     L3 CONN112_10137002101LF-CONN112_A    I53 @S9S_MB_2U_LIB.S9S_MB_2U(SCH_1):PAGE319

P5E_CPU1_PE2_TX_C_DP<6> @S9S_MB_2U_LIB.S9S_MB_2U(SCH_1):P5E_CPU1_PE2_TX_C_DP(6)
  C761    1      1 Q_CAP_DIFFBUS_C0201-DIFF BUS_0A   I137 @S9S_MB_2U_LIB.S9S_MB_2U(SCH_1):PAGE167
  J109   K2     K2 CONN112_10137002101LF-CONN112_A    I53 @S9S_MB_2U_LIB.S9S_MB_2U(SCH_1):PAGE319

P5E_CPU1_PE2_TX_C_DP<7> @S9S_MB_2U_LIB.S9S_MB_2U(SCH_1):P5E_CPU1_PE2_TX_C_DP(7)
  C759    1      1 Q_CAP_DIFFBUS_C0201-DIFF BUS_0A   I139 @S9S_MB_2U_LIB.S9S_MB_2U(SCH_1):PAGE167
  J109   L1     L1 CONN112_10137002101LF-CONN112_A    I53 @S9S_MB_2U_LIB.S9S_MB_2U(SCH_1):PAGE319

P5E_CPU1_PE2_TX_C_DP<8> @S9S_MB_2U_LIB.S9S_MB_2U(SCH_1):P5E_CPU1_PE2_TX_C_DP(8)
  C757    1      1 Q_CAP_DIFFBUS_C0201-DIFF BUS_0A   I155 @S9S_MB_2U_LIB.S9S_MB_2U(SCH_1):PAGE167
  J110   K8     K8 CONN112_10137002101LF-CONN112_A    I16 @S9S_MB_2U_LIB.S9S_MB_2U(SCH_1):PAGE318

P5E_CPU1_PE2_TX_C_DP<9> @S9S_MB_2U_LIB.S9S_MB_2U(SCH_1):P5E_CPU1_PE2_TX_C_DP(9)
  C755    1      1 Q_CAP_DIFFBUS_C0201-DIFF BUS_0A   I156 @S9S_MB_2U_LIB.S9S_MB_2U(SCH_1):PAGE167
  J110   L7     L7 CONN112_10137002101LF-CONN112_A    I16 @S9S_MB_2U_LIB.S9S_MB_2U(SCH_1):PAGE318

P5E_CPU1_PE2_TX_DN<0> @S9S_MB_2U_LIB.S9S_MB_2U(SCH_1):P5E_CPU1_PE2_TX_DN(0)
    U1 CU13 PE2_TX_DN0 SOCKET4677_AZIF0045P001C01CS-SA    I54 @S9S_MB_2U_LIB.S9S_MB_2U(SCH_1):PAGE61
  C772    2      2 Q_CAP_DIFFBUS_C0201-DIFF BUS_0A   I123 @S9S_MB_2U_LIB.S9S_MB_2U(SCH_1):PAGE167

P5E_CPU1_PE2_TX_DN<10> @S9S_MB_2U_LIB.S9S_MB_2U(SCH_1):P5E_CPU1_PE2_TX_DN(10)
    U1 DU13 PE2_TX_DN10 SOCKET4677_AZIF0045P001C01CS-SA    I54 @S9S_MB_2U_LIB.S9S_MB_2U(SCH_1):PAGE61
  C752    2      2 Q_CAP_DIFFBUS_C0201-DIFF BUS_0A   I159 @S9S_MB_2U_LIB.S9S_MB_2U(SCH_1):PAGE167

P5E_CPU1_PE2_TX_DN<11> @S9S_MB_2U_LIB.S9S_MB_2U(SCH_1):P5E_CPU1_PE2_TX_DN(11)
    U1 DV14 PE2_TX_DN11 SOCKET4677_AZIF0045P001C01CS-SA    I54 @S9S_MB_2U_LIB.S9S_MB_2U(SCH_1):PAGE61
  C750    2      2 Q_CAP_DIFFBUS_C0201-DIFF BUS_0A   I160 @S9S_MB_2U_LIB.S9S_MB_2U(SCH_1):PAGE167

P5E_CPU1_PE2_TX_DN<12> @S9S_MB_2U_LIB.S9S_MB_2U(SCH_1):P5E_CPU1_PE2_TX_DN(12)
    U1 EA13 PE2_TX_DN12 SOCKET4677_AZIF0045P001C01CS-SA    I54 @S9S_MB_2U_LIB.S9S_MB_2U(SCH_1):PAGE61
  C748    2      2 Q_CAP_DIFFBUS_C0201-DIFF BUS_0A   I163 @S9S_MB_2U_LIB.S9S_MB_2U(SCH_1):PAGE167

P5E_CPU1_PE2_TX_DN<13> @S9S_MB_2U_LIB.S9S_MB_2U(SCH_1):P5E_CPU1_PE2_TX_DN(13)
    U1 EB14 PE2_TX_DN13 SOCKET4677_AZIF0045P001C01CS-SA    I54 @S9S_MB_2U_LIB.S9S_MB_2U(SCH_1):PAGE61
  C746    2      2 Q_CAP_DIFFBUS_C0201-DIFF BUS_0A   I168 @S9S_MB_2U_LIB.S9S_MB_2U(SCH_1):PAGE167

P5E_CPU1_PE2_TX_DN<14> @S9S_MB_2U_LIB.S9S_MB_2U(SCH_1):P5E_CPU1_PE2_TX_DN(14)
    U1 EE13 PE2_TX_DN14 SOCKET4677_AZIF0045P001C01CS-SA    I54 @S9S_MB_2U_LIB.S9S_MB_2U(SCH_1):PAGE61
  C744    2      2 Q_CAP_DIFFBUS_C0201-DIFF BUS_0A   I170 @S9S_MB_2U_LIB.S9S_MB_2U(SCH_1):PAGE167

P5E_CPU1_PE2_TX_DN<15> @S9S_MB_2U_LIB.S9S_MB_2U(SCH_1):P5E_CPU1_PE2_TX_DN(15)
    U1 EF14 PE2_TX_DN15 SOCKET4677_AZIF0045P001C01CS-SA    I54 @S9S_MB_2U_LIB.S9S_MB_2U(SCH_1):PAGE61
  C742    2      2 Q_CAP_DIFFBUS_C0201-DIFF BUS_0A   I172 @S9S_MB_2U_LIB.S9S_MB_2U(SCH_1):PAGE167

P5E_CPU1_PE2_TX_DN<1> @S9S_MB_2U_LIB.S9S_MB_2U(SCH_1):P5E_CPU1_PE2_TX_DN(1)
    U1 CV14 PE2_TX_DN1 SOCKET4677_AZIF0045P001C01CS-SA    I54 @S9S_MB_2U_LIB.S9S_MB_2U(SCH_1):PAGE61
  C770    2      2 Q_CAP_DIFFBUS_C0201-DIFF BUS_0A   I125 @S9S_MB_2U_LIB.S9S_MB_2U(SCH_1):PAGE167

P5E_CPU1_PE2_TX_DN<2> @S9S_MB_2U_LIB.S9S_MB_2U(SCH_1):P5E_CPU1_PE2_TX_DN(2)
    U1 DA13 PE2_TX_DN2 SOCKET4677_AZIF0045P001C01CS-SA    I54 @S9S_MB_2U_LIB.S9S_MB_2U(SCH_1):PAGE61
  C768    2      2 Q_CAP_DIFFBUS_C0201-DIFF BUS_0A   I127 @S9S_MB_2U_LIB.S9S_MB_2U(SCH_1):PAGE167

P5E_CPU1_PE2_TX_DN<3> @S9S_MB_2U_LIB.S9S_MB_2U(SCH_1):P5E_CPU1_PE2_TX_DN(3)
    U1 DB14 PE2_TX_DN3 SOCKET4677_AZIF0045P001C01CS-SA    I54 @S9S_MB_2U_LIB.S9S_MB_2U(SCH_1):PAGE61
  C766    2      2 Q_CAP_DIFFBUS_C0201-DIFF BUS_0A   I129 @S9S_MB_2U_LIB.S9S_MB_2U(SCH_1):PAGE167

P5E_CPU1_PE2_TX_DN<4> @S9S_MB_2U_LIB.S9S_MB_2U(SCH_1):P5E_CPU1_PE2_TX_DN(4)
    U1 DE13 PE2_TX_DN4 SOCKET4677_AZIF0045P001C01CS-SA    I54 @S9S_MB_2U_LIB.S9S_MB_2U(SCH_1):PAGE61
  C764    2      2 Q_CAP_DIFFBUS_C0201-DIFF BUS_0A   I130 @S9S_MB_2U_LIB.S9S_MB_2U(SCH_1):PAGE167

P5E_CPU1_PE2_TX_DN<5> @S9S_MB_2U_LIB.S9S_MB_2U(SCH_1):P5E_CPU1_PE2_TX_DN(5)
    U1 DF14 PE2_TX_DN5 SOCKET4677_AZIF0045P001C01CS-SA    I54 @S9S_MB_2U_LIB.S9S_MB_2U(SCH_1):PAGE61
  C762    2      2 Q_CAP_DIFFBUS_C0201-DIFF BUS_0A   I136 @S9S_MB_2U_LIB.S9S_MB_2U(SCH_1):PAGE167

P5E_CPU1_PE2_TX_DN<6> @S9S_MB_2U_LIB.S9S_MB_2U(SCH_1):P5E_CPU1_PE2_TX_DN(6)
    U1 DJ13 PE2_TX_DN6 SOCKET4677_AZIF0045P001C01CS-SA    I54 @S9S_MB_2U_LIB.S9S_MB_2U(SCH_1):PAGE61
  C760    2      2 Q_CAP_DIFFBUS_C0201-DIFF BUS_0A   I138 @S9S_MB_2U_LIB.S9S_MB_2U(SCH_1):PAGE167

P5E_CPU1_PE2_TX_DN<7> @S9S_MB_2U_LIB.S9S_MB_2U(SCH_1):P5E_CPU1_PE2_TX_DN(7)
    U1 DK14 PE2_TX_DN7 SOCKET4677_AZIF0045P001C01CS-SA    I54 @S9S_MB_2U_LIB.S9S_MB_2U(SCH_1):PAGE61
  C758    2      2 Q_CAP_DIFFBUS_C0201-DIFF BUS_0A   I140 @S9S_MB_2U_LIB.S9S_MB_2U(SCH_1):PAGE167

P5E_CPU1_PE2_TX_DN<8> @S9S_MB_2U_LIB.S9S_MB_2U(SCH_1):P5E_CPU1_PE2_TX_DN(8)
    U1 DN13 PE2_TX_DN8 SOCKET4677_AZIF0045P001C01CS-SA    I54 @S9S_MB_2U_LIB.S9S_MB_2U(SCH_1):PAGE61
  C756    2      2 Q_CAP_DIFFBUS_C0201-DIFF BUS_0A   I154 @S9S_MB_2U_LIB.S9S_MB_2U(SCH_1):PAGE167

P5E_CPU1_PE2_TX_DN<9> @S9S_MB_2U_LIB.S9S_MB_2U(SCH_1):P5E_CPU1_PE2_TX_DN(9)
    U1 DP14 PE2_TX_DN9 SOCKET4677_AZIF0045P001C01CS-SA    I54 @S9S_MB_2U_LIB.S9S_MB_2U(SCH_1):PAGE61
  C754    2      2 Q_CAP_DIFFBUS_C0201-DIFF BUS_0A   I157 @S9S_MB_2U_LIB.S9S_MB_2U(SCH_1):PAGE167

P5E_CPU1_PE2_TX_DP<0> @S9S_MB_2U_LIB.S9S_MB_2U(SCH_1):P5E_CPU1_PE2_TX_DP(0)
    U1 CT14 PE2_TX_DP0 SOCKET4677_AZIF0045P001C01CS-SA    I54 @S9S_MB_2U_LIB.S9S_MB_2U(SCH_1):PAGE61
  C773    2      2 Q_CAP_DIFFBUS_C0201-DIFF BUS_0A   I122 @S9S_MB_2U_LIB.S9S_MB_2U(SCH_1):PAGE167

P5E_CPU1_PE2_TX_DP<10> @S9S_MB_2U_LIB.S9S_MB_2U(SCH_1):P5E_CPU1_PE2_TX_DP(10)
    U1 DT14 PE2_TX_DP10 SOCKET4677_AZIF0045P001C01CS-SA    I54 @S9S_MB_2U_LIB.S9S_MB_2U(SCH_1):PAGE61
  C753    2      2 Q_CAP_DIFFBUS_C0201-DIFF BUS_0A   I158 @S9S_MB_2U_LIB.S9S_MB_2U(SCH_1):PAGE167

P5E_CPU1_PE2_TX_DP<11> @S9S_MB_2U_LIB.S9S_MB_2U(SCH_1):P5E_CPU1_PE2_TX_DP(11)
    U1 DW15 PE2_TX_DP11 SOCKET4677_AZIF0045P001C01CS-SA    I54 @S9S_MB_2U_LIB.S9S_MB_2U(SCH_1):PAGE61
  C751    2      2 Q_CAP_DIFFBUS_C0201-DIFF BUS_0A   I161 @S9S_MB_2U_LIB.S9S_MB_2U(SCH_1):PAGE167

P5E_CPU1_PE2_TX_DP<12> @S9S_MB_2U_LIB.S9S_MB_2U(SCH_1):P5E_CPU1_PE2_TX_DP(12)
    U1 DY14 PE2_TX_DP12 SOCKET4677_AZIF0045P001C01CS-SA    I54 @S9S_MB_2U_LIB.S9S_MB_2U(SCH_1):PAGE61
  C749    2      2 Q_CAP_DIFFBUS_C0201-DIFF BUS_0A   I162 @S9S_MB_2U_LIB.S9S_MB_2U(SCH_1):PAGE167

P5E_CPU1_PE2_TX_DP<13> @S9S_MB_2U_LIB.S9S_MB_2U(SCH_1):P5E_CPU1_PE2_TX_DP(13)
    U1 EC15 PE2_TX_DP13 SOCKET4677_AZIF0045P001C01CS-SA    I54 @S9S_MB_2U_LIB.S9S_MB_2U(SCH_1):PAGE61
  C747    2      2 Q_CAP_DIFFBUS_C0201-DIFF BUS_0A   I167 @S9S_MB_2U_LIB.S9S_MB_2U(SCH_1):PAGE167

P5E_CPU1_PE2_TX_DP<14> @S9S_MB_2U_LIB.S9S_MB_2U(SCH_1):P5E_CPU1_PE2_TX_DP(14)
    U1 ED14 PE2_TX_DP14 SOCKET4677_AZIF0045P001C01CS-SA    I54 @S9S_MB_2U_LIB.S9S_MB_2U(SCH_1):PAGE61
  C745    2      2 Q_CAP_DIFFBUS_C0201-DIFF BUS_0A   I169 @S9S_MB_2U_LIB.S9S_MB_2U(SCH_1):PAGE167

P5E_CPU1_PE2_TX_DP<15> @S9S_MB_2U_LIB.S9S_MB_2U(SCH_1):P5E_CPU1_PE2_TX_DP(15)
    U1 EG15 PE2_TX_DP15 SOCKET4677_AZIF0045P001C01CS-SA    I54 @S9S_MB_2U_LIB.S9S_MB_2U(SCH_1):PAGE61
  C743    2      2 Q_CAP_DIFFBUS_C0201-DIFF BUS_0A   I171 @S9S_MB_2U_LIB.S9S_MB_2U(SCH_1):PAGE167

P5E_CPU1_PE2_TX_DP<1> @S9S_MB_2U_LIB.S9S_MB_2U(SCH_1):P5E_CPU1_PE2_TX_DP(1)
    U1 CW15 PE2_TX_DP1 SOCKET4677_AZIF0045P001C01CS-SA    I54 @S9S_MB_2U_LIB.S9S_MB_2U(SCH_1):PAGE61
  C771    2      2 Q_CAP_DIFFBUS_C0201-DIFF BUS_0A   I124 @S9S_MB_2U_LIB.S9S_MB_2U(SCH_1):PAGE167

P5E_CPU1_PE2_TX_DP<2> @S9S_MB_2U_LIB.S9S_MB_2U(SCH_1):P5E_CPU1_PE2_TX_DP(2)
    U1 CY14 PE2_TX_DP2 SOCKET4677_AZIF0045P001C01CS-SA    I54 @S9S_MB_2U_LIB.S9S_MB_2U(SCH_1):PAGE61
  C769    2      2 Q_CAP_DIFFBUS_C0201-DIFF BUS_0A   I126 @S9S_MB_2U_LIB.S9S_MB_2U(SCH_1):PAGE167

P5E_CPU1_PE2_TX_DP<3> @S9S_MB_2U_LIB.S9S_MB_2U(SCH_1):P5E_CPU1_PE2_TX_DP(3)
    U1 DC15 PE2_TX_DP3 SOCKET4677_AZIF0045P001C01CS-SA    I54 @S9S_MB_2U_LIB.S9S_MB_2U(SCH_1):PAGE61
  C767    2      2 Q_CAP_DIFFBUS_C0201-DIFF BUS_0A   I128 @S9S_MB_2U_LIB.S9S_MB_2U(SCH_1):PAGE167

P5E_CPU1_PE2_TX_DP<4> @S9S_MB_2U_LIB.S9S_MB_2U(SCH_1):P5E_CPU1_PE2_TX_DP(4)
    U1 DD14 PE2_TX_DP4 SOCKET4677_AZIF0045P001C01CS-SA    I54 @S9S_MB_2U_LIB.S9S_MB_2U(SCH_1):PAGE61
  C765    2      2 Q_CAP_DIFFBUS_C0201-DIFF BUS_0A   I131 @S9S_MB_2U_LIB.S9S_MB_2U(SCH_1):PAGE167

P5E_CPU1_PE2_TX_DP<5> @S9S_MB_2U_LIB.S9S_MB_2U(SCH_1):P5E_CPU1_PE2_TX_DP(5)
    U1 DG15 PE2_TX_DP5 SOCKET4677_AZIF0045P001C01CS-SA    I54 @S9S_MB_2U_LIB.S9S_MB_2U(SCH_1):PAGE61
  C763    2      2 Q_CAP_DIFFBUS_C0201-DIFF BUS_0A   I135 @S9S_MB_2U_LIB.S9S_MB_2U(SCH_1):PAGE167

P5E_CPU1_PE2_TX_DP<6> @S9S_MB_2U_LIB.S9S_MB_2U(SCH_1):P5E_CPU1_PE2_TX_DP(6)
    U1 DH14 PE2_TX_DP6 SOCKET4677_AZIF0045P001C01CS-SA    I54 @S9S_MB_2U_LIB.S9S_MB_2U(SCH_1):PAGE61
  C761    2      2 Q_CAP_DIFFBUS_C0201-DIFF BUS_0A   I137 @S9S_MB_2U_LIB.S9S_MB_2U(SCH_1):PAGE167

P5E_CPU1_PE2_TX_DP<7> @S9S_MB_2U_LIB.S9S_MB_2U(SCH_1):P5E_CPU1_PE2_TX_DP(7)
    U1 DL15 PE2_TX_DP7 SOCKET4677_AZIF0045P001C01CS-SA    I54 @S9S_MB_2U_LIB.S9S_MB_2U(SCH_1):PAGE61
  C759    2      2 Q_CAP_DIFFBUS_C0201-DIFF BUS_0A   I139 @S9S_MB_2U_LIB.S9S_MB_2U(SCH_1):PAGE167

P5E_CPU1_PE2_TX_DP<8> @S9S_MB_2U_LIB.S9S_MB_2U(SCH_1):P5E_CPU1_PE2_TX_DP(8)
    U1 DM14 PE2_TX_DP8 SOCKET4677_AZIF0045P001C01CS-SA    I54 @S9S_MB_2U_LIB.S9S_MB_2U(SCH_1):PAGE61
  C757    2      2 Q_CAP_DIFFBUS_C0201-DIFF BUS_0A   I155 @S9S_MB_2U_LIB.S9S_MB_2U(SCH_1):PAGE167

P5E_CPU1_PE2_TX_DP<9> @S9S_MB_2U_LIB.S9S_MB_2U(SCH_1):P5E_CPU1_PE2_TX_DP(9)
    U1 DR15 PE2_TX_DP9 SOCKET4677_AZIF0045P001C01CS-SA    I54 @S9S_MB_2U_LIB.S9S_MB_2U(SCH_1):PAGE61
  C755    2      2 Q_CAP_DIFFBUS_C0201-DIFF BUS_0A   I156 @S9S_MB_2U_LIB.S9S_MB_2U(SCH_1):PAGE167

P5E_CPU1_PE3_RX_DN<0> @S9S_MB_2U_LIB.S9S_MB_2U(SCH_1):P5E_CPU1_PE3_RX_DN(0)
    U1 EH89 PE3_RX_DN0 SOCKET4677_AZIF0045P001C01CS-SA    I12 @S9S_MB_2U_LIB.S9S_MB_2U(SCH_1):PAGE61
  J109   C8     C8 CONN112_10137002101LF-CONN112_A    I76 @S9S_MB_2U_LIB.S9S_MB_2U(SCH_1):PAGE319

P5E_CPU1_PE3_RX_DN<10> @S9S_MB_2U_LIB.S9S_MB_2U(SCH_1):P5E_CPU1_PE3_RX_DN(10)
    U1 DG90 PE3_RX_DN10 SOCKET4677_AZIF0045P001C01CS-SA    I12 @S9S_MB_2U_LIB.S9S_MB_2U(SCH_1):PAGE61
  J110   B6     B6 CONN112_10137002101LF-CONN112_A    I16 @S9S_MB_2U_LIB.S9S_MB_2U(SCH_1):PAGE318

P5E_CPU1_PE3_RX_DN<11> @S9S_MB_2U_LIB.S9S_MB_2U(SCH_1):P5E_CPU1_PE3_RX_DN(11)
    U1 DD91 PE3_RX_DN11 SOCKET4677_AZIF0045P001C01CS-SA    I12 @S9S_MB_2U_LIB.S9S_MB_2U(SCH_1):PAGE61
  J110   C5     C5 CONN112_10137002101LF-CONN112_A    I16 @S9S_MB_2U_LIB.S9S_MB_2U(SCH_1):PAGE318

P5E_CPU1_PE3_RX_DN<12> @S9S_MB_2U_LIB.S9S_MB_2U(SCH_1):P5E_CPU1_PE3_RX_DN(12)
    U1 DB89 PE3_RX_DN12 SOCKET4677_AZIF0045P001C01CS-SA    I12 @S9S_MB_2U_LIB.S9S_MB_2U(SCH_1):PAGE61
  J110   C4     C4 CONN112_10137002101LF-CONN112_A    I54 @S9S_MB_2U_LIB.S9S_MB_2U(SCH_1):PAGE318

P5E_CPU1_PE3_RX_DN<13> @S9S_MB_2U_LIB.S9S_MB_2U(SCH_1):P5E_CPU1_PE3_RX_DN(13)
    U1 DA90 PE3_RX_DN13 SOCKET4677_AZIF0045P001C01CS-SA    I12 @S9S_MB_2U_LIB.S9S_MB_2U(SCH_1):PAGE61
  J110   D3     D3 CONN112_10137002101LF-CONN112_A    I54 @S9S_MB_2U_LIB.S9S_MB_2U(SCH_1):PAGE318

P5E_CPU1_PE3_RX_DN<14> @S9S_MB_2U_LIB.S9S_MB_2U(SCH_1):P5E_CPU1_PE3_RX_DN(14)
    U1 CV89 PE3_RX_DN14 SOCKET4677_AZIF0045P001C01CS-SA    I12 @S9S_MB_2U_LIB.S9S_MB_2U(SCH_1):PAGE61
  J110   C2     C2 CONN112_10137002101LF-CONN112_A    I54 @S9S_MB_2U_LIB.S9S_MB_2U(SCH_1):PAGE318

P5E_CPU1_PE3_RX_DN<15> @S9S_MB_2U_LIB.S9S_MB_2U(SCH_1):P5E_CPU1_PE3_RX_DN(15)
    U1 CU90 PE3_RX_DN15 SOCKET4677_AZIF0045P001C01CS-SA    I12 @S9S_MB_2U_LIB.S9S_MB_2U(SCH_1):PAGE61
  J110   D1     D1 CONN112_10137002101LF-CONN112_A    I54 @S9S_MB_2U_LIB.S9S_MB_2U(SCH_1):PAGE318

P5E_CPU1_PE3_RX_DN<1> @S9S_MB_2U_LIB.S9S_MB_2U(SCH_1):P5E_CPU1_PE3_RX_DN(1)
    U1 ED91 PE3_RX_DN1 SOCKET4677_AZIF0045P001C01CS-SA    I12 @S9S_MB_2U_LIB.S9S_MB_2U(SCH_1):PAGE61
  J109   C7     C7 CONN112_10137002101LF-CONN112_A    I76 @S9S_MB_2U_LIB.S9S_MB_2U(SCH_1):PAGE319

P5E_CPU1_PE3_RX_DN<2> @S9S_MB_2U_LIB.S9S_MB_2U(SCH_1):P5E_CPU1_PE3_RX_DN(2)
    U1 EC90 PE3_RX_DN2 SOCKET4677_AZIF0045P001C01CS-SA    I12 @S9S_MB_2U_LIB.S9S_MB_2U(SCH_1):PAGE61
  J109   B6     B6 CONN112_10137002101LF-CONN112_A    I76 @S9S_MB_2U_LIB.S9S_MB_2U(SCH_1):PAGE319

P5E_CPU1_PE3_RX_DN<3> @S9S_MB_2U_LIB.S9S_MB_2U(SCH_1):P5E_CPU1_PE3_RX_DN(3)
    U1 DY91 PE3_RX_DN3 SOCKET4677_AZIF0045P001C01CS-SA    I12 @S9S_MB_2U_LIB.S9S_MB_2U(SCH_1):PAGE61
  J109   C5     C5 CONN112_10137002101LF-CONN112_A    I76 @S9S_MB_2U_LIB.S9S_MB_2U(SCH_1):PAGE319

P5E_CPU1_PE3_RX_DN<4> @S9S_MB_2U_LIB.S9S_MB_2U(SCH_1):P5E_CPU1_PE3_RX_DN(4)
    U1 DV89 PE3_RX_DN4 SOCKET4677_AZIF0045P001C01CS-SA    I12 @S9S_MB_2U_LIB.S9S_MB_2U(SCH_1):PAGE61
  J109   C4     C4 CONN112_10137002101LF-CONN112_A    I53 @S9S_MB_2U_LIB.S9S_MB_2U(SCH_1):PAGE319

P5E_CPU1_PE3_RX_DN<5> @S9S_MB_2U_LIB.S9S_MB_2U(SCH_1):P5E_CPU1_PE3_RX_DN(5)
    U1 DU90 PE3_RX_DN5 SOCKET4677_AZIF0045P001C01CS-SA    I12 @S9S_MB_2U_LIB.S9S_MB_2U(SCH_1):PAGE61
  J109   D3     D3 CONN112_10137002101LF-CONN112_A    I53 @S9S_MB_2U_LIB.S9S_MB_2U(SCH_1):PAGE319

P5E_CPU1_PE3_RX_DN<6> @S9S_MB_2U_LIB.S9S_MB_2U(SCH_1):P5E_CPU1_PE3_RX_DN(6)
    U1 DP89 PE3_RX_DN6 SOCKET4677_AZIF0045P001C01CS-SA    I12 @S9S_MB_2U_LIB.S9S_MB_2U(SCH_1):PAGE61
  J109   C2     C2 CONN112_10137002101LF-CONN112_A    I53 @S9S_MB_2U_LIB.S9S_MB_2U(SCH_1):PAGE319

P5E_CPU1_PE3_RX_DN<7> @S9S_MB_2U_LIB.S9S_MB_2U(SCH_1):P5E_CPU1_PE3_RX_DN(7)
    U1 DN90 PE3_RX_DN7 SOCKET4677_AZIF0045P001C01CS-SA    I12 @S9S_MB_2U_LIB.S9S_MB_2U(SCH_1):PAGE61
  J109   D1     D1 CONN112_10137002101LF-CONN112_A    I53 @S9S_MB_2U_LIB.S9S_MB_2U(SCH_1):PAGE319

P5E_CPU1_PE3_RX_DN<8> @S9S_MB_2U_LIB.S9S_MB_2U(SCH_1):P5E_CPU1_PE3_RX_DN(8)
    U1 DL90 PE3_RX_DN8 SOCKET4677_AZIF0045P001C01CS-SA    I12 @S9S_MB_2U_LIB.S9S_MB_2U(SCH_1):PAGE61
  J110   B8     B8 CONN112_10137002101LF-CONN112_A    I16 @S9S_MB_2U_LIB.S9S_MB_2U(SCH_1):PAGE318

P5E_CPU1_PE3_RX_DN<9> @S9S_MB_2U_LIB.S9S_MB_2U(SCH_1):P5E_CPU1_PE3_RX_DN(9)
    U1 DH91 PE3_RX_DN9 SOCKET4677_AZIF0045P001C01CS-SA    I12 @S9S_MB_2U_LIB.S9S_MB_2U(SCH_1):PAGE61
  J110   C7     C7 CONN112_10137002101LF-CONN112_A    I16 @S9S_MB_2U_LIB.S9S_MB_2U(SCH_1):PAGE318

P5E_CPU1_PE3_RX_DP<0> @S9S_MB_2U_LIB.S9S_MB_2U(SCH_1):P5E_CPU1_PE3_RX_DP(0)
    U1 EJ90 PE3_RX_DP0 SOCKET4677_AZIF0045P001C01CS-SA    I12 @S9S_MB_2U_LIB.S9S_MB_2U(SCH_1):PAGE61
  J109   B8     B8 CONN112_10137002101LF-CONN112_A    I76 @S9S_MB_2U_LIB.S9S_MB_2U(SCH_1):PAGE319

P5E_CPU1_PE3_RX_DP<10> @S9S_MB_2U_LIB.S9S_MB_2U(SCH_1):P5E_CPU1_PE3_RX_DP(10)
    U1 DF89 PE3_RX_DP10 SOCKET4677_AZIF0045P001C01CS-SA    I12 @S9S_MB_2U_LIB.S9S_MB_2U(SCH_1):PAGE61
  J110   C6     C6 CONN112_10137002101LF-CONN112_A    I16 @S9S_MB_2U_LIB.S9S_MB_2U(SCH_1):PAGE318

P5E_CPU1_PE3_RX_DP<11> @S9S_MB_2U_LIB.S9S_MB_2U(SCH_1):P5E_CPU1_PE3_RX_DP(11)
    U1 DE90 PE3_RX_DP11 SOCKET4677_AZIF0045P001C01CS-SA    I12 @S9S_MB_2U_LIB.S9S_MB_2U(SCH_1):PAGE61
  J110   D5     D5 CONN112_10137002101LF-CONN112_A    I16 @S9S_MB_2U_LIB.S9S_MB_2U(SCH_1):PAGE318

P5E_CPU1_PE3_RX_DP<12> @S9S_MB_2U_LIB.S9S_MB_2U(SCH_1):P5E_CPU1_PE3_RX_DP(12)
    U1 DC90 PE3_RX_DP12 SOCKET4677_AZIF0045P001C01CS-SA    I12 @S9S_MB_2U_LIB.S9S_MB_2U(SCH_1):PAGE61
  J110   B4     B4 CONN112_10137002101LF-CONN112_A    I54 @S9S_MB_2U_LIB.S9S_MB_2U(SCH_1):PAGE318

P5E_CPU1_PE3_RX_DP<13> @S9S_MB_2U_LIB.S9S_MB_2U(SCH_1):P5E_CPU1_PE3_RX_DP(13)
    U1 CY91 PE3_RX_DP13 SOCKET4677_AZIF0045P001C01CS-SA    I12 @S9S_MB_2U_LIB.S9S_MB_2U(SCH_1):PAGE61
  J110   C3     C3 CONN112_10137002101LF-CONN112_A    I54 @S9S_MB_2U_LIB.S9S_MB_2U(SCH_1):PAGE318

P5E_CPU1_PE3_RX_DP<14> @S9S_MB_2U_LIB.S9S_MB_2U(SCH_1):P5E_CPU1_PE3_RX_DP(14)
    U1 CW90 PE3_RX_DP14 SOCKET4677_AZIF0045P001C01CS-SA    I12 @S9S_MB_2U_LIB.S9S_MB_2U(SCH_1):PAGE61
  J110   B2     B2 CONN112_10137002101LF-CONN112_A    I54 @S9S_MB_2U_LIB.S9S_MB_2U(SCH_1):PAGE318

P5E_CPU1_PE3_RX_DP<15> @S9S_MB_2U_LIB.S9S_MB_2U(SCH_1):P5E_CPU1_PE3_RX_DP(15)
    U1 CT91 PE3_RX_DP15 SOCKET4677_AZIF0045P001C01CS-SA    I12 @S9S_MB_2U_LIB.S9S_MB_2U(SCH_1):PAGE61
  J110   C1     C1 CONN112_10137002101LF-CONN112_A    I54 @S9S_MB_2U_LIB.S9S_MB_2U(SCH_1):PAGE318

P5E_CPU1_PE3_RX_DP<1> @S9S_MB_2U_LIB.S9S_MB_2U(SCH_1):P5E_CPU1_PE3_RX_DP(1)
    U1 EE90 PE3_RX_DP1 SOCKET4677_AZIF0045P001C01CS-SA    I12 @S9S_MB_2U_LIB.S9S_MB_2U(SCH_1):PAGE61
  J109   D7     D7 CONN112_10137002101LF-CONN112_A    I76 @S9S_MB_2U_LIB.S9S_MB_2U(SCH_1):PAGE319

P5E_CPU1_PE3_RX_DP<2> @S9S_MB_2U_LIB.S9S_MB_2U(SCH_1):P5E_CPU1_PE3_RX_DP(2)
    U1 EB89 PE3_RX_DP2 SOCKET4677_AZIF0045P001C01CS-SA    I12 @S9S_MB_2U_LIB.S9S_MB_2U(SCH_1):PAGE61
  J109   C6     C6 CONN112_10137002101LF-CONN112_A    I76 @S9S_MB_2U_LIB.S9S_MB_2U(SCH_1):PAGE319

P5E_CPU1_PE3_RX_DP<3> @S9S_MB_2U_LIB.S9S_MB_2U(SCH_1):P5E_CPU1_PE3_RX_DP(3)
    U1 EA90 PE3_RX_DP3 SOCKET4677_AZIF0045P001C01CS-SA    I12 @S9S_MB_2U_LIB.S9S_MB_2U(SCH_1):PAGE61
  J109   D5     D5 CONN112_10137002101LF-CONN112_A    I76 @S9S_MB_2U_LIB.S9S_MB_2U(SCH_1):PAGE319

P5E_CPU1_PE3_RX_DP<4> @S9S_MB_2U_LIB.S9S_MB_2U(SCH_1):P5E_CPU1_PE3_RX_DP(4)
    U1 DW90 PE3_RX_DP4 SOCKET4677_AZIF0045P001C01CS-SA    I12 @S9S_MB_2U_LIB.S9S_MB_2U(SCH_1):PAGE61
  J109   B4     B4 CONN112_10137002101LF-CONN112_A    I53 @S9S_MB_2U_LIB.S9S_MB_2U(SCH_1):PAGE319

P5E_CPU1_PE3_RX_DP<5> @S9S_MB_2U_LIB.S9S_MB_2U(SCH_1):P5E_CPU1_PE3_RX_DP(5)
    U1 DT91 PE3_RX_DP5 SOCKET4677_AZIF0045P001C01CS-SA    I12 @S9S_MB_2U_LIB.S9S_MB_2U(SCH_1):PAGE61
  J109   C3     C3 CONN112_10137002101LF-CONN112_A    I53 @S9S_MB_2U_LIB.S9S_MB_2U(SCH_1):PAGE319

P5E_CPU1_PE3_RX_DP<6> @S9S_MB_2U_LIB.S9S_MB_2U(SCH_1):P5E_CPU1_PE3_RX_DP(6)
    U1 DR90 PE3_RX_DP6 SOCKET4677_AZIF0045P001C01CS-SA    I12 @S9S_MB_2U_LIB.S9S_MB_2U(SCH_1):PAGE61
  J109   B2     B2 CONN112_10137002101LF-CONN112_A    I53 @S9S_MB_2U_LIB.S9S_MB_2U(SCH_1):PAGE319

P5E_CPU1_PE3_RX_DP<7> @S9S_MB_2U_LIB.S9S_MB_2U(SCH_1):P5E_CPU1_PE3_RX_DP(7)
    U1 DM91 PE3_RX_DP7 SOCKET4677_AZIF0045P001C01CS-SA    I12 @S9S_MB_2U_LIB.S9S_MB_2U(SCH_1):PAGE61
  J109   C1     C1 CONN112_10137002101LF-CONN112_A    I53 @S9S_MB_2U_LIB.S9S_MB_2U(SCH_1):PAGE319

P5E_CPU1_PE3_RX_DP<8> @S9S_MB_2U_LIB.S9S_MB_2U(SCH_1):P5E_CPU1_PE3_RX_DP(8)
    U1 DK89 PE3_RX_DP8 SOCKET4677_AZIF0045P001C01CS-SA    I12 @S9S_MB_2U_LIB.S9S_MB_2U(SCH_1):PAGE61
  J110   C8     C8 CONN112_10137002101LF-CONN112_A    I16 @S9S_MB_2U_LIB.S9S_MB_2U(SCH_1):PAGE318

P5E_CPU1_PE3_RX_DP<9> @S9S_MB_2U_LIB.S9S_MB_2U(SCH_1):P5E_CPU1_PE3_RX_DP(9)
    U1 DJ90 PE3_RX_DP9 SOCKET4677_AZIF0045P001C01CS-SA    I12 @S9S_MB_2U_LIB.S9S_MB_2U(SCH_1):PAGE61
  J110   D7     D7 CONN112_10137002101LF-CONN112_A    I16 @S9S_MB_2U_LIB.S9S_MB_2U(SCH_1):PAGE318

P5E_CPU1_PE3_TX_C_DN<0> @S9S_MB_2U_LIB.S9S_MB_2U(SCH_1):P5E_CPU1_PE3_TX_C_DN(0)
 C1546    1      1 Q_CAP_DIFFBUS_C0201-DIFF BUS_0A   I230 @S9S_MB_2U_LIB.S9S_MB_2U(SCH_1):PAGE168
  J109   I8     I8 CONN112_10137002101LF-CONN112_A    I76 @S9S_MB_2U_LIB.S9S_MB_2U(SCH_1):PAGE319

P5E_CPU1_PE3_TX_C_DN<10> @S9S_MB_2U_LIB.S9S_MB_2U(SCH_1):P5E_CPU1_PE3_TX_C_DN(10)
 C1526    1      1 Q_CAP_DIFFBUS_C0201-DIFF BUS_0A   I282 @S9S_MB_2U_LIB.S9S_MB_2U(SCH_1):PAGE168
  J110   H6     H6 CONN112_10137002101LF-CONN112_A    I16 @S9S_MB_2U_LIB.S9S_MB_2U(SCH_1):PAGE318

P5E_CPU1_PE3_TX_C_DN<11> @S9S_MB_2U_LIB.S9S_MB_2U(SCH_1):P5E_CPU1_PE3_TX_C_DN(11)
 C1524    1      1 Q_CAP_DIFFBUS_C0201-DIFF BUS_0A   I284 @S9S_MB_2U_LIB.S9S_MB_2U(SCH_1):PAGE168
  J110   I5     I5 CONN112_10137002101LF-CONN112_A    I16 @S9S_MB_2U_LIB.S9S_MB_2U(SCH_1):PAGE318

P5E_CPU1_PE3_TX_C_DN<12> @S9S_MB_2U_LIB.S9S_MB_2U(SCH_1):P5E_CPU1_PE3_TX_C_DN(12)
 C1522    1      1 Q_CAP_DIFFBUS_C0201-DIFF BUS_0A   I286 @S9S_MB_2U_LIB.S9S_MB_2U(SCH_1):PAGE168
  J110   H4     H4 CONN112_10137002101LF-CONN112_A    I54 @S9S_MB_2U_LIB.S9S_MB_2U(SCH_1):PAGE318

P5E_CPU1_PE3_TX_C_DN<13> @S9S_MB_2U_LIB.S9S_MB_2U(SCH_1):P5E_CPU1_PE3_TX_C_DN(13)
 C1520    1      1 Q_CAP_DIFFBUS_C0201-DIFF BUS_0A   I297 @S9S_MB_2U_LIB.S9S_MB_2U(SCH_1):PAGE168
  J110   I3     I3 CONN112_10137002101LF-CONN112_A    I54 @S9S_MB_2U_LIB.S9S_MB_2U(SCH_1):PAGE318

P5E_CPU1_PE3_TX_C_DN<14> @S9S_MB_2U_LIB.S9S_MB_2U(SCH_1):P5E_CPU1_PE3_TX_C_DN(14)
 C1518    1      1 Q_CAP_DIFFBUS_C0201-DIFF BUS_0A   I300 @S9S_MB_2U_LIB.S9S_MB_2U(SCH_1):PAGE168
  J110   H2     H2 CONN112_10137002101LF-CONN112_A    I54 @S9S_MB_2U_LIB.S9S_MB_2U(SCH_1):PAGE318

P5E_CPU1_PE3_TX_C_DN<15> @S9S_MB_2U_LIB.S9S_MB_2U(SCH_1):P5E_CPU1_PE3_TX_C_DN(15)
 C1516    1      1 Q_CAP_DIFFBUS_C0201-DIFF BUS_0A   I302 @S9S_MB_2U_LIB.S9S_MB_2U(SCH_1):PAGE168
  J110   I1     I1 CONN112_10137002101LF-CONN112_A    I54 @S9S_MB_2U_LIB.S9S_MB_2U(SCH_1):PAGE318

P5E_CPU1_PE3_TX_C_DN<1> @S9S_MB_2U_LIB.S9S_MB_2U(SCH_1):P5E_CPU1_PE3_TX_C_DN(1)
 C1544    1      1 Q_CAP_DIFFBUS_C0201-DIFF BUS_0A   I232 @S9S_MB_2U_LIB.S9S_MB_2U(SCH_1):PAGE168
  J109   I7     I7 CONN112_10137002101LF-CONN112_A    I76 @S9S_MB_2U_LIB.S9S_MB_2U(SCH_1):PAGE319

P5E_CPU1_PE3_TX_C_DN<2> @S9S_MB_2U_LIB.S9S_MB_2U(SCH_1):P5E_CPU1_PE3_TX_C_DN(2)
 C1542    1      1 Q_CAP_DIFFBUS_C0201-DIFF BUS_0A   I233 @S9S_MB_2U_LIB.S9S_MB_2U(SCH_1):PAGE168
  J109   H6     H6 CONN112_10137002101LF-CONN112_A    I76 @S9S_MB_2U_LIB.S9S_MB_2U(SCH_1):PAGE319

P5E_CPU1_PE3_TX_C_DN<3> @S9S_MB_2U_LIB.S9S_MB_2U(SCH_1):P5E_CPU1_PE3_TX_C_DN(3)
 C1540    1      1 Q_CAP_DIFFBUS_C0201-DIFF BUS_0A   I236 @S9S_MB_2U_LIB.S9S_MB_2U(SCH_1):PAGE168
  J109   I5     I5 CONN112_10137002101LF-CONN112_A    I76 @S9S_MB_2U_LIB.S9S_MB_2U(SCH_1):PAGE319

P5E_CPU1_PE3_TX_C_DN<4> @S9S_MB_2U_LIB.S9S_MB_2U(SCH_1):P5E_CPU1_PE3_TX_C_DN(4)
 C1538    1      1 Q_CAP_DIFFBUS_C0201-DIFF BUS_0A   I238 @S9S_MB_2U_LIB.S9S_MB_2U(SCH_1):PAGE168
  J109   H4     H4 CONN112_10137002101LF-CONN112_A    I53 @S9S_MB_2U_LIB.S9S_MB_2U(SCH_1):PAGE319

P5E_CPU1_PE3_TX_C_DN<5> @S9S_MB_2U_LIB.S9S_MB_2U(SCH_1):P5E_CPU1_PE3_TX_C_DN(5)
 C1536    1      1 Q_CAP_DIFFBUS_C0201-DIFF BUS_0A   I250 @S9S_MB_2U_LIB.S9S_MB_2U(SCH_1):PAGE168
  J109   I3     I3 CONN112_10137002101LF-CONN112_A    I53 @S9S_MB_2U_LIB.S9S_MB_2U(SCH_1):PAGE319

P5E_CPU1_PE3_TX_C_DN<6> @S9S_MB_2U_LIB.S9S_MB_2U(SCH_1):P5E_CPU1_PE3_TX_C_DN(6)
 C1534    1      1 Q_CAP_DIFFBUS_C0201-DIFF BUS_0A   I251 @S9S_MB_2U_LIB.S9S_MB_2U(SCH_1):PAGE168
  J109   H2     H2 CONN112_10137002101LF-CONN112_A    I53 @S9S_MB_2U_LIB.S9S_MB_2U(SCH_1):PAGE319

P5E_CPU1_PE3_TX_C_DN<7> @S9S_MB_2U_LIB.S9S_MB_2U(SCH_1):P5E_CPU1_PE3_TX_C_DN(7)
 C1532    1      1 Q_CAP_DIFFBUS_C0201-DIFF BUS_0A   I254 @S9S_MB_2U_LIB.S9S_MB_2U(SCH_1):PAGE168
  J109   I1     I1 CONN112_10137002101LF-CONN112_A    I53 @S9S_MB_2U_LIB.S9S_MB_2U(SCH_1):PAGE319

P5E_CPU1_PE3_TX_C_DN<8> @S9S_MB_2U_LIB.S9S_MB_2U(SCH_1):P5E_CPU1_PE3_TX_C_DN(8)
 C1530    1      1 Q_CAP_DIFFBUS_C0201-DIFF BUS_0A   I277 @S9S_MB_2U_LIB.S9S_MB_2U(SCH_1):PAGE168
  J110   H8     H8 CONN112_10137002101LF-CONN112_A    I16 @S9S_MB_2U_LIB.S9S_MB_2U(SCH_1):PAGE318

P5E_CPU1_PE3_TX_C_DN<9> @S9S_MB_2U_LIB.S9S_MB_2U(SCH_1):P5E_CPU1_PE3_TX_C_DN(9)
 C1528    1      1 Q_CAP_DIFFBUS_C0201-DIFF BUS_0A   I280 @S9S_MB_2U_LIB.S9S_MB_2U(SCH_1):PAGE168
  J110   I7     I7 CONN112_10137002101LF-CONN112_A    I16 @S9S_MB_2U_LIB.S9S_MB_2U(SCH_1):PAGE318

P5E_CPU1_PE3_TX_C_DP<0> @S9S_MB_2U_LIB.S9S_MB_2U(SCH_1):P5E_CPU1_PE3_TX_C_DP(0)
 C1547    1      1 Q_CAP_DIFFBUS_C0201-DIFF BUS_0A   I229 @S9S_MB_2U_LIB.S9S_MB_2U(SCH_1):PAGE168
  J109   H8     H8 CONN112_10137002101LF-CONN112_A    I76 @S9S_MB_2U_LIB.S9S_MB_2U(SCH_1):PAGE319

P5E_CPU1_PE3_TX_C_DP<10> @S9S_MB_2U_LIB.S9S_MB_2U(SCH_1):P5E_CPU1_PE3_TX_C_DP(10)
 C1527    1      1 Q_CAP_DIFFBUS_C0201-DIFF BUS_0A   I281 @S9S_MB_2U_LIB.S9S_MB_2U(SCH_1):PAGE168
  J110   I6     I6 CONN112_10137002101LF-CONN112_A    I16 @S9S_MB_2U_LIB.S9S_MB_2U(SCH_1):PAGE318

P5E_CPU1_PE3_TX_C_DP<11> @S9S_MB_2U_LIB.S9S_MB_2U(SCH_1):P5E_CPU1_PE3_TX_C_DP(11)
 C1525    1      1 Q_CAP_DIFFBUS_C0201-DIFF BUS_0A   I283 @S9S_MB_2U_LIB.S9S_MB_2U(SCH_1):PAGE168
  J110   J5     J5 CONN112_10137002101LF-CONN112_A    I16 @S9S_MB_2U_LIB.S9S_MB_2U(SCH_1):PAGE318

P5E_CPU1_PE3_TX_C_DP<12> @S9S_MB_2U_LIB.S9S_MB_2U(SCH_1):P5E_CPU1_PE3_TX_C_DP(12)
 C1523    1      1 Q_CAP_DIFFBUS_C0201-DIFF BUS_0A   I285 @S9S_MB_2U_LIB.S9S_MB_2U(SCH_1):PAGE168
  J110   I4     I4 CONN112_10137002101LF-CONN112_A    I54 @S9S_MB_2U_LIB.S9S_MB_2U(SCH_1):PAGE318

P5E_CPU1_PE3_TX_C_DP<13> @S9S_MB_2U_LIB.S9S_MB_2U(SCH_1):P5E_CPU1_PE3_TX_C_DP(13)
 C1521    1      1 Q_CAP_DIFFBUS_C0201-DIFF BUS_0A   I298 @S9S_MB_2U_LIB.S9S_MB_2U(SCH_1):PAGE168
  J110   J3     J3 CONN112_10137002101LF-CONN112_A    I54 @S9S_MB_2U_LIB.S9S_MB_2U(SCH_1):PAGE318

P5E_CPU1_PE3_TX_C_DP<14> @S9S_MB_2U_LIB.S9S_MB_2U(SCH_1):P5E_CPU1_PE3_TX_C_DP(14)
 C1519    1      1 Q_CAP_DIFFBUS_C0201-DIFF BUS_0A   I299 @S9S_MB_2U_LIB.S9S_MB_2U(SCH_1):PAGE168
  J110   I2     I2 CONN112_10137002101LF-CONN112_A    I54 @S9S_MB_2U_LIB.S9S_MB_2U(SCH_1):PAGE318

P5E_CPU1_PE3_TX_C_DP<15> @S9S_MB_2U_LIB.S9S_MB_2U(SCH_1):P5E_CPU1_PE3_TX_C_DP(15)
 C1517    1      1 Q_CAP_DIFFBUS_C0201-DIFF BUS_0A   I301 @S9S_MB_2U_LIB.S9S_MB_2U(SCH_1):PAGE168
  J110   J1     J1 CONN112_10137002101LF-CONN112_A    I54 @S9S_MB_2U_LIB.S9S_MB_2U(SCH_1):PAGE318

P5E_CPU1_PE3_TX_C_DP<1> @S9S_MB_2U_LIB.S9S_MB_2U(SCH_1):P5E_CPU1_PE3_TX_C_DP(1)
 C1545    1      1 Q_CAP_DIFFBUS_C0201-DIFF BUS_0A   I231 @S9S_MB_2U_LIB.S9S_MB_2U(SCH_1):PAGE168
  J109   J7     J7 CONN112_10137002101LF-CONN112_A    I76 @S9S_MB_2U_LIB.S9S_MB_2U(SCH_1):PAGE319

P5E_CPU1_PE3_TX_C_DP<2> @S9S_MB_2U_LIB.S9S_MB_2U(SCH_1):P5E_CPU1_PE3_TX_C_DP(2)
 C1543    1      1 Q_CAP_DIFFBUS_C0201-DIFF BUS_0A   I234 @S9S_MB_2U_LIB.S9S_MB_2U(SCH_1):PAGE168
  J109   I6     I6 CONN112_10137002101LF-CONN112_A    I76 @S9S_MB_2U_LIB.S9S_MB_2U(SCH_1):PAGE319

P5E_CPU1_PE3_TX_C_DP<3> @S9S_MB_2U_LIB.S9S_MB_2U(SCH_1):P5E_CPU1_PE3_TX_C_DP(3)
 C1541    1      1 Q_CAP_DIFFBUS_C0201-DIFF BUS_0A   I235 @S9S_MB_2U_LIB.S9S_MB_2U(SCH_1):PAGE168
  J109   J5     J5 CONN112_10137002101LF-CONN112_A    I76 @S9S_MB_2U_LIB.S9S_MB_2U(SCH_1):PAGE319

P5E_CPU1_PE3_TX_C_DP<4> @S9S_MB_2U_LIB.S9S_MB_2U(SCH_1):P5E_CPU1_PE3_TX_C_DP(4)
 C1539    1      1 Q_CAP_DIFFBUS_C0201-DIFF BUS_0A   I237 @S9S_MB_2U_LIB.S9S_MB_2U(SCH_1):PAGE168
  J109   I4     I4 CONN112_10137002101LF-CONN112_A    I53 @S9S_MB_2U_LIB.S9S_MB_2U(SCH_1):PAGE319

P5E_CPU1_PE3_TX_C_DP<5> @S9S_MB_2U_LIB.S9S_MB_2U(SCH_1):P5E_CPU1_PE3_TX_C_DP(5)
 C1537    1      1 Q_CAP_DIFFBUS_C0201-DIFF BUS_0A   I249 @S9S_MB_2U_LIB.S9S_MB_2U(SCH_1):PAGE168
  J109   J3     J3 CONN112_10137002101LF-CONN112_A    I53 @S9S_MB_2U_LIB.S9S_MB_2U(SCH_1):PAGE319

P5E_CPU1_PE3_TX_C_DP<6> @S9S_MB_2U_LIB.S9S_MB_2U(SCH_1):P5E_CPU1_PE3_TX_C_DP(6)
 C1535    1      1 Q_CAP_DIFFBUS_C0201-DIFF BUS_0A   I252 @S9S_MB_2U_LIB.S9S_MB_2U(SCH_1):PAGE168
  J109   I2     I2 CONN112_10137002101LF-CONN112_A    I53 @S9S_MB_2U_LIB.S9S_MB_2U(SCH_1):PAGE319

P5E_CPU1_PE3_TX_C_DP<7> @S9S_MB_2U_LIB.S9S_MB_2U(SCH_1):P5E_CPU1_PE3_TX_C_DP(7)
 C1533    1      1 Q_CAP_DIFFBUS_C0201-DIFF BUS_0A   I253 @S9S_MB_2U_LIB.S9S_MB_2U(SCH_1):PAGE168
  J109   J1     J1 CONN112_10137002101LF-CONN112_A    I53 @S9S_MB_2U_LIB.S9S_MB_2U(SCH_1):PAGE319

P5E_CPU1_PE3_TX_C_DP<8> @S9S_MB_2U_LIB.S9S_MB_2U(SCH_1):P5E_CPU1_PE3_TX_C_DP(8)
 C1531    1      1 Q_CAP_DIFFBUS_C0201-DIFF BUS_0A   I278 @S9S_MB_2U_LIB.S9S_MB_2U(SCH_1):PAGE168
  J110   I8     I8 CONN112_10137002101LF-CONN112_A    I16 @S9S_MB_2U_LIB.S9S_MB_2U(SCH_1):PAGE318

P5E_CPU1_PE3_TX_C_DP<9> @S9S_MB_2U_LIB.S9S_MB_2U(SCH_1):P5E_CPU1_PE3_TX_C_DP(9)
 C1529    1      1 Q_CAP_DIFFBUS_C0201-DIFF BUS_0A   I279 @S9S_MB_2U_LIB.S9S_MB_2U(SCH_1):PAGE168
  J110   J7     J7 CONN112_10137002101LF-CONN112_A    I16 @S9S_MB_2U_LIB.S9S_MB_2U(SCH_1):PAGE318

P5E_CPU1_PE3_TX_DN<0> @S9S_MB_2U_LIB.S9S_MB_2U(SCH_1):P5E_CPU1_PE3_TX_DN(0)
    U1 EE86 PE3_TX_DN0 SOCKET4677_AZIF0045P001C01CS-SA    I12 @S9S_MB_2U_LIB.S9S_MB_2U(SCH_1):PAGE61
 C1546    2      2 Q_CAP_DIFFBUS_C0201-DIFF BUS_0A   I230 @S9S_MB_2U_LIB.S9S_MB_2U(SCH_1):PAGE168

P5E_CPU1_PE3_TX_DN<10> @S9S_MB_2U_LIB.S9S_MB_2U(SCH_1):P5E_CPU1_PE3_TX_DN(10)
    U1 DD87 PE3_TX_DN10 SOCKET4677_AZIF0045P001C01CS-SA    I12 @S9S_MB_2U_LIB.S9S_MB_2U(SCH_1):PAGE61
 C1526    2      2 Q_CAP_DIFFBUS_C0201-DIFF BUS_0A   I282 @S9S_MB_2U_LIB.S9S_MB_2U(SCH_1):PAGE168

P5E_CPU1_PE3_TX_DN<11> @S9S_MB_2U_LIB.S9S_MB_2U(SCH_1):P5E_CPU1_PE3_TX_DN(11)
    U1 DB85 PE3_TX_DN11 SOCKET4677_AZIF0045P001C01CS-SA    I12 @S9S_MB_2U_LIB.S9S_MB_2U(SCH_1):PAGE61
 C1524    2      2 Q_CAP_DIFFBUS_C0201-DIFF BUS_0A   I284 @S9S_MB_2U_LIB.S9S_MB_2U(SCH_1):PAGE168

P5E_CPU1_PE3_TX_DN<12> @S9S_MB_2U_LIB.S9S_MB_2U(SCH_1):P5E_CPU1_PE3_TX_DN(12)
    U1 CY87 PE3_TX_DN12 SOCKET4677_AZIF0045P001C01CS-SA    I12 @S9S_MB_2U_LIB.S9S_MB_2U(SCH_1):PAGE61
 C1522    2      2 Q_CAP_DIFFBUS_C0201-DIFF BUS_0A   I286 @S9S_MB_2U_LIB.S9S_MB_2U(SCH_1):PAGE168

P5E_CPU1_PE3_TX_DN<13> @S9S_MB_2U_LIB.S9S_MB_2U(SCH_1):P5E_CPU1_PE3_TX_DN(13)
    U1 CV85 PE3_TX_DN13 SOCKET4677_AZIF0045P001C01CS-SA    I12 @S9S_MB_2U_LIB.S9S_MB_2U(SCH_1):PAGE61
 C1520    2      2 Q_CAP_DIFFBUS_C0201-DIFF BUS_0A   I297 @S9S_MB_2U_LIB.S9S_MB_2U(SCH_1):PAGE168

P5E_CPU1_PE3_TX_DN<14> @S9S_MB_2U_LIB.S9S_MB_2U(SCH_1):P5E_CPU1_PE3_TX_DN(14)
    U1 CT87 PE3_TX_DN14 SOCKET4677_AZIF0045P001C01CS-SA    I12 @S9S_MB_2U_LIB.S9S_MB_2U(SCH_1):PAGE61
 C1518    2      2 Q_CAP_DIFFBUS_C0201-DIFF BUS_0A   I300 @S9S_MB_2U_LIB.S9S_MB_2U(SCH_1):PAGE168

P5E_CPU1_PE3_TX_DN<15> @S9S_MB_2U_LIB.S9S_MB_2U(SCH_1):P5E_CPU1_PE3_TX_DN(15)
    U1 CP85 PE3_TX_DN15 SOCKET4677_AZIF0045P001C01CS-SA    I12 @S9S_MB_2U_LIB.S9S_MB_2U(SCH_1):PAGE61
 C1516    2      2 Q_CAP_DIFFBUS_C0201-DIFF BUS_0A   I302 @S9S_MB_2U_LIB.S9S_MB_2U(SCH_1):PAGE168

P5E_CPU1_PE3_TX_DN<1> @S9S_MB_2U_LIB.S9S_MB_2U(SCH_1):P5E_CPU1_PE3_TX_DN(1)
    U1 EB85 PE3_TX_DN1 SOCKET4677_AZIF0045P001C01CS-SA    I12 @S9S_MB_2U_LIB.S9S_MB_2U(SCH_1):PAGE61
 C1544    2      2 Q_CAP_DIFFBUS_C0201-DIFF BUS_0A   I232 @S9S_MB_2U_LIB.S9S_MB_2U(SCH_1):PAGE168

P5E_CPU1_PE3_TX_DN<2> @S9S_MB_2U_LIB.S9S_MB_2U(SCH_1):P5E_CPU1_PE3_TX_DN(2)
    U1 DY87 PE3_TX_DN2 SOCKET4677_AZIF0045P001C01CS-SA    I12 @S9S_MB_2U_LIB.S9S_MB_2U(SCH_1):PAGE61
 C1542    2      2 Q_CAP_DIFFBUS_C0201-DIFF BUS_0A   I233 @S9S_MB_2U_LIB.S9S_MB_2U(SCH_1):PAGE168

P5E_CPU1_PE3_TX_DN<3> @S9S_MB_2U_LIB.S9S_MB_2U(SCH_1):P5E_CPU1_PE3_TX_DN(3)
    U1 DV85 PE3_TX_DN3 SOCKET4677_AZIF0045P001C01CS-SA    I12 @S9S_MB_2U_LIB.S9S_MB_2U(SCH_1):PAGE61
 C1540    2      2 Q_CAP_DIFFBUS_C0201-DIFF BUS_0A   I236 @S9S_MB_2U_LIB.S9S_MB_2U(SCH_1):PAGE168

P5E_CPU1_PE3_TX_DN<4> @S9S_MB_2U_LIB.S9S_MB_2U(SCH_1):P5E_CPU1_PE3_TX_DN(4)
    U1 DT87 PE3_TX_DN4 SOCKET4677_AZIF0045P001C01CS-SA    I12 @S9S_MB_2U_LIB.S9S_MB_2U(SCH_1):PAGE61
 C1538    2      2 Q_CAP_DIFFBUS_C0201-DIFF BUS_0A   I238 @S9S_MB_2U_LIB.S9S_MB_2U(SCH_1):PAGE168

P5E_CPU1_PE3_TX_DN<5> @S9S_MB_2U_LIB.S9S_MB_2U(SCH_1):P5E_CPU1_PE3_TX_DN(5)
    U1 DP85 PE3_TX_DN5 SOCKET4677_AZIF0045P001C01CS-SA    I12 @S9S_MB_2U_LIB.S9S_MB_2U(SCH_1):PAGE61
 C1536    2      2 Q_CAP_DIFFBUS_C0201-DIFF BUS_0A   I250 @S9S_MB_2U_LIB.S9S_MB_2U(SCH_1):PAGE168

P5E_CPU1_PE3_TX_DN<6> @S9S_MB_2U_LIB.S9S_MB_2U(SCH_1):P5E_CPU1_PE3_TX_DN(6)
    U1 DM87 PE3_TX_DN6 SOCKET4677_AZIF0045P001C01CS-SA    I12 @S9S_MB_2U_LIB.S9S_MB_2U(SCH_1):PAGE61
 C1534    2      2 Q_CAP_DIFFBUS_C0201-DIFF BUS_0A   I251 @S9S_MB_2U_LIB.S9S_MB_2U(SCH_1):PAGE168

P5E_CPU1_PE3_TX_DN<7> @S9S_MB_2U_LIB.S9S_MB_2U(SCH_1):P5E_CPU1_PE3_TX_DN(7)
    U1 DK85 PE3_TX_DN7 SOCKET4677_AZIF0045P001C01CS-SA    I12 @S9S_MB_2U_LIB.S9S_MB_2U(SCH_1):PAGE61
 C1532    2      2 Q_CAP_DIFFBUS_C0201-DIFF BUS_0A   I254 @S9S_MB_2U_LIB.S9S_MB_2U(SCH_1):PAGE168

P5E_CPU1_PE3_TX_DN<8> @S9S_MB_2U_LIB.S9S_MB_2U(SCH_1):P5E_CPU1_PE3_TX_DN(8)
    U1 DH87 PE3_TX_DN8 SOCKET4677_AZIF0045P001C01CS-SA    I12 @S9S_MB_2U_LIB.S9S_MB_2U(SCH_1):PAGE61
 C1530    2      2 Q_CAP_DIFFBUS_C0201-DIFF BUS_0A   I277 @S9S_MB_2U_LIB.S9S_MB_2U(SCH_1):PAGE168

P5E_CPU1_PE3_TX_DN<9> @S9S_MB_2U_LIB.S9S_MB_2U(SCH_1):P5E_CPU1_PE3_TX_DN(9)
    U1 DF85 PE3_TX_DN9 SOCKET4677_AZIF0045P001C01CS-SA    I12 @S9S_MB_2U_LIB.S9S_MB_2U(SCH_1):PAGE61
 C1528    2      2 Q_CAP_DIFFBUS_C0201-DIFF BUS_0A   I280 @S9S_MB_2U_LIB.S9S_MB_2U(SCH_1):PAGE168

P5E_CPU1_PE3_TX_DP<0> @S9S_MB_2U_LIB.S9S_MB_2U(SCH_1):P5E_CPU1_PE3_TX_DP(0)
    U1 ED87 PE3_TX_DP0 SOCKET4677_AZIF0045P001C01CS-SA    I12 @S9S_MB_2U_LIB.S9S_MB_2U(SCH_1):PAGE61
 C1547    2      2 Q_CAP_DIFFBUS_C0201-DIFF BUS_0A   I229 @S9S_MB_2U_LIB.S9S_MB_2U(SCH_1):PAGE168

P5E_CPU1_PE3_TX_DP<10> @S9S_MB_2U_LIB.S9S_MB_2U(SCH_1):P5E_CPU1_PE3_TX_DP(10)
    U1 DE86 PE3_TX_DP10 SOCKET4677_AZIF0045P001C01CS-SA    I12 @S9S_MB_2U_LIB.S9S_MB_2U(SCH_1):PAGE61
 C1527    2      2 Q_CAP_DIFFBUS_C0201-DIFF BUS_0A   I281 @S9S_MB_2U_LIB.S9S_MB_2U(SCH_1):PAGE168

P5E_CPU1_PE3_TX_DP<11> @S9S_MB_2U_LIB.S9S_MB_2U(SCH_1):P5E_CPU1_PE3_TX_DP(11)
    U1 DC86 PE3_TX_DP11 SOCKET4677_AZIF0045P001C01CS-SA    I12 @S9S_MB_2U_LIB.S9S_MB_2U(SCH_1):PAGE61
 C1525    2      2 Q_CAP_DIFFBUS_C0201-DIFF BUS_0A   I283 @S9S_MB_2U_LIB.S9S_MB_2U(SCH_1):PAGE168

P5E_CPU1_PE3_TX_DP<12> @S9S_MB_2U_LIB.S9S_MB_2U(SCH_1):P5E_CPU1_PE3_TX_DP(12)
    U1 DA86 PE3_TX_DP12 SOCKET4677_AZIF0045P001C01CS-SA    I12 @S9S_MB_2U_LIB.S9S_MB_2U(SCH_1):PAGE61
 C1523    2      2 Q_CAP_DIFFBUS_C0201-DIFF BUS_0A   I285 @S9S_MB_2U_LIB.S9S_MB_2U(SCH_1):PAGE168

P5E_CPU1_PE3_TX_DP<13> @S9S_MB_2U_LIB.S9S_MB_2U(SCH_1):P5E_CPU1_PE3_TX_DP(13)
    U1 CW86 PE3_TX_DP13 SOCKET4677_AZIF0045P001C01CS-SA    I12 @S9S_MB_2U_LIB.S9S_MB_2U(SCH_1):PAGE61
 C1521    2      2 Q_CAP_DIFFBUS_C0201-DIFF BUS_0A   I298 @S9S_MB_2U_LIB.S9S_MB_2U(SCH_1):PAGE168

P5E_CPU1_PE3_TX_DP<14> @S9S_MB_2U_LIB.S9S_MB_2U(SCH_1):P5E_CPU1_PE3_TX_DP(14)
    U1 CU86 PE3_TX_DP14 SOCKET4677_AZIF0045P001C01CS-SA    I12 @S9S_MB_2U_LIB.S9S_MB_2U(SCH_1):PAGE61
 C1519    2      2 Q_CAP_DIFFBUS_C0201-DIFF BUS_0A   I299 @S9S_MB_2U_LIB.S9S_MB_2U(SCH_1):PAGE168

P5E_CPU1_PE3_TX_DP<15> @S9S_MB_2U_LIB.S9S_MB_2U(SCH_1):P5E_CPU1_PE3_TX_DP(15)
    U1 CR86 PE3_TX_DP15 SOCKET4677_AZIF0045P001C01CS-SA    I12 @S9S_MB_2U_LIB.S9S_MB_2U(SCH_1):PAGE61
 C1517    2      2 Q_CAP_DIFFBUS_C0201-DIFF BUS_0A   I301 @S9S_MB_2U_LIB.S9S_MB_2U(SCH_1):PAGE168

P5E_CPU1_PE3_TX_DP<1> @S9S_MB_2U_LIB.S9S_MB_2U(SCH_1):P5E_CPU1_PE3_TX_DP(1)
    U1 EC86 PE3_TX_DP1 SOCKET4677_AZIF0045P001C01CS-SA    I12 @S9S_MB_2U_LIB.S9S_MB_2U(SCH_1):PAGE61
 C1545    2      2 Q_CAP_DIFFBUS_C0201-DIFF BUS_0A   I231 @S9S_MB_2U_LIB.S9S_MB_2U(SCH_1):PAGE168

P5E_CPU1_PE3_TX_DP<2> @S9S_MB_2U_LIB.S9S_MB_2U(SCH_1):P5E_CPU1_PE3_TX_DP(2)
    U1 EA86 PE3_TX_DP2 SOCKET4677_AZIF0045P001C01CS-SA    I12 @S9S_MB_2U_LIB.S9S_MB_2U(SCH_1):PAGE61
 C1543    2      2 Q_CAP_DIFFBUS_C0201-DIFF BUS_0A   I234 @S9S_MB_2U_LIB.S9S_MB_2U(SCH_1):PAGE168

P5E_CPU1_PE3_TX_DP<3> @S9S_MB_2U_LIB.S9S_MB_2U(SCH_1):P5E_CPU1_PE3_TX_DP(3)
    U1 DW86 PE3_TX_DP3 SOCKET4677_AZIF0045P001C01CS-SA    I12 @S9S_MB_2U_LIB.S9S_MB_2U(SCH_1):PAGE61
 C1541    2      2 Q_CAP_DIFFBUS_C0201-DIFF BUS_0A   I235 @S9S_MB_2U_LIB.S9S_MB_2U(SCH_1):PAGE168

P5E_CPU1_PE3_TX_DP<4> @S9S_MB_2U_LIB.S9S_MB_2U(SCH_1):P5E_CPU1_PE3_TX_DP(4)
    U1 DU86 PE3_TX_DP4 SOCKET4677_AZIF0045P001C01CS-SA    I12 @S9S_MB_2U_LIB.S9S_MB_2U(SCH_1):PAGE61
 C1539    2      2 Q_CAP_DIFFBUS_C0201-DIFF BUS_0A   I237 @S9S_MB_2U_LIB.S9S_MB_2U(SCH_1):PAGE168

P5E_CPU1_PE3_TX_DP<5> @S9S_MB_2U_LIB.S9S_MB_2U(SCH_1):P5E_CPU1_PE3_TX_DP(5)
    U1 DR86 PE3_TX_DP5 SOCKET4677_AZIF0045P001C01CS-SA    I12 @S9S_MB_2U_LIB.S9S_MB_2U(SCH_1):PAGE61
 C1537    2      2 Q_CAP_DIFFBUS_C0201-DIFF BUS_0A   I249 @S9S_MB_2U_LIB.S9S_MB_2U(SCH_1):PAGE168

P5E_CPU1_PE3_TX_DP<6> @S9S_MB_2U_LIB.S9S_MB_2U(SCH_1):P5E_CPU1_PE3_TX_DP(6)
    U1 DN86 PE3_TX_DP6 SOCKET4677_AZIF0045P001C01CS-SA    I12 @S9S_MB_2U_LIB.S9S_MB_2U(SCH_1):PAGE61
 C1535    2      2 Q_CAP_DIFFBUS_C0201-DIFF BUS_0A   I252 @S9S_MB_2U_LIB.S9S_MB_2U(SCH_1):PAGE168

P5E_CPU1_PE3_TX_DP<7> @S9S_MB_2U_LIB.S9S_MB_2U(SCH_1):P5E_CPU1_PE3_TX_DP(7)
    U1 DL86 PE3_TX_DP7 SOCKET4677_AZIF0045P001C01CS-SA    I12 @S9S_MB_2U_LIB.S9S_MB_2U(SCH_1):PAGE61
 C1533    2      2 Q_CAP_DIFFBUS_C0201-DIFF BUS_0A   I253 @S9S_MB_2U_LIB.S9S_MB_2U(SCH_1):PAGE168

P5E_CPU1_PE3_TX_DP<8> @S9S_MB_2U_LIB.S9S_MB_2U(SCH_1):P5E_CPU1_PE3_TX_DP(8)
    U1 DJ86 PE3_TX_DP8 SOCKET4677_AZIF0045P001C01CS-SA    I12 @S9S_MB_2U_LIB.S9S_MB_2U(SCH_1):PAGE61
 C1531    2      2 Q_CAP_DIFFBUS_C0201-DIFF BUS_0A   I278 @S9S_MB_2U_LIB.S9S_MB_2U(SCH_1):PAGE168

P5E_CPU1_PE3_TX_DP<9> @S9S_MB_2U_LIB.S9S_MB_2U(SCH_1):P5E_CPU1_PE3_TX_DP(9)
    U1 DG86 PE3_TX_DP9 SOCKET4677_AZIF0045P001C01CS-SA    I12 @S9S_MB_2U_LIB.S9S_MB_2U(SCH_1):PAGE61
 C1529    2      2 Q_CAP_DIFFBUS_C0201-DIFF BUS_0A   I279 @S9S_MB_2U_LIB.S9S_MB_2U(SCH_1):PAGE168

P5E_CPU1_PE4_RX_DN<0> @S9S_MB_2U_LIB.S9S_MB_2U(SCH_1):P5E_CPU1_PE4_RX_DN(0)
    U1  J90 PE4_RX_DN0 SOCKET4677_AZIF0045P001C01CS-SA    I18 @S9S_MB_2U_LIB.S9S_MB_2U(SCH_1):PAGE62
  J112   F1     F1 CONN160_10131762101LF-CONN160_A    I76 @S9S_MB_2U_LIB.S9S_MB_2U(SCH_1):PAGE149

P5E_CPU1_PE4_RX_DN<10> @S9S_MB_2U_LIB.S9S_MB_2U(SCH_1):P5E_CPU1_PE4_RX_DN(10)
    U1 AM91 PE4_RX_DN10 SOCKET4677_AZIF0045P001C01CS-SA    I18 @S9S_MB_2U_LIB.S9S_MB_2U(SCH_1):PAGE62
  J111   F3     F3 CONN112_10137002101LF-CONN112_A    I75 @S9S_MB_2U_LIB.S9S_MB_2U(SCH_1):PAGE148

P5E_CPU1_PE4_RX_DN<11> @S9S_MB_2U_LIB.S9S_MB_2U(SCH_1):P5E_CPU1_PE4_RX_DN(11)
    U1 AP89 PE4_RX_DN11 SOCKET4677_AZIF0045P001C01CS-SA    I18 @S9S_MB_2U_LIB.S9S_MB_2U(SCH_1):PAGE62
  J111   F4     F4 CONN112_10137002101LF-CONN112_A    I75 @S9S_MB_2U_LIB.S9S_MB_2U(SCH_1):PAGE148

P5E_CPU1_PE4_RX_DN<12> @S9S_MB_2U_LIB.S9S_MB_2U(SCH_1):P5E_CPU1_PE4_RX_DN(12)
    U1 AT91 PE4_RX_DN12 SOCKET4677_AZIF0045P001C01CS-SA    I18 @S9S_MB_2U_LIB.S9S_MB_2U(SCH_1):PAGE62
  J111   F5     F5 CONN112_10137002101LF-CONN112_A    I74 @S9S_MB_2U_LIB.S9S_MB_2U(SCH_1):PAGE148

P5E_CPU1_PE4_RX_DN<13> @S9S_MB_2U_LIB.S9S_MB_2U(SCH_1):P5E_CPU1_PE4_RX_DN(13)
    U1 AV89 PE4_RX_DN13 SOCKET4677_AZIF0045P001C01CS-SA    I18 @S9S_MB_2U_LIB.S9S_MB_2U(SCH_1):PAGE62
  J111   F6     F6 CONN112_10137002101LF-CONN112_A    I74 @S9S_MB_2U_LIB.S9S_MB_2U(SCH_1):PAGE148

P5E_CPU1_PE4_RX_DN<14> @S9S_MB_2U_LIB.S9S_MB_2U(SCH_1):P5E_CPU1_PE4_RX_DN(14)
    U1 AY91 PE4_RX_DN14 SOCKET4677_AZIF0045P001C01CS-SA    I18 @S9S_MB_2U_LIB.S9S_MB_2U(SCH_1):PAGE62
  J111   F7     F7 CONN112_10137002101LF-CONN112_A    I74 @S9S_MB_2U_LIB.S9S_MB_2U(SCH_1):PAGE148

P5E_CPU1_PE4_RX_DN<15> @S9S_MB_2U_LIB.S9S_MB_2U(SCH_1):P5E_CPU1_PE4_RX_DN(15)
    U1 BB89 PE4_RX_DN15 SOCKET4677_AZIF0045P001C01CS-SA    I18 @S9S_MB_2U_LIB.S9S_MB_2U(SCH_1):PAGE62
  J111   F8     F8 CONN112_10137002101LF-CONN112_A    I74 @S9S_MB_2U_LIB.S9S_MB_2U(SCH_1):PAGE148

P5E_CPU1_PE4_RX_DN<1> @S9S_MB_2U_LIB.S9S_MB_2U(SCH_1):P5E_CPU1_PE4_RX_DN(1)
    U1  P89 PE4_RX_DN1 SOCKET4677_AZIF0045P001C01CS-SA    I18 @S9S_MB_2U_LIB.S9S_MB_2U(SCH_1):PAGE62
  J112   F2     F2 CONN160_10131762101LF-CONN160_A    I76 @S9S_MB_2U_LIB.S9S_MB_2U(SCH_1):PAGE149

P5E_CPU1_PE4_RX_DN<2> @S9S_MB_2U_LIB.S9S_MB_2U(SCH_1):P5E_CPU1_PE4_RX_DN(2)
    U1  T91 PE4_RX_DN2 SOCKET4677_AZIF0045P001C01CS-SA    I18 @S9S_MB_2U_LIB.S9S_MB_2U(SCH_1):PAGE62
  J112   F3     F3 CONN160_10131762101LF-CONN160_A    I76 @S9S_MB_2U_LIB.S9S_MB_2U(SCH_1):PAGE149

P5E_CPU1_PE4_RX_DN<3> @S9S_MB_2U_LIB.S9S_MB_2U(SCH_1):P5E_CPU1_PE4_RX_DN(3)
    U1  V89 PE4_RX_DN3 SOCKET4677_AZIF0045P001C01CS-SA    I18 @S9S_MB_2U_LIB.S9S_MB_2U(SCH_1):PAGE62
  J112   F4     F4 CONN160_10131762101LF-CONN160_A    I76 @S9S_MB_2U_LIB.S9S_MB_2U(SCH_1):PAGE149

P5E_CPU1_PE4_RX_DN<4> @S9S_MB_2U_LIB.S9S_MB_2U(SCH_1):P5E_CPU1_PE4_RX_DN(4)
    U1  Y91 PE4_RX_DN4 SOCKET4677_AZIF0045P001C01CS-SA    I18 @S9S_MB_2U_LIB.S9S_MB_2U(SCH_1):PAGE62
  J112   F5     F5 CONN160_10131762101LF-CONN160_A    I75 @S9S_MB_2U_LIB.S9S_MB_2U(SCH_1):PAGE149

P5E_CPU1_PE4_RX_DN<5> @S9S_MB_2U_LIB.S9S_MB_2U(SCH_1):P5E_CPU1_PE4_RX_DN(5)
    U1 AB89 PE4_RX_DN5 SOCKET4677_AZIF0045P001C01CS-SA    I18 @S9S_MB_2U_LIB.S9S_MB_2U(SCH_1):PAGE62
  J112   F6     F6 CONN160_10131762101LF-CONN160_A    I75 @S9S_MB_2U_LIB.S9S_MB_2U(SCH_1):PAGE149

P5E_CPU1_PE4_RX_DN<6> @S9S_MB_2U_LIB.S9S_MB_2U(SCH_1):P5E_CPU1_PE4_RX_DN(6)
    U1 AD91 PE4_RX_DN6 SOCKET4677_AZIF0045P001C01CS-SA    I18 @S9S_MB_2U_LIB.S9S_MB_2U(SCH_1):PAGE62
  J112   F7     F7 CONN160_10131762101LF-CONN160_A    I75 @S9S_MB_2U_LIB.S9S_MB_2U(SCH_1):PAGE149

P5E_CPU1_PE4_RX_DN<7> @S9S_MB_2U_LIB.S9S_MB_2U(SCH_1):P5E_CPU1_PE4_RX_DN(7)
    U1 AF89 PE4_RX_DN7 SOCKET4677_AZIF0045P001C01CS-SA    I18 @S9S_MB_2U_LIB.S9S_MB_2U(SCH_1):PAGE62
  J112   F8     F8 CONN160_10131762101LF-CONN160_A    I75 @S9S_MB_2U_LIB.S9S_MB_2U(SCH_1):PAGE149

P5E_CPU1_PE4_RX_DN<8> @S9S_MB_2U_LIB.S9S_MB_2U(SCH_1):P5E_CPU1_PE4_RX_DN(8)
    U1 AH91 PE4_RX_DN8 SOCKET4677_AZIF0045P001C01CS-SA    I18 @S9S_MB_2U_LIB.S9S_MB_2U(SCH_1):PAGE62
  J111   F1     F1 CONN112_10137002101LF-CONN112_A    I75 @S9S_MB_2U_LIB.S9S_MB_2U(SCH_1):PAGE148

P5E_CPU1_PE4_RX_DN<9> @S9S_MB_2U_LIB.S9S_MB_2U(SCH_1):P5E_CPU1_PE4_RX_DN(9)
    U1 AK89 PE4_RX_DN9 SOCKET4677_AZIF0045P001C01CS-SA    I18 @S9S_MB_2U_LIB.S9S_MB_2U(SCH_1):PAGE62
  J111   F2     F2 CONN112_10137002101LF-CONN112_A    I75 @S9S_MB_2U_LIB.S9S_MB_2U(SCH_1):PAGE148

P5E_CPU1_PE4_RX_DP<0> @S9S_MB_2U_LIB.S9S_MB_2U(SCH_1):P5E_CPU1_PE4_RX_DP(0)
    U1  K89 PE4_RX_DP0 SOCKET4677_AZIF0045P001C01CS-SA    I18 @S9S_MB_2U_LIB.S9S_MB_2U(SCH_1):PAGE62
  J112   G1     G1 CONN160_10131762101LF-CONN160_A    I76 @S9S_MB_2U_LIB.S9S_MB_2U(SCH_1):PAGE149

P5E_CPU1_PE4_RX_DP<10> @S9S_MB_2U_LIB.S9S_MB_2U(SCH_1):P5E_CPU1_PE4_RX_DP(10)
    U1 AL90 PE4_RX_DP10 SOCKET4677_AZIF0045P001C01CS-SA    I18 @S9S_MB_2U_LIB.S9S_MB_2U(SCH_1):PAGE62
  J111   G3     G3 CONN112_10137002101LF-CONN112_A    I75 @S9S_MB_2U_LIB.S9S_MB_2U(SCH_1):PAGE148

P5E_CPU1_PE4_RX_DP<11> @S9S_MB_2U_LIB.S9S_MB_2U(SCH_1):P5E_CPU1_PE4_RX_DP(11)
    U1 AN90 PE4_RX_DP11 SOCKET4677_AZIF0045P001C01CS-SA    I18 @S9S_MB_2U_LIB.S9S_MB_2U(SCH_1):PAGE62
  J111   E4     E4 CONN112_10137002101LF-CONN112_A    I75 @S9S_MB_2U_LIB.S9S_MB_2U(SCH_1):PAGE148

P5E_CPU1_PE4_RX_DP<12> @S9S_MB_2U_LIB.S9S_MB_2U(SCH_1):P5E_CPU1_PE4_RX_DP(12)
    U1 AR90 PE4_RX_DP12 SOCKET4677_AZIF0045P001C01CS-SA    I18 @S9S_MB_2U_LIB.S9S_MB_2U(SCH_1):PAGE62
  J111   G5     G5 CONN112_10137002101LF-CONN112_A    I74 @S9S_MB_2U_LIB.S9S_MB_2U(SCH_1):PAGE148

P5E_CPU1_PE4_RX_DP<13> @S9S_MB_2U_LIB.S9S_MB_2U(SCH_1):P5E_CPU1_PE4_RX_DP(13)
    U1 AU90 PE4_RX_DP13 SOCKET4677_AZIF0045P001C01CS-SA    I18 @S9S_MB_2U_LIB.S9S_MB_2U(SCH_1):PAGE62
  J111   E6     E6 CONN112_10137002101LF-CONN112_A    I74 @S9S_MB_2U_LIB.S9S_MB_2U(SCH_1):PAGE148

P5E_CPU1_PE4_RX_DP<14> @S9S_MB_2U_LIB.S9S_MB_2U(SCH_1):P5E_CPU1_PE4_RX_DP(14)
    U1 AW90 PE4_RX_DP14 SOCKET4677_AZIF0045P001C01CS-SA    I18 @S9S_MB_2U_LIB.S9S_MB_2U(SCH_1):PAGE62
  J111   G7     G7 CONN112_10137002101LF-CONN112_A    I74 @S9S_MB_2U_LIB.S9S_MB_2U(SCH_1):PAGE148

P5E_CPU1_PE4_RX_DP<15> @S9S_MB_2U_LIB.S9S_MB_2U(SCH_1):P5E_CPU1_PE4_RX_DP(15)
    U1 BA90 PE4_RX_DP15 SOCKET4677_AZIF0045P001C01CS-SA    I18 @S9S_MB_2U_LIB.S9S_MB_2U(SCH_1):PAGE62
  J111   E8     E8 CONN112_10137002101LF-CONN112_A    I74 @S9S_MB_2U_LIB.S9S_MB_2U(SCH_1):PAGE148

P5E_CPU1_PE4_RX_DP<1> @S9S_MB_2U_LIB.S9S_MB_2U(SCH_1):P5E_CPU1_PE4_RX_DP(1)
    U1  N90 PE4_RX_DP1 SOCKET4677_AZIF0045P001C01CS-SA    I18 @S9S_MB_2U_LIB.S9S_MB_2U(SCH_1):PAGE62
  J112   E2     E2 CONN160_10131762101LF-CONN160_A    I76 @S9S_MB_2U_LIB.S9S_MB_2U(SCH_1):PAGE149

P5E_CPU1_PE4_RX_DP<2> @S9S_MB_2U_LIB.S9S_MB_2U(SCH_1):P5E_CPU1_PE4_RX_DP(2)
    U1  R90 PE4_RX_DP2 SOCKET4677_AZIF0045P001C01CS-SA    I18 @S9S_MB_2U_LIB.S9S_MB_2U(SCH_1):PAGE62
  J112   G3     G3 CONN160_10131762101LF-CONN160_A    I76 @S9S_MB_2U_LIB.S9S_MB_2U(SCH_1):PAGE149

P5E_CPU1_PE4_RX_DP<3> @S9S_MB_2U_LIB.S9S_MB_2U(SCH_1):P5E_CPU1_PE4_RX_DP(3)
    U1  U90 PE4_RX_DP3 SOCKET4677_AZIF0045P001C01CS-SA    I18 @S9S_MB_2U_LIB.S9S_MB_2U(SCH_1):PAGE62
  J112   E4     E4 CONN160_10131762101LF-CONN160_A    I76 @S9S_MB_2U_LIB.S9S_MB_2U(SCH_1):PAGE149

P5E_CPU1_PE4_RX_DP<4> @S9S_MB_2U_LIB.S9S_MB_2U(SCH_1):P5E_CPU1_PE4_RX_DP(4)
    U1  W90 PE4_RX_DP4 SOCKET4677_AZIF0045P001C01CS-SA    I18 @S9S_MB_2U_LIB.S9S_MB_2U(SCH_1):PAGE62
  J112   G5     G5 CONN160_10131762101LF-CONN160_A    I75 @S9S_MB_2U_LIB.S9S_MB_2U(SCH_1):PAGE149

P5E_CPU1_PE4_RX_DP<5> @S9S_MB_2U_LIB.S9S_MB_2U(SCH_1):P5E_CPU1_PE4_RX_DP(5)
    U1 AA90 PE4_RX_DP5 SOCKET4677_AZIF0045P001C01CS-SA    I18 @S9S_MB_2U_LIB.S9S_MB_2U(SCH_1):PAGE62
  J112   E6     E6 CONN160_10131762101LF-CONN160_A    I75 @S9S_MB_2U_LIB.S9S_MB_2U(SCH_1):PAGE149

P5E_CPU1_PE4_RX_DP<6> @S9S_MB_2U_LIB.S9S_MB_2U(SCH_1):P5E_CPU1_PE4_RX_DP(6)
    U1 AC90 PE4_RX_DP6 SOCKET4677_AZIF0045P001C01CS-SA    I18 @S9S_MB_2U_LIB.S9S_MB_2U(SCH_1):PAGE62
  J112   G7     G7 CONN160_10131762101LF-CONN160_A    I75 @S9S_MB_2U_LIB.S9S_MB_2U(SCH_1):PAGE149

P5E_CPU1_PE4_RX_DP<7> @S9S_MB_2U_LIB.S9S_MB_2U(SCH_1):P5E_CPU1_PE4_RX_DP(7)
    U1 AE90 PE4_RX_DP7 SOCKET4677_AZIF0045P001C01CS-SA    I18 @S9S_MB_2U_LIB.S9S_MB_2U(SCH_1):PAGE62
  J112   E8     E8 CONN160_10131762101LF-CONN160_A    I75 @S9S_MB_2U_LIB.S9S_MB_2U(SCH_1):PAGE149

P5E_CPU1_PE4_RX_DP<8> @S9S_MB_2U_LIB.S9S_MB_2U(SCH_1):P5E_CPU1_PE4_RX_DP(8)
    U1 AG90 PE4_RX_DP8 SOCKET4677_AZIF0045P001C01CS-SA    I18 @S9S_MB_2U_LIB.S9S_MB_2U(SCH_1):PAGE62
  J111   G1     G1 CONN112_10137002101LF-CONN112_A    I75 @S9S_MB_2U_LIB.S9S_MB_2U(SCH_1):PAGE148

P5E_CPU1_PE4_RX_DP<9> @S9S_MB_2U_LIB.S9S_MB_2U(SCH_1):P5E_CPU1_PE4_RX_DP(9)
    U1 AJ90 PE4_RX_DP9 SOCKET4677_AZIF0045P001C01CS-SA    I18 @S9S_MB_2U_LIB.S9S_MB_2U(SCH_1):PAGE62
  J111   E2     E2 CONN112_10137002101LF-CONN112_A    I75 @S9S_MB_2U_LIB.S9S_MB_2U(SCH_1):PAGE148

P5E_CPU1_PE4_TX_C_DN<0> @S9S_MB_2U_LIB.S9S_MB_2U(SCH_1):P5E_CPU1_PE4_TX_C_DN(0)
  C708    1      1 Q_CAP_DIFFBUS_C0201-DIFF BUS_0A   I125 @S9S_MB_2U_LIB.S9S_MB_2U(SCH_1):PAGE168
  J112   L1     L1 CONN160_10131762101LF-CONN160_A    I76 @S9S_MB_2U_LIB.S9S_MB_2U(SCH_1):PAGE149

P5E_CPU1_PE4_TX_C_DN<10> @S9S_MB_2U_LIB.S9S_MB_2U(SCH_1):P5E_CPU1_PE4_TX_C_DN(10)
  C688    1      1 Q_CAP_DIFFBUS_C0201-DIFF BUS_0A   I162 @S9S_MB_2U_LIB.S9S_MB_2U(SCH_1):PAGE168
  J111   L3     L3 CONN112_10137002101LF-CONN112_A    I75 @S9S_MB_2U_LIB.S9S_MB_2U(SCH_1):PAGE148

P5E_CPU1_PE4_TX_C_DN<11> @S9S_MB_2U_LIB.S9S_MB_2U(SCH_1):P5E_CPU1_PE4_TX_C_DN(11)
  C686    1      1 Q_CAP_DIFFBUS_C0201-DIFF BUS_0A   I164 @S9S_MB_2U_LIB.S9S_MB_2U(SCH_1):PAGE168
  J111   L4     L4 CONN112_10137002101LF-CONN112_A    I75 @S9S_MB_2U_LIB.S9S_MB_2U(SCH_1):PAGE148

P5E_CPU1_PE4_TX_C_DN<12> @S9S_MB_2U_LIB.S9S_MB_2U(SCH_1):P5E_CPU1_PE4_TX_C_DN(12)
  C684    1      1 Q_CAP_DIFFBUS_C0201-DIFF BUS_0A   I166 @S9S_MB_2U_LIB.S9S_MB_2U(SCH_1):PAGE168
  J111   L5     L5 CONN112_10137002101LF-CONN112_A    I74 @S9S_MB_2U_LIB.S9S_MB_2U(SCH_1):PAGE148

P5E_CPU1_PE4_TX_C_DN<13> @S9S_MB_2U_LIB.S9S_MB_2U(SCH_1):P5E_CPU1_PE4_TX_C_DN(13)
  C682    1      1 Q_CAP_DIFFBUS_C0201-DIFF BUS_0A   I167 @S9S_MB_2U_LIB.S9S_MB_2U(SCH_1):PAGE168
  J111   K6     K6 CONN112_10137002101LF-CONN112_A    I74 @S9S_MB_2U_LIB.S9S_MB_2U(SCH_1):PAGE148

P5E_CPU1_PE4_TX_C_DN<14> @S9S_MB_2U_LIB.S9S_MB_2U(SCH_1):P5E_CPU1_PE4_TX_C_DN(14)
  C680    1      1 Q_CAP_DIFFBUS_C0201-DIFF BUS_0A   I170 @S9S_MB_2U_LIB.S9S_MB_2U(SCH_1):PAGE168
  J111   L7     L7 CONN112_10137002101LF-CONN112_A    I74 @S9S_MB_2U_LIB.S9S_MB_2U(SCH_1):PAGE148

P5E_CPU1_PE4_TX_C_DN<15> @S9S_MB_2U_LIB.S9S_MB_2U(SCH_1):P5E_CPU1_PE4_TX_C_DN(15)
  C678    1      1 Q_CAP_DIFFBUS_C0201-DIFF BUS_0A   I172 @S9S_MB_2U_LIB.S9S_MB_2U(SCH_1):PAGE168
  J111   K8     K8 CONN112_10137002101LF-CONN112_A    I74 @S9S_MB_2U_LIB.S9S_MB_2U(SCH_1):PAGE148

P5E_CPU1_PE4_TX_C_DN<1> @S9S_MB_2U_LIB.S9S_MB_2U(SCH_1):P5E_CPU1_PE4_TX_C_DN(1)
  C706    1      1 Q_CAP_DIFFBUS_C0201-DIFF BUS_0A   I127 @S9S_MB_2U_LIB.S9S_MB_2U(SCH_1):PAGE168
  J112   L2     L2 CONN160_10131762101LF-CONN160_A    I76 @S9S_MB_2U_LIB.S9S_MB_2U(SCH_1):PAGE149

P5E_CPU1_PE4_TX_C_DN<2> @S9S_MB_2U_LIB.S9S_MB_2U(SCH_1):P5E_CPU1_PE4_TX_C_DN(2)
  C704    1      1 Q_CAP_DIFFBUS_C0201-DIFF BUS_0A   I129 @S9S_MB_2U_LIB.S9S_MB_2U(SCH_1):PAGE168
  J112   L3     L3 CONN160_10131762101LF-CONN160_A    I76 @S9S_MB_2U_LIB.S9S_MB_2U(SCH_1):PAGE149

P5E_CPU1_PE4_TX_C_DN<3> @S9S_MB_2U_LIB.S9S_MB_2U(SCH_1):P5E_CPU1_PE4_TX_C_DN(3)
  C702    1      1 Q_CAP_DIFFBUS_C0201-DIFF BUS_0A   I132 @S9S_MB_2U_LIB.S9S_MB_2U(SCH_1):PAGE168
  J112   K4     K4 CONN160_10131762101LF-CONN160_A    I76 @S9S_MB_2U_LIB.S9S_MB_2U(SCH_1):PAGE149

P5E_CPU1_PE4_TX_C_DN<4> @S9S_MB_2U_LIB.S9S_MB_2U(SCH_1):P5E_CPU1_PE4_TX_C_DN(4)
  C700    1      1 Q_CAP_DIFFBUS_C0201-DIFF BUS_0A   I134 @S9S_MB_2U_LIB.S9S_MB_2U(SCH_1):PAGE168
  J112   L5     L5 CONN160_10131762101LF-CONN160_A    I75 @S9S_MB_2U_LIB.S9S_MB_2U(SCH_1):PAGE149

P5E_CPU1_PE4_TX_C_DN<5> @S9S_MB_2U_LIB.S9S_MB_2U(SCH_1):P5E_CPU1_PE4_TX_C_DN(5)
  C698    1      1 Q_CAP_DIFFBUS_C0201-DIFF BUS_0A   I135 @S9S_MB_2U_LIB.S9S_MB_2U(SCH_1):PAGE168
  J112   K6     K6 CONN160_10131762101LF-CONN160_A    I75 @S9S_MB_2U_LIB.S9S_MB_2U(SCH_1):PAGE149

P5E_CPU1_PE4_TX_C_DN<6> @S9S_MB_2U_LIB.S9S_MB_2U(SCH_1):P5E_CPU1_PE4_TX_C_DN(6)
  C696    1      1 Q_CAP_DIFFBUS_C0201-DIFF BUS_0A   I137 @S9S_MB_2U_LIB.S9S_MB_2U(SCH_1):PAGE168
  J112   L7     L7 CONN160_10131762101LF-CONN160_A    I75 @S9S_MB_2U_LIB.S9S_MB_2U(SCH_1):PAGE149

P5E_CPU1_PE4_TX_C_DN<7> @S9S_MB_2U_LIB.S9S_MB_2U(SCH_1):P5E_CPU1_PE4_TX_C_DN(7)
  C694    1      1 Q_CAP_DIFFBUS_C0201-DIFF BUS_0A   I140 @S9S_MB_2U_LIB.S9S_MB_2U(SCH_1):PAGE168
  J112   K8     K8 CONN160_10131762101LF-CONN160_A    I75 @S9S_MB_2U_LIB.S9S_MB_2U(SCH_1):PAGE149

P5E_CPU1_PE4_TX_C_DN<8> @S9S_MB_2U_LIB.S9S_MB_2U(SCH_1):P5E_CPU1_PE4_TX_C_DN(8)
  C692    1      1 Q_CAP_DIFFBUS_C0201-DIFF BUS_0A   I158 @S9S_MB_2U_LIB.S9S_MB_2U(SCH_1):PAGE168
  J111   L1     L1 CONN112_10137002101LF-CONN112_A    I75 @S9S_MB_2U_LIB.S9S_MB_2U(SCH_1):PAGE148

P5E_CPU1_PE4_TX_C_DN<9> @S9S_MB_2U_LIB.S9S_MB_2U(SCH_1):P5E_CPU1_PE4_TX_C_DN(9)
  C690    1      1 Q_CAP_DIFFBUS_C0201-DIFF BUS_0A   I159 @S9S_MB_2U_LIB.S9S_MB_2U(SCH_1):PAGE168
  J111   K2     K2 CONN112_10137002101LF-CONN112_A    I75 @S9S_MB_2U_LIB.S9S_MB_2U(SCH_1):PAGE148

P5E_CPU1_PE4_TX_C_DP<0> @S9S_MB_2U_LIB.S9S_MB_2U(SCH_1):P5E_CPU1_PE4_TX_C_DP(0)
  C709    1      1 Q_CAP_DIFFBUS_C0201-DIFF BUS_0A   I126 @S9S_MB_2U_LIB.S9S_MB_2U(SCH_1):PAGE168
  J112   M1     M1 CONN160_10131762101LF-CONN160_A    I76 @S9S_MB_2U_LIB.S9S_MB_2U(SCH_1):PAGE149

P5E_CPU1_PE4_TX_C_DP<10> @S9S_MB_2U_LIB.S9S_MB_2U(SCH_1):P5E_CPU1_PE4_TX_C_DP(10)
  C689    1      1 Q_CAP_DIFFBUS_C0201-DIFF BUS_0A   I163 @S9S_MB_2U_LIB.S9S_MB_2U(SCH_1):PAGE168
  J111   M3     M3 CONN112_10137002101LF-CONN112_A    I75 @S9S_MB_2U_LIB.S9S_MB_2U(SCH_1):PAGE148

P5E_CPU1_PE4_TX_C_DP<11> @S9S_MB_2U_LIB.S9S_MB_2U(SCH_1):P5E_CPU1_PE4_TX_C_DP(11)
  C687    1      1 Q_CAP_DIFFBUS_C0201-DIFF BUS_0A   I161 @S9S_MB_2U_LIB.S9S_MB_2U(SCH_1):PAGE168
  J111   K4     K4 CONN112_10137002101LF-CONN112_A    I75 @S9S_MB_2U_LIB.S9S_MB_2U(SCH_1):PAGE148

P5E_CPU1_PE4_TX_C_DP<12> @S9S_MB_2U_LIB.S9S_MB_2U(SCH_1):P5E_CPU1_PE4_TX_C_DP(12)
  C685    1      1 Q_CAP_DIFFBUS_C0201-DIFF BUS_0A   I165 @S9S_MB_2U_LIB.S9S_MB_2U(SCH_1):PAGE168
  J111   M5     M5 CONN112_10137002101LF-CONN112_A    I74 @S9S_MB_2U_LIB.S9S_MB_2U(SCH_1):PAGE148

P5E_CPU1_PE4_TX_C_DP<13> @S9S_MB_2U_LIB.S9S_MB_2U(SCH_1):P5E_CPU1_PE4_TX_C_DP(13)
  C683    1      1 Q_CAP_DIFFBUS_C0201-DIFF BUS_0A   I168 @S9S_MB_2U_LIB.S9S_MB_2U(SCH_1):PAGE168
  J111   L6     L6 CONN112_10137002101LF-CONN112_A    I74 @S9S_MB_2U_LIB.S9S_MB_2U(SCH_1):PAGE148

P5E_CPU1_PE4_TX_C_DP<14> @S9S_MB_2U_LIB.S9S_MB_2U(SCH_1):P5E_CPU1_PE4_TX_C_DP(14)
  C681    1      1 Q_CAP_DIFFBUS_C0201-DIFF BUS_0A   I171 @S9S_MB_2U_LIB.S9S_MB_2U(SCH_1):PAGE168
  J111   M7     M7 CONN112_10137002101LF-CONN112_A    I74 @S9S_MB_2U_LIB.S9S_MB_2U(SCH_1):PAGE148

P5E_CPU1_PE4_TX_C_DP<15> @S9S_MB_2U_LIB.S9S_MB_2U(SCH_1):P5E_CPU1_PE4_TX_C_DP(15)
  C679    1      1 Q_CAP_DIFFBUS_C0201-DIFF BUS_0A   I169 @S9S_MB_2U_LIB.S9S_MB_2U(SCH_1):PAGE168
  J111   L8     L8 CONN112_10137002101LF-CONN112_A    I74 @S9S_MB_2U_LIB.S9S_MB_2U(SCH_1):PAGE148

P5E_CPU1_PE4_TX_C_DP<1> @S9S_MB_2U_LIB.S9S_MB_2U(SCH_1):P5E_CPU1_PE4_TX_C_DP(1)
  C707    1      1 Q_CAP_DIFFBUS_C0201-DIFF BUS_0A   I128 @S9S_MB_2U_LIB.S9S_MB_2U(SCH_1):PAGE168
  J112   K2     K2 CONN160_10131762101LF-CONN160_A    I76 @S9S_MB_2U_LIB.S9S_MB_2U(SCH_1):PAGE149

P5E_CPU1_PE4_TX_C_DP<2> @S9S_MB_2U_LIB.S9S_MB_2U(SCH_1):P5E_CPU1_PE4_TX_C_DP(2)
  C705    1      1 Q_CAP_DIFFBUS_C0201-DIFF BUS_0A   I130 @S9S_MB_2U_LIB.S9S_MB_2U(SCH_1):PAGE168
  J112   M3     M3 CONN160_10131762101LF-CONN160_A    I76 @S9S_MB_2U_LIB.S9S_MB_2U(SCH_1):PAGE149

P5E_CPU1_PE4_TX_C_DP<3> @S9S_MB_2U_LIB.S9S_MB_2U(SCH_1):P5E_CPU1_PE4_TX_C_DP(3)
  C703    1      1 Q_CAP_DIFFBUS_C0201-DIFF BUS_0A   I133 @S9S_MB_2U_LIB.S9S_MB_2U(SCH_1):PAGE168
  J112   L4     L4 CONN160_10131762101LF-CONN160_A    I76 @S9S_MB_2U_LIB.S9S_MB_2U(SCH_1):PAGE149

P5E_CPU1_PE4_TX_C_DP<4> @S9S_MB_2U_LIB.S9S_MB_2U(SCH_1):P5E_CPU1_PE4_TX_C_DP(4)
  C701    1      1 Q_CAP_DIFFBUS_C0201-DIFF BUS_0A   I131 @S9S_MB_2U_LIB.S9S_MB_2U(SCH_1):PAGE168
  J112   M5     M5 CONN160_10131762101LF-CONN160_A    I75 @S9S_MB_2U_LIB.S9S_MB_2U(SCH_1):PAGE149

P5E_CPU1_PE4_TX_C_DP<5> @S9S_MB_2U_LIB.S9S_MB_2U(SCH_1):P5E_CPU1_PE4_TX_C_DP(5)
  C699    1      1 Q_CAP_DIFFBUS_C0201-DIFF BUS_0A   I136 @S9S_MB_2U_LIB.S9S_MB_2U(SCH_1):PAGE168
  J112   L6     L6 CONN160_10131762101LF-CONN160_A    I75 @S9S_MB_2U_LIB.S9S_MB_2U(SCH_1):PAGE149

P5E_CPU1_PE4_TX_C_DP<6> @S9S_MB_2U_LIB.S9S_MB_2U(SCH_1):P5E_CPU1_PE4_TX_C_DP(6)
  C697    1      1 Q_CAP_DIFFBUS_C0201-DIFF BUS_0A   I138 @S9S_MB_2U_LIB.S9S_MB_2U(SCH_1):PAGE168
  J112   M7     M7 CONN160_10131762101LF-CONN160_A    I75 @S9S_MB_2U_LIB.S9S_MB_2U(SCH_1):PAGE149

P5E_CPU1_PE4_TX_C_DP<7> @S9S_MB_2U_LIB.S9S_MB_2U(SCH_1):P5E_CPU1_PE4_TX_C_DP(7)
  C695    1      1 Q_CAP_DIFFBUS_C0201-DIFF BUS_0A   I139 @S9S_MB_2U_LIB.S9S_MB_2U(SCH_1):PAGE168
  J112   L8     L8 CONN160_10131762101LF-CONN160_A    I75 @S9S_MB_2U_LIB.S9S_MB_2U(SCH_1):PAGE149

P5E_CPU1_PE4_TX_C_DP<8> @S9S_MB_2U_LIB.S9S_MB_2U(SCH_1):P5E_CPU1_PE4_TX_C_DP(8)
  C693    1      1 Q_CAP_DIFFBUS_C0201-DIFF BUS_0A   I157 @S9S_MB_2U_LIB.S9S_MB_2U(SCH_1):PAGE168
  J111   M1     M1 CONN112_10137002101LF-CONN112_A    I75 @S9S_MB_2U_LIB.S9S_MB_2U(SCH_1):PAGE148

P5E_CPU1_PE4_TX_C_DP<9> @S9S_MB_2U_LIB.S9S_MB_2U(SCH_1):P5E_CPU1_PE4_TX_C_DP(9)
  C691    1      1 Q_CAP_DIFFBUS_C0201-DIFF BUS_0A   I160 @S9S_MB_2U_LIB.S9S_MB_2U(SCH_1):PAGE168
  J111   L2     L2 CONN112_10137002101LF-CONN112_A    I75 @S9S_MB_2U_LIB.S9S_MB_2U(SCH_1):PAGE148

P5E_CPU1_PE4_TX_DN<0> @S9S_MB_2U_LIB.S9S_MB_2U(SCH_1):P5E_CPU1_PE4_TX_DN(0)
    U1  L86 PE4_TX_DN0 SOCKET4677_AZIF0045P001C01CS-SA    I18 @S9S_MB_2U_LIB.S9S_MB_2U(SCH_1):PAGE62
  C708    2      2 Q_CAP_DIFFBUS_C0201-DIFF BUS_0A   I125 @S9S_MB_2U_LIB.S9S_MB_2U(SCH_1):PAGE168

P5E_CPU1_PE4_TX_DN<10> @S9S_MB_2U_LIB.S9S_MB_2U(SCH_1):P5E_CPU1_PE4_TX_DN(10)
    U1 AL86 PE4_TX_DN10 SOCKET4677_AZIF0045P001C01CS-SA    I18 @S9S_MB_2U_LIB.S9S_MB_2U(SCH_1):PAGE62
  C688    2      2 Q_CAP_DIFFBUS_C0201-DIFF BUS_0A   I162 @S9S_MB_2U_LIB.S9S_MB_2U(SCH_1):PAGE168

P5E_CPU1_PE4_TX_DN<11> @S9S_MB_2U_LIB.S9S_MB_2U(SCH_1):P5E_CPU1_PE4_TX_DN(11)
    U1 AP85 PE4_TX_DN11 SOCKET4677_AZIF0045P001C01CS-SA    I18 @S9S_MB_2U_LIB.S9S_MB_2U(SCH_1):PAGE62
  C686    2      2 Q_CAP_DIFFBUS_C0201-DIFF BUS_0A   I164 @S9S_MB_2U_LIB.S9S_MB_2U(SCH_1):PAGE168

P5E_CPU1_PE4_TX_DN<12> @S9S_MB_2U_LIB.S9S_MB_2U(SCH_1):P5E_CPU1_PE4_TX_DN(12)
    U1 AR86 PE4_TX_DN12 SOCKET4677_AZIF0045P001C01CS-SA    I18 @S9S_MB_2U_LIB.S9S_MB_2U(SCH_1):PAGE62
  C684    2      2 Q_CAP_DIFFBUS_C0201-DIFF BUS_0A   I166 @S9S_MB_2U_LIB.S9S_MB_2U(SCH_1):PAGE168

P5E_CPU1_PE4_TX_DN<13> @S9S_MB_2U_LIB.S9S_MB_2U(SCH_1):P5E_CPU1_PE4_TX_DN(13)
    U1 AU86 PE4_TX_DN13 SOCKET4677_AZIF0045P001C01CS-SA    I18 @S9S_MB_2U_LIB.S9S_MB_2U(SCH_1):PAGE62
  C682    2      2 Q_CAP_DIFFBUS_C0201-DIFF BUS_0A   I167 @S9S_MB_2U_LIB.S9S_MB_2U(SCH_1):PAGE168

P5E_CPU1_PE4_TX_DN<14> @S9S_MB_2U_LIB.S9S_MB_2U(SCH_1):P5E_CPU1_PE4_TX_DN(14)
    U1 AW86 PE4_TX_DN14 SOCKET4677_AZIF0045P001C01CS-SA    I18 @S9S_MB_2U_LIB.S9S_MB_2U(SCH_1):PAGE62
  C680    2      2 Q_CAP_DIFFBUS_C0201-DIFF BUS_0A   I170 @S9S_MB_2U_LIB.S9S_MB_2U(SCH_1):PAGE168

P5E_CPU1_PE4_TX_DN<15> @S9S_MB_2U_LIB.S9S_MB_2U(SCH_1):P5E_CPU1_PE4_TX_DN(15)
    U1 BA86 PE4_TX_DN15 SOCKET4677_AZIF0045P001C01CS-SA    I18 @S9S_MB_2U_LIB.S9S_MB_2U(SCH_1):PAGE62
  C678    2      2 Q_CAP_DIFFBUS_C0201-DIFF BUS_0A   I172 @S9S_MB_2U_LIB.S9S_MB_2U(SCH_1):PAGE168

P5E_CPU1_PE4_TX_DN<1> @S9S_MB_2U_LIB.S9S_MB_2U(SCH_1):P5E_CPU1_PE4_TX_DN(1)
    U1  P85 PE4_TX_DN1 SOCKET4677_AZIF0045P001C01CS-SA    I18 @S9S_MB_2U_LIB.S9S_MB_2U(SCH_1):PAGE62
  C706    2      2 Q_CAP_DIFFBUS_C0201-DIFF BUS_0A   I127 @S9S_MB_2U_LIB.S9S_MB_2U(SCH_1):PAGE168

P5E_CPU1_PE4_TX_DN<2> @S9S_MB_2U_LIB.S9S_MB_2U(SCH_1):P5E_CPU1_PE4_TX_DN(2)
    U1  R86 PE4_TX_DN2 SOCKET4677_AZIF0045P001C01CS-SA    I18 @S9S_MB_2U_LIB.S9S_MB_2U(SCH_1):PAGE62
  C704    2      2 Q_CAP_DIFFBUS_C0201-DIFF BUS_0A   I129 @S9S_MB_2U_LIB.S9S_MB_2U(SCH_1):PAGE168

P5E_CPU1_PE4_TX_DN<3> @S9S_MB_2U_LIB.S9S_MB_2U(SCH_1):P5E_CPU1_PE4_TX_DN(3)
    U1  U86 PE4_TX_DN3 SOCKET4677_AZIF0045P001C01CS-SA    I18 @S9S_MB_2U_LIB.S9S_MB_2U(SCH_1):PAGE62
  C702    2      2 Q_CAP_DIFFBUS_C0201-DIFF BUS_0A   I132 @S9S_MB_2U_LIB.S9S_MB_2U(SCH_1):PAGE168

P5E_CPU1_PE4_TX_DN<4> @S9S_MB_2U_LIB.S9S_MB_2U(SCH_1):P5E_CPU1_PE4_TX_DN(4)
    U1  W86 PE4_TX_DN4 SOCKET4677_AZIF0045P001C01CS-SA    I18 @S9S_MB_2U_LIB.S9S_MB_2U(SCH_1):PAGE62
  C700    2      2 Q_CAP_DIFFBUS_C0201-DIFF BUS_0A   I134 @S9S_MB_2U_LIB.S9S_MB_2U(SCH_1):PAGE168

P5E_CPU1_PE4_TX_DN<5> @S9S_MB_2U_LIB.S9S_MB_2U(SCH_1):P5E_CPU1_PE4_TX_DN(5)
    U1 AA86 PE4_TX_DN5 SOCKET4677_AZIF0045P001C01CS-SA    I18 @S9S_MB_2U_LIB.S9S_MB_2U(SCH_1):PAGE62
  C698    2      2 Q_CAP_DIFFBUS_C0201-DIFF BUS_0A   I135 @S9S_MB_2U_LIB.S9S_MB_2U(SCH_1):PAGE168

P5E_CPU1_PE4_TX_DN<6> @S9S_MB_2U_LIB.S9S_MB_2U(SCH_1):P5E_CPU1_PE4_TX_DN(6)
    U1 AC86 PE4_TX_DN6 SOCKET4677_AZIF0045P001C01CS-SA    I18 @S9S_MB_2U_LIB.S9S_MB_2U(SCH_1):PAGE62
  C696    2      2 Q_CAP_DIFFBUS_C0201-DIFF BUS_0A   I137 @S9S_MB_2U_LIB.S9S_MB_2U(SCH_1):PAGE168

P5E_CPU1_PE4_TX_DN<7> @S9S_MB_2U_LIB.S9S_MB_2U(SCH_1):P5E_CPU1_PE4_TX_DN(7)
    U1 AE86 PE4_TX_DN7 SOCKET4677_AZIF0045P001C01CS-SA    I18 @S9S_MB_2U_LIB.S9S_MB_2U(SCH_1):PAGE62
  C694    2      2 Q_CAP_DIFFBUS_C0201-DIFF BUS_0A   I140 @S9S_MB_2U_LIB.S9S_MB_2U(SCH_1):PAGE168

P5E_CPU1_PE4_TX_DN<8> @S9S_MB_2U_LIB.S9S_MB_2U(SCH_1):P5E_CPU1_PE4_TX_DN(8)
    U1 AG86 PE4_TX_DN8 SOCKET4677_AZIF0045P001C01CS-SA    I18 @S9S_MB_2U_LIB.S9S_MB_2U(SCH_1):PAGE62
  C692    2      2 Q_CAP_DIFFBUS_C0201-DIFF BUS_0A   I158 @S9S_MB_2U_LIB.S9S_MB_2U(SCH_1):PAGE168

P5E_CPU1_PE4_TX_DN<9> @S9S_MB_2U_LIB.S9S_MB_2U(SCH_1):P5E_CPU1_PE4_TX_DN(9)
    U1 AJ86 PE4_TX_DN9 SOCKET4677_AZIF0045P001C01CS-SA    I18 @S9S_MB_2U_LIB.S9S_MB_2U(SCH_1):PAGE62
  C690    2      2 Q_CAP_DIFFBUS_C0201-DIFF BUS_0A   I159 @S9S_MB_2U_LIB.S9S_MB_2U(SCH_1):PAGE168

P5E_CPU1_PE4_TX_DP<0> @S9S_MB_2U_LIB.S9S_MB_2U(SCH_1):P5E_CPU1_PE4_TX_DP(0)
    U1  M87 PE4_TX_DP0 SOCKET4677_AZIF0045P001C01CS-SA    I18 @S9S_MB_2U_LIB.S9S_MB_2U(SCH_1):PAGE62
  C709    2      2 Q_CAP_DIFFBUS_C0201-DIFF BUS_0A   I126 @S9S_MB_2U_LIB.S9S_MB_2U(SCH_1):PAGE168

P5E_CPU1_PE4_TX_DP<10> @S9S_MB_2U_LIB.S9S_MB_2U(SCH_1):P5E_CPU1_PE4_TX_DP(10)
    U1 AM87 PE4_TX_DP10 SOCKET4677_AZIF0045P001C01CS-SA    I18 @S9S_MB_2U_LIB.S9S_MB_2U(SCH_1):PAGE62
  C689    2      2 Q_CAP_DIFFBUS_C0201-DIFF BUS_0A   I163 @S9S_MB_2U_LIB.S9S_MB_2U(SCH_1):PAGE168

P5E_CPU1_PE4_TX_DP<11> @S9S_MB_2U_LIB.S9S_MB_2U(SCH_1):P5E_CPU1_PE4_TX_DP(11)
    U1 AN86 PE4_TX_DP11 SOCKET4677_AZIF0045P001C01CS-SA    I18 @S9S_MB_2U_LIB.S9S_MB_2U(SCH_1):PAGE62
  C687    2      2 Q_CAP_DIFFBUS_C0201-DIFF BUS_0A   I161 @S9S_MB_2U_LIB.S9S_MB_2U(SCH_1):PAGE168

P5E_CPU1_PE4_TX_DP<12> @S9S_MB_2U_LIB.S9S_MB_2U(SCH_1):P5E_CPU1_PE4_TX_DP(12)
    U1 AT87 PE4_TX_DP12 SOCKET4677_AZIF0045P001C01CS-SA    I18 @S9S_MB_2U_LIB.S9S_MB_2U(SCH_1):PAGE62
  C685    2      2 Q_CAP_DIFFBUS_C0201-DIFF BUS_0A   I165 @S9S_MB_2U_LIB.S9S_MB_2U(SCH_1):PAGE168

P5E_CPU1_PE4_TX_DP<13> @S9S_MB_2U_LIB.S9S_MB_2U(SCH_1):P5E_CPU1_PE4_TX_DP(13)
    U1 AV85 PE4_TX_DP13 SOCKET4677_AZIF0045P001C01CS-SA    I18 @S9S_MB_2U_LIB.S9S_MB_2U(SCH_1):PAGE62
  C683    2      2 Q_CAP_DIFFBUS_C0201-DIFF BUS_0A   I168 @S9S_MB_2U_LIB.S9S_MB_2U(SCH_1):PAGE168

P5E_CPU1_PE4_TX_DP<14> @S9S_MB_2U_LIB.S9S_MB_2U(SCH_1):P5E_CPU1_PE4_TX_DP(14)
    U1 AY87 PE4_TX_DP14 SOCKET4677_AZIF0045P001C01CS-SA    I18 @S9S_MB_2U_LIB.S9S_MB_2U(SCH_1):PAGE62
  C681    2      2 Q_CAP_DIFFBUS_C0201-DIFF BUS_0A   I171 @S9S_MB_2U_LIB.S9S_MB_2U(SCH_1):PAGE168

P5E_CPU1_PE4_TX_DP<15> @S9S_MB_2U_LIB.S9S_MB_2U(SCH_1):P5E_CPU1_PE4_TX_DP(15)
    U1 BB85 PE4_TX_DP15 SOCKET4677_AZIF0045P001C01CS-SA    I18 @S9S_MB_2U_LIB.S9S_MB_2U(SCH_1):PAGE62
  C679    2      2 Q_CAP_DIFFBUS_C0201-DIFF BUS_0A   I169 @S9S_MB_2U_LIB.S9S_MB_2U(SCH_1):PAGE168

P5E_CPU1_PE4_TX_DP<1> @S9S_MB_2U_LIB.S9S_MB_2U(SCH_1):P5E_CPU1_PE4_TX_DP(1)
    U1  N86 PE4_TX_DP1 SOCKET4677_AZIF0045P001C01CS-SA    I18 @S9S_MB_2U_LIB.S9S_MB_2U(SCH_1):PAGE62
  C707    2      2 Q_CAP_DIFFBUS_C0201-DIFF BUS_0A   I128 @S9S_MB_2U_LIB.S9S_MB_2U(SCH_1):PAGE168

P5E_CPU1_PE4_TX_DP<2> @S9S_MB_2U_LIB.S9S_MB_2U(SCH_1):P5E_CPU1_PE4_TX_DP(2)
    U1  T87 PE4_TX_DP2 SOCKET4677_AZIF0045P001C01CS-SA    I18 @S9S_MB_2U_LIB.S9S_MB_2U(SCH_1):PAGE62
  C705    2      2 Q_CAP_DIFFBUS_C0201-DIFF BUS_0A   I130 @S9S_MB_2U_LIB.S9S_MB_2U(SCH_1):PAGE168

P5E_CPU1_PE4_TX_DP<3> @S9S_MB_2U_LIB.S9S_MB_2U(SCH_1):P5E_CPU1_PE4_TX_DP(3)
    U1  V85 PE4_TX_DP3 SOCKET4677_AZIF0045P001C01CS-SA    I18 @S9S_MB_2U_LIB.S9S_MB_2U(SCH_1):PAGE62
  C703    2      2 Q_CAP_DIFFBUS_C0201-DIFF BUS_0A   I133 @S9S_MB_2U_LIB.S9S_MB_2U(SCH_1):PAGE168

P5E_CPU1_PE4_TX_DP<4> @S9S_MB_2U_LIB.S9S_MB_2U(SCH_1):P5E_CPU1_PE4_TX_DP(4)
    U1  Y87 PE4_TX_DP4 SOCKET4677_AZIF0045P001C01CS-SA    I18 @S9S_MB_2U_LIB.S9S_MB_2U(SCH_1):PAGE62
  C701    2      2 Q_CAP_DIFFBUS_C0201-DIFF BUS_0A   I131 @S9S_MB_2U_LIB.S9S_MB_2U(SCH_1):PAGE168

P5E_CPU1_PE4_TX_DP<5> @S9S_MB_2U_LIB.S9S_MB_2U(SCH_1):P5E_CPU1_PE4_TX_DP(5)
    U1 AB85 PE4_TX_DP5 SOCKET4677_AZIF0045P001C01CS-SA    I18 @S9S_MB_2U_LIB.S9S_MB_2U(SCH_1):PAGE62
  C699    2      2 Q_CAP_DIFFBUS_C0201-DIFF BUS_0A   I136 @S9S_MB_2U_LIB.S9S_MB_2U(SCH_1):PAGE168

P5E_CPU1_PE4_TX_DP<6> @S9S_MB_2U_LIB.S9S_MB_2U(SCH_1):P5E_CPU1_PE4_TX_DP(6)
    U1 AD87 PE4_TX_DP6 SOCKET4677_AZIF0045P001C01CS-SA    I18 @S9S_MB_2U_LIB.S9S_MB_2U(SCH_1):PAGE62
  C697    2      2 Q_CAP_DIFFBUS_C0201-DIFF BUS_0A   I138 @S9S_MB_2U_LIB.S9S_MB_2U(SCH_1):PAGE168

P5E_CPU1_PE4_TX_DP<7> @S9S_MB_2U_LIB.S9S_MB_2U(SCH_1):P5E_CPU1_PE4_TX_DP(7)
    U1 AF85 PE4_TX_DP7 SOCKET4677_AZIF0045P001C01CS-SA    I18 @S9S_MB_2U_LIB.S9S_MB_2U(SCH_1):PAGE62
  C695    2      2 Q_CAP_DIFFBUS_C0201-DIFF BUS_0A   I139 @S9S_MB_2U_LIB.S9S_MB_2U(SCH_1):PAGE168

P5E_CPU1_PE4_TX_DP<8> @S9S_MB_2U_LIB.S9S_MB_2U(SCH_1):P5E_CPU1_PE4_TX_DP(8)
    U1 AH87 PE4_TX_DP8 SOCKET4677_AZIF0045P001C01CS-SA    I18 @S9S_MB_2U_LIB.S9S_MB_2U(SCH_1):PAGE62
  C693    2      2 Q_CAP_DIFFBUS_C0201-DIFF BUS_0A   I157 @S9S_MB_2U_LIB.S9S_MB_2U(SCH_1):PAGE168

P5E_CPU1_PE4_TX_DP<9> @S9S_MB_2U_LIB.S9S_MB_2U(SCH_1):P5E_CPU1_PE4_TX_DP(9)
    U1 AK85 PE4_TX_DP9 SOCKET4677_AZIF0045P001C01CS-SA    I18 @S9S_MB_2U_LIB.S9S_MB_2U(SCH_1):PAGE62
  C691    2      2 Q_CAP_DIFFBUS_C0201-DIFF BUS_0A   I160 @S9S_MB_2U_LIB.S9S_MB_2U(SCH_1):PAGE168

P5V @S9S_MB_2U_LIB.S9S_MB_2U(SCH_1):P5V
 R3102    2      B Q_RES_0402LF-470,1%,1/16W,CHIPA    I61 @S9S_MB_2U_LIB.S9S_MB_2U(SCH_1):PAGE242
 R3005    1      A Q_RES_0402LF-18K,1%,1/16W,CHIPA   I168 @S9S_MB_2U_LIB.S9S_MB_2U(SCH_1):PAGE239
 C1172    1      A Q_CAP_C0402-100NF,50V,10%,X7R,A     I2 @S9S_MB_2U_LIB.S9S_MB_2U(SCH_1):PAGE246
   U99    3    VDD RT9818C44GV-RT9818C-44GV,SMLF,A     I4 @S9S_MB_2U_LIB.S9S_MB_2U(SCH_1):PAGE246
   Q57    1      1 MOSFET_NCH_1D3S-PSMNR58-30YLH,A    I30 @S9S_MB_2U_LIB.S9S_MB_2U(SCH_1):PAGE246
   Q57    2      2 MOSFET_NCH_1D3S-PSMNR58-30YLH,A    I30 @S9S_MB_2U_LIB.S9S_MB_2U(SCH_1):PAGE246
   Q57    3      3 MOSFET_NCH_1D3S-PSMNR58-30YLH,A    I30 @S9S_MB_2U_LIB.S9S_MB_2U(SCH_1):PAGE246
    D7    3      3 BAT547F-BAT547F,SMLF,IC,BC0BATA    I32 @S9S_MB_2U_LIB.S9S_MB_2U(SCH_1):PAGE246
 C1227    1      A Q_CAP_C0402-100NF,50V,10%,X7R,A    I44 @S9S_MB_2U_LIB.S9S_MB_2U(SCH_1):PAGE246
 C1331    1      A Q_CAP_C0805-10UF,16V,10%,X6S,CA    I45 @S9S_MB_2U_LIB.S9S_MB_2U(SCH_1):PAGE246
 PR678    1      A Q_RES_0402LF-0,5%,1/16W,CHIP,CA     I4 @S9S_MB_2U_LIB.S9S_MB_2U(SCH_1):PAGE280
 PR402    1      A Q_RES_0402LF-0,5%,1/16W,CHIP,CA    I26 @S9S_MB_2U_LIB.S9S_MB_2U(SCH_1):PAGE253
 PR442    1      A Q_RES_0402LF-0,5%,1/16W,CHIP,CA     I8 @S9S_MB_2U_LIB.S9S_MB_2U(SCH_1):PAGE262
 PR701    1      A Q_RES_0402LF-0,5%,1/16W,CHIP,CA    I32 @S9S_MB_2U_LIB.S9S_MB_2U(SCH_1):PAGE275
 PR702    1      A Q_RES_0402LF-0,5%,1/16W,CHIP,CA    I13 @S9S_MB_2U_LIB.S9S_MB_2U(SCH_1):PAGE275
 PR447    1      A Q_RES_0402LF-0,5%,1/16W,CHIP,CA     I4 @S9S_MB_2U_LIB.S9S_MB_2U(SCH_1):PAGE257
 PR444    1      A Q_RES_0402LF-0,5%,1/16W,CHIP,CA     I9 @S9S_MB_2U_LIB.S9S_MB_2U(SCH_1):PAGE257
 PR639    1      A Q_RES_0402LF-0,5%,1/16W,CHIP,CA    I26 @S9S_MB_2U_LIB.S9S_MB_2U(SCH_1):PAGE271
 R4638    1      A Q_RES_1206LF-243,1%,1/4W,CHIP,A    I77 @S9S_MB_2U_LIB.S9S_MB_2U(SCH_1):PAGE246
 R4639    1      A Q_RES_1206LF-243,1%,1/4W,CHIP,A    I78 @S9S_MB_2U_LIB.S9S_MB_2U(SCH_1):PAGE246
 R4640    1      A Q_RES_1206LF-243,1%,1/4W,CHIP,A    I79 @S9S_MB_2U_LIB.S9S_MB_2U(SCH_1):PAGE246
 R4641    1      A Q_RES_1206LF-243,1%,1/4W,CHIP,A    I80 @S9S_MB_2U_LIB.S9S_MB_2U(SCH_1):PAGE246
 R4679    1      A Q_RES_0402LF-10K,1%,1/16W,CHIPA    I96 @S9S_MB_2U_LIB.S9S_MB_2U(SCH_1):PAGE246

P5V_ADC @S9S_MB_2U_LIB.S9S_MB_2U(SCH_1):P5V_ADC
 R1791    1      A Q_RES_0402LF-9.09K,1%,1/16W,CHA   I163 @S9S_MB_2U_LIB.S9S_MB_2U(SCH_1):PAGE239
 R3005    2      B Q_RES_0402LF-18K,1%,1/16W,CHIPA   I168 @S9S_MB_2U_LIB.S9S_MB_2U(SCH_1):PAGE239
 R3685    1      A Q_RES_0402LF-0,5%,1/16W,EMPTY,A   I190 @S9S_MB_2U_LIB.S9S_MB_2U(SCH_1):PAGE239
 R3686    1      A Q_RES_0402LF-0,5%,1/16W,CHIP,CA   I191 @S9S_MB_2U_LIB.S9S_MB_2U(SCH_1):PAGE239

P5V_ADC_MAM @S9S_MB_2U_LIB.S9S_MB_2U(SCH_1):P5V_ADC_MAM
  U193    8   AIN3 MAX11617EEET-MAX11617EEE+T,SMLA    I57 @S9S_MB_2U_LIB.S9S_MB_2U(SCH_1):PAGE239
 C2044    1      A Q_CAP_0402-100PF,50V,5%,EMPTY,A   I187 @S9S_MB_2U_LIB.S9S_MB_2U(SCH_1):PAGE239
 R3685    2      B Q_RES_0402LF-0,5%,1/16W,EMPTY,A   I190 @S9S_MB_2U_LIB.S9S_MB_2U(SCH_1):PAGE239

P5V_ADC_TIC @S9S_MB_2U_LIB.S9S_MB_2U(SCH_1):P5V_ADC_TIC
  U269   13    IN3 ADC128D818CIMTXNOPB-ADC128D818A   I103 @S9S_MB_2U_LIB.S9S_MB_2U(SCH_1):PAGE239
 C2049    1      A Q_CAP_0402-0.1UF,25V,10%,X7R,CA   I188 @S9S_MB_2U_LIB.S9S_MB_2U(SCH_1):PAGE239
 R3686    2      B Q_RES_0402LF-0,5%,1/16W,CHIP,CA   I191 @S9S_MB_2U_LIB.S9S_MB_2U(SCH_1):PAGE239

P5V_AUX @S9S_MB_2U_LIB.S9S_MB_2U(SCH_1):P5V_AUX
PC1856    1      A Q_CAP_C0805-22UF,10V,20%,X6S,CA    I34 @S9S_MB_2U_LIB.S9S_MB_2U(SCH_1):PAGE244
 R3101    2      B Q_RES_0402LF-470,1%,1/16W,CHIPA    I62 @S9S_MB_2U_LIB.S9S_MB_2U(SCH_1):PAGE242
  PL65    2      2 Q_INDUCTOR_SMLF-4.7UH,IND,CV-4A    I30 @S9S_MB_2U_LIB.S9S_MB_2U(SCH_1):PAGE244
 C1042    1      A Q_CAP_C0402-100NF,50V,10%,X7R,A    I11 @S9S_MB_2U_LIB.S9S_MB_2U(SCH_1):PAGE246
 C1170    1      A Q_CAP_C0805-10UF,16V,10%,X6S,CA    I24 @S9S_MB_2U_LIB.S9S_MB_2U(SCH_1):PAGE246
 C1171    1      A Q_CAP_C0805-10UF,16V,10%,EMPTYA    I25 @S9S_MB_2U_LIB.S9S_MB_2U(SCH_1):PAGE246
   Q57    5      5 MOSFET_NCH_1D3S-PSMNR58-30YLH,A    I30 @S9S_MB_2U_LIB.S9S_MB_2U(SCH_1):PAGE246
PC1877    2      B Q_CAP_0402-47PF,50V,5%,NPO,TMPA    I22 @S9S_MB_2U_LIB.S9S_MB_2U(SCH_1):PAGE244
PC1845    1      A Q_CAPP_SMLF-220UF,6.3V,20%,ALUA    I32 @S9S_MB_2U_LIB.S9S_MB_2U(SCH_1):PAGE244
PC1855    1      A Q_CAP_C0805-22UF,10V,20%,X6S,CA    I33 @S9S_MB_2U_LIB.S9S_MB_2U(SCH_1):PAGE244
PC1852    1      A Q_CAP_0402-0.1UF,25V,10%,X7R,CA    I36 @S9S_MB_2U_LIB.S9S_MB_2U(SCH_1):PAGE244
 PR396    1      A Q_RES_0402LF-0,5%,1/16W,EMPTY,A     I2 @S9S_MB_2U_LIB.S9S_MB_2U(SCH_1):PAGE249
  PR92    2      B Q_RES_0402LF-88.7K,1%,1/16W,CHA    I39 @S9S_MB_2U_LIB.S9S_MB_2U(SCH_1):PAGE244

P5V_AUX_CS @S9S_MB_2U_LIB.S9S_MB_2U(SCH_1):P5V_AUX_CS
  PR89    1      A Q_RES_0402LF-16.9K,1%,1/16W,CHA    I16 @S9S_MB_2U_LIB.S9S_MB_2U(SCH_1):PAGE244
 PU181    3     CS RS53318LR-RS53318LR,SMLF,IC,ALA    I20 @S9S_MB_2U_LIB.S9S_MB_2U(SCH_1):PAGE244

P5V_AUX_FB @S9S_MB_2U_LIB.S9S_MB_2U(SCH_1):P5V_AUX_FB
  PR91    1      A Q_RES_0402LF-11.8K,0.1%,1/16W,A    I25 @S9S_MB_2U_LIB.S9S_MB_2U(SCH_1):PAGE244
 PU181    7     FB RS53318LR-RS53318LR,SMLF,IC,ALA    I20 @S9S_MB_2U_LIB.S9S_MB_2U(SCH_1):PAGE244
PC1877    1      A Q_CAP_0402-47PF,50V,5%,NPO,TMPA    I22 @S9S_MB_2U_LIB.S9S_MB_2U(SCH_1):PAGE244
  PR92    1      A Q_RES_0402LF-88.7K,1%,1/16W,CHA    I39 @S9S_MB_2U_LIB.S9S_MB_2U(SCH_1):PAGE244

P5V_AUX_MODE @S9S_MB_2U_LIB.S9S_MB_2U(SCH_1):P5V_AUX_MODE
PR3337    1      A Q_RES_0402LF-0,5%,1/16W,CHIP,CA    I10 @S9S_MB_2U_LIB.S9S_MB_2U(SCH_1):PAGE244
 PU181    4   MODE RS53318LR-RS53318LR,SMLF,IC,ALA    I20 @S9S_MB_2U_LIB.S9S_MB_2U(SCH_1):PAGE244

P5V_AUX_REF @S9S_MB_2U_LIB.S9S_MB_2U(SCH_1):P5V_AUX_REF
 PU181    5    REF RS53318LR-RS53318LR,SMLF,IC,ALA    I20 @S9S_MB_2U_LIB.S9S_MB_2U(SCH_1):PAGE244
PC1853    1      A Q_CAP_0402-0.1UF,25V,10%,X7R,CA    I21 @S9S_MB_2U_LIB.S9S_MB_2U(SCH_1):PAGE244

P5V_AUX_VCC @S9S_MB_2U_LIB.S9S_MB_2U(SCH_1):P5V_AUX_VCC
 R2356    1      A Q_RES_0402LF-10K,1%,1/16W,CHIPA    I27 @S9S_MB_2U_LIB.S9S_MB_2U(SCH_1):PAGE244
 R2343    1      A Q_RES_0402LF-10K,1%,1/16W,EMPTA    I41 @S9S_MB_2U_LIB.S9S_MB_2U(SCH_1):PAGE314
PC1848    1      A Q_CAP_C0402-1UF,25V,10%,X6S,CHA     I8 @S9S_MB_2U_LIB.S9S_MB_2U(SCH_1):PAGE244
 PU181   19    VCC RS53318LR-RS53318LR,SMLF,IC,ALA    I20 @S9S_MB_2U_LIB.S9S_MB_2U(SCH_1):PAGE244

PCA9543_S3M_ADDR0 @S9S_MB_2U_LIB.S9S_MB_2U(SCH_1):PCA9543_S3M_ADDR0
 R2310    2      B Q_RES_0402LF-10K,1%,1/16W,EMPTA    I83 @S9S_MB_2U_LIB.S9S_MB_2U(SCH_1):PAGE224
 R2311    1      A Q_RES_0402LF-1K,1%,1/16W,CHIP,A    I86 @S9S_MB_2U_LIB.S9S_MB_2U(SCH_1):PAGE224
  U143    1     A0 PCA9545APW-PCA9545APW,SMLF,IC,A   I106 @S9S_MB_2U_LIB.S9S_MB_2U(SCH_1):PAGE224

PCA9543_S3M_ADDR1 @S9S_MB_2U_LIB.S9S_MB_2U(SCH_1):PCA9543_S3M_ADDR1
 R2308    2      B Q_RES_0402LF-10K,1%,1/16W,EMPTA    I84 @S9S_MB_2U_LIB.S9S_MB_2U(SCH_1):PAGE224
 R2309    1      A Q_RES_0402LF-1K,1%,1/16W,CHIP,A    I85 @S9S_MB_2U_LIB.S9S_MB_2U(SCH_1):PAGE224
  U143    2     A1 PCA9545APW-PCA9545APW,SMLF,IC,A   I106 @S9S_MB_2U_LIB.S9S_MB_2U(SCH_1):PAGE224

PCA9543_S3M_INT0_N @S9S_MB_2U_LIB.S9S_MB_2U(SCH_1):PCA9543_S3M_INT0_N
 R2315    2      B Q_RES_0402LF-10K,1%,1/16W,CHIPA   I103 @S9S_MB_2U_LIB.S9S_MB_2U(SCH_1):PAGE224
  U143    4  INT0# PCA9545APW-PCA9545APW,SMLF,IC,A   I106 @S9S_MB_2U_LIB.S9S_MB_2U(SCH_1):PAGE224

PCA9543_S3M_INT1_N @S9S_MB_2U_LIB.S9S_MB_2U(SCH_1):PCA9543_S3M_INT1_N
  U143    7  INT1# PCA9545APW-PCA9545APW,SMLF,IC,A   I106 @S9S_MB_2U_LIB.S9S_MB_2U(SCH_1):PAGE224
 R3127    2      B Q_RES_0402LF-10K,1%,1/16W,CHIPA   I109 @S9S_MB_2U_LIB.S9S_MB_2U(SCH_1):PAGE224

PCA9543_S3M_INT2_N @S9S_MB_2U_LIB.S9S_MB_2U(SCH_1):PCA9543_S3M_INT2_N
  U143   11  INT2# PCA9545APW-PCA9545APW,SMLF,IC,A   I106 @S9S_MB_2U_LIB.S9S_MB_2U(SCH_1):PAGE224
 R3130    2      B Q_RES_0402LF-10K,1%,1/16W,CHIPA   I110 @S9S_MB_2U_LIB.S9S_MB_2U(SCH_1):PAGE224

PCA9543_S3M_INT3_N @S9S_MB_2U_LIB.S9S_MB_2U(SCH_1):PCA9543_S3M_INT3_N
  U143   14  INT3# PCA9545APW-PCA9545APW,SMLF,IC,A   I106 @S9S_MB_2U_LIB.S9S_MB_2U(SCH_1):PAGE224
 R3131    2      B Q_RES_0402LF-10K,1%,1/16W,CHIPA   I111 @S9S_MB_2U_LIB.S9S_MB_2U(SCH_1):PAGE224

PCA9545_S3M_INT_N @S9S_MB_2U_LIB.S9S_MB_2U(SCH_1):PCA9545_S3M_INT_N
 R2312    2      B Q_RES_0402LF-10K,1%,1/16W,CHIPA   I101 @S9S_MB_2U_LIB.S9S_MB_2U(SCH_1):PAGE224
  U143   17   INT# PCA9545APW-PCA9545APW,SMLF,IC,A   I106 @S9S_MB_2U_LIB.S9S_MB_2U(SCH_1):PAGE224

PCA9548_PCIE0_ADDR0 @S9S_MB_2U_LIB.S9S_MB_2U(SCH_1):PCA9548_PCIE0_ADDR0
 R3709    1      A Q_RES_0402LF-1K,1%,1/16W,CHIP,A     I8 @S9S_MB_2U_LIB.S9S_MB_2U(SCH_1):PAGE221
 R3708    2      B Q_RES_0402LF-10K,1%,1/16W,EMPTA    I10 @S9S_MB_2U_LIB.S9S_MB_2U(SCH_1):PAGE221
   U39    1     A0 TCA9548APWR-TCA9548APWR,SMLF,IA   I103 @S9S_MB_2U_LIB.S9S_MB_2U(SCH_1):PAGE221

PCA9548_PCIE0_ADDR1 @S9S_MB_2U_LIB.S9S_MB_2U(SCH_1):PCA9548_PCIE0_ADDR1
 R3707    1      A Q_RES_0402LF-1K,1%,1/16W,CHIP,A     I6 @S9S_MB_2U_LIB.S9S_MB_2U(SCH_1):PAGE221
 R3706    2      B Q_RES_0402LF-10K,1%,1/16W,EMPTA     I9 @S9S_MB_2U_LIB.S9S_MB_2U(SCH_1):PAGE221
   U39    2     A1 TCA9548APWR-TCA9548APWR,SMLF,IA   I103 @S9S_MB_2U_LIB.S9S_MB_2U(SCH_1):PAGE221

PCA9548_PCIE0_ADDR2 @S9S_MB_2U_LIB.S9S_MB_2U(SCH_1):PCA9548_PCIE0_ADDR2
 R3704    1      A Q_RES_0402LF-1K,1%,1/16W,CHIP,A     I2 @S9S_MB_2U_LIB.S9S_MB_2U(SCH_1):PAGE221
 R3703    2      B Q_RES_0402LF-10K,1%,1/16W,EMPTA     I3 @S9S_MB_2U_LIB.S9S_MB_2U(SCH_1):PAGE221
   U39   21     A2 TCA9548APWR-TCA9548APWR,SMLF,IA   I103 @S9S_MB_2U_LIB.S9S_MB_2U(SCH_1):PAGE221

PCA9548_PCIE3_ADDR0 @S9S_MB_2U_LIB.S9S_MB_2U(SCH_1):PCA9548_PCIE3_ADDR0
  R540    2      B Q_RES_0402LF-10K,1%,1/16W,EMPTA    I10 @S9S_MB_2U_LIB.S9S_MB_2U(SCH_1):PAGE219
  R587    1      A Q_RES_0402LF-1K,1%,1/16W,CHIP,A     I8 @S9S_MB_2U_LIB.S9S_MB_2U(SCH_1):PAGE219
   U36    1     A0 TCA9548APWR-TCA9548APWR,SMLF,IA    I45 @S9S_MB_2U_LIB.S9S_MB_2U(SCH_1):PAGE219

PCA9548_PCIE3_ADDR1 @S9S_MB_2U_LIB.S9S_MB_2U(SCH_1):PCA9548_PCIE3_ADDR1
  R539    1      A Q_RES_0402LF-1K,1%,1/16W,CHIP,A     I6 @S9S_MB_2U_LIB.S9S_MB_2U(SCH_1):PAGE219
  R538    2      B Q_RES_0402LF-10K,1%,1/16W,EMPTA     I9 @S9S_MB_2U_LIB.S9S_MB_2U(SCH_1):PAGE219
   U36    2     A1 TCA9548APWR-TCA9548APWR,SMLF,IA    I45 @S9S_MB_2U_LIB.S9S_MB_2U(SCH_1):PAGE219

PCA9548_PCIE3_ADDR2 @S9S_MB_2U_LIB.S9S_MB_2U(SCH_1):PCA9548_PCIE3_ADDR2
  R537    1      A Q_RES_0402LF-1K,1%,1/16W,CHIP,A     I2 @S9S_MB_2U_LIB.S9S_MB_2U(SCH_1):PAGE219
  R536    2      B Q_RES_0402LF-10K,1%,1/16W,EMPTA     I3 @S9S_MB_2U_LIB.S9S_MB_2U(SCH_1):PAGE219
   U36   21     A2 TCA9548APWR-TCA9548APWR,SMLF,IA    I45 @S9S_MB_2U_LIB.S9S_MB_2U(SCH_1):PAGE219

PCH_PCIEUP_RCOMPN @S9S_MB_2U_LIB.S9S_MB_2U(SCH_1):PCH_PCIEUP_RCOMPN
  R495    2      B Q_RES_0402LF-100,1%,1/16W,CHIPA     I1 @S9S_MB_2U_LIB.S9S_MB_2U(SCH_1):PAGE173
    U4 AP31 PHY_PCIE3_RCOMPN EMMITSBURG_REV0P9-GFNOCPU04302A   I110 @S9S_MB_2U_LIB.S9S_MB_2U(SCH_1):PAGE173

PCH_PCIEUP_RCOMPP @S9S_MB_2U_LIB.S9S_MB_2U(SCH_1):PCH_PCIEUP_RCOMPP
  R495    1      A Q_RES_0402LF-100,1%,1/16W,CHIPA     I1 @S9S_MB_2U_LIB.S9S_MB_2U(SCH_1):PAGE173
    U4 AR29 PHY_PCIE3_RCOMPP EMMITSBURG_REV0P9-GFNOCPU04302A   I110 @S9S_MB_2U_LIB.S9S_MB_2U(SCH_1):PAGE173

PCIE_M2_SSD0_PRSNT_N @S9S_MB_2U_LIB.S9S_MB_2U(SCH_1):PCIE_M2_SSD0_PRSNT_N
  R478    2      B Q_RES_0402LF-4.7K,1%,1/16W,CHIA   I176 @S9S_MB_2U_LIB.S9S_MB_2U(SCH_1):PAGE182
   J59    1   GND1 SCONN75K_APCI0155P004A-SCONN75A   I178 @S9S_MB_2U_LIB.S9S_MB_2U(SCH_1):PAGE182
  U249   Y5  PB10C LCMXO3LF9400C5BG484C-LCMXO3LF-A     I1 @S9S_MB_2U_LIB.S9S_MB_2U(SCH_1):PAGE312

PDB_PRSNT_N @S9S_MB_2U_LIB.S9S_MB_2U(SCH_1):PDB_PRSNT_N
 R3907    1      A Q_RES_0402LF-33K,1%,1/16W,CHIPA     I4 @S9S_MB_2U_LIB.S9S_MB_2U(SCH_1):PAGE303
  U290    G      G MOSFET_NCH_GDS_ESD_PROTECTED-2A     I5 @S9S_MB_2U_LIB.S9S_MB_2U(SCH_1):PAGE303
 R3923    2      B Q_RES_0402LF-63.4K,1%,1/16W,CHA    I10 @S9S_MB_2U_LIB.S9S_MB_2U(SCH_1):PAGE303
 C1797    1      A Q_CAP_0402-0.1UF,25V,10%,X7R,CA     I3 @S9S_MB_2U_LIB.S9S_MB_2U(SCH_1):PAGE303
JP4003    2      2 CONN3_210HP1030BR1-CONN3_210-HB    I12 @S9S_MB_2U_LIB.S9S_MB_2U(SCH_1):PAGE303
   J45   D3     D3 CONN60_101062636003K02LF-CONN6A    I12 @S9S_MB_2U_LIB.S9S_MB_2U(SCH_1):PAGE233
 C2294    1      A Q_CAP_0402-0.1UF,25V,10%,EMPTYA    I55 @S9S_MB_2U_LIB.S9S_MB_2U(SCH_1):PAGE233

PD_74CB_A9 @S9S_MB_2U_LIB.S9S_MB_2U(SCH_1):PD_74CB_A9
   U17    9     3A 74CBTLV3126PW-74CBTLV3126PW,SMA    I80 @S9S_MB_2U_LIB.S9S_MB_2U(SCH_1):PAGE134
  R746    1      A Q_RES_0402LF-0,5%,1/16W,CHIP,CA    I90 @S9S_MB_2U_LIB.S9S_MB_2U(SCH_1):PAGE134

PD_BIOS_IMAGE_SWAP_N @S9S_MB_2U_LIB.S9S_MB_2U(SCH_1):PD_BIOS_IMAGE_SWAP_N
 R1324    2      B Q_RES_0402LF-1K,1%,1/16W,CHIP,A    I87 @S9S_MB_2U_LIB.S9S_MB_2U(SCH_1):PAGE189
  J104    7      7 CONN14_210HP207GBR1-CONN14_210A   I134 @S9S_MB_2U_LIB.S9S_MB_2U(SCH_1):PAGE189

PD_CHA_CPU0_DIMM1_SAA @S9S_MB_2U_LIB.S9S_MB_2U(SCH_1):PD_CHA_CPU0_DIMM1_SAA
   R26    1      A Q_RES_0402LF-10K,1%,1/16W,CHIPA   I196 @S9S_MB_2U_LIB.S9S_MB_2U(SCH_1):PAGE82
    J1  148    HSA SCONN288_ADR50017P130CC-SCONN2A   I198 @S9S_MB_2U_LIB.S9S_MB_2U(SCH_1):PAGE82

PD_CHA_CPU0_DIMM2_SAA @S9S_MB_2U_LIB.S9S_MB_2U(SCH_1):PD_CHA_CPU0_DIMM2_SAA
   R27    1      A Q_RES_0402LF-15.4K,1%,1/16W,CHA    I10 @S9S_MB_2U_LIB.S9S_MB_2U(SCH_1):PAGE83
    J2  148    HSA SCONN288_ADR50017P087CC-SCONN2A   I177 @S9S_MB_2U_LIB.S9S_MB_2U(SCH_1):PAGE83

PD_CHA_CPU1_DIMM1_SAA @S9S_MB_2U_LIB.S9S_MB_2U(SCH_1):PD_CHA_CPU1_DIMM1_SAA
   R42    1      A Q_RES_0402LF-10K,1%,1/16W,CHIPA    I11 @S9S_MB_2U_LIB.S9S_MB_2U(SCH_1):PAGE98
   J17  148    HSA SCONN288_ADR50017P130CC-SCONN2A    I12 @S9S_MB_2U_LIB.S9S_MB_2U(SCH_1):PAGE98

PD_CHA_CPU1_DIMM2_SAA @S9S_MB_2U_LIB.S9S_MB_2U(SCH_1):PD_CHA_CPU1_DIMM2_SAA
   R43    1      A Q_RES_0402LF-15.4K,1%,1/16W,CHA     I2 @S9S_MB_2U_LIB.S9S_MB_2U(SCH_1):PAGE99
   J18  148    HSA SCONN288_ADR50017P087CC-SCONN2A    I24 @S9S_MB_2U_LIB.S9S_MB_2U(SCH_1):PAGE99

PD_CHB_CPU0_DIMM1_SAA @S9S_MB_2U_LIB.S9S_MB_2U(SCH_1):PD_CHB_CPU0_DIMM1_SAA
   R28    1      A Q_RES_0402LF-23.2K,1%,1/16W,CHA    I10 @S9S_MB_2U_LIB.S9S_MB_2U(SCH_1):PAGE84
    J3  148    HSA SCONN288_ADR50017P130CC-SCONN2A   I180 @S9S_MB_2U_LIB.S9S_MB_2U(SCH_1):PAGE84

PD_CHB_CPU0_DIMM2_SAA @S9S_MB_2U_LIB.S9S_MB_2U(SCH_1):PD_CHB_CPU0_DIMM2_SAA
   R29    1      A Q_RES_0402LF-35.7K,1%,1/16W,CHA     I1 @S9S_MB_2U_LIB.S9S_MB_2U(SCH_1):PAGE85
    J4  148    HSA SCONN288_ADR50017P087CC-SCONN2A    I23 @S9S_MB_2U_LIB.S9S_MB_2U(SCH_1):PAGE85

PD_CHB_CPU1_DIMM1_SAA @S9S_MB_2U_LIB.S9S_MB_2U(SCH_1):PD_CHB_CPU1_DIMM1_SAA
   R44    1      A Q_RES_0402LF-23.2K,1%,1/16W,CHA     I3 @S9S_MB_2U_LIB.S9S_MB_2U(SCH_1):PAGE100
   J19  148    HSA SCONN288_ADR50017P130CC-SCONN2A    I25 @S9S_MB_2U_LIB.S9S_MB_2U(SCH_1):PAGE100

PD_CHB_CPU1_DIMM2_SAA @S9S_MB_2U_LIB.S9S_MB_2U(SCH_1):PD_CHB_CPU1_DIMM2_SAA
   R45    1      A Q_RES_0402LF-35.7K,1%,1/16W,CHA    I46 @S9S_MB_2U_LIB.S9S_MB_2U(SCH_1):PAGE101
   J20  148    HSA SCONN288_ADR50017P087CC-SCONN2A    I47 @S9S_MB_2U_LIB.S9S_MB_2U(SCH_1):PAGE101

PD_CHC_CPU0_DIMM1_SAA @S9S_MB_2U_LIB.S9S_MB_2U(SCH_1):PD_CHC_CPU0_DIMM1_SAA
   R30    1      A Q_RES_0402LF-54.9K,1%,1/16W,CHA     I3 @S9S_MB_2U_LIB.S9S_MB_2U(SCH_1):PAGE86
    J5  148    HSA SCONN288_ADR50017P130CC-SCONN2A    I24 @S9S_MB_2U_LIB.S9S_MB_2U(SCH_1):PAGE86

PD_CHC_CPU0_DIMM2_SAA @S9S_MB_2U_LIB.S9S_MB_2U(SCH_1):PD_CHC_CPU0_DIMM2_SAA
   R31    1      A Q_RES_0402LF-84.5K,1%,1/16W,CHA    I45 @S9S_MB_2U_LIB.S9S_MB_2U(SCH_1):PAGE87
    J6  148    HSA SCONN288_ADR50017P087CC-SCONN2A    I46 @S9S_MB_2U_LIB.S9S_MB_2U(SCH_1):PAGE87

PD_CHC_CPU1_DIMM1_SAA @S9S_MB_2U_LIB.S9S_MB_2U(SCH_1):PD_CHC_CPU1_DIMM1_SAA
   R46    1      A Q_RES_0402LF-54.9K,1%,1/16W,CHA     I2 @S9S_MB_2U_LIB.S9S_MB_2U(SCH_1):PAGE102
   J21  148    HSA SCONN288_ADR50017P130CC-SCONN2A    I13 @S9S_MB_2U_LIB.S9S_MB_2U(SCH_1):PAGE102

PD_CHC_CPU1_DIMM2_SAA @S9S_MB_2U_LIB.S9S_MB_2U(SCH_1):PD_CHC_CPU1_DIMM2_SAA
   R47    1      A Q_RES_0402LF-84.5K,1%,1/16W,CHA     I2 @S9S_MB_2U_LIB.S9S_MB_2U(SCH_1):PAGE103
   J22  148    HSA SCONN288_ADR50017P087CC-SCONN2A    I51 @S9S_MB_2U_LIB.S9S_MB_2U(SCH_1):PAGE103

PD_CHD_CPU0_DIMM1_SAA @S9S_MB_2U_LIB.S9S_MB_2U(SCH_1):PD_CHD_CPU0_DIMM1_SAA
   R32    1      A Q_RES_0402LF-127K,1%,1/16W,CHIA     I2 @S9S_MB_2U_LIB.S9S_MB_2U(SCH_1):PAGE88
    J7  148    HSA SCONN288_ADR50017P130CC-SCONN2A    I12 @S9S_MB_2U_LIB.S9S_MB_2U(SCH_1):PAGE88

PD_CHD_CPU0_DIMM2_SAA @S9S_MB_2U_LIB.S9S_MB_2U(SCH_1):PD_CHD_CPU0_DIMM2_SAA
   R33    1      A Q_RES_0402LF-196K,1%,1/16W,CHIA     I2 @S9S_MB_2U_LIB.S9S_MB_2U(SCH_1):PAGE89
    J8  148    HSA SCONN288_ADR50017P087CC-SCONN2A    I50 @S9S_MB_2U_LIB.S9S_MB_2U(SCH_1):PAGE89

PD_CHD_CPU1_DIMM1_SAA @S9S_MB_2U_LIB.S9S_MB_2U(SCH_1):PD_CHD_CPU1_DIMM1_SAA
   R48    1      A Q_RES_0402LF-127K,1%,1/16W,CHIA     I2 @S9S_MB_2U_LIB.S9S_MB_2U(SCH_1):PAGE104
   J23  148    HSA SCONN288_ADR50017P130CC-SCONN2A    I25 @S9S_MB_2U_LIB.S9S_MB_2U(SCH_1):PAGE104

PD_CHD_CPU1_DIMM2_SAA @S9S_MB_2U_LIB.S9S_MB_2U(SCH_1):PD_CHD_CPU1_DIMM2_SAA
   R80    1      A Q_RES_0402LF-196K,1%,1/16W,CHIA     I2 @S9S_MB_2U_LIB.S9S_MB_2U(SCH_1):PAGE105
   J24  148    HSA SCONN288_ADR50017P087CC-SCONN2A   I178 @S9S_MB_2U_LIB.S9S_MB_2U(SCH_1):PAGE105

PD_CHE_CPU0_DIMM1_SAA @S9S_MB_2U_LIB.S9S_MB_2U(SCH_1):PD_CHE_CPU0_DIMM1_SAA
   R34    1      A Q_RES_0402LF-10K,1%,1/16W,CHIPA    I11 @S9S_MB_2U_LIB.S9S_MB_2U(SCH_1):PAGE90
    J9  148    HSA SCONN288_ADR50017P130CC-SCONN2A    I12 @S9S_MB_2U_LIB.S9S_MB_2U(SCH_1):PAGE90

PD_CHE_CPU0_DIMM2_SAA @S9S_MB_2U_LIB.S9S_MB_2U(SCH_1):PD_CHE_CPU0_DIMM2_SAA
   R35    1      A Q_RES_0402LF-15.4K,1%,1/16W,CHA     I2 @S9S_MB_2U_LIB.S9S_MB_2U(SCH_1):PAGE91
   J10  148    HSA SCONN288_ADR50017P087CC-SCONN2A    I13 @S9S_MB_2U_LIB.S9S_MB_2U(SCH_1):PAGE91

PD_CHE_CPU1_DIMM1_SAA @S9S_MB_2U_LIB.S9S_MB_2U(SCH_1):PD_CHE_CPU1_DIMM1_SAA
   R79    1      A Q_RES_0402LF-10K,1%,1/16W,CHIPA     I2 @S9S_MB_2U_LIB.S9S_MB_2U(SCH_1):PAGE106
   J25  148    HSA SCONN288_ADR50017P130CC-SCONN2A   I180 @S9S_MB_2U_LIB.S9S_MB_2U(SCH_1):PAGE106

PD_CHE_CPU1_DIMM2_SAA @S9S_MB_2U_LIB.S9S_MB_2U(SCH_1):PD_CHE_CPU1_DIMM2_SAA
   R78    1      A Q_RES_0402LF-15.4K,1%,1/16W,CHA     I2 @S9S_MB_2U_LIB.S9S_MB_2U(SCH_1):PAGE107
   J26  148    HSA SCONN288_ADR50017P087CC-SCONN2A   I180 @S9S_MB_2U_LIB.S9S_MB_2U(SCH_1):PAGE107

PD_CHF_CPU0_DIMM1_SAA @S9S_MB_2U_LIB.S9S_MB_2U(SCH_1):PD_CHF_CPU0_DIMM1_SAA
   R36    1      A Q_RES_0402LF-23.2K,1%,1/16W,CHA     I2 @S9S_MB_2U_LIB.S9S_MB_2U(SCH_1):PAGE92
   J11  148    HSA SCONN288_ADR50017P130CC-SCONN2A    I25 @S9S_MB_2U_LIB.S9S_MB_2U(SCH_1):PAGE92

PD_CHF_CPU0_DIMM2_SAA @S9S_MB_2U_LIB.S9S_MB_2U(SCH_1):PD_CHF_CPU0_DIMM2_SAA
   R37    1      A Q_RES_0402LF-35.7K,1%,1/16W,CHA     I2 @S9S_MB_2U_LIB.S9S_MB_2U(SCH_1):PAGE93
   J12  148    HSA SCONN288_ADR50017P087CC-SCONN2A    I24 @S9S_MB_2U_LIB.S9S_MB_2U(SCH_1):PAGE93

PD_CHF_CPU1_DIMM1_SAA @S9S_MB_2U_LIB.S9S_MB_2U(SCH_1):PD_CHF_CPU1_DIMM1_SAA
   R77    1      A Q_RES_0402LF-23.2K,1%,1/16W,CHA    I10 @S9S_MB_2U_LIB.S9S_MB_2U(SCH_1):PAGE108
   J27  148    HSA SCONN288_ADR50017P130CC-SCONN2A   I179 @S9S_MB_2U_LIB.S9S_MB_2U(SCH_1):PAGE108

PD_CHF_CPU1_DIMM2_SAA @S9S_MB_2U_LIB.S9S_MB_2U(SCH_1):PD_CHF_CPU1_DIMM2_SAA
   R76    1      A Q_RES_0402LF-35.7K,1%,1/16W,CHA    I46 @S9S_MB_2U_LIB.S9S_MB_2U(SCH_1):PAGE109
   J28  148    HSA SCONN288_ADR50017P087CC-SCONN2A    I47 @S9S_MB_2U_LIB.S9S_MB_2U(SCH_1):PAGE109

PD_CHG_CPU0_DIMM1_SAA @S9S_MB_2U_LIB.S9S_MB_2U(SCH_1):PD_CHG_CPU0_DIMM1_SAA
   R38    1      A Q_RES_0402LF-54.9K,1%,1/16W,CHA    I10 @S9S_MB_2U_LIB.S9S_MB_2U(SCH_1):PAGE94
   J13  148    HSA SCONN288_ADR50017P130CC-SCONN2A    I11 @S9S_MB_2U_LIB.S9S_MB_2U(SCH_1):PAGE94

PD_CHG_CPU0_DIMM2_SAA @S9S_MB_2U_LIB.S9S_MB_2U(SCH_1):PD_CHG_CPU0_DIMM2_SAA
   R39    1      A Q_RES_0402LF-84.5K,1%,1/16W,CHA    I46 @S9S_MB_2U_LIB.S9S_MB_2U(SCH_1):PAGE95
   J14  148    HSA SCONN288_ADR50017P087CC-SCONN2A    I47 @S9S_MB_2U_LIB.S9S_MB_2U(SCH_1):PAGE95

PD_CHG_CPU1_DIMM1_SAA @S9S_MB_2U_LIB.S9S_MB_2U(SCH_1):PD_CHG_CPU1_DIMM1_SAA
   R75    1      A Q_RES_0402LF-54.9K,1%,1/16W,CHA    I47 @S9S_MB_2U_LIB.S9S_MB_2U(SCH_1):PAGE110
   J29  148    HSA SCONN288_ADR50017P130CC-SCONN2A   I179 @S9S_MB_2U_LIB.S9S_MB_2U(SCH_1):PAGE110

PD_CHG_CPU1_DIMM2_SAA @S9S_MB_2U_LIB.S9S_MB_2U(SCH_1):PD_CHG_CPU1_DIMM2_SAA
   R74    1      A Q_RES_0402LF-84.5K,1%,1/16W,CHA     I5 @S9S_MB_2U_LIB.S9S_MB_2U(SCH_1):PAGE111
   J30  148    HSA SCONN288_ADR50017P087CC-SCONN2A   I179 @S9S_MB_2U_LIB.S9S_MB_2U(SCH_1):PAGE111

PD_CHH_CPU0_DIMM1_SAA @S9S_MB_2U_LIB.S9S_MB_2U(SCH_1):PD_CHH_CPU0_DIMM1_SAA
   R40    1      A Q_RES_0402LF-127K,1%,1/16W,CHIA    I47 @S9S_MB_2U_LIB.S9S_MB_2U(SCH_1):PAGE96
   J15  148    HSA SCONN288_ADR50017P130CC-SCONN2A    I48 @S9S_MB_2U_LIB.S9S_MB_2U(SCH_1):PAGE96

PD_CHH_CPU0_DIMM2_SAA @S9S_MB_2U_LIB.S9S_MB_2U(SCH_1):PD_CHH_CPU0_DIMM2_SAA
   R41    1      A Q_RES_0402LF-196K,1%,1/16W,CHIA     I5 @S9S_MB_2U_LIB.S9S_MB_2U(SCH_1):PAGE97
   J16  148    HSA SCONN288_ADR50017P087CC-SCONN2A     I6 @S9S_MB_2U_LIB.S9S_MB_2U(SCH_1):PAGE97

PD_CHH_CPU1_DIMM1_SAA @S9S_MB_2U_LIB.S9S_MB_2U(SCH_1):PD_CHH_CPU1_DIMM1_SAA
   R73    1      A Q_RES_0402LF-127K,1%,1/16W,CHIA     I3 @S9S_MB_2U_LIB.S9S_MB_2U(SCH_1):PAGE112
   J31  148    HSA SCONN288_ADR50017P130CC-SCONN2A   I180 @S9S_MB_2U_LIB.S9S_MB_2U(SCH_1):PAGE112

PD_CHH_CPU1_DIMM2_SAA @S9S_MB_2U_LIB.S9S_MB_2U(SCH_1):PD_CHH_CPU1_DIMM2_SAA
   R72    1      A Q_RES_0402LF-196K,1%,1/16W,CHIA     I2 @S9S_MB_2U_LIB.S9S_MB_2U(SCH_1):PAGE113
   J32  148    HSA SCONN288_ADR50017P087CC-SCONN2A   I179 @S9S_MB_2U_LIB.S9S_MB_2U(SCH_1):PAGE113

PD_CK440_SBI_CLK @S9S_MB_2U_LIB.S9S_MB_2U(SCH_1):PD_CK440_SBI_CLK
   U13  A54 SBI_CLK 9SQ440NQQI8-9SQ440NQQI8,SMLF,IA   I180 @S9S_MB_2U_LIB.S9S_MB_2U(SCH_1):PAGE197
 R1462    1      A Q_RES_0402LF-1K,1%,1/16W,CHIP,A   I274 @S9S_MB_2U_LIB.S9S_MB_2U(SCH_1):PAGE197

PD_CK440_SBI_DATA_IN @S9S_MB_2U_LIB.S9S_MB_2U(SCH_1):PD_CK440_SBI_DATA_IN
   U13  B43 SBI_IN 9SQ440NQQI8-9SQ440NQQI8,SMLF,IA   I180 @S9S_MB_2U_LIB.S9S_MB_2U(SCH_1):PAGE197
 R1500    1      A Q_RES_0402LF-4.75K,1%,1/16W,CHA   I271 @S9S_MB_2U_LIB.S9S_MB_2U(SCH_1):PAGE197

PD_CPU0_BIST_ENABLE @S9S_MB_2U_LIB.S9S_MB_2U(SCH_1):PD_CPU0_BIST_ENABLE
    U2 AT18 BIST_ENABLE SOCKET4677_AZIF0045P001C01CS-SA    I57 @S9S_MB_2U_LIB.S9S_MB_2U(SCH_1):PAGE13
 R4262    2      B Q_RES_0402LF-240,1%,1/16W,EMPTA   I215 @S9S_MB_2U_LIB.S9S_MB_2U(SCH_1):PAGE119
 R4263    1      A Q_RES_0402LF-240,1%,1/16W,EMPTA   I216 @S9S_MB_2U_LIB.S9S_MB_2U(SCH_1):PAGE119

PD_CPU0_DMIMODE_OVERRIDE @S9S_MB_2U_LIB.S9S_MB_2U(SCH_1):PD_CPU0_DMIMODE_OVERRIDE
    U2 AW17 DMIMODE_OVERRIDE SOCKET4677_AZIF0045P001C01CS-SA    I57 @S9S_MB_2U_LIB.S9S_MB_2U(SCH_1):PAGE13
  R294    2      B Q_RES_0402LF-240,1%,1/16W,EMPTA    I71 @S9S_MB_2U_LIB.S9S_MB_2U(SCH_1):PAGE119

PD_CPU0_ENH_MCECC_DIS @S9S_MB_2U_LIB.S9S_MB_2U(SCH_1):PD_CPU0_ENH_MCECC_DIS
    U2 CH22 RSVD96 SOCKET4677_AZIF0045P001C01CS-SA     I1 @S9S_MB_2U_LIB.S9S_MB_2U(SCH_1):PAGE14
  R295    2      B Q_RES_0402LF-240,1%,1/16W,EMPTA    I72 @S9S_MB_2U_LIB.S9S_MB_2U(SCH_1):PAGE119

PD_CPU0_ERRS_DIR @S9S_MB_2U_LIB.S9S_MB_2U(SCH_1):PD_CPU0_ERRS_DIR
 R4029    1      A Q_RES_0402LF-1K,1%,1/16W,CHIP,A    I77 @S9S_MB_2U_LIB.S9S_MB_2U(SCH_1):PAGE321
  U301    1    DIR GTL2014PW-GTL2014PW,SMLF,IC,ALA    I91 @S9S_MB_2U_LIB.S9S_MB_2U(SCH_1):PAGE321

PD_CPU0_TXT_PLTEN @S9S_MB_2U_LIB.S9S_MB_2U(SCH_1):PD_CPU0_TXT_PLTEN
    U2 CT20 TXT_PLTEN SOCKET4677_AZIF0045P001C01CS-SA    I57 @S9S_MB_2U_LIB.S9S_MB_2U(SCH_1):PAGE13
  R292    2      B Q_RES_0402LF-240,1%,1/16W,EMPTA   I196 @S9S_MB_2U_LIB.S9S_MB_2U(SCH_1):PAGE119
  R293    1      A Q_RES_0402LF-240,1%,1/16W,EMPTA   I211 @S9S_MB_2U_LIB.S9S_MB_2U(SCH_1):PAGE119

PD_CPU1_BIST_ENABLE @S9S_MB_2U_LIB.S9S_MB_2U(SCH_1):PD_CPU1_BIST_ENABLE
    U1 AT18 BIST_ENABLE SOCKET4677_AZIF0045P001C01CS-SA    I51 @S9S_MB_2U_LIB.S9S_MB_2U(SCH_1):PAGE44
 R4260    2      B Q_RES_0402LF-240,1%,1/16W,EMPTA   I219 @S9S_MB_2U_LIB.S9S_MB_2U(SCH_1):PAGE119
 R4261    1      A Q_RES_0402LF-240,1%,1/16W,EMPTA   I220 @S9S_MB_2U_LIB.S9S_MB_2U(SCH_1):PAGE119

PD_CPU1_DMIMODE_OVERRIDE @S9S_MB_2U_LIB.S9S_MB_2U(SCH_1):PD_CPU1_DMIMODE_OVERRIDE
    U1 AW17 DMIMODE_OVERRIDE SOCKET4677_AZIF0045P001C01CS-SA    I51 @S9S_MB_2U_LIB.S9S_MB_2U(SCH_1):PAGE44
  R290    2      B Q_RES_0402LF-240,1%,1/16W,CHIPA   I135 @S9S_MB_2U_LIB.S9S_MB_2U(SCH_1):PAGE119

PD_CPU1_ENH_MCECC_DIS @S9S_MB_2U_LIB.S9S_MB_2U(SCH_1):PD_CPU1_ENH_MCECC_DIS
    U1 CH22 RSVD96 SOCKET4677_AZIF0045P001C01CS-SA    I29 @S9S_MB_2U_LIB.S9S_MB_2U(SCH_1):PAGE45
  R291    2      B Q_RES_0402LF-240,1%,1/16W,EMPTA   I116 @S9S_MB_2U_LIB.S9S_MB_2U(SCH_1):PAGE119

PD_CPU1_ERRS_U306_DIR @S9S_MB_2U_LIB.S9S_MB_2U(SCH_1):PD_CPU1_ERRS_U306_DIR
  U306    1    DIR GTL2014PW-GTL2014PW,SMLF,IC,ALA    I80 @S9S_MB_2U_LIB.S9S_MB_2U(SCH_1):PAGE322
 R4055    1      A Q_RES_0402LF-1K,1%,1/16W,CHIP,A    I91 @S9S_MB_2U_LIB.S9S_MB_2U(SCH_1):PAGE322

PD_CPU1_PROCDIS_COD_GTL_N @S9S_MB_2U_LIB.S9S_MB_2U(SCH_1):PD_CPU1_PROCDIS_COD_GTL_N
    U1 DA52 PROCDIS_N SOCKET4677_AZIF0045P001C01CS-SA    I51 @S9S_MB_2U_LIB.S9S_MB_2U(SCH_1):PAGE44
 R1270    1      A Q_RES_0402LF-240,1%,1/16W,EMPTA    I55 @S9S_MB_2U_LIB.S9S_MB_2U(SCH_1):PAGE44

PD_CPU1_TXT_PLTEN @S9S_MB_2U_LIB.S9S_MB_2U(SCH_1):PD_CPU1_TXT_PLTEN
    U1 CT20 TXT_PLTEN SOCKET4677_AZIF0045P001C01CS-SA    I51 @S9S_MB_2U_LIB.S9S_MB_2U(SCH_1):PAGE44
  R288    2      B Q_RES_0402LF-240,1%,1/16W,EMPTA   I224 @S9S_MB_2U_LIB.S9S_MB_2U(SCH_1):PAGE119
  R289    1      A Q_RES_0402LF-240,1%,1/16W,EMPTA   I225 @S9S_MB_2U_LIB.S9S_MB_2U(SCH_1):PAGE119

PD_DB2000_SMB_SA0 @S9S_MB_2U_LIB.S9S_MB_2U(SCH_1):PD_DB2000_SMB_SA0
   U38   B4 ^VSADR0_TRI 9QXL2001BNHGI8-9QXL2001BNHGI8,A   I119 @S9S_MB_2U_LIB.S9S_MB_2U(SCH_1):PAGE195
  R569    2      B Q_RES_0402LF-4.7K,1%,1/16W,EMPA   I185 @S9S_MB_2U_LIB.S9S_MB_2U(SCH_1):PAGE195
  R570    1      A Q_RES_0402LF-4.7K,1%,1/16W,CHIA   I187 @S9S_MB_2U_LIB.S9S_MB_2U(SCH_1):PAGE195

PD_DB2000_SMB_SA1 @S9S_MB_2U_LIB.S9S_MB_2U(SCH_1):PD_DB2000_SMB_SA1
   U38   B8 ^VSADR1_TRI 9QXL2001BNHGI8-9QXL2001BNHGI8,A   I119 @S9S_MB_2U_LIB.S9S_MB_2U(SCH_1):PAGE195
  R568    1      A Q_RES_0402LF-4.7K,1%,1/16W,CHIA   I178 @S9S_MB_2U_LIB.S9S_MB_2U(SCH_1):PAGE195
  R567    2      B Q_RES_0402LF-4.7K,1%,1/16W,EMPA   I179 @S9S_MB_2U_LIB.S9S_MB_2U(SCH_1):PAGE195

PD_EXT_CLK_SEL_CPU0 @S9S_MB_2U_LIB.S9S_MB_2U(SCH_1):PD_EXT_CLK_SEL_CPU0
    U2 BY24 RSVD76 SOCKET4677_AZIF0045P001C01CS-SA    I57 @S9S_MB_2U_LIB.S9S_MB_2U(SCH_1):PAGE13
 R1237    2      B Q_RES_0402LF-240,1%,1/16W,EMPTA   I160 @S9S_MB_2U_LIB.S9S_MB_2U(SCH_1):PAGE119

PD_EXT_CLK_SEL_CPU1 @S9S_MB_2U_LIB.S9S_MB_2U(SCH_1):PD_EXT_CLK_SEL_CPU1
    U1 BY24 RSVD76 SOCKET4677_AZIF0045P001C01CS-SA    I51 @S9S_MB_2U_LIB.S9S_MB_2U(SCH_1):PAGE44
 R3024    2      B Q_RES_0402LF-240,1%,1/16W,EMPTA   I172 @S9S_MB_2U_LIB.S9S_MB_2U(SCH_1):PAGE119

PD_FORCE_PWRON @S9S_MB_2U_LIB.S9S_MB_2U(SCH_1):PD_FORCE_PWRON
  JP15    3      3 CONN3_210HP1030BR1-CONN3_210-HB   I187 @S9S_MB_2U_LIB.S9S_MB_2U(SCH_1):PAGE312
 R1495    1      A Q_RES_0402LF-10K,1%,1/16W,CHIPA   I190 @S9S_MB_2U_LIB.S9S_MB_2U(SCH_1):PAGE312

PD_GPP_I_13 @S9S_MB_2U_LIB.S9S_MB_2U(SCH_1):PD_GPP_I_13
    U4   N2 GPP_I_13_HDA_RST_N EMMITSBURG_REV0P9-GFNOCPU04302A    I22 @S9S_MB_2U_LIB.S9S_MB_2U(SCH_1):PAGE176
 R4565    1      A Q_RES_0402LF-10K,1%,1/16W,CHIPA   I240 @S9S_MB_2U_LIB.S9S_MB_2U(SCH_1):PAGE176

PD_GPP_I_14 @S9S_MB_2U_LIB.S9S_MB_2U(SCH_1):PD_GPP_I_14
    U4   P1 GPP_I_14_HDA_SYNC EMMITSBURG_REV0P9-GFNOCPU04302A    I22 @S9S_MB_2U_LIB.S9S_MB_2U(SCH_1):PAGE176
 R4564    1      A Q_RES_0402LF-10K,1%,1/16W,CHIPA   I239 @S9S_MB_2U_LIB.S9S_MB_2U(SCH_1):PAGE176

PD_GPP_I_15 @S9S_MB_2U_LIB.S9S_MB_2U(SCH_1):PD_GPP_I_15
    U4   R2 GPP_I_15_HDA_SDO EMMITSBURG_REV0P9-GFNOCPU04302A    I22 @S9S_MB_2U_LIB.S9S_MB_2U(SCH_1):PAGE176
 R4109    1      A Q_RES_0402LF-10K,1%,1/16W,CHIPA   I195 @S9S_MB_2U_LIB.S9S_MB_2U(SCH_1):PAGE176

PD_GPP_I_16 @S9S_MB_2U_LIB.S9S_MB_2U(SCH_1):PD_GPP_I_16
    U4   U1 GPP_I_16_HDA_SDI_0 EMMITSBURG_REV0P9-GFNOCPU04302A    I22 @S9S_MB_2U_LIB.S9S_MB_2U(SCH_1):PAGE176
 R4108    1      A Q_RES_0402LF-10K,1%,1/16W,CHIPA   I196 @S9S_MB_2U_LIB.S9S_MB_2U(SCH_1):PAGE176

PD_GPP_I_17 @S9S_MB_2U_LIB.S9S_MB_2U(SCH_1):PD_GPP_I_17
    U4   V4 GPP_I_17_HDA_SDI_1 EMMITSBURG_REV0P9-GFNOCPU04302A    I22 @S9S_MB_2U_LIB.S9S_MB_2U(SCH_1):PAGE176
 R4107    1      A Q_RES_0402LF-10K,1%,1/16W,CHIPA   I197 @S9S_MB_2U_LIB.S9S_MB_2U(SCH_1):PAGE176

PD_GPP_M_15 @S9S_MB_2U_LIB.S9S_MB_2U(SCH_1):PD_GPP_M_15
    U4   T8 GPP_M_15 EMMITSBURG_REV0P9-GFNOCPU04302A    I22 @S9S_MB_2U_LIB.S9S_MB_2U(SCH_1):PAGE176
 R4105    1      A Q_RES_0402LF-10K,1%,1/16W,CHIPA   I183 @S9S_MB_2U_LIB.S9S_MB_2U(SCH_1):PAGE176

PD_GPP_M_16 @S9S_MB_2U_LIB.S9S_MB_2U(SCH_1):PD_GPP_M_16
    U4  N10 GPP_M_16 EMMITSBURG_REV0P9-GFNOCPU04302A    I22 @S9S_MB_2U_LIB.S9S_MB_2U(SCH_1):PAGE176
 R4104    1      A Q_RES_0402LF-10K,1%,1/16W,CHIPA   I185 @S9S_MB_2U_LIB.S9S_MB_2U(SCH_1):PAGE176

PD_GPP_M_17 @S9S_MB_2U_LIB.S9S_MB_2U(SCH_1):PD_GPP_M_17
    U4  W13 GPP_M_17 EMMITSBURG_REV0P9-GFNOCPU04302A    I22 @S9S_MB_2U_LIB.S9S_MB_2U(SCH_1):PAGE176
 R4103    1      A Q_RES_0402LF-10K,1%,1/16W,CHIPA   I186 @S9S_MB_2U_LIB.S9S_MB_2U(SCH_1):PAGE176

PD_GPP_M_8 @S9S_MB_2U_LIB.S9S_MB_2U(SCH_1):PD_GPP_M_8
    U4  W10 GPP_M_8 EMMITSBURG_REV0P9-GFNOCPU04302A    I22 @S9S_MB_2U_LIB.S9S_MB_2U(SCH_1):PAGE176
 R4106    1      A Q_RES_0402LF-10K,1%,1/16W,CHIPA   I184 @S9S_MB_2U_LIB.S9S_MB_2U(SCH_1):PAGE176

PD_GTL2014_BMC_JTAG_DIR_0 @S9S_MB_2U_LIB.S9S_MB_2U(SCH_1):PD_GTL2014_BMC_JTAG_DIR_0
  U304    1    DIR GTL2014PW-GTL2014PW,SMLF,IC,ALA    I27 @S9S_MB_2U_LIB.S9S_MB_2U(SCH_1):PAGE322
 R4053    1      A Q_RES_0402LF-1K,1%,1/16W,CHIP,A    I66 @S9S_MB_2U_LIB.S9S_MB_2U(SCH_1):PAGE322

PD_GTL2014_BMC_JTAG_DIR_1 @S9S_MB_2U_LIB.S9S_MB_2U(SCH_1):PD_GTL2014_BMC_JTAG_DIR_1
  U305    1    DIR GTL2014PW-GTL2014PW,SMLF,IC,ALA    I44 @S9S_MB_2U_LIB.S9S_MB_2U(SCH_1):PAGE322
 R4054    1      A Q_RES_0402LF-1K,1%,1/16W,CHIP,A    I67 @S9S_MB_2U_LIB.S9S_MB_2U(SCH_1):PAGE322

PD_GTL2014_BMC_JTAG_DIR_2 @S9S_MB_2U_LIB.S9S_MB_2U(SCH_1):PD_GTL2014_BMC_JTAG_DIR_2
   U83    1    DIR GTL2014PW-GTL2014PW,SMLF,IC,ALA    I45 @S9S_MB_2U_LIB.S9S_MB_2U(SCH_1):PAGE226
 R2513    1      A Q_RES_0402LF-0,5%,1/16W,CHIP,CA    I90 @S9S_MB_2U_LIB.S9S_MB_2U(SCH_1):PAGE226

PD_GTL2014_BMC_JTAG_VREF_1 @S9S_MB_2U_LIB.S9S_MB_2U(SCH_1):PD_GTL2014_BMC_JTAG_VREF_1
 R1347    1      A Q_RES_0402LF-1K,1%,1/16W,CHIP,A    I10 @S9S_MB_2U_LIB.S9S_MB_2U(SCH_1):PAGE226
   U84    4   VREF GTL2014PW-GTL2014PW,SMLF,IC,ALA    I18 @S9S_MB_2U_LIB.S9S_MB_2U(SCH_1):PAGE226

PD_GTL2014_ERROR_B0 @S9S_MB_2U_LIB.S9S_MB_2U(SCH_1):PD_GTL2014_ERROR_B0
  U306    2     B0 GTL2014PW-GTL2014PW,SMLF,IC,ALA    I80 @S9S_MB_2U_LIB.S9S_MB_2U(SCH_1):PAGE322
 R4391    1      A Q_RES_0402LF-150,1%,1/16W,CHIPA   I190 @S9S_MB_2U_LIB.S9S_MB_2U(SCH_1):PAGE322

PD_I3C_SPD_DDR_CPU0_OE_N @S9S_MB_2U_LIB.S9S_MB_2U(SCH_1):PD_I3C_SPD_DDR_CPU0_OE_N
  R678    1      A Q_RES_0402LF-1K,1%,1/16W,CHIP,A    I13 @S9S_MB_2U_LIB.S9S_MB_2U(SCH_1):PAGE217
   U15   15     E* QS3VH257QG8_SMLF-QS3VH257QG8,IA    I19 @S9S_MB_2U_LIB.S9S_MB_2U(SCH_1):PAGE217

PD_I3C_SPD_DDR_CPU1_OE_N @S9S_MB_2U_LIB.S9S_MB_2U(SCH_1):PD_I3C_SPD_DDR_CPU1_OE_N
  R661    1      A Q_RES_0402LF-1K,1%,1/16W,CHIP,A     I4 @S9S_MB_2U_LIB.S9S_MB_2U(SCH_1):PAGE218
   U14   15     E* QS3VH257QG8_SMLF-QS3VH257QG8,IA    I12 @S9S_MB_2U_LIB.S9S_MB_2U(SCH_1):PAGE218

PD_JTAG_BMC_NTRST_N @S9S_MB_2U_LIB.S9S_MB_2U(SCH_1):PD_JTAG_BMC_NTRST_N
   U86    1    1OE 74CBTLV3126PW-74CBTLV3126PW,SMA    I84 @S9S_MB_2U_LIB.S9S_MB_2U(SCH_1):PAGE137
   U86   13    4OE 74CBTLV3126PW-74CBTLV3126PW,SMA    I84 @S9S_MB_2U_LIB.S9S_MB_2U(SCH_1):PAGE137
 R1374    1      A Q_RES_0402LF-1K,1%,1/16W,CHIP,A   I103 @S9S_MB_2U_LIB.S9S_MB_2U(SCH_1):PAGE137

PD_JTAG_CPU0_PLD_TCK @S9S_MB_2U_LIB.S9S_MB_2U(SCH_1):PD_JTAG_CPU0_PLD_TCK
    U2 CY22 TEST_5 SOCKET4677_AZIF0045P001C01CS-SA     I1 @S9S_MB_2U_LIB.S9S_MB_2U(SCH_1):PAGE15
 R1226    1      A Q_RES_0402LF-10K,1%,1/16W,CHIPA    I52 @S9S_MB_2U_LIB.S9S_MB_2U(SCH_1):PAGE43

PD_JTAG_CPU1_PLD_TCK @S9S_MB_2U_LIB.S9S_MB_2U(SCH_1):PD_JTAG_CPU1_PLD_TCK
 R1227    1      A Q_RES_0402LF-10K,1%,1/16W,CHIPA    I56 @S9S_MB_2U_LIB.S9S_MB_2U(SCH_1):PAGE43
    U1 CY22 TEST_5 SOCKET4677_AZIF0045P001C01CS-SA     I5 @S9S_MB_2U_LIB.S9S_MB_2U(SCH_1):PAGE46

PD_JTAG_DBP_B0 @S9S_MB_2U_LIB.S9S_MB_2U(SCH_1):PD_JTAG_DBP_B0
   U83    2     B0 GTL2014PW-GTL2014PW,SMLF,IC,ALA    I45 @S9S_MB_2U_LIB.S9S_MB_2U(SCH_1):PAGE226
 R1369    1      A Q_RES_0402LF-1K,1%,1/16W,CHIP,A    I47 @S9S_MB_2U_LIB.S9S_MB_2U(SCH_1):PAGE226

PD_JTAG_DBP_B2 @S9S_MB_2U_LIB.S9S_MB_2U(SCH_1):PD_JTAG_DBP_B2
   U83    5     B2 GTL2014PW-GTL2014PW,SMLF,IC,ALA    I45 @S9S_MB_2U_LIB.S9S_MB_2U(SCH_1):PAGE226
 R1368    1      A Q_RES_0402LF-1K,1%,1/16W,CHIP,A    I48 @S9S_MB_2U_LIB.S9S_MB_2U(SCH_1):PAGE226

PD_M2_0_DEVSLP @S9S_MB_2U_LIB.S9S_MB_2U(SCH_1):PD_M2_0_DEVSLP
 R1605    1      A Q_RES_0402LF-1K,1%,1/16W,CHIP,A   I105 @S9S_MB_2U_LIB.S9S_MB_2U(SCH_1):PAGE182
   J59   38 DEVSLP SCONN75K_APCI0155P004A-SCONN75A   I178 @S9S_MB_2U_LIB.S9S_MB_2U(SCH_1):PAGE182

PD_MB_FRU_WP @S9S_MB_2U_LIB.S9S_MB_2U(SCH_1):PD_MB_FRU_WP
   U64    7    WC# M24128BWMN6TP-M24128-BWMN6TP,SA    I35 @S9S_MB_2U_LIB.S9S_MB_2U(SCH_1):PAGE231
  R710    1      A Q_RES_0402LF-1K,1%,1/16W,CHIP,A    I57 @S9S_MB_2U_LIB.S9S_MB_2U(SCH_1):PAGE231

PD_ME_RCVR_N @S9S_MB_2U_LIB.S9S_MB_2U(SCH_1):PD_ME_RCVR_N
 R3039    2      B Q_RES_0402LF-1K,1%,1/16W,CHIP,A   I132 @S9S_MB_2U_LIB.S9S_MB_2U(SCH_1):PAGE189
  J104   11     11 CONN14_210HP207GBR1-CONN14_210A   I134 @S9S_MB_2U_LIB.S9S_MB_2U(SCH_1):PAGE189

PD_P2E_BUF2_ENSMB @S9S_MB_2U_LIB.S9S_MB_2U(SCH_1):PD_P2E_BUF2_ENSMB
  U328    3  ENSMB DS125BR111RTWR-DS125BR111RTWR,A    I95 @S9S_MB_2U_LIB.S9S_MB_2U(SCH_1):PAGE159
 R3362    1      A Q_RES_0402LF-1K,1%,1/16W,CHIP,A    I53 @S9S_MB_2U_LIB.S9S_MB_2U(SCH_1):PAGE159

PD_PASSWORD_CLEAR @S9S_MB_2U_LIB.S9S_MB_2U(SCH_1):PD_PASSWORD_CLEAR
 R1335    2      B Q_RES_0402LF-1K,1%,1/16W,CHIP,A   I133 @S9S_MB_2U_LIB.S9S_MB_2U(SCH_1):PAGE189
  J104   13     13 CONN14_210HP207GBR1-CONN14_210A   I134 @S9S_MB_2U_LIB.S9S_MB_2U(SCH_1):PAGE189

PD_PCH_GPPC_A_10 @S9S_MB_2U_LIB.S9S_MB_2U(SCH_1):PD_PCH_GPPC_A_10
    U4 BD17 GPPC_A_10_SRCCLKREQ_N_0 EMMITSBURG_REV0P9-GFNOCPU04302A    I93 @S9S_MB_2U_LIB.S9S_MB_2U(SCH_1):PAGE175
 R4099    1      A Q_RES_0402LF-10K,1%,1/16W,CHIPA   I288 @S9S_MB_2U_LIB.S9S_MB_2U(SCH_1):PAGE175

PD_PCH_GPPC_A_14 @S9S_MB_2U_LIB.S9S_MB_2U(SCH_1):PD_PCH_GPPC_A_14
    U4 BE12 GPPC_A_14_SRCCLKREQ_N_4 EMMITSBURG_REV0P9-GFNOCPU04302A    I93 @S9S_MB_2U_LIB.S9S_MB_2U(SCH_1):PAGE175
 R4098    1      A Q_RES_0402LF-10K,1%,1/16W,CHIPA   I287 @S9S_MB_2U_LIB.S9S_MB_2U(SCH_1):PAGE175

PD_PCH_GPPC_A_15 @S9S_MB_2U_LIB.S9S_MB_2U(SCH_1):PD_PCH_GPPC_A_15
    U4 BE14 GPPC_A_15_SRCCLKREQ_N_5 EMMITSBURG_REV0P9-GFNOCPU04302A    I93 @S9S_MB_2U_LIB.S9S_MB_2U(SCH_1):PAGE175
 R4097    1      A Q_RES_0402LF-10K,1%,1/16W,CHIPA   I286 @S9S_MB_2U_LIB.S9S_MB_2U(SCH_1):PAGE175

PD_PCH_GPPC_A_18 @S9S_MB_2U_LIB.S9S_MB_2U(SCH_1):PD_PCH_GPPC_A_18
    U4 BF11 GPPC_A_18_SRCCLKREQ_N_8 EMMITSBURG_REV0P9-GFNOCPU04302A    I93 @S9S_MB_2U_LIB.S9S_MB_2U(SCH_1):PAGE175
 R4096    1      A Q_RES_0402LF-10K,1%,1/16W,CHIPA   I285 @S9S_MB_2U_LIB.S9S_MB_2U(SCH_1):PAGE175

PD_PCH_GPPC_A_19 @S9S_MB_2U_LIB.S9S_MB_2U(SCH_1):PD_PCH_GPPC_A_19
    U4 BG14 GPPC_A_19_SRCCLKREQ_N_9 EMMITSBURG_REV0P9-GFNOCPU04302A    I93 @S9S_MB_2U_LIB.S9S_MB_2U(SCH_1):PAGE175
 R4095    1      A Q_RES_0402LF-10K,1%,1/16W,CHIPA   I284 @S9S_MB_2U_LIB.S9S_MB_2U(SCH_1):PAGE175

PD_PCH_GPPC_C10 @S9S_MB_2U_LIB.S9S_MB_2U(SCH_1):PD_PCH_GPPC_C10
    U4  AP3 GPPC_C_10_ME_SML2DATA EMMITSBURG_REV0P9-GFNOCPU04302A    I93 @S9S_MB_2U_LIB.S9S_MB_2U(SCH_1):PAGE175
 R4100    1      A Q_RES_0402LF-10K,1%,1/16W,CHIPA   I300 @S9S_MB_2U_LIB.S9S_MB_2U(SCH_1):PAGE175

PD_PCH_GPPC_C5 @S9S_MB_2U_LIB.S9S_MB_2U(SCH_1):PD_PCH_GPPC_C5
    U4  AT3 GPPC_C_5_ME_SML0BALERT_N EMMITSBURG_REV0P9-GFNOCPU04302A    I93 @S9S_MB_2U_LIB.S9S_MB_2U(SCH_1):PAGE175
 R4102    1      A Q_RES_0402LF-10K,1%,1/16W,CHIPA   I298 @S9S_MB_2U_LIB.S9S_MB_2U(SCH_1):PAGE175

PD_PCH_GPPC_C9 @S9S_MB_2U_LIB.S9S_MB_2U(SCH_1):PD_PCH_GPPC_C9
    U4  AR2 GPPC_C_9_ME_SML2CLK EMMITSBURG_REV0P9-GFNOCPU04302A    I93 @S9S_MB_2U_LIB.S9S_MB_2U(SCH_1):PAGE175
 R4101    1      A Q_RES_0402LF-10K,1%,1/16W,CHIPA   I299 @S9S_MB_2U_LIB.S9S_MB_2U(SCH_1):PAGE175

PD_PCH_GPP_E_10 @S9S_MB_2U_LIB.S9S_MB_2U(SCH_1):PD_PCH_GPP_E_10
    U4 AV31 GPP_E_10_SATA0_SDATAOUT_SATA0_GP EMMITSBURG_REV0P9-GFNOCPU04302A    I22 @S9S_MB_2U_LIB.S9S_MB_2U(SCH_1):PAGE176
 R4114    1      A Q_RES_0402LF-10K,1%,1/16W,CHIPA   I205 @S9S_MB_2U_LIB.S9S_MB_2U(SCH_1):PAGE176

PD_PCH_GPP_E_11 @S9S_MB_2U_LIB.S9S_MB_2U(SCH_1):PD_PCH_GPP_E_11
    U4 AV34 GPP_E_11_SATA1_SCLOCK_SATA1_LED_N EMMITSBURG_REV0P9-GFNOCPU04302A    I22 @S9S_MB_2U_LIB.S9S_MB_2U(SCH_1):PAGE176
 R4113    1      A Q_RES_0402LF-10K,1%,1/16W,CHIPA   I206 @S9S_MB_2U_LIB.S9S_MB_2U(SCH_1):PAGE176

PD_PCH_GPP_E_12 @S9S_MB_2U_LIB.S9S_MB_2U(SCH_1):PD_PCH_GPP_E_12
    U4 BB28 GPP_E_12_SATA1_SLOAD_SATA1_GP EMMITSBURG_REV0P9-GFNOCPU04302A    I22 @S9S_MB_2U_LIB.S9S_MB_2U(SCH_1):PAGE176
 R4112    1      A Q_RES_0402LF-10K,1%,1/16W,CHIPA   I203 @S9S_MB_2U_LIB.S9S_MB_2U(SCH_1):PAGE176

PD_PCH_GPP_E_13 @S9S_MB_2U_LIB.S9S_MB_2U(SCH_1):PD_PCH_GPP_E_13
    U4 BA32 GPP_E_13_SATA1_SDATAOUT_SATA1_DEVSLP EMMITSBURG_REV0P9-GFNOCPU04302A    I22 @S9S_MB_2U_LIB.S9S_MB_2U(SCH_1):PAGE176
 R4111    1      A Q_RES_0402LF-10K,1%,1/16W,CHIPA   I204 @S9S_MB_2U_LIB.S9S_MB_2U(SCH_1):PAGE176

PD_PCH_GPP_E_14 @S9S_MB_2U_LIB.S9S_MB_2U(SCH_1):PD_PCH_GPP_E_14
    U4 BB34 GPP_E_14_SATA2_SCLOCK_SATA2_LED_N EMMITSBURG_REV0P9-GFNOCPU04302A    I22 @S9S_MB_2U_LIB.S9S_MB_2U(SCH_1):PAGE176
 R4110    1      A Q_RES_0402LF-10K,1%,1/16W,CHIPA   I202 @S9S_MB_2U_LIB.S9S_MB_2U(SCH_1):PAGE176

PD_PCH_GPP_E_3 @S9S_MB_2U_LIB.S9S_MB_2U(SCH_1):PD_PCH_GPP_E_3
    U4 BB21 GPP_E_3_SATA1_XPCIE_3 EMMITSBURG_REV0P9-GFNOCPU04302A    I22 @S9S_MB_2U_LIB.S9S_MB_2U(SCH_1):PAGE176
 R4117    1      A Q_RES_0402LF-10K,1%,1/16W,CHIPA   I209 @S9S_MB_2U_LIB.S9S_MB_2U(SCH_1):PAGE176

PD_PCH_GPP_E_8 @S9S_MB_2U_LIB.S9S_MB_2U(SCH_1):PD_PCH_GPP_E_8
    U4 AW36 GPP_E_8_SATA0_SCLOCK_SATA0_LED_N EMMITSBURG_REV0P9-GFNOCPU04302A    I22 @S9S_MB_2U_LIB.S9S_MB_2U(SCH_1):PAGE176
 R4116    1      A Q_RES_0402LF-10K,1%,1/16W,CHIPA   I207 @S9S_MB_2U_LIB.S9S_MB_2U(SCH_1):PAGE176

PD_PCH_GPP_E_9 @S9S_MB_2U_LIB.S9S_MB_2U(SCH_1):PD_PCH_GPP_E_9
    U4 BA29 GPP_E_9_SATA0_SLOAD_SATA0_DEVSLP EMMITSBURG_REV0P9-GFNOCPU04302A    I22 @S9S_MB_2U_LIB.S9S_MB_2U(SCH_1):PAGE176
 R4115    1      A Q_RES_0402LF-10K,1%,1/16W,CHIPA   I201 @S9S_MB_2U_LIB.S9S_MB_2U(SCH_1):PAGE176

PD_PCH_USB2_COMP @S9S_MB_2U_LIB.S9S_MB_2U(SCH_1):PD_PCH_USB2_COMP
  R496    1      A Q_RES_0402LF-113,1%,1/16W,CHIPA    I10 @S9S_MB_2U_LIB.S9S_MB_2U(SCH_1):PAGE172
    U4 BB41 USB2_COMP EMMITSBURG_REV0P9-GFNOCPU04302A    I11 @S9S_MB_2U_LIB.S9S_MB_2U(SCH_1):PAGE172

PD_PCH_XCLK_BIASREF @S9S_MB_2U_LIB.S9S_MB_2U(SCH_1):PD_PCH_XCLK_BIASREF
  R477    1      A Q_RES_0402LF-60.4,1%,1/16W,CHIA    I69 @S9S_MB_2U_LIB.S9S_MB_2U(SCH_1):PAGE171
    U4  N29 XCLK_BIASREF EMMITSBURG_REV0P9-GFNOCPU04302A    I78 @S9S_MB_2U_LIB.S9S_MB_2U(SCH_1):PAGE171

PD_PIROM_CPU0_ADDR0 @S9S_MB_2U_LIB.S9S_MB_2U(SCH_1):PD_PIROM_CPU0_ADDR0
    U2 CR70 PIROM_AD0 SOCKET4677_AZIF0045P001C01CS-SA     I1 @S9S_MB_2U_LIB.S9S_MB_2U(SCH_1):PAGE14
  R335    2      B Q_RES_0402LF-1K,1%,1/16W,EMPTYA     I5 @S9S_MB_2U_LIB.S9S_MB_2U(SCH_1):PAGE127
  R515    1      A Q_RES_0402LF-10K,1%,1/16W,CHIPA     I7 @S9S_MB_2U_LIB.S9S_MB_2U(SCH_1):PAGE127

PD_PIROM_CPU0_ADDR1 @S9S_MB_2U_LIB.S9S_MB_2U(SCH_1):PD_PIROM_CPU0_ADDR1
    U2 CT71 PIROM_AD1 SOCKET4677_AZIF0045P001C01CS-SA     I1 @S9S_MB_2U_LIB.S9S_MB_2U(SCH_1):PAGE14
  R334    1      A Q_RES_0402LF-10K,1%,1/16W,CHIPA     I1 @S9S_MB_2U_LIB.S9S_MB_2U(SCH_1):PAGE127
  R333    2      B Q_RES_0402LF-1K,1%,1/16W,EMPTYA     I6 @S9S_MB_2U_LIB.S9S_MB_2U(SCH_1):PAGE127

PD_PIROM_CPU0_ADDR2 @S9S_MB_2U_LIB.S9S_MB_2U(SCH_1):PD_PIROM_CPU0_ADDR2
    U2 CP71 PIROM_AD2 SOCKET4677_AZIF0045P001C01CS-SA     I1 @S9S_MB_2U_LIB.S9S_MB_2U(SCH_1):PAGE14
  R331    2      B Q_RES_0402LF-1K,1%,1/16W,EMPTYA    I20 @S9S_MB_2U_LIB.S9S_MB_2U(SCH_1):PAGE127
  R332    1      A Q_RES_0402LF-10K,1%,1/16W,CHIPA    I21 @S9S_MB_2U_LIB.S9S_MB_2U(SCH_1):PAGE127

PD_PIROM_CPU1_ADDR1 @S9S_MB_2U_LIB.S9S_MB_2U(SCH_1):PD_PIROM_CPU1_ADDR1
    U1 CT71 PIROM_AD1 SOCKET4677_AZIF0045P001C01CS-SA    I29 @S9S_MB_2U_LIB.S9S_MB_2U(SCH_1):PAGE45
  R627    2      B Q_RES_0402LF-1K,1%,1/16W,EMPTYA    I14 @S9S_MB_2U_LIB.S9S_MB_2U(SCH_1):PAGE127
  R628    1      A Q_RES_0402LF-10K,1%,1/16W,CHIPA    I17 @S9S_MB_2U_LIB.S9S_MB_2U(SCH_1):PAGE127

PD_PIROM_CPU1_ADDR2 @S9S_MB_2U_LIB.S9S_MB_2U(SCH_1):PD_PIROM_CPU1_ADDR2
    U1 CP71 PIROM_AD2 SOCKET4677_AZIF0045P001C01CS-SA    I29 @S9S_MB_2U_LIB.S9S_MB_2U(SCH_1):PAGE45
  R625    2      B Q_RES_0402LF-1K,1%,1/16W,EMPTYA    I24 @S9S_MB_2U_LIB.S9S_MB_2U(SCH_1):PAGE127
  R626    1      A Q_RES_0402LF-10K,1%,1/16W,CHIPA    I26 @S9S_MB_2U_LIB.S9S_MB_2U(SCH_1):PAGE127

PD_RCOMP_1P8_3P3 @S9S_MB_2U_LIB.S9S_MB_2U(SCH_1):PD_RCOMP_1P8_3P3
  R497    1      A Q_RES_0402LF-200,1%,1/16W,CHIPA     I2 @S9S_MB_2U_LIB.S9S_MB_2U(SCH_1):PAGE179
    U4 AC13 GPIO_RCOMP_1P8_3P3 EMMITSBURG_REV0P9-GFNOCPU04302A     I4 @S9S_MB_2U_LIB.S9S_MB_2U(SCH_1):PAGE179

PD_RST_RTCRST_N @S9S_MB_2U_LIB.S9S_MB_2U(SCH_1):PD_RST_RTCRST_N
   SW5    1      1 SW_PUSHBUTTON4P_24-SW4S_DTSM-6A   I122 @S9S_MB_2U_LIB.S9S_MB_2U(SCH_1):PAGE189
   SW5    2      2 SW_PUSHBUTTON4P_24-SW4S_DTSM-6A   I122 @S9S_MB_2U_LIB.S9S_MB_2U(SCH_1):PAGE189
 R1333    2      B Q_RES_0402LF-1K,1%,1/16W,CHIP,A   I123 @S9S_MB_2U_LIB.S9S_MB_2U(SCH_1):PAGE189

PD_SMB_OCP1_HP_ADD0 @S9S_MB_2U_LIB.S9S_MB_2U(SCH_1):PD_SMB_OCP1_HP_ADD0
 R1127    2      B Q_RES_0402LF-1K,1%,1/16W,EMPTYA   I133 @S9S_MB_2U_LIB.S9S_MB_2U(SCH_1):PAGE154
 R1128    1      A Q_RES_0402LF-1K,1%,1/16W,CHIP,A   I137 @S9S_MB_2U_LIB.S9S_MB_2U(SCH_1):PAGE154
  U209   21     A0 PCA9555APW-PCA9555APW,SMLF,IC,A   I206 @S9S_MB_2U_LIB.S9S_MB_2U(SCH_1):PAGE154

PD_SMB_OCP1_HP_ADD1 @S9S_MB_2U_LIB.S9S_MB_2U(SCH_1):PD_SMB_OCP1_HP_ADD1
 R3037    2      B Q_RES_0402LF-1K,1%,1/16W,EMPTYA   I134 @S9S_MB_2U_LIB.S9S_MB_2U(SCH_1):PAGE154
 R1126    1      A Q_RES_0402LF-1K,1%,1/16W,CHIP,A   I140 @S9S_MB_2U_LIB.S9S_MB_2U(SCH_1):PAGE154
  U209    2     A1 PCA9555APW-PCA9555APW,SMLF,IC,A   I206 @S9S_MB_2U_LIB.S9S_MB_2U(SCH_1):PAGE154

PD_SMB_OCP1_HP_ADD2 @S9S_MB_2U_LIB.S9S_MB_2U(SCH_1):PD_SMB_OCP1_HP_ADD2
 R1123    2      B Q_RES_0402LF-1K,1%,1/16W,EMPTYA   I142 @S9S_MB_2U_LIB.S9S_MB_2U(SCH_1):PAGE154
 R1124    1      A Q_RES_0402LF-1K,1%,1/16W,CHIP,A   I143 @S9S_MB_2U_LIB.S9S_MB_2U(SCH_1):PAGE154
  U209    3     A2 PCA9555APW-PCA9555APW,SMLF,IC,A   I206 @S9S_MB_2U_LIB.S9S_MB_2U(SCH_1):PAGE154

PD_SMB_OCP2_HP_ADD0 @S9S_MB_2U_LIB.S9S_MB_2U(SCH_1):PD_SMB_OCP2_HP_ADD0
 R3153    2      B Q_RES_0402LF-1K,1%,1/16W,EMPTYA    I32 @S9S_MB_2U_LIB.S9S_MB_2U(SCH_1):PAGE132
 R3154    1      A Q_RES_0402LF-1K,1%,1/16W,CHIP,A    I65 @S9S_MB_2U_LIB.S9S_MB_2U(SCH_1):PAGE132
   U51   21     A0 PCA9555APW-PCA9555APW,SMLF,IC,A    I66 @S9S_MB_2U_LIB.S9S_MB_2U(SCH_1):PAGE132

PD_SMB_OCP2_HP_ADD1 @S9S_MB_2U_LIB.S9S_MB_2U(SCH_1):PD_SMB_OCP2_HP_ADD1
 R3152    1      A Q_RES_0402LF-1K,1%,1/16W,CHIP,A    I27 @S9S_MB_2U_LIB.S9S_MB_2U(SCH_1):PAGE132
 R3151    2      B Q_RES_0402LF-1K,1%,1/16W,EMPTYA    I31 @S9S_MB_2U_LIB.S9S_MB_2U(SCH_1):PAGE132
   U51    2     A1 PCA9555APW-PCA9555APW,SMLF,IC,A    I66 @S9S_MB_2U_LIB.S9S_MB_2U(SCH_1):PAGE132

PD_SMB_OCP2_HP_ADD2 @S9S_MB_2U_LIB.S9S_MB_2U(SCH_1):PD_SMB_OCP2_HP_ADD2
 R3149    2      B Q_RES_0402LF-1K,1%,1/16W,EMPTYA    I29 @S9S_MB_2U_LIB.S9S_MB_2U(SCH_1):PAGE132
 R3150    1      A Q_RES_0402LF-1K,1%,1/16W,CHIP,A    I25 @S9S_MB_2U_LIB.S9S_MB_2U(SCH_1):PAGE132
   U51    3     A2 PCA9555APW-PCA9555APW,SMLF,IC,A    I66 @S9S_MB_2U_LIB.S9S_MB_2U(SCH_1):PAGE132

PD_SUSCLK @S9S_MB_2U_LIB.S9S_MB_2U(SCH_1):PD_SUSCLK
    U4  AR7 SUSCLK EMMITSBURG_REV0P9-GFNOCPU04302A    I36 @S9S_MB_2U_LIB.S9S_MB_2U(SCH_1):PAGE174
 R1197    2      B Q_RES_0402LF-1K,1%,1/16W,EMPTYA    I50 @S9S_MB_2U_LIB.S9S_MB_2U(SCH_1):PAGE174

PD_TRST_P3 @S9S_MB_2U_LIB.S9S_MB_2U(SCH_1):PD_TRST_P3
   J42    8      8 SCONN60_ASP21410801-SCONN60_ASA    I44 @S9S_MB_2U_LIB.S9S_MB_2U(SCH_1):PAGE133
  R769    1      A Q_RES_0402LF-10K,1%,1/16W,CHIPA   I102 @S9S_MB_2U_LIB.S9S_MB_2U(SCH_1):PAGE133

PD_U5201_EQ @S9S_MB_2U_LIB.S9S_MB_2U(SCH_1):PD_U5201_EQ
 R5238    1      A Q_RES_0402LF-3.9K,5%,1/16W,EMPA    I83 @S9S_MB_2U_LIB.S9S_MB_2U(SCH_1):PAGE155
 U5201    6     EQ TUSB211IRWBR-TUSB211IRWBR,SMLFA    I84 @S9S_MB_2U_LIB.S9S_MB_2U(SCH_1):PAGE155

PD_U5201_RSTN @S9S_MB_2U_LIB.S9S_MB_2U(SCH_1):PD_U5201_RSTN
 C5232    1      A Q_CAP_0402-0.1UF,25V,10%,EMPTYA    I81 @S9S_MB_2U_LIB.S9S_MB_2U(SCH_1):PAGE155
 U5201    5   RSTN TUSB211IRWBR-TUSB211IRWBR,SMLFA    I84 @S9S_MB_2U_LIB.S9S_MB_2U(SCH_1):PAGE155

PD_U5201_VREG @S9S_MB_2U_LIB.S9S_MB_2U(SCH_1):PD_U5201_VREG
 U5201   11   VREG TUSB211IRWBR-TUSB211IRWBR,SMLFA    I84 @S9S_MB_2U_LIB.S9S_MB_2U(SCH_1):PAGE155
 C5236    1      A Q_CAP_0402-0.1UF,25V,10%,EMPTYA    I87 @S9S_MB_2U_LIB.S9S_MB_2U(SCH_1):PAGE155

PD_USB_HUB_2_EQ @S9S_MB_2U_LIB.S9S_MB_2U(SCH_1):PD_USB_HUB_2_EQ
 R4465    1      A Q_RES_0402LF-3.9K,5%,1/16W,EMPA     I4 @S9S_MB_2U_LIB.S9S_MB_2U(SCH_1):PAGE194
  U312    6     EQ TUSB211IRWBR-TUSB211IRWBR,SMLFA    I20 @S9S_MB_2U_LIB.S9S_MB_2U(SCH_1):PAGE194

PD_USB_HUB_2_RSTN @S9S_MB_2U_LIB.S9S_MB_2U(SCH_1):PD_USB_HUB_2_RSTN
 C2321    1      A Q_CAP_0402-0.1UF,25V,10%,EMPTYA     I2 @S9S_MB_2U_LIB.S9S_MB_2U(SCH_1):PAGE194
  U312    5   RSTN TUSB211IRWBR-TUSB211IRWBR,SMLFA    I20 @S9S_MB_2U_LIB.S9S_MB_2U(SCH_1):PAGE194

PD_USB_HUB_2_VREG @S9S_MB_2U_LIB.S9S_MB_2U(SCH_1):PD_USB_HUB_2_VREG
  U312   11   VREG TUSB211IRWBR-TUSB211IRWBR,SMLFA    I20 @S9S_MB_2U_LIB.S9S_MB_2U(SCH_1):PAGE194
 C2325    1      A Q_CAP_0402-0.1UF,25V,10%,EMPTYA    I55 @S9S_MB_2U_LIB.S9S_MB_2U(SCH_1):PAGE194

PECI_BMC @S9S_MB_2U_LIB.S9S_MB_2U(SCH_1):PECI_BMC
  R144    1      A Q_RES_0402LF-0,5%,1/16W,CHIP,CA    I51 @S9S_MB_2U_LIB.S9S_MB_2U(SCH_1):PAGE185
   J41  B27  PETP3 SCONN168_ME1016810202011-SCONNA   I173 @S9S_MB_2U_LIB.S9S_MB_2U(SCH_1):PAGE227

PECI_BMC_B1 @S9S_MB_2U_LIB.S9S_MB_2U(SCH_1):PECI_BMC_B1
 R1297    2      B Q_RES_0402LF-0,5%,1/16W,CHIP,CA    I32 @S9S_MB_2U_LIB.S9S_MB_2U(SCH_1):PAGE185
  U142    1     B1 NC7SB3157_SMLF-NC7SB3157P6X,NCA    I35 @S9S_MB_2U_LIB.S9S_MB_2U(SCH_1):PAGE185

PECI_BMC_ME @S9S_MB_2U_LIB.S9S_MB_2U(SCH_1):PECI_BMC_ME
 R3064    2      B Q_RES_0402LF-0,5%,1/16W,EMPTY,A    I45 @S9S_MB_2U_LIB.S9S_MB_2U(SCH_1):PAGE185
  J100   16     16 SCONN20_513860200CV01-SCONN20_A    I32 @S9S_MB_2U_LIB.S9S_MB_2U(SCH_1):PAGE215

PECI_BMC_R @S9S_MB_2U_LIB.S9S_MB_2U(SCH_1):PECI_BMC_R
  R146    2      B Q_RES_0402LF-4.75K,1%,1/16W,EMA    I30 @S9S_MB_2U_LIB.S9S_MB_2U(SCH_1):PAGE185
 R1297    1      A Q_RES_0402LF-0,5%,1/16W,CHIP,CA    I32 @S9S_MB_2U_LIB.S9S_MB_2U(SCH_1):PAGE185
  R148    1      A Q_RES_0402LF-10K,1%,1/16W,EMPTA    I49 @S9S_MB_2U_LIB.S9S_MB_2U(SCH_1):PAGE185
  R144    2      B Q_RES_0402LF-0,5%,1/16W,CHIP,CA    I51 @S9S_MB_2U_LIB.S9S_MB_2U(SCH_1):PAGE185

PECI_CPU0_GTL_R @S9S_MB_2U_LIB.S9S_MB_2U(SCH_1):PECI_CPU0_GTL_R
    R3    2      B Q_RES_0402LF-33.2,1%,1/16W,CHIA    I21 @S9S_MB_2U_LIB.S9S_MB_2U(SCH_1):PAGE13
    U2 BH24   PECI SOCKET4677_AZIF0045P001C01CS-SA    I57 @S9S_MB_2U_LIB.S9S_MB_2U(SCH_1):PAGE13

PECI_CPU1_GTL_R @S9S_MB_2U_LIB.S9S_MB_2U(SCH_1):PECI_CPU1_GTL_R
   R63    2      B Q_RES_0402LF-33.2,1%,1/16W,CHIA    I10 @S9S_MB_2U_LIB.S9S_MB_2U(SCH_1):PAGE44
    U1 BH24   PECI SOCKET4677_AZIF0045P001C01CS-SA    I51 @S9S_MB_2U_LIB.S9S_MB_2U(SCH_1):PAGE44

PECI_CPU_GTL @S9S_MB_2U_LIB.S9S_MB_2U(SCH_1):PECI_CPU_GTL
    R3    1      A Q_RES_0402LF-33.2,1%,1/16W,CHIA    I21 @S9S_MB_2U_LIB.S9S_MB_2U(SCH_1):PAGE13
   R63    1      A Q_RES_0402LF-33.2,1%,1/16W,CHIA    I10 @S9S_MB_2U_LIB.S9S_MB_2U(SCH_1):PAGE44
  U142    4      A NC7SB3157_SMLF-NC7SB3157P6X,NCA    I35 @S9S_MB_2U_LIB.S9S_MB_2U(SCH_1):PAGE185
 R3064    1      A Q_RES_0402LF-0,5%,1/16W,EMPTY,A    I45 @S9S_MB_2U_LIB.S9S_MB_2U(SCH_1):PAGE185

PECI_MUX_SEL_R @S9S_MB_2U_LIB.S9S_MB_2U(SCH_1):PECI_MUX_SEL_R
  U142    6      S NC7SB3157_SMLF-NC7SB3157P6X,NCA    I35 @S9S_MB_2U_LIB.S9S_MB_2U(SCH_1):PAGE185
 R2253    2      B Q_RES_0402LF-4.75K,1%,1/16W,CHA    I39 @S9S_MB_2U_LIB.S9S_MB_2U(SCH_1):PAGE185
 R2255    1      A Q_RES_0402LF-0,5%,1/16W,CHIP,CA    I41 @S9S_MB_2U_LIB.S9S_MB_2U(SCH_1):PAGE185
 R2252    1      A Q_RES_0402LF-100K,1%,1/16W,EMPA    I42 @S9S_MB_2U_LIB.S9S_MB_2U(SCH_1):PAGE185

PECI_PCH @S9S_MB_2U_LIB.S9S_MB_2U(SCH_1):PECI_PCH
    U4  J10 ME_PECI EMMITSBURG_REV0P9-GFNOCPU04302A    I36 @S9S_MB_2U_LIB.S9S_MB_2U(SCH_1):PAGE174
  R143    1      A Q_RES_0402LF-49.9,1%,1/16W,CHIA    I47 @S9S_MB_2U_LIB.S9S_MB_2U(SCH_1):PAGE185

PECI_PCH_B1 @S9S_MB_2U_LIB.S9S_MB_2U(SCH_1):PECI_PCH_B1
  R149    2      B Q_RES_0402LF-0,5%,1/16W,CHIP,CA    I24 @S9S_MB_2U_LIB.S9S_MB_2U(SCH_1):PAGE185
  U142    3     B0 NC7SB3157_SMLF-NC7SB3157P6X,NCA    I35 @S9S_MB_2U_LIB.S9S_MB_2U(SCH_1):PAGE185

PECI_PCH_R @S9S_MB_2U_LIB.S9S_MB_2U(SCH_1):PECI_PCH_R
  R149    1      A Q_RES_0402LF-0,5%,1/16W,CHIP,CA    I24 @S9S_MB_2U_LIB.S9S_MB_2U(SCH_1):PAGE185
  R145    2      B Q_RES_0402LF-4.75K,1%,1/16W,EMA    I26 @S9S_MB_2U_LIB.S9S_MB_2U(SCH_1):PAGE185
  R143    2      B Q_RES_0402LF-49.9,1%,1/16W,CHIA    I47 @S9S_MB_2U_LIB.S9S_MB_2U(SCH_1):PAGE185
  R147    1      A Q_RES_0402LF-10K,1%,1/16W,CHIPA    I50 @S9S_MB_2U_LIB.S9S_MB_2U(SCH_1):PAGE185

PGPPA_AUX @S9S_MB_2U_LIB.S9S_MB_2U(SCH_1):PGPPA_AUX
   U60    5    VCC NC7SB3157_SMLF-NC7SB3157P6X,NCA    I34 @S9S_MB_2U_LIB.S9S_MB_2U(SCH_1):PAGE190
  C607    1      A Q_CAP_0402-0.1UF,25V,10%,X7R,CA    I36 @S9S_MB_2U_LIB.S9S_MB_2U(SCH_1):PAGE190
  C605    1      A Q_CAP_C0402-1UF,25V,10%,X6S,CHA    I37 @S9S_MB_2U_LIB.S9S_MB_2U(SCH_1):PAGE190
   U61    5    VCC NC7SB3157_SMLF-NC7SB3157P6X,NCA    I39 @S9S_MB_2U_LIB.S9S_MB_2U(SCH_1):PAGE190
  C608    1      A Q_CAP_0402-0.1UF,25V,10%,X7R,CA    I43 @S9S_MB_2U_LIB.S9S_MB_2U(SCH_1):PAGE190
  C606    1      A Q_CAP_C0402-1UF,25V,10%,X6S,CHA    I45 @S9S_MB_2U_LIB.S9S_MB_2U(SCH_1):PAGE190
 R1961    1      A Q_RES_0402LF-10K,1%,1/16W,CHIPA    I70 @S9S_MB_2U_LIB.S9S_MB_2U(SCH_1):PAGE190
 R1750    1      A Q_RES_0402LF-1K,1%,1/16W,CHIP,A    I87 @S9S_MB_2U_LIB.S9S_MB_2U(SCH_1):PAGE190
 R1253    1      A Q_RES_0402LF-1K,1%,1/16W,CHIP,A    I23 @S9S_MB_2U_LIB.S9S_MB_2U(SCH_1):PAGE192
 R1254    1      A Q_RES_0402LF-10K,1%,1/16W,CHIPA    I24 @S9S_MB_2U_LIB.S9S_MB_2U(SCH_1):PAGE192
 R1255    1      A Q_RES_0402LF-1K,1%,1/16W,CHIP,A    I26 @S9S_MB_2U_LIB.S9S_MB_2U(SCH_1):PAGE192
 R1747    2      B Q_RES_0805LF-0,5%,1/8W,CHIP,CSA     I2 @S9S_MB_2U_LIB.S9S_MB_2U(SCH_1):PAGE243
  C535    1      A Q_CAP_C0805-22UF,16V,20%,X6S,CA     I4 @S9S_MB_2U_LIB.S9S_MB_2U(SCH_1):PAGE243
  C513    1      A Q_CAP_C0805-22UF,16V,20%,X6S,CA     I5 @S9S_MB_2U_LIB.S9S_MB_2U(SCH_1):PAGE243
 R1763    1      A Q_RES_0402LF-10K,1%,1/16W,EMPTA     I7 @S9S_MB_2U_LIB.S9S_MB_2U(SCH_1):PAGE243
 R1765    1      A Q_RES_0805LF-0,5%,1/8W,EMPTY,CA    I13 @S9S_MB_2U_LIB.S9S_MB_2U(SCH_1):PAGE243

PRSNT0_N @S9S_MB_2U_LIB.S9S_MB_2U(SCH_1):PRSNT0_N
 R1801    1      A Q_RES_0402LF-0,5%,1/16W,CHIP,CA   I172 @S9S_MB_2U_LIB.S9S_MB_2U(SCH_1):PAGE227
   J41  OB3    LD# SCONN168_ME1016810202011-SCONNA   I173 @S9S_MB_2U_LIB.S9S_MB_2U(SCH_1):PAGE227

PRSNT_CABLE_GPU_A1 @S9S_MB_2U_LIB.S9S_MB_2U(SCH_1):PRSNT_CABLE_GPU_A1
  Q134    6     D1 MOSFET_NCH_DUAL-PJT138K,SMLF,IA    I99 @S9S_MB_2U_LIB.S9S_MB_2U(SCH_1):PAGE143
 R4155    2      B Q_RES_0402LF-4.7K,5%,1/16W,CHIA   I100 @S9S_MB_2U_LIB.S9S_MB_2U(SCH_1):PAGE143
  Q134    5     G2 MOSFET_NCH_DUAL-PJT138K,SMLF,IA   I107 @S9S_MB_2U_LIB.S9S_MB_2U(SCH_1):PAGE143

PRSNT_CABLE_GPU_A1_ISO_N @S9S_MB_2U_LIB.S9S_MB_2U(SCH_1):PRSNT_CABLE_GPU_A1_ISO_N
 R4156    2      B Q_RES_0402LF-4.7K,5%,1/16W,CHIA   I101 @S9S_MB_2U_LIB.S9S_MB_2U(SCH_1):PAGE143
 C2270    1      A Q_CAP_0402-1000PF,50V,5%,EMPTYA   I105 @S9S_MB_2U_LIB.S9S_MB_2U(SCH_1):PAGE143
  Q134    3     D2 MOSFET_NCH_DUAL-PJT138K,SMLF,IA   I107 @S9S_MB_2U_LIB.S9S_MB_2U(SCH_1):PAGE143
 R4157    1      A Q_RES_0402LF-33.2,1%,1/16W,CHIA   I114 @S9S_MB_2U_LIB.S9S_MB_2U(SCH_1):PAGE312
 R4574    2      B Q_RES_0402LF-0,5%,1/16W,EMPTY,A   I136 @S9S_MB_2U_LIB.S9S_MB_2U(SCH_1):PAGE143
 R4742    1      A Q_RES_0402LF-0,5%,1/16W,CHIP,CA   I161 @S9S_MB_2U_LIB.S9S_MB_2U(SCH_1):PAGE214

PRSNT_CABLE_GPU_A1_ISO_R1_N @S9S_MB_2U_LIB.S9S_MB_2U(SCH_1):PRSNT_CABLE_GPU_A1_ISO_R1_N
  U181   19  IO1_6 PCA9539RPW-PCA9539RPW,SMLF,IC,A    I66 @S9S_MB_2U_LIB.S9S_MB_2U(SCH_1):PAGE214
 R4742    2      B Q_RES_0402LF-0,5%,1/16W,CHIP,CA   I161 @S9S_MB_2U_LIB.S9S_MB_2U(SCH_1):PAGE214

PRSNT_CABLE_GPU_A1_ISO_R_N @S9S_MB_2U_LIB.S9S_MB_2U(SCH_1):PRSNT_CABLE_GPU_A1_ISO_R_N
  U249  Y12  PB27A LCMXO3LF9400C5BG484C-LCMXO3LF-A     I1 @S9S_MB_2U_LIB.S9S_MB_2U(SCH_1):PAGE312
 R4157    2      B Q_RES_0402LF-33.2,1%,1/16W,CHIA   I114 @S9S_MB_2U_LIB.S9S_MB_2U(SCH_1):PAGE312

PRSNT_CABLE_GPU_A1_N @S9S_MB_2U_LIB.S9S_MB_2U(SCH_1):PRSNT_CABLE_GPU_A1_N
  J106   A7     A7 CONN112_10137002101LF-CONN112_A    I68 @S9S_MB_2U_LIB.S9S_MB_2U(SCH_1):PAGE144
  Q134    2     G1 MOSFET_NCH_DUAL-PJT138K,SMLF,IA    I99 @S9S_MB_2U_LIB.S9S_MB_2U(SCH_1):PAGE143
 R4154    1      A Q_RES_0402LF-100K,1%,1/16W,EMPA   I113 @S9S_MB_2U_LIB.S9S_MB_2U(SCH_1):PAGE143
 R4574    1      A Q_RES_0402LF-0,5%,1/16W,EMPTY,A   I136 @S9S_MB_2U_LIB.S9S_MB_2U(SCH_1):PAGE143
 R4153    2      B Q_RES_0402LF-10K,1%,1/16W,CHIPA   I145 @S9S_MB_2U_LIB.S9S_MB_2U(SCH_1):PAGE143

PRSNT_CABLE_GPU_A2 @S9S_MB_2U_LIB.S9S_MB_2U(SCH_1):PRSNT_CABLE_GPU_A2
  Q133    5     G2 MOSFET_NCH_DUAL-PJT138K,SMLF,IA    I71 @S9S_MB_2U_LIB.S9S_MB_2U(SCH_1):PAGE143
 R4139    2      B Q_RES_0402LF-4.7K,5%,1/16W,CHIA    I76 @S9S_MB_2U_LIB.S9S_MB_2U(SCH_1):PAGE143
  Q133    6     D1 MOSFET_NCH_DUAL-PJT138K,SMLF,IA    I78 @S9S_MB_2U_LIB.S9S_MB_2U(SCH_1):PAGE143

PRSNT_CABLE_GPU_A2_ISO_N @S9S_MB_2U_LIB.S9S_MB_2U(SCH_1):PRSNT_CABLE_GPU_A2_ISO_N
 C2269    1      A Q_CAP_0402-1000PF,50V,5%,EMPTYA    I57 @S9S_MB_2U_LIB.S9S_MB_2U(SCH_1):PAGE143
 R4142    2      B Q_RES_0402LF-4.7K,5%,1/16W,CHIA    I60 @S9S_MB_2U_LIB.S9S_MB_2U(SCH_1):PAGE143
  Q133    3     D2 MOSFET_NCH_DUAL-PJT138K,SMLF,IA    I71 @S9S_MB_2U_LIB.S9S_MB_2U(SCH_1):PAGE143
 R4147    1      A Q_RES_0402LF-33.2,1%,1/16W,CHIA   I104 @S9S_MB_2U_LIB.S9S_MB_2U(SCH_1):PAGE312
 R4578    2      B Q_RES_0402LF-0,5%,1/16W,EMPTY,A   I138 @S9S_MB_2U_LIB.S9S_MB_2U(SCH_1):PAGE143
 R4736    1      A Q_RES_0402LF-0,5%,1/16W,CHIP,CA   I153 @S9S_MB_2U_LIB.S9S_MB_2U(SCH_1):PAGE214

PRSNT_CABLE_GPU_A2_ISO_R1_N @S9S_MB_2U_LIB.S9S_MB_2U(SCH_1):PRSNT_CABLE_GPU_A2_ISO_R1_N
  U181   13  IO1_0 PCA9539RPW-PCA9539RPW,SMLF,IC,A    I66 @S9S_MB_2U_LIB.S9S_MB_2U(SCH_1):PAGE214
 R4736    2      B Q_RES_0402LF-0,5%,1/16W,CHIP,CA   I153 @S9S_MB_2U_LIB.S9S_MB_2U(SCH_1):PAGE214

PRSNT_CABLE_GPU_A2_ISO_R_N @S9S_MB_2U_LIB.S9S_MB_2U(SCH_1):PRSNT_CABLE_GPU_A2_ISO_R_N
  U249  V11  PB24C LCMXO3LF9400C5BG484C-LCMXO3LF-A     I1 @S9S_MB_2U_LIB.S9S_MB_2U(SCH_1):PAGE312
 R4147    2      B Q_RES_0402LF-33.2,1%,1/16W,CHIA   I104 @S9S_MB_2U_LIB.S9S_MB_2U(SCH_1):PAGE312

PRSNT_CABLE_GPU_A2_N @S9S_MB_2U_LIB.S9S_MB_2U(SCH_1):PRSNT_CABLE_GPU_A2_N
  J108   A3     A3 CONN112_10137002101LF-CONN112_A    I57 @S9S_MB_2U_LIB.S9S_MB_2U(SCH_1):PAGE320
  Q133    2     G1 MOSFET_NCH_DUAL-PJT138K,SMLF,IA    I78 @S9S_MB_2U_LIB.S9S_MB_2U(SCH_1):PAGE143
 R4136    1      A Q_RES_0402LF-100K,1%,1/16W,EMPA    I91 @S9S_MB_2U_LIB.S9S_MB_2U(SCH_1):PAGE143
 R4578    1      A Q_RES_0402LF-0,5%,1/16W,EMPTY,A   I138 @S9S_MB_2U_LIB.S9S_MB_2U(SCH_1):PAGE143
 R4135    2      B Q_RES_0402LF-10K,1%,1/16W,CHIPA   I144 @S9S_MB_2U_LIB.S9S_MB_2U(SCH_1):PAGE143

PRSNT_CABLE_GPU_A3 @S9S_MB_2U_LIB.S9S_MB_2U(SCH_1):PRSNT_CABLE_GPU_A3
  Q154    5     G2 MOSFET_NCH_DUAL-PJT138K,SMLF,IA    I62 @S9S_MB_2U_LIB.S9S_MB_2U(SCH_1):PAGE147
 R4800    2      B Q_RES_0402LF-4.7K,5%,1/16W,CHIA    I70 @S9S_MB_2U_LIB.S9S_MB_2U(SCH_1):PAGE147
  Q154    6     D1 MOSFET_NCH_DUAL-PJT138K,SMLF,IA    I71 @S9S_MB_2U_LIB.S9S_MB_2U(SCH_1):PAGE147

PRSNT_CABLE_GPU_A3_ISO_N @S9S_MB_2U_LIB.S9S_MB_2U(SCH_1):PRSNT_CABLE_GPU_A3_ISO_N
  Q154    3     D2 MOSFET_NCH_DUAL-PJT138K,SMLF,IA    I62 @S9S_MB_2U_LIB.S9S_MB_2U(SCH_1):PAGE147
 R4801    2      B Q_RES_0402LF-4.7K,5%,1/16W,CHIA    I65 @S9S_MB_2U_LIB.S9S_MB_2U(SCH_1):PAGE147
 C2391    1      A Q_CAP_0402-1000PF,50V,5%,EMPTYA    I66 @S9S_MB_2U_LIB.S9S_MB_2U(SCH_1):PAGE147
 R4802    1      A Q_RES_0402LF-0,5%,1/16W,CHIP,CA   I164 @S9S_MB_2U_LIB.S9S_MB_2U(SCH_1):PAGE214

PRSNT_CABLE_GPU_A3_ISO_R_N @S9S_MB_2U_LIB.S9S_MB_2U(SCH_1):PRSNT_CABLE_GPU_A3_ISO_R_N
  U181   20  IO1_7 PCA9539RPW-PCA9539RPW,SMLF,IC,A    I66 @S9S_MB_2U_LIB.S9S_MB_2U(SCH_1):PAGE214
 R4802    2      B Q_RES_0402LF-0,5%,1/16W,CHIP,CA   I164 @S9S_MB_2U_LIB.S9S_MB_2U(SCH_1):PAGE214

PRSNT_CABLE_GPU_A3_N @S9S_MB_2U_LIB.S9S_MB_2U(SCH_1):PRSNT_CABLE_GPU_A3_N
  J108   N8     N8 CONN112_10137002101LF-CONN112_A    I76 @S9S_MB_2U_LIB.S9S_MB_2U(SCH_1):PAGE320
  Q154    2     G1 MOSFET_NCH_DUAL-PJT138K,SMLF,IA    I71 @S9S_MB_2U_LIB.S9S_MB_2U(SCH_1):PAGE147
 R4798    2      B Q_RES_0402LF-10K,1%,1/16W,CHIPA    I75 @S9S_MB_2U_LIB.S9S_MB_2U(SCH_1):PAGE147
 R4799    1      A Q_RES_0402LF-100K,1%,1/16W,EMPA    I76 @S9S_MB_2U_LIB.S9S_MB_2U(SCH_1):PAGE147

PRSNT_CABLE_GPU_B3 @S9S_MB_2U_LIB.S9S_MB_2U(SCH_1):PRSNT_CABLE_GPU_B3
  Q132    5     G2 MOSFET_NCH_DUAL-PJT138K,SMLF,IA    I35 @S9S_MB_2U_LIB.S9S_MB_2U(SCH_1):PAGE143
 R4126    2      B Q_RES_0402LF-4.7K,5%,1/16W,CHIA    I43 @S9S_MB_2U_LIB.S9S_MB_2U(SCH_1):PAGE143
  Q132    6     D1 MOSFET_NCH_DUAL-PJT138K,SMLF,IA    I44 @S9S_MB_2U_LIB.S9S_MB_2U(SCH_1):PAGE143

PRSNT_CABLE_GPU_B3_ISO_N @S9S_MB_2U_LIB.S9S_MB_2U(SCH_1):PRSNT_CABLE_GPU_B3_ISO_N
  Q132    3     D2 MOSFET_NCH_DUAL-PJT138K,SMLF,IA    I35 @S9S_MB_2U_LIB.S9S_MB_2U(SCH_1):PAGE143
 R4129    2      B Q_RES_0402LF-4.7K,5%,1/16W,CHIA    I36 @S9S_MB_2U_LIB.S9S_MB_2U(SCH_1):PAGE143
 C2265    1      A Q_CAP_0402-1000PF,50V,5%,EMPTYA    I40 @S9S_MB_2U_LIB.S9S_MB_2U(SCH_1):PAGE143
 R4145    1      A Q_RES_0402LF-33.2,1%,1/16W,CHIA    I97 @S9S_MB_2U_LIB.S9S_MB_2U(SCH_1):PAGE312
 R4573    2      B Q_RES_0402LF-0,5%,1/16W,EMPTY,A   I140 @S9S_MB_2U_LIB.S9S_MB_2U(SCH_1):PAGE143
 R4734    1      A Q_RES_0402LF-0,5%,1/16W,CHIP,CA   I144 @S9S_MB_2U_LIB.S9S_MB_2U(SCH_1):PAGE214

PRSNT_CABLE_GPU_B3_ISO_R1_N @S9S_MB_2U_LIB.S9S_MB_2U(SCH_1):PRSNT_CABLE_GPU_B3_ISO_R1_N
  U181   10  IO0_6 PCA9539RPW-PCA9539RPW,SMLF,IC,A    I66 @S9S_MB_2U_LIB.S9S_MB_2U(SCH_1):PAGE214
 R4734    2      B Q_RES_0402LF-0,5%,1/16W,CHIP,CA   I144 @S9S_MB_2U_LIB.S9S_MB_2U(SCH_1):PAGE214

PRSNT_CABLE_GPU_B3_ISO_R_N @S9S_MB_2U_LIB.S9S_MB_2U(SCH_1):PRSNT_CABLE_GPU_B3_ISO_R_N
  U249 AA11  PB24A LCMXO3LF9400C5BG484C-LCMXO3LF-A     I1 @S9S_MB_2U_LIB.S9S_MB_2U(SCH_1):PAGE312
 R4145    2      B Q_RES_0402LF-33.2,1%,1/16W,CHIA    I97 @S9S_MB_2U_LIB.S9S_MB_2U(SCH_1):PAGE312

PRSNT_CABLE_GPU_B3_N @S9S_MB_2U_LIB.S9S_MB_2U(SCH_1):PRSNT_CABLE_GPU_B3_N
  J109   N8     N8 CONN112_10137002101LF-CONN112_A    I76 @S9S_MB_2U_LIB.S9S_MB_2U(SCH_1):PAGE319
  Q132    2     G1 MOSFET_NCH_DUAL-PJT138K,SMLF,IA    I44 @S9S_MB_2U_LIB.S9S_MB_2U(SCH_1):PAGE143
 R4122    1      A Q_RES_0402LF-100K,1%,1/16W,EMPA    I49 @S9S_MB_2U_LIB.S9S_MB_2U(SCH_1):PAGE143
 R4573    1      A Q_RES_0402LF-0,5%,1/16W,EMPTY,A   I140 @S9S_MB_2U_LIB.S9S_MB_2U(SCH_1):PAGE143
 R4121    2      B Q_RES_0402LF-10K,1%,1/16W,CHIPA   I143 @S9S_MB_2U_LIB.S9S_MB_2U(SCH_1):PAGE143

PRSNT_CABLE_SWB_B1 @S9S_MB_2U_LIB.S9S_MB_2U(SCH_1):PRSNT_CABLE_SWB_B1
  Q153    5     G2 MOSFET_NCH_DUAL-PJT138K,SMLF,IA    I51 @S9S_MB_2U_LIB.S9S_MB_2U(SCH_1):PAGE147
 R4739    2      B Q_RES_0402LF-4.7K,5%,1/16W,CHIA    I54 @S9S_MB_2U_LIB.S9S_MB_2U(SCH_1):PAGE147
  Q153    6     D1 MOSFET_NCH_DUAL-PJT138K,SMLF,IA    I55 @S9S_MB_2U_LIB.S9S_MB_2U(SCH_1):PAGE147

PRSNT_CABLE_SWB_B1_ISO_N @S9S_MB_2U_LIB.S9S_MB_2U(SCH_1):PRSNT_CABLE_SWB_B1_ISO_N
 C2374    1      A Q_CAP_0402-1000PF,50V,5%,EMPTYA    I47 @S9S_MB_2U_LIB.S9S_MB_2U(SCH_1):PAGE147
 R4740    2      B Q_RES_0402LF-4.7K,5%,1/16W,CHIA    I50 @S9S_MB_2U_LIB.S9S_MB_2U(SCH_1):PAGE147
  Q153    3     D2 MOSFET_NCH_DUAL-PJT138K,SMLF,IA    I51 @S9S_MB_2U_LIB.S9S_MB_2U(SCH_1):PAGE147
 R4741    1      A Q_RES_0402LF-0,5%,1/16W,CHIP,CA   I156 @S9S_MB_2U_LIB.S9S_MB_2U(SCH_1):PAGE214

PRSNT_CABLE_SWB_B1_ISO_R_N @S9S_MB_2U_LIB.S9S_MB_2U(SCH_1):PRSNT_CABLE_SWB_B1_ISO_R_N
  U181   14  IO1_1 PCA9539RPW-PCA9539RPW,SMLF,IC,A    I66 @S9S_MB_2U_LIB.S9S_MB_2U(SCH_1):PAGE214
 R4741    2      B Q_RES_0402LF-0,5%,1/16W,CHIP,CA   I156 @S9S_MB_2U_LIB.S9S_MB_2U(SCH_1):PAGE214

PRSNT_CABLE_SWB_B1_N @S9S_MB_2U_LIB.S9S_MB_2U(SCH_1):PRSNT_CABLE_SWB_B1_N
  J106   A1     A1 CONN112_10137002101LF-CONN112_A    I65 @S9S_MB_2U_LIB.S9S_MB_2U(SCH_1):PAGE144
  Q153    2     G1 MOSFET_NCH_DUAL-PJT138K,SMLF,IA    I55 @S9S_MB_2U_LIB.S9S_MB_2U(SCH_1):PAGE147
 R4737    2      B Q_RES_0402LF-10K,1%,1/16W,CHIPA    I58 @S9S_MB_2U_LIB.S9S_MB_2U(SCH_1):PAGE147
 R4738    1      A Q_RES_0402LF-100K,1%,1/16W,EMPA    I60 @S9S_MB_2U_LIB.S9S_MB_2U(SCH_1):PAGE147

PRSNT_CABLE_SWB_B2 @S9S_MB_2U_LIB.S9S_MB_2U(SCH_1):PRSNT_CABLE_SWB_B2
  Q152    5     G2 MOSFET_NCH_DUAL-PJT138K,SMLF,IA    I26 @S9S_MB_2U_LIB.S9S_MB_2U(SCH_1):PAGE147
 R4732    2      B Q_RES_0402LF-4.7K,5%,1/16W,CHIA    I36 @S9S_MB_2U_LIB.S9S_MB_2U(SCH_1):PAGE147
  Q152    6     D1 MOSFET_NCH_DUAL-PJT138K,SMLF,IA    I38 @S9S_MB_2U_LIB.S9S_MB_2U(SCH_1):PAGE147

PRSNT_CABLE_SWB_B2_ISO_N @S9S_MB_2U_LIB.S9S_MB_2U(SCH_1):PRSNT_CABLE_SWB_B2_ISO_N
 R4735    1      A Q_RES_0402LF-0,5%,1/16W,CHIP,CA   I148 @S9S_MB_2U_LIB.S9S_MB_2U(SCH_1):PAGE214
 C2373    1      A Q_CAP_0402-1000PF,50V,5%,EMPTYA    I22 @S9S_MB_2U_LIB.S9S_MB_2U(SCH_1):PAGE147
 R4733    2      B Q_RES_0402LF-4.7K,5%,1/16W,CHIA    I25 @S9S_MB_2U_LIB.S9S_MB_2U(SCH_1):PAGE147
  Q152    3     D2 MOSFET_NCH_DUAL-PJT138K,SMLF,IA    I26 @S9S_MB_2U_LIB.S9S_MB_2U(SCH_1):PAGE147

PRSNT_CABLE_SWB_B2_ISO_R_N @S9S_MB_2U_LIB.S9S_MB_2U(SCH_1):PRSNT_CABLE_SWB_B2_ISO_R_N
  U181   11  IO0_7 PCA9539RPW-PCA9539RPW,SMLF,IC,A    I66 @S9S_MB_2U_LIB.S9S_MB_2U(SCH_1):PAGE214
 R4735    2      B Q_RES_0402LF-0,5%,1/16W,CHIP,CA   I148 @S9S_MB_2U_LIB.S9S_MB_2U(SCH_1):PAGE214

PRSNT_CABLE_SWB_B2_N @S9S_MB_2U_LIB.S9S_MB_2U(SCH_1):PRSNT_CABLE_SWB_B2_N
  J107   N2     N2 CONN112_10137002101LF-CONN112_A    I58 @S9S_MB_2U_LIB.S9S_MB_2U(SCH_1):PAGE317
  Q152    2     G1 MOSFET_NCH_DUAL-PJT138K,SMLF,IA    I38 @S9S_MB_2U_LIB.S9S_MB_2U(SCH_1):PAGE147
 R4730    2      B Q_RES_0402LF-10K,1%,1/16W,CHIPA    I41 @S9S_MB_2U_LIB.S9S_MB_2U(SCH_1):PAGE147
 R4731    1      A Q_RES_0402LF-100K,1%,1/16W,EMPA    I42 @S9S_MB_2U_LIB.S9S_MB_2U(SCH_1):PAGE147

PRSNT_SWB @S9S_MB_2U_LIB.S9S_MB_2U(SCH_1):PRSNT_SWB
  Q151    5     G2 MOSFET_NCH_DUAL-PJT138K,SMLF,IA    I20 @S9S_MB_2U_LIB.S9S_MB_2U(SCH_1):PAGE147
 R4725    2      B Q_RES_0402LF-4.7K,5%,1/16W,CHIA    I28 @S9S_MB_2U_LIB.S9S_MB_2U(SCH_1):PAGE147
  Q151    6     D1 MOSFET_NCH_DUAL-PJT138K,SMLF,IA    I31 @S9S_MB_2U_LIB.S9S_MB_2U(SCH_1):PAGE147

PRSNT_SWB_ISO_N @S9S_MB_2U_LIB.S9S_MB_2U(SCH_1):PRSNT_SWB_ISO_N
 R4057    1      A Q_RES_0402LF-33.2,1%,1/16W,CHIA   I217 @S9S_MB_2U_LIB.S9S_MB_2U(SCH_1):PAGE312
 R4728    1      A Q_RES_0402LF-0,5%,1/16W,CHIP,CA   I137 @S9S_MB_2U_LIB.S9S_MB_2U(SCH_1):PAGE214
 C2372    1      A Q_CAP_0402-1000PF,50V,5%,EMPTYA    I15 @S9S_MB_2U_LIB.S9S_MB_2U(SCH_1):PAGE147
 R4726    2      B Q_RES_0402LF-4.7K,5%,1/16W,CHIA    I18 @S9S_MB_2U_LIB.S9S_MB_2U(SCH_1):PAGE147
  Q151    3     D2 MOSFET_NCH_DUAL-PJT138K,SMLF,IA    I20 @S9S_MB_2U_LIB.S9S_MB_2U(SCH_1):PAGE147

PRSNT_SWB_ISO_R1_N @S9S_MB_2U_LIB.S9S_MB_2U(SCH_1):PRSNT_SWB_ISO_R1_N
  U181    8  IO0_4 PCA9539RPW-PCA9539RPW,SMLF,IC,A    I66 @S9S_MB_2U_LIB.S9S_MB_2U(SCH_1):PAGE214
 R4728    2      B Q_RES_0402LF-0,5%,1/16W,CHIP,CA   I137 @S9S_MB_2U_LIB.S9S_MB_2U(SCH_1):PAGE214

PRSNT_SWB_ISO_R_N @S9S_MB_2U_LIB.S9S_MB_2U(SCH_1):PRSNT_SWB_ISO_R_N
  U249   Y9  PB21C LCMXO3LF9400C5BG484C-LCMXO3LF-A     I1 @S9S_MB_2U_LIB.S9S_MB_2U(SCH_1):PAGE312
 R4057    2      B Q_RES_0402LF-33.2,1%,1/16W,CHIA   I217 @S9S_MB_2U_LIB.S9S_MB_2U(SCH_1):PAGE312

PRSNT_SWB_N @S9S_MB_2U_LIB.S9S_MB_2U(SCH_1):PRSNT_SWB_N
  J112   A7     A7 CONN160_10131762101LF-CONN160_A    I75 @S9S_MB_2U_LIB.S9S_MB_2U(SCH_1):PAGE149
  Q151    2     G1 MOSFET_NCH_DUAL-PJT138K,SMLF,IA    I31 @S9S_MB_2U_LIB.S9S_MB_2U(SCH_1):PAGE147
 R4727    2      B Q_RES_0402LF-10K,1%,1/16W,CHIPA    I33 @S9S_MB_2U_LIB.S9S_MB_2U(SCH_1):PAGE147
 R4724    1      A Q_RES_0402LF-100K,1%,1/16W,EMPA    I34 @S9S_MB_2U_LIB.S9S_MB_2U(SCH_1):PAGE147

PUD_PCH_BOOT_MODE_CPU0 @S9S_MB_2U_LIB.S9S_MB_2U(SCH_1):PUD_PCH_BOOT_MODE_CPU0
    U2 CF61 TEST_6 SOCKET4677_AZIF0045P001C01CS-SA     I1 @S9S_MB_2U_LIB.S9S_MB_2U(SCH_1):PAGE15
  R252    2      B Q_RES_0402LF-240,1%,1/16W,CHIPA    I30 @S9S_MB_2U_LIB.S9S_MB_2U(SCH_1):PAGE120

PUD_PCH_BOOT_MODE_CPU1 @S9S_MB_2U_LIB.S9S_MB_2U(SCH_1):PUD_PCH_BOOT_MODE_CPU1
    U1 CF61 TEST_6 SOCKET4677_AZIF0045P001C01CS-SA     I5 @S9S_MB_2U_LIB.S9S_MB_2U(SCH_1):PAGE46
  R258    2      B Q_RES_0402LF-240,1%,1/16W,CHIPA    I44 @S9S_MB_2U_LIB.S9S_MB_2U(SCH_1):PAGE120

PUD_XTAL_CPU0_MODE0 @S9S_MB_2U_LIB.S9S_MB_2U(SCH_1):PUD_XTAL_CPU0_MODE0
    U2 CL72 RSVD120 SOCKET4677_AZIF0045P001C01CS-SA    I57 @S9S_MB_2U_LIB.S9S_MB_2U(SCH_1):PAGE13
 R1232    2      B Q_RES_0402LF-240,1%,1/16W,EMPTA   I156 @S9S_MB_2U_LIB.S9S_MB_2U(SCH_1):PAGE119
 R1238    2      B Q_RES_0402LF-240,1%,1/16W,EMPTA   I161 @S9S_MB_2U_LIB.S9S_MB_2U(SCH_1):PAGE119

PUD_XTAL_CPU0_MODE1 @S9S_MB_2U_LIB.S9S_MB_2U(SCH_1):PUD_XTAL_CPU0_MODE1
    U2 CJ72 RSVD108 SOCKET4677_AZIF0045P001C01CS-SA    I57 @S9S_MB_2U_LIB.S9S_MB_2U(SCH_1):PAGE13
 R1233    2      B Q_RES_0402LF-240,1%,1/16W,EMPTA   I158 @S9S_MB_2U_LIB.S9S_MB_2U(SCH_1):PAGE119
 R1239    2      B Q_RES_0402LF-240,1%,1/16W,EMPTA   I163 @S9S_MB_2U_LIB.S9S_MB_2U(SCH_1):PAGE119

PUD_XTAL_CPU1_MODE0 @S9S_MB_2U_LIB.S9S_MB_2U(SCH_1):PUD_XTAL_CPU1_MODE0
    U1 CL72 RSVD120 SOCKET4677_AZIF0045P001C01CS-SA    I51 @S9S_MB_2U_LIB.S9S_MB_2U(SCH_1):PAGE44
 R1229    2      B Q_RES_0402LF-240,1%,1/16W,EMPTA   I169 @S9S_MB_2U_LIB.S9S_MB_2U(SCH_1):PAGE119
 R1235    2      B Q_RES_0402LF-240,1%,1/16W,EMPTA   I176 @S9S_MB_2U_LIB.S9S_MB_2U(SCH_1):PAGE119

PUD_XTAL_CPU1_MODE1 @S9S_MB_2U_LIB.S9S_MB_2U(SCH_1):PUD_XTAL_CPU1_MODE1
    U1 CJ72 RSVD108 SOCKET4677_AZIF0045P001C01CS-SA    I51 @S9S_MB_2U_LIB.S9S_MB_2U(SCH_1):PAGE44
 R1230    2      B Q_RES_0402LF-240,1%,1/16W,EMPTA   I170 @S9S_MB_2U_LIB.S9S_MB_2U(SCH_1):PAGE119
 R1236    2      B Q_RES_0402LF-240,1%,1/16W,EMPTA   I177 @S9S_MB_2U_LIB.S9S_MB_2U(SCH_1):PAGE119

PULL_FPGA_PB46A @S9S_MB_2U_LIB.S9S_MB_2U(SCH_1):PULL_FPGA_PB46A
  U249 AB21 PB46A||SN LCMXO3LF9400C5BG484C-LCMXO3LF-A     I1 @S9S_MB_2U_LIB.S9S_MB_2U(SCH_1):PAGE312
 R4086    2      B Q_RES_0402LF-10K,1%,1/16W,CHIPA    I86 @S9S_MB_2U_LIB.S9S_MB_2U(SCH_1):PAGE312

PU_ACPRESENT @S9S_MB_2U_LIB.S9S_MB_2U(SCH_1):PU_ACPRESENT
    U4  AN7 ACPRESENT EMMITSBURG_REV0P9-GFNOCPU04302A    I36 @S9S_MB_2U_LIB.S9S_MB_2U(SCH_1):PAGE174
 R1198    2      B Q_RES_0402LF-10K,1%,1/16W,CHIPA    I48 @S9S_MB_2U_LIB.S9S_MB_2U(SCH_1):PAGE174

PU_BIOS_RCVR_BOOT @S9S_MB_2U_LIB.S9S_MB_2U(SCH_1):PU_BIOS_RCVR_BOOT
 R1317    2      B Q_RES_0402LF-1K,1%,1/16W,CHIP,A    I88 @S9S_MB_2U_LIB.S9S_MB_2U(SCH_1):PAGE189
  J104    3      3 CONN14_210HP207GBR1-CONN14_210A   I134 @S9S_MB_2U_LIB.S9S_MB_2U(SCH_1):PAGE189

PU_BUFFER_HDD_ACTIVITY @S9S_MB_2U_LIB.S9S_MB_2U(SCH_1):PU_BUFFER_HDD_ACTIVITY
 R5377    2      B Q_RES_0402LF-0,5%,1/16W,CHIP,CA   I312 @S9S_MB_2U_LIB.S9S_MB_2U(SCH_1):PAGE182
  U239    1     OE 74LVC1G126SE7-74LVC1G126SE-7,SA   I315 @S9S_MB_2U_LIB.S9S_MB_2U(SCH_1):PAGE182

PU_CK440_SHFT_LD_N @S9S_MB_2U_LIB.S9S_MB_2U(SCH_1):PU_CK440_SHFT_LD_N
   U13  B42 SHFT_LD# 9SQ440NQQI8-9SQ440NQQI8,SMLF,IA   I180 @S9S_MB_2U_LIB.S9S_MB_2U(SCH_1):PAGE197
 R1204    2      B Q_RES_0402LF-10K,1%,1/16W,EMPTA   I273 @S9S_MB_2U_LIB.S9S_MB_2U(SCH_1):PAGE197
 R1267    1      A Q_RES_0402LF-1K,1%,1/16W,CHIP,A   I276 @S9S_MB_2U_LIB.S9S_MB_2U(SCH_1):PAGE197

PU_CLK25M_OSC_FPGA_EN @S9S_MB_2U_LIB.S9S_MB_2U(SCH_1):PU_CLK25M_OSC_FPGA_EN
  OSC2    1     OE Q_OSC4P_SMLF-25MHZ,OSC,BF62500A   I127 @S9S_MB_2U_LIB.S9S_MB_2U(SCH_1):PAGE313
 R1099    2      B Q_RES_0402LF-10K,1%,1/16W,CHIPA   I129 @S9S_MB_2U_LIB.S9S_MB_2U(SCH_1):PAGE313

PU_CLK_BUF_ISO_EN @S9S_MB_2U_LIB.S9S_MB_2U(SCH_1):PU_CLK_BUF_ISO_EN
  U315    5     EN PCA9617ADP-PCA9617ADP,SMLF,IC,A    I17 @S9S_MB_2U_LIB.S9S_MB_2U(SCH_1):PAGE225
 R4500    2      B Q_RES_0402LF-10K,1%,1/16W,EMPTA    I32 @S9S_MB_2U_LIB.S9S_MB_2U(SCH_1):PAGE225

PU_CLK_PFT_LOST_N @S9S_MB_2U_LIB.S9S_MB_2U(SCH_1):PU_CLK_PFT_LOST_N
   U13   B4 PFT_LOST# 9SQ440NQQI8-9SQ440NQQI8,SMLF,IA   I180 @S9S_MB_2U_LIB.S9S_MB_2U(SCH_1):PAGE197
 R1958    2      B Q_RES_0402LF-10K,1%,1/16W,CHIPA   I303 @S9S_MB_2U_LIB.S9S_MB_2U(SCH_1):PAGE197

PU_CPU0_FRMAGENT @S9S_MB_2U_LIB.S9S_MB_2U(SCH_1):PU_CPU0_FRMAGENT
    U2 AU17 FRMAGENT SOCKET4677_AZIF0045P001C01CS-SA    I57 @S9S_MB_2U_LIB.S9S_MB_2U(SCH_1):PAGE13
  R277    2      B Q_RES_0402LF-240,1%,1/16W,CHIPA    I62 @S9S_MB_2U_LIB.S9S_MB_2U(SCH_1):PAGE119

PU_CPU0_LEGACY_SKT @S9S_MB_2U_LIB.S9S_MB_2U(SCH_1):PU_CPU0_LEGACY_SKT
    U2 CY59 LEGACY_SKT SOCKET4677_AZIF0045P001C01CS-SA    I57 @S9S_MB_2U_LIB.S9S_MB_2U(SCH_1):PAGE13
  R282    2      B Q_RES_0402LF-240,1%,1/16W,CHIPA    I53 @S9S_MB_2U_LIB.S9S_MB_2U(SCH_1):PAGE119

PU_CPU0_SAFE_MODE_BOOT @S9S_MB_2U_LIB.S9S_MB_2U(SCH_1):PU_CPU0_SAFE_MODE_BOOT
    U2 AU23 SAFE_MODE_BOOT SOCKET4677_AZIF0045P001C01CS-SA    I57 @S9S_MB_2U_LIB.S9S_MB_2U(SCH_1):PAGE13
  R276    2      B Q_RES_0402LF-240,1%,1/16W,EMPTA    I66 @S9S_MB_2U_LIB.S9S_MB_2U(SCH_1):PAGE119

PU_CPU0_SOCKET_ID0 @S9S_MB_2U_LIB.S9S_MB_2U(SCH_1):PU_CPU0_SOCKET_ID0
    U2 CW60 SOCKET_ID0 SOCKET4677_AZIF0045P001C01CS-SA    I57 @S9S_MB_2U_LIB.S9S_MB_2U(SCH_1):PAGE13
  R279    2      B Q_RES_0402LF-240,1%,1/16W,EMPTA    I54 @S9S_MB_2U_LIB.S9S_MB_2U(SCH_1):PAGE119

PU_CPU0_SOCKET_ID1 @S9S_MB_2U_LIB.S9S_MB_2U(SCH_1):PU_CPU0_SOCKET_ID1
    U2 CY61 SOCKET_ID1 SOCKET4677_AZIF0045P001C01CS-SA    I57 @S9S_MB_2U_LIB.S9S_MB_2U(SCH_1):PAGE13
  R280    2      B Q_RES_0402LF-240,1%,1/16W,EMPTA    I57 @S9S_MB_2U_LIB.S9S_MB_2U(SCH_1):PAGE119

PU_CPU0_SOCKET_ID2 @S9S_MB_2U_LIB.S9S_MB_2U(SCH_1):PU_CPU0_SOCKET_ID2
    U2 CT61 SOCKET_ID2 SOCKET4677_AZIF0045P001C01CS-SA    I57 @S9S_MB_2U_LIB.S9S_MB_2U(SCH_1):PAGE13
  R281    2      B Q_RES_0402LF-240,1%,1/16W,EMPTA    I58 @S9S_MB_2U_LIB.S9S_MB_2U(SCH_1):PAGE119

PU_CPU0_TXT_AGENT @S9S_MB_2U_LIB.S9S_MB_2U(SCH_1):PU_CPU0_TXT_AGENT
    U2 BT26 TXT_AGENT SOCKET4677_AZIF0045P001C01CS-SA    I57 @S9S_MB_2U_LIB.S9S_MB_2U(SCH_1):PAGE13
  R275    2      B Q_RES_0402LF-240,1%,1/16W,CHIPA    I68 @S9S_MB_2U_LIB.S9S_MB_2U(SCH_1):PAGE119

PU_CPU0_UPI0_AC_COUPLING @S9S_MB_2U_LIB.S9S_MB_2U(SCH_1):PU_CPU0_UPI0_AC_COUPLING
    U2 BA23 UPI0_AC_COUPLING SOCKET4677_AZIF0045P001C01CS-SA     I1 @S9S_MB_2U_LIB.S9S_MB_2U(SCH_1):PAGE19
   R94    2      B Q_RES_0402LF-240,1%,1/16W,EMPTA    I25 @S9S_MB_2U_LIB.S9S_MB_2U(SCH_1):PAGE126

PU_CPU0_UPI1_AC_COUPLING @S9S_MB_2U_LIB.S9S_MB_2U(SCH_1):PU_CPU0_UPI1_AC_COUPLING
    U2 CW19 UPI1_AC_COUPLING SOCKET4677_AZIF0045P001C01CS-SA     I1 @S9S_MB_2U_LIB.S9S_MB_2U(SCH_1):PAGE19
   R95    2      B Q_RES_0402LF-240,1%,1/16W,EMPTA    I23 @S9S_MB_2U_LIB.S9S_MB_2U(SCH_1):PAGE126

PU_CPU0_UPI2_AC_COUPLING @S9S_MB_2U_LIB.S9S_MB_2U(SCH_1):PU_CPU0_UPI2_AC_COUPLING
    U2 BB65 UPI2_AC_COUPLING SOCKET4677_AZIF0045P001C01CS-SA     I1 @S9S_MB_2U_LIB.S9S_MB_2U(SCH_1):PAGE19
   R96    2      B Q_RES_0402LF-240,1%,1/16W,EMPTA    I22 @S9S_MB_2U_LIB.S9S_MB_2U(SCH_1):PAGE126

PU_CPU0_UPI3_AC_COUPLING @S9S_MB_2U_LIB.S9S_MB_2U(SCH_1):PU_CPU0_UPI3_AC_COUPLING
    U2 CK71 UPI3_AC_COUPLING SOCKET4677_AZIF0045P001C01CS-SA     I1 @S9S_MB_2U_LIB.S9S_MB_2U(SCH_1):PAGE19
   R97    2      B Q_RES_0402LF-240,1%,1/16W,EMPTA   I114 @S9S_MB_2U_LIB.S9S_MB_2U(SCH_1):PAGE126

PU_CPU1_FRMAGENT @S9S_MB_2U_LIB.S9S_MB_2U(SCH_1):PU_CPU1_FRMAGENT
    U1 AU17 FRMAGENT SOCKET4677_AZIF0045P001C01CS-SA    I51 @S9S_MB_2U_LIB.S9S_MB_2U(SCH_1):PAGE44
  R263    2      B Q_RES_0402LF-240,1%,1/16W,EMPTA   I125 @S9S_MB_2U_LIB.S9S_MB_2U(SCH_1):PAGE119

PU_CPU1_LEGACY_SKT @S9S_MB_2U_LIB.S9S_MB_2U(SCH_1):PU_CPU1_LEGACY_SKT
    U1 CY59 LEGACY_SKT SOCKET4677_AZIF0045P001C01CS-SA    I51 @S9S_MB_2U_LIB.S9S_MB_2U(SCH_1):PAGE44
  R268    2      B Q_RES_0402LF-240,1%,1/16W,EMPTA    I94 @S9S_MB_2U_LIB.S9S_MB_2U(SCH_1):PAGE119

PU_CPU1_SAFE_MODE_BOOT @S9S_MB_2U_LIB.S9S_MB_2U(SCH_1):PU_CPU1_SAFE_MODE_BOOT
    U1 AU23 SAFE_MODE_BOOT SOCKET4677_AZIF0045P001C01CS-SA    I51 @S9S_MB_2U_LIB.S9S_MB_2U(SCH_1):PAGE44
  R262    2      B Q_RES_0402LF-240,1%,1/16W,EMPTA   I100 @S9S_MB_2U_LIB.S9S_MB_2U(SCH_1):PAGE119

PU_CPU1_SOCKET_ID0 @S9S_MB_2U_LIB.S9S_MB_2U(SCH_1):PU_CPU1_SOCKET_ID0
    U1 CW60 SOCKET_ID0 SOCKET4677_AZIF0045P001C01CS-SA    I51 @S9S_MB_2U_LIB.S9S_MB_2U(SCH_1):PAGE44
  R265    2      B Q_RES_0402LF-240,1%,1/16W,CHIPA    I97 @S9S_MB_2U_LIB.S9S_MB_2U(SCH_1):PAGE119

PU_CPU1_SOCKET_ID1 @S9S_MB_2U_LIB.S9S_MB_2U(SCH_1):PU_CPU1_SOCKET_ID1
    U1 CY61 SOCKET_ID1 SOCKET4677_AZIF0045P001C01CS-SA    I51 @S9S_MB_2U_LIB.S9S_MB_2U(SCH_1):PAGE44
  R266    2      B Q_RES_0402LF-240,1%,1/16W,EMPTA    I96 @S9S_MB_2U_LIB.S9S_MB_2U(SCH_1):PAGE119

PU_CPU1_SOCKET_ID2 @S9S_MB_2U_LIB.S9S_MB_2U(SCH_1):PU_CPU1_SOCKET_ID2
    U1 CT61 SOCKET_ID2 SOCKET4677_AZIF0045P001C01CS-SA    I51 @S9S_MB_2U_LIB.S9S_MB_2U(SCH_1):PAGE44
  R267    2      B Q_RES_0402LF-240,1%,1/16W,EMPTA    I95 @S9S_MB_2U_LIB.S9S_MB_2U(SCH_1):PAGE119

PU_CPU1_TXT_AGENT @S9S_MB_2U_LIB.S9S_MB_2U(SCH_1):PU_CPU1_TXT_AGENT
    U1 BT26 TXT_AGENT SOCKET4677_AZIF0045P001C01CS-SA    I51 @S9S_MB_2U_LIB.S9S_MB_2U(SCH_1):PAGE44
  R261    2      B Q_RES_0402LF-240,1%,1/16W,EMPTA   I101 @S9S_MB_2U_LIB.S9S_MB_2U(SCH_1):PAGE119

PU_CPU1_UPI0_AC_COUPLING @S9S_MB_2U_LIB.S9S_MB_2U(SCH_1):PU_CPU1_UPI0_AC_COUPLING
    U1 BA23 UPI0_AC_COUPLING SOCKET4677_AZIF0045P001C01CS-SA    I23 @S9S_MB_2U_LIB.S9S_MB_2U(SCH_1):PAGE50
   R90    2      B Q_RES_0402LF-240,1%,1/16W,EMPTA   I135 @S9S_MB_2U_LIB.S9S_MB_2U(SCH_1):PAGE126

PU_CPU1_UPI1_AC_COUPLING @S9S_MB_2U_LIB.S9S_MB_2U(SCH_1):PU_CPU1_UPI1_AC_COUPLING
    U1 CW19 UPI1_AC_COUPLING SOCKET4677_AZIF0045P001C01CS-SA    I23 @S9S_MB_2U_LIB.S9S_MB_2U(SCH_1):PAGE50
   R91    2      B Q_RES_0402LF-240,1%,1/16W,EMPTA   I136 @S9S_MB_2U_LIB.S9S_MB_2U(SCH_1):PAGE126

PU_CPU1_UPI2_AC_COUPLING @S9S_MB_2U_LIB.S9S_MB_2U(SCH_1):PU_CPU1_UPI2_AC_COUPLING
    U1 BB65 UPI2_AC_COUPLING SOCKET4677_AZIF0045P001C01CS-SA    I23 @S9S_MB_2U_LIB.S9S_MB_2U(SCH_1):PAGE50
   R92    2      B Q_RES_0402LF-240,1%,1/16W,EMPTA   I140 @S9S_MB_2U_LIB.S9S_MB_2U(SCH_1):PAGE126

PU_CPU1_UPI3_AC_COUPLING @S9S_MB_2U_LIB.S9S_MB_2U(SCH_1):PU_CPU1_UPI3_AC_COUPLING
    U1 CK71 UPI3_AC_COUPLING SOCKET4677_AZIF0045P001C01CS-SA    I23 @S9S_MB_2U_LIB.S9S_MB_2U(SCH_1):PAGE50
   R93    2      B Q_RES_0402LF-240,1%,1/16W,EMPTA   I141 @S9S_MB_2U_LIB.S9S_MB_2U(SCH_1):PAGE126

PU_E1S_0_DUALPORT_EN_N @S9S_MB_2U_LIB.S9S_MB_2U(SCH_1):PU_E1S_0_DUALPORT_EN_N
 R2317    2      B Q_RES_0402LF-10K,1%,1/16W,CHIPA   I264 @S9S_MB_2U_LIB.S9S_MB_2U(SCH_1):PAGE297
   J90   B9 DUALPORTEN# SCONN56_123276793-SCONN56_1-23A   I318 @S9S_MB_2U_LIB.S9S_MB_2U(SCH_1):PAGE297

PU_ESPI_ENABLE_STRAP @S9S_MB_2U_LIB.S9S_MB_2U(SCH_1):PU_ESPI_ENABLE_STRAP
 R2133    2      B Q_RES_0402LF-1K,1%,1/16W,CHIP,A    I86 @S9S_MB_2U_LIB.S9S_MB_2U(SCH_1):PAGE189
  J104    1      1 CONN14_210HP207GBR1-CONN14_210A   I134 @S9S_MB_2U_LIB.S9S_MB_2U(SCH_1):PAGE189

PU_FLASH_SECURITY_STRAP @S9S_MB_2U_LIB.S9S_MB_2U(SCH_1):PU_FLASH_SECURITY_STRAP
 R1325    2      B Q_RES_0402LF-1K,1%,1/16W,CHIP,A    I93 @S9S_MB_2U_LIB.S9S_MB_2U(SCH_1):PAGE189
  J104    9      9 CONN14_210HP207GBR1-CONN14_210A   I134 @S9S_MB_2U_LIB.S9S_MB_2U(SCH_1):PAGE189

PU_FORCE_PWRON @S9S_MB_2U_LIB.S9S_MB_2U(SCH_1):PU_FORCE_PWRON
  JP15    1      1 CONN3_210HP1030BR1-CONN3_210-HB   I187 @S9S_MB_2U_LIB.S9S_MB_2U(SCH_1):PAGE312
 R1493    2      B Q_RES_0402LF-1K,1%,1/16W,CHIP,A   I191 @S9S_MB_2U_LIB.S9S_MB_2U(SCH_1):PAGE312

PU_FPGA_D12_PROGRAMN @S9S_MB_2U_LIB.S9S_MB_2U(SCH_1):PU_FPGA_D12_PROGRAMN
 R3249    2      B Q_RES_0402LF-10K,1%,1/16W,CHIPA    I29 @S9S_MB_2U_LIB.S9S_MB_2U(SCH_1):PAGE311
  U249  E15 PT31D||PROGRAMN LCMXO3LF9400C5BG484C-LCMXO3LF-A    I70 @S9S_MB_2U_LIB.S9S_MB_2U(SCH_1):PAGE311

PU_GTL2014_BMC_JTAG_DIR_1 @S9S_MB_2U_LIB.S9S_MB_2U(SCH_1):PU_GTL2014_BMC_JTAG_DIR_1
 R3055    2      B Q_RES_0402LF-1K,1%,1/16W,CHIP,A    I11 @S9S_MB_2U_LIB.S9S_MB_2U(SCH_1):PAGE226
   U84    1    DIR GTL2014PW-GTL2014PW,SMLF,IC,ALA    I18 @S9S_MB_2U_LIB.S9S_MB_2U(SCH_1):PAGE226
 R2514    1      A Q_RES_0402LF-1K,1%,1/16W,EMPTYA    I89 @S9S_MB_2U_LIB.S9S_MB_2U(SCH_1):PAGE226

PU_JTAG_SW_PU @S9S_MB_2U_LIB.S9S_MB_2U(SCH_1):PU_JTAG_SW_PU
 R4623    2      B Q_RES_0402LF-1K,1%,1/16W,CHIP,A    I11 @S9S_MB_2U_LIB.S9S_MB_2U(SCH_1):PAGE235
  JP16    1      1 CONN3_210HP1030BR1-CONN3_210-HB    I13 @S9S_MB_2U_LIB.S9S_MB_2U(SCH_1):PAGE235

PU_LAN_WAKE_N @S9S_MB_2U_LIB.S9S_MB_2U(SCH_1):PU_LAN_WAKE_N
    U4  AU7 LAN_WAKE_N EMMITSBURG_REV0P9-GFNOCPU04302A    I36 @S9S_MB_2U_LIB.S9S_MB_2U(SCH_1):PAGE174
  R453    2      B Q_RES_0402LF-10K,1%,1/16W,CHIPA    I77 @S9S_MB_2U_LIB.S9S_MB_2U(SCH_1):PAGE174

PU_LPC_PME_N @S9S_MB_2U_LIB.S9S_MB_2U(SCH_1):PU_LPC_PME_N
    U4  AJ3 GPP_D_9_PME_N EMMITSBURG_REV0P9-GFNOCPU04302A    I93 @S9S_MB_2U_LIB.S9S_MB_2U(SCH_1):PAGE175
 R1259    2      B Q_RES_0402LF-10K,1%,1/16W,CHIPA     I8 @S9S_MB_2U_LIB.S9S_MB_2U(SCH_1):PAGE192

PU_MAIN_FPGA_CONFIG_DONE @S9S_MB_2U_LIB.S9S_MB_2U(SCH_1):PU_MAIN_FPGA_CONFIG_DONE
 R1401    1      A Q_RES_0402LF-10K,1%,1/16W,CHIPA    I16 @S9S_MB_2U_LIB.S9S_MB_2U(SCH_1):PAGE209
  U249  B19  PT41B LCMXO3LF9400C5BG484C-LCMXO3LF-A   I188 @S9S_MB_2U_LIB.S9S_MB_2U(SCH_1):PAGE314

PU_OC2_USB_N @S9S_MB_2U_LIB.S9S_MB_2U(SCH_1):PU_OC2_USB_N
    U4 BG30 GPPC_B_7_USB2_OCB_2 EMMITSBURG_REV0P9-GFNOCPU04302A    I93 @S9S_MB_2U_LIB.S9S_MB_2U(SCH_1):PAGE175
 R3938    1      A Q_RES_0402LF-10K,1%,1/16W,CHIPA   I272 @S9S_MB_2U_LIB.S9S_MB_2U(SCH_1):PAGE175

PU_OC3_USB_N @S9S_MB_2U_LIB.S9S_MB_2U(SCH_1):PU_OC3_USB_N
    U4 BG28 GPPC_B_8_USB2_OCB_3 EMMITSBURG_REV0P9-GFNOCPU04302A    I93 @S9S_MB_2U_LIB.S9S_MB_2U(SCH_1):PAGE175
  R635    1      A Q_RES_0402LF-10K,1%,1/16W,CHIPA   I234 @S9S_MB_2U_LIB.S9S_MB_2U(SCH_1):PAGE175

PU_OC4_USB_N @S9S_MB_2U_LIB.S9S_MB_2U(SCH_1):PU_OC4_USB_N
    U4 BG26 GPPC_B_9_USB2_OCB_4 EMMITSBURG_REV0P9-GFNOCPU04302A    I93 @S9S_MB_2U_LIB.S9S_MB_2U(SCH_1):PAGE175
  R727    1      A Q_RES_0402LF-10K,1%,1/16W,CHIPA   I236 @S9S_MB_2U_LIB.S9S_MB_2U(SCH_1):PAGE175

PU_OC5_USB_N @S9S_MB_2U_LIB.S9S_MB_2U(SCH_1):PU_OC5_USB_N
    U4 BG24 GPPC_B_10_USB2_OCB_5 EMMITSBURG_REV0P9-GFNOCPU04302A    I93 @S9S_MB_2U_LIB.S9S_MB_2U(SCH_1):PAGE175
  R770    1      A Q_RES_0402LF-10K,1%,1/16W,CHIPA   I239 @S9S_MB_2U_LIB.S9S_MB_2U(SCH_1):PAGE175

PU_OC6_USB_N @S9S_MB_2U_LIB.S9S_MB_2U(SCH_1):PU_OC6_USB_N
    U4 BG22 GPPC_B_11_USB2_OCB_6 EMMITSBURG_REV0P9-GFNOCPU04302A    I93 @S9S_MB_2U_LIB.S9S_MB_2U(SCH_1):PAGE175
  R913    1      A Q_RES_0402LF-10K,1%,1/16W,CHIPA   I241 @S9S_MB_2U_LIB.S9S_MB_2U(SCH_1):PAGE175

PU_OCP_SFF_WAKE_OE @S9S_MB_2U_LIB.S9S_MB_2U(SCH_1):PU_OCP_SFF_WAKE_OE
 R1592    2      B Q_RES_0402LF-10K,1%,1/16W,CHIPA    I37 @S9S_MB_2U_LIB.S9S_MB_2U(SCH_1):PAGE152
   U82    1     OE 74LVC1G126SE7-74LVC1G126SE-7,SA    I79 @S9S_MB_2U_LIB.S9S_MB_2U(SCH_1):PAGE152

PU_OCP_V3_2_WAKE_OE @S9S_MB_2U_LIB.S9S_MB_2U(SCH_1):PU_OCP_V3_2_WAKE_OE
 R3183    2      B Q_RES_0402LF-10K,1%,1/16W,CHIPA     I7 @S9S_MB_2U_LIB.S9S_MB_2U(SCH_1):PAGE156
  U217    1     OE 74LVC1G126SE7-74LVC1G126SE-7,SA    I79 @S9S_MB_2U_LIB.S9S_MB_2U(SCH_1):PAGE156

PU_PCH_PLD_3V3AUX_ALERT_N @S9S_MB_2U_LIB.S9S_MB_2U(SCH_1):PU_PCH_PLD_3V3AUX_ALERT_N
    U4  AN2 GPPC_C_21_MC_SMBALERT_N EMMITSBURG_REV0P9-GFNOCPU04302A    I93 @S9S_MB_2U_LIB.S9S_MB_2U(SCH_1):PAGE175
 R1583    1      A Q_RES_0402LF-10K,1%,1/16W,CHIPA   I144 @S9S_MB_2U_LIB.S9S_MB_2U(SCH_1):PAGE175

PU_PCH_PMCALERT_N @S9S_MB_2U_LIB.S9S_MB_2U(SCH_1):PU_PCH_PMCALERT_N
    U4   J4 GPPC_H_18_PMCALERT_N EMMITSBURG_REV0P9-GFNOCPU04302A    I22 @S9S_MB_2U_LIB.S9S_MB_2U(SCH_1):PAGE176
  R456    2      B Q_RES_0402LF-10K,1%,1/16W,CHIPA    I66 @S9S_MB_2U_LIB.S9S_MB_2U(SCH_1):PAGE192

PU_PCH_VRALERT_N @S9S_MB_2U_LIB.S9S_MB_2U(SCH_1):PU_PCH_VRALERT_N
    U4  AC3 GPP_D_15_VRALERT_N EMMITSBURG_REV0P9-GFNOCPU04302A    I93 @S9S_MB_2U_LIB.S9S_MB_2U(SCH_1):PAGE175
 R1257    2      B Q_RES_0402LF-10K,1%,1/16W,CHIPA     I4 @S9S_MB_2U_LIB.S9S_MB_2U(SCH_1):PAGE192

PU_PIROM_CPU0_SM_WP @S9S_MB_2U_LIB.S9S_MB_2U(SCH_1):PU_PIROM_CPU0_SM_WP
    U2 CR72 PIROM_SM_WP SOCKET4677_AZIF0045P001C01CS-SA     I1 @S9S_MB_2U_LIB.S9S_MB_2U(SCH_1):PAGE14
  R997    1      A Q_RES_0402LF-10K,1%,1/16W,EMPTA    I31 @S9S_MB_2U_LIB.S9S_MB_2U(SCH_1):PAGE127
  R650    2      B Q_RES_0402LF-1K,1%,1/16W,CHIP,A    I32 @S9S_MB_2U_LIB.S9S_MB_2U(SCH_1):PAGE127

PU_PIROM_CPU1_ADDR0 @S9S_MB_2U_LIB.S9S_MB_2U(SCH_1):PU_PIROM_CPU1_ADDR0
    U1 CR70 PIROM_AD0 SOCKET4677_AZIF0045P001C01CS-SA    I29 @S9S_MB_2U_LIB.S9S_MB_2U(SCH_1):PAGE45
  R629    2      B Q_RES_0402LF-1K,1%,1/16W,CHIP,A    I13 @S9S_MB_2U_LIB.S9S_MB_2U(SCH_1):PAGE127
  R630    1      A Q_RES_0402LF-10K,1%,1/16W,EMPTA    I15 @S9S_MB_2U_LIB.S9S_MB_2U(SCH_1):PAGE127

PU_PIROM_CPU1_SM_WP @S9S_MB_2U_LIB.S9S_MB_2U(SCH_1):PU_PIROM_CPU1_SM_WP
    U1 CR72 PIROM_SM_WP SOCKET4677_AZIF0045P001C01CS-SA    I29 @S9S_MB_2U_LIB.S9S_MB_2U(SCH_1):PAGE45
 R1004    2      B Q_RES_0402LF-1K,1%,1/16W,CHIP,A    I35 @S9S_MB_2U_LIB.S9S_MB_2U(SCH_1):PAGE127
 R1005    1      A Q_RES_0402LF-10K,1%,1/16W,EMPTA    I36 @S9S_MB_2U_LIB.S9S_MB_2U(SCH_1):PAGE127

PU_PLD_HEARTBEAT_LVC3 @S9S_MB_2U_LIB.S9S_MB_2U(SCH_1):PU_PLD_HEARTBEAT_LVC3
    D0    A      A Q_LED_SMLF-LED_BLUE,LTST-C281TA   I277 @S9S_MB_2U_LIB.S9S_MB_2U(SCH_1):PAGE207
 R1195    2      B Q_RES_0402LF-130,1%,1/16W,CHIPA   I278 @S9S_MB_2U_LIB.S9S_MB_2U(SCH_1):PAGE207

PU_RST_DEDI_BUSY_PLD_N @S9S_MB_2U_LIB.S9S_MB_2U(SCH_1):PU_RST_DEDI_BUSY_PLD_N
 R1681    2      B Q_RES_0402LF-10K,1%,1/16W,CHIPA    I47 @S9S_MB_2U_LIB.S9S_MB_2U(SCH_1):PAGE314
  U249   D9  PT20D LCMXO3LF9400C5BG484C-LCMXO3LF-A   I188 @S9S_MB_2U_LIB.S9S_MB_2U(SCH_1):PAGE314

PU_RST_SMB_PCIE0_N @S9S_MB_2U_LIB.S9S_MB_2U(SCH_1):PU_RST_SMB_PCIE0_N
 R2268    2      B Q_RES_0402LF-0,5%,1/16W,CHIP,CA    I41 @S9S_MB_2U_LIB.S9S_MB_2U(SCH_1):PAGE219
   U36    3 RESET# TCA9548APWR-TCA9548APWR,SMLF,IA    I45 @S9S_MB_2U_LIB.S9S_MB_2U(SCH_1):PAGE219

PU_RST_SMB_PCIE2_N @S9S_MB_2U_LIB.S9S_MB_2U(SCH_1):PU_RST_SMB_PCIE2_N
   U39    3 RESET# TCA9548APWR-TCA9548APWR,SMLF,IA   I103 @S9S_MB_2U_LIB.S9S_MB_2U(SCH_1):PAGE221
 R3710    2      B Q_RES_0402LF-0,5%,1/16W,CHIP,CA   I145 @S9S_MB_2U_LIB.S9S_MB_2U(SCH_1):PAGE221

PU_RST_SMB_U181_N @S9S_MB_2U_LIB.S9S_MB_2U(SCH_1):PU_RST_SMB_U181_N
  U181    3  RESET PCA9539RPW-PCA9539RPW,SMLF,IC,A    I66 @S9S_MB_2U_LIB.S9S_MB_2U(SCH_1):PAGE214
 R2922    2      B Q_RES_0402LF-0,5%,1/16W,CHIP,CA    I95 @S9S_MB_2U_LIB.S9S_MB_2U(SCH_1):PAGE214

PU_S3M_CPU0_CPLD_CONFD @S9S_MB_2U_LIB.S9S_MB_2U(SCH_1):PU_S3M_CPU0_CPLD_CONFD
    U2 CJ64 TEST_1 SOCKET4677_AZIF0045P001C01CS-SA     I1 @S9S_MB_2U_LIB.S9S_MB_2U(SCH_1):PAGE15
  R320    2      B Q_RES_0402LF-10K,1%,1/16W,CHIPA     I7 @S9S_MB_2U_LIB.S9S_MB_2U(SCH_1):PAGE80

PU_S3M_CPU0_CPLD_STATUS @S9S_MB_2U_LIB.S9S_MB_2U(SCH_1):PU_S3M_CPU0_CPLD_STATUS
    U2 CH65 TEST_3 SOCKET4677_AZIF0045P001C01CS-SA     I1 @S9S_MB_2U_LIB.S9S_MB_2U(SCH_1):PAGE15
  R319    2      B Q_RES_0402LF-10K,1%,1/16W,CHIPA     I8 @S9S_MB_2U_LIB.S9S_MB_2U(SCH_1):PAGE80

PU_S3M_CPU1_CPLD_CONFD @S9S_MB_2U_LIB.S9S_MB_2U(SCH_1):PU_S3M_CPU1_CPLD_CONFD
    U1 CJ64 TEST_1 SOCKET4677_AZIF0045P001C01CS-SA     I5 @S9S_MB_2U_LIB.S9S_MB_2U(SCH_1):PAGE46
  R326    2      B Q_RES_0402LF-10K,1%,1/16W,CHIPA    I26 @S9S_MB_2U_LIB.S9S_MB_2U(SCH_1):PAGE80

PU_S3M_CPU1_CPLD_STATUS @S9S_MB_2U_LIB.S9S_MB_2U(SCH_1):PU_S3M_CPU1_CPLD_STATUS
    U1 CH65 TEST_3 SOCKET4677_AZIF0045P001C01CS-SA     I5 @S9S_MB_2U_LIB.S9S_MB_2U(SCH_1):PAGE46
  R325    2      B Q_RES_0402LF-10K,1%,1/16W,CHIPA    I27 @S9S_MB_2U_LIB.S9S_MB_2U(SCH_1):PAGE80

PU_SMB_PCH_PLD_3V3AUX_SCL @S9S_MB_2U_LIB.S9S_MB_2U(SCH_1):PU_SMB_PCH_PLD_3V3AUX_SCL
    U4  AL1 GPPC_C_19_MC_SMBCLK EMMITSBURG_REV0P9-GFNOCPU04302A    I93 @S9S_MB_2U_LIB.S9S_MB_2U(SCH_1):PAGE175
 R1581    1      A Q_RES_0402LF-2K,1%,1/16W,CHIP,A   I142 @S9S_MB_2U_LIB.S9S_MB_2U(SCH_1):PAGE175

PU_SMB_PCH_PLD_3V3AUX_SDA @S9S_MB_2U_LIB.S9S_MB_2U(SCH_1):PU_SMB_PCH_PLD_3V3AUX_SDA
    U4  AT1 GPPC_C_20_MC_SMBDATA EMMITSBURG_REV0P9-GFNOCPU04302A    I93 @S9S_MB_2U_LIB.S9S_MB_2U(SCH_1):PAGE175
 R1582    1      A Q_RES_0402LF-2K,1%,1/16W,CHIP,A   I141 @S9S_MB_2U_LIB.S9S_MB_2U(SCH_1):PAGE175

PU_SMB_SML3_3V3AUX_PCH_SCL @S9S_MB_2U_LIB.S9S_MB_2U(SCH_1):PU_SMB_SML3_3V3AUX_PCH_SCL
    U4  AN4 GPPC_C_12_ME_SML3CLK EMMITSBURG_REV0P9-GFNOCPU04302A    I93 @S9S_MB_2U_LIB.S9S_MB_2U(SCH_1):PAGE175
 R1451    1      A Q_RES_0402LF-2K,1%,1/16W,CHIP,A   I109 @S9S_MB_2U_LIB.S9S_MB_2U(SCH_1):PAGE175

PU_SMB_SML3_3V3AUX_PCH_SDA @S9S_MB_2U_LIB.S9S_MB_2U(SCH_1):PU_SMB_SML3_3V3AUX_PCH_SDA
    U4  AY1 GPPC_C_13_ME_SML3DATA EMMITSBURG_REV0P9-GFNOCPU04302A    I93 @S9S_MB_2U_LIB.S9S_MB_2U(SCH_1):PAGE175
 R1452    1      A Q_RES_0402LF-2K,1%,1/16W,CHIP,A   I112 @S9S_MB_2U_LIB.S9S_MB_2U(SCH_1):PAGE175

PU_SMB_SML4_3V3AUX_PCH_SCL @S9S_MB_2U_LIB.S9S_MB_2U(SCH_1):PU_SMB_SML4_3V3AUX_PCH_SCL
    U4  BA2 GPPC_C_15_ME_SML4CLK EMMITSBURG_REV0P9-GFNOCPU04302A    I93 @S9S_MB_2U_LIB.S9S_MB_2U(SCH_1):PAGE175
 R1453    1      A Q_RES_0402LF-2K,1%,1/16W,CHIP,A   I120 @S9S_MB_2U_LIB.S9S_MB_2U(SCH_1):PAGE175

PU_SMB_SML4_3V3AUX_PCH_SDA @S9S_MB_2U_LIB.S9S_MB_2U(SCH_1):PU_SMB_SML4_3V3AUX_PCH_SDA
    U4  AV1 GPPC_C_16_ME_SML4DATA EMMITSBURG_REV0P9-GFNOCPU04302A    I93 @S9S_MB_2U_LIB.S9S_MB_2U(SCH_1):PAGE175
 R1454    1      A Q_RES_0402LF-2K,1%,1/16W,CHIP,A   I121 @S9S_MB_2U_LIB.S9S_MB_2U(SCH_1):PAGE175

PU_SWAP_OVERRIDE_N @S9S_MB_2U_LIB.S9S_MB_2U(SCH_1):PU_SWAP_OVERRIDE_N
 R1320    2      B Q_RES_0402LF-1K,1%,1/16W,CHIP,A    I89 @S9S_MB_2U_LIB.S9S_MB_2U(SCH_1):PAGE189
  J104    5      5 CONN14_210HP207GBR1-CONN14_210A   I134 @S9S_MB_2U_LIB.S9S_MB_2U(SCH_1):PAGE189

PU_TAP_ODT_CPU0_EN @S9S_MB_2U_LIB.S9S_MB_2U(SCH_1):PU_TAP_ODT_CPU0_EN
    U2 AY20 TAP_ODT_EN SOCKET4677_AZIF0045P001C01CS-SA     I1 @S9S_MB_2U_LIB.S9S_MB_2U(SCH_1):PAGE14
 R1009    2      B Q_RES_0402LF-1K,1%,1/16W,EMPTYA   I136 @S9S_MB_2U_LIB.S9S_MB_2U(SCH_1):PAGE119

PU_TAP_ODT_CPU1_EN @S9S_MB_2U_LIB.S9S_MB_2U(SCH_1):PU_TAP_ODT_CPU1_EN
    U1 AY20 TAP_ODT_EN SOCKET4677_AZIF0045P001C01CS-SA    I29 @S9S_MB_2U_LIB.S9S_MB_2U(SCH_1):PAGE45
 R1008    2      B Q_RES_0402LF-1K,1%,1/16W,EMPTYA   I139 @S9S_MB_2U_LIB.S9S_MB_2U(SCH_1):PAGE119

PU_TEST @S9S_MB_2U_LIB.S9S_MB_2U(SCH_1):PU_TEST
  U237    5  TEST# PI3EQX12902AZLEX-PI3EQX12902AZA    I50 @S9S_MB_2U_LIB.S9S_MB_2U(SCH_1):PAGE136
 R3291    1      A Q_RES_0402LF-4.7K,1%,1/16W,EMPA    I82 @S9S_MB_2U_LIB.S9S_MB_2U(SCH_1):PAGE136

PU_U181_INT @S9S_MB_2U_LIB.S9S_MB_2U(SCH_1):PU_U181_INT
  U181    1    INT PCA9539RPW-PCA9539RPW,SMLF,IC,A    I66 @S9S_MB_2U_LIB.S9S_MB_2U(SCH_1):PAGE214
 R2923    2      B Q_RES_0402LF-4.7K,5%,1/16W,EMPA    I90 @S9S_MB_2U_LIB.S9S_MB_2U(SCH_1):PAGE214

PVCC1_AUX @S9S_MB_2U_LIB.S9S_MB_2U(SCH_1):PVCC1_AUX
 PR395    2      B Q_RES_0402LF-0,5%,1/16W,CHIP,CA     I8 @S9S_MB_2U_LIB.S9S_MB_2U(SCH_1):PAGE249
 PR396    2      B Q_RES_0402LF-0,5%,1/16W,EMPTY,A     I2 @S9S_MB_2U_LIB.S9S_MB_2U(SCH_1):PAGE249
PR1329    1      A Q_RES_0402LF-5.1,5%,1/16W,CHIPA     I5 @S9S_MB_2U_LIB.S9S_MB_2U(SCH_1):PAGE249

PVCCD_HV_CPU0 @S9S_MB_2U_LIB.S9S_MB_2U(SCH_1):PVCCD_HV_CPU0
    U2 AT36 VCCD_HV0 SOCKET4677_AZIF0045P001C01CS-SA     I8 @S9S_MB_2U_LIB.S9S_MB_2U(SCH_1):PAGE37
    U2 AT55 VCCD_HV1 SOCKET4677_AZIF0045P001C01CS-SA     I8 @S9S_MB_2U_LIB.S9S_MB_2U(SCH_1):PAGE37
    U2  AU3 VCCD_HV2 SOCKET4677_AZIF0045P001C01CS-SA     I8 @S9S_MB_2U_LIB.S9S_MB_2U(SCH_1):PAGE37
    U2 AU35 VCCD_HV3 SOCKET4677_AZIF0045P001C01CS-SA     I8 @S9S_MB_2U_LIB.S9S_MB_2U(SCH_1):PAGE37
    U2 AU54 VCCD_HV4 SOCKET4677_AZIF0045P001C01CS-SA     I8 @S9S_MB_2U_LIB.S9S_MB_2U(SCH_1):PAGE37
    U2  AU7 VCCD_HV5 SOCKET4677_AZIF0045P001C01CS-SA     I8 @S9S_MB_2U_LIB.S9S_MB_2U(SCH_1):PAGE37
    U2 AV34 VCCD_HV6 SOCKET4677_AZIF0045P001C01CS-SA     I8 @S9S_MB_2U_LIB.S9S_MB_2U(SCH_1):PAGE37
    U2 AV36 VCCD_HV7 SOCKET4677_AZIF0045P001C01CS-SA     I8 @S9S_MB_2U_LIB.S9S_MB_2U(SCH_1):PAGE37
    U2 AV53 VCCD_HV8 SOCKET4677_AZIF0045P001C01CS-SA     I8 @S9S_MB_2U_LIB.S9S_MB_2U(SCH_1):PAGE37
    U2 AV55 VCCD_HV9 SOCKET4677_AZIF0045P001C01CS-SA     I8 @S9S_MB_2U_LIB.S9S_MB_2U(SCH_1):PAGE37
    U2  BA3 VCCD_HV10 SOCKET4677_AZIF0045P001C01CS-SA     I8 @S9S_MB_2U_LIB.S9S_MB_2U(SCH_1):PAGE37
    U2  BA7 VCCD_HV11 SOCKET4677_AZIF0045P001C01CS-SA     I8 @S9S_MB_2U_LIB.S9S_MB_2U(SCH_1):PAGE37
    U2 BE11 VCCD_HV12 SOCKET4677_AZIF0045P001C01CS-SA     I8 @S9S_MB_2U_LIB.S9S_MB_2U(SCH_1):PAGE37
    U2  BE3 VCCD_HV13 SOCKET4677_AZIF0045P001C01CS-SA     I8 @S9S_MB_2U_LIB.S9S_MB_2U(SCH_1):PAGE37
    U2  BE7 VCCD_HV14 SOCKET4677_AZIF0045P001C01CS-SA     I8 @S9S_MB_2U_LIB.S9S_MB_2U(SCH_1):PAGE37
    U2 BJ11 VCCD_HV15 SOCKET4677_AZIF0045P001C01CS-SA     I8 @S9S_MB_2U_LIB.S9S_MB_2U(SCH_1):PAGE37
    U2  BJ3 VCCD_HV16 SOCKET4677_AZIF0045P001C01CS-SA     I8 @S9S_MB_2U_LIB.S9S_MB_2U(SCH_1):PAGE37
    U2  BJ7 VCCD_HV17 SOCKET4677_AZIF0045P001C01CS-SA     I8 @S9S_MB_2U_LIB.S9S_MB_2U(SCH_1):PAGE37
    U2  BN7 VCCD_HV18 SOCKET4677_AZIF0045P001C01CS-SA     I8 @S9S_MB_2U_LIB.S9S_MB_2U(SCH_1):PAGE37
    U2  CA7 VCCD_HV19 SOCKET4677_AZIF0045P001C01CS-SA     I8 @S9S_MB_2U_LIB.S9S_MB_2U(SCH_1):PAGE37
    U2  CE7 VCCD_HV20 SOCKET4677_AZIF0045P001C01CS-SA     I8 @S9S_MB_2U_LIB.S9S_MB_2U(SCH_1):PAGE37
    U2 CW35 VCCD_HV21 SOCKET4677_AZIF0045P001C01CS-SA     I8 @S9S_MB_2U_LIB.S9S_MB_2U(SCH_1):PAGE37
    U2 CW37 VCCD_HV22 SOCKET4677_AZIF0045P001C01CS-SA     I8 @S9S_MB_2U_LIB.S9S_MB_2U(SCH_1):PAGE37
    U2 CW52 VCCD_HV23 SOCKET4677_AZIF0045P001C01CS-SA     I8 @S9S_MB_2U_LIB.S9S_MB_2U(SCH_1):PAGE37
    U2 CW54 VCCD_HV24 SOCKET4677_AZIF0045P001C01CS-SA     I8 @S9S_MB_2U_LIB.S9S_MB_2U(SCH_1):PAGE37
    U2 CW56 VCCD_HV25 SOCKET4677_AZIF0045P001C01CS-SA     I8 @S9S_MB_2U_LIB.S9S_MB_2U(SCH_1):PAGE37
    U2 CY34 VCCD_HV26 SOCKET4677_AZIF0045P001C01CS-SA     I8 @S9S_MB_2U_LIB.S9S_MB_2U(SCH_1):PAGE37
    U2 CY36 VCCD_HV27 SOCKET4677_AZIF0045P001C01CS-SA     I8 @S9S_MB_2U_LIB.S9S_MB_2U(SCH_1):PAGE37
    U2 CY53 VCCD_HV28 SOCKET4677_AZIF0045P001C01CS-SA     I8 @S9S_MB_2U_LIB.S9S_MB_2U(SCH_1):PAGE37
  C401    1      A Q_CAP_C0402-22UF,4V,20%,X6S,CHA    I17 @S9S_MB_2U_LIB.S9S_MB_2U(SCH_1):PAGE74
  C403    1      A Q_CAP_C0402-22UF,4V,20%,X6S,CHA    I19 @S9S_MB_2U_LIB.S9S_MB_2U(SCH_1):PAGE74
  C499    1      A Q_CAP_C0805-47UF,4V,20%,X6S,CHA    I18 @S9S_MB_2U_LIB.S9S_MB_2U(SCH_1):PAGE76
  C503    1      A Q_CAP_C0805-47UF,4V,20%,X6S,CHA    I20 @S9S_MB_2U_LIB.S9S_MB_2U(SCH_1):PAGE76
  R181    2      B Q_RES_0402LF-100,1%,1/16W,CHIPA    I68 @S9S_MB_2U_LIB.S9S_MB_2U(SCH_1):PAGE124
  R179    2      B Q_RES_0402LF-100,1%,1/16W,CHIPA    I70 @S9S_MB_2U_LIB.S9S_MB_2U(SCH_1):PAGE124
  R177    2      B Q_RES_0402LF-100,1%,1/16W,CHIPA    I72 @S9S_MB_2U_LIB.S9S_MB_2U(SCH_1):PAGE124
  R840    1      A Q_RES_0402LF-1K,1%,1/16W,CHIP,A   I119 @S9S_MB_2U_LIB.S9S_MB_2U(SCH_1):PAGE129
  R841    1      A Q_RES_0402LF-1K,1%,1/16W,CHIP,A   I121 @S9S_MB_2U_LIB.S9S_MB_2U(SCH_1):PAGE129
  R842    1      A Q_RES_0402LF-1K,1%,1/16W,CHIP,A   I123 @S9S_MB_2U_LIB.S9S_MB_2U(SCH_1):PAGE129
  R839    1      A Q_RES_0402LF-1K,1%,1/16W,CHIP,A   I125 @S9S_MB_2U_LIB.S9S_MB_2U(SCH_1):PAGE129
  R175    2      B Q_RES_0402LF-100,1%,1/16W,CHIPA    I76 @S9S_MB_2U_LIB.S9S_MB_2U(SCH_1):PAGE124
  C399    1      A Q_CAP_C0402-22UF,4V,20%,X6S,CHA    I11 @S9S_MB_2U_LIB.S9S_MB_2U(SCH_1):PAGE74
  C405    1      A Q_CAP_C0402-22UF,4V,20%,X6S,CHA    I34 @S9S_MB_2U_LIB.S9S_MB_2U(SCH_1):PAGE74
  C491    1      A Q_CAP_C0805-47UF,4V,20%,X6S,CHA    I13 @S9S_MB_2U_LIB.S9S_MB_2U(SCH_1):PAGE75
  C495    1      A Q_CAP_C0805-47UF,4V,20%,X6S,CHA    I18 @S9S_MB_2U_LIB.S9S_MB_2U(SCH_1):PAGE75
  C515    1      A Q_CAP_C0805-47UF,4V,20%,X6S,CHA    I19 @S9S_MB_2U_LIB.S9S_MB_2U(SCH_1):PAGE75
  C518    1      A Q_CAP_C0805-47UF,4V,20%,X6S,CHA    I31 @S9S_MB_2U_LIB.S9S_MB_2U(SCH_1):PAGE75
  C507    1      A Q_CAP_C0805-47UF,4V,20%,X6S,CHA    I21 @S9S_MB_2U_LIB.S9S_MB_2U(SCH_1):PAGE76
  C511    1      A Q_CAP_C0805-47UF,4V,20%,X6S,CHA    I43 @S9S_MB_2U_LIB.S9S_MB_2U(SCH_1):PAGE76
PR1785    2      B Q_RES_0402LF-0,5%,1/16W,CHIP,CA    I17 @S9S_MB_2U_LIB.S9S_MB_2U(SCH_1):PAGE265
 PC641    1      A Q_CAP_C0805-22UF,4V,20%,X6S,CHA    I25 @S9S_MB_2U_LIB.S9S_MB_2U(SCH_1):PAGE265
PC1910    1      A Q_CAPP_SMLF-330UF,2V,35%,SPCAPA    I26 @S9S_MB_2U_LIB.S9S_MB_2U(SCH_1):PAGE265
 PC642    1      A Q_CAP_C0805-22UF,4V,20%,X6S,CHA    I28 @S9S_MB_2U_LIB.S9S_MB_2U(SCH_1):PAGE265
   PC1    1      A Q_CAP_C0805-22UF,4V,20%,X6S,CHA    I29 @S9S_MB_2U_LIB.S9S_MB_2U(SCH_1):PAGE265
PC1645    1      A Q_CAPP_THLF-560UF,2.5V,20%,OSCA    I34 @S9S_MB_2U_LIB.S9S_MB_2U(SCH_1):PAGE265
PR4237    1      A Q_RES_0402LF-499,1%,1/16W,CHIPA    I37 @S9S_MB_2U_LIB.S9S_MB_2U(SCH_1):PAGE265
 PC639    1      A Q_CAP_C0402-100NF,50V,10%,X7R,A    I24 @S9S_MB_2U_LIB.S9S_MB_2U(SCH_1):PAGE265
PC1644    1      A Q_CAPP_THLF-560UF,2.5V,20%,OSCA    I27 @S9S_MB_2U_LIB.S9S_MB_2U(SCH_1):PAGE265
 PR592    2      B Q_RES_0402LF-100,1%,1/16W,CHIPA    I31 @S9S_MB_2U_LIB.S9S_MB_2U(SCH_1):PAGE264
  PL35    2      2 Q_INDUCTOR_SMLF-120NH/69A,IND,A    I30 @S9S_MB_2U_LIB.S9S_MB_2U(SCH_1):PAGE265

PVCCD_HV_CPU0_ACSP1 @S9S_MB_2U_LIB.S9S_MB_2U(SCH_1):PVCCD_HV_CPU0_ACSP1
  PU35   23    CS7 ISL69260IRAZT-ISL69260IRAZ-T,SA    I53 @S9S_MB_2U_LIB.S9S_MB_2U(SCH_1):PAGE264
  PU36   38   IOUT ISL99390FRZTR5935-ISL99390FRZ-A     I8 @S9S_MB_2U_LIB.S9S_MB_2U(SCH_1):PAGE265

PVCCD_HV_CPU0_ADDR @S9S_MB_2U_LIB.S9S_MB_2U(SCH_1):PVCCD_HV_CPU0_ADDR
  PU35   34 ADDR_CFG ISL69260IRAZT-ISL69260IRAZ-T,SA    I53 @S9S_MB_2U_LIB.S9S_MB_2U(SCH_1):PAGE264
 PR357    2      B Q_RES_0402LF-28K,1%,1/16W,EMPTA     I5 @S9S_MB_2U_LIB.S9S_MB_2U(SCH_1):PAGE264
 PR358    2      B Q_RES_0402LF-3.57K,1%,1/16W,CHA    I95 @S9S_MB_2U_LIB.S9S_MB_2U(SCH_1):PAGE264

PVCCD_HV_CPU0_APWM1 @S9S_MB_2U_LIB.S9S_MB_2U(SCH_1):PVCCD_HV_CPU0_APWM1
  PU35    8   PWM7 ISL69260IRAZT-ISL69260IRAZ-T,SA    I53 @S9S_MB_2U_LIB.S9S_MB_2U(SCH_1):PAGE264
  PU36   34    PWM ISL99390FRZTR5935-ISL99390FRZ-A     I8 @S9S_MB_2U_LIB.S9S_MB_2U(SCH_1):PAGE265

PVCCD_HV_CPU0_ATSEN @S9S_MB_2U_LIB.S9S_MB_2U(SCH_1):PVCCD_HV_CPU0_ATSEN
  PU35   35  TEMP0 ISL69260IRAZT-ISL69260IRAZ-T,SA    I53 @S9S_MB_2U_LIB.S9S_MB_2U(SCH_1):PAGE264
  PU36   36 TOUT_FLT ISL99390FRZTR5935-ISL99390FRZ-A     I8 @S9S_MB_2U_LIB.S9S_MB_2U(SCH_1):PAGE265
 PR634    1      A Q_RES_0402LF-10K,1%,1/16W,EMPTA    I57 @S9S_MB_2U_LIB.S9S_MB_2U(SCH_1):PAGE264
 PC631    1      A Q_CAP_0402-470PF,50V,10%,X7R,TA    I56 @S9S_MB_2U_LIB.S9S_MB_2U(SCH_1):PAGE264

PVCCD_HV_CPU0_EN_R @S9S_MB_2U_LIB.S9S_MB_2U(SCH_1):PVCCD_HV_CPU0_EN_R
  R363    2      B Q_RES_0402LF-0,5%,1/16W,CHIP,CA    I45 @S9S_MB_2U_LIB.S9S_MB_2U(SCH_1):PAGE264
  PU35   13    EN0 ISL69260IRAZT-ISL69260IRAZ-T,SA    I53 @S9S_MB_2U_LIB.S9S_MB_2U(SCH_1):PAGE264

PVCCD_HV_CPU0_FAULT @S9S_MB_2U_LIB.S9S_MB_2U(SCH_1):PVCCD_HV_CPU0_FAULT
  PU35   33    CFP ISL69260IRAZT-ISL69260IRAZ-T,SA    I53 @S9S_MB_2U_LIB.S9S_MB_2U(SCH_1):PAGE264
 PR372    2      B Q_RES_0402LF-1K,1%,1/16W,CHIP,A    I14 @S9S_MB_2U_LIB.S9S_MB_2U(SCH_1):PAGE264

PVCCD_HV_CPU0_ISENSE_N @S9S_MB_2U_LIB.S9S_MB_2U(SCH_1):PVCCD_HV_CPU0_ISENSE_N
 PR373    1      A Q_RES_0402LF-1K,1%,1/16W,EMPTYA    I48 @S9S_MB_2U_LIB.S9S_MB_2U(SCH_1):PAGE264
 PC628    1      A Q_CAP_0402-0.1UF,25V,10%,X7R,CA    I50 @S9S_MB_2U_LIB.S9S_MB_2U(SCH_1):PAGE264
  PU35   38 VINSEN||VSYS ISL69260IRAZT-ISL69260IRAZ-T,SA    I53 @S9S_MB_2U_LIB.S9S_MB_2U(SCH_1):PAGE264
PR1390    2      B Q_RES_0402LF-49.9,1%,1/16W,CHIA    I10 @S9S_MB_2U_LIB.S9S_MB_2U(SCH_1):PAGE264
 PC813    1      A Q_CAP_C0402-1UF,16V,10%,X6S,CHA    I51 @S9S_MB_2U_LIB.S9S_MB_2U(SCH_1):PAGE264

PVCCD_HV_CPU0_ISENSE_P @S9S_MB_2U_LIB.S9S_MB_2U(SCH_1):PVCCD_HV_CPU0_ISENSE_P
  PU35   37 VMON||IINSEN||VSYS||ISYS ISL69260IRAZT-ISL69260IRAZ-T,SA    I53 @S9S_MB_2U_LIB.S9S_MB_2U(SCH_1):PAGE264
 PR369    1      A Q_RES_0402LF-1K,1%,1/16W,EMPTYA     I7 @S9S_MB_2U_LIB.S9S_MB_2U(SCH_1):PAGE264
 PC624    1      A Q_CAP_0402-0.1UF,25V,10%,X7R,CA     I9 @S9S_MB_2U_LIB.S9S_MB_2U(SCH_1):PAGE264
PR1380    2      B Q_RES_0402LF-49.9,1%,1/16W,CHIA    I11 @S9S_MB_2U_LIB.S9S_MB_2U(SCH_1):PAGE264
 PC813    2      B Q_CAP_C0402-1UF,16V,10%,X6S,CHA    I51 @S9S_MB_2U_LIB.S9S_MB_2U(SCH_1):PAGE264

PVCCD_HV_CPU0_ISYS_R @S9S_MB_2U_LIB.S9S_MB_2U(SCH_1):PVCCD_HV_CPU0_ISYS_R
  PU35   36 TEMP1||ISYS ISL69260IRAZT-ISL69260IRAZ-T,SA    I53 @S9S_MB_2U_LIB.S9S_MB_2U(SCH_1):PAGE264
PR1311    1      A Q_RES_0402LF-0,5%,1/16W,CHIP,CA    I59 @S9S_MB_2U_LIB.S9S_MB_2U(SCH_1):PAGE264
 PR409    1      A Q_RES_0402LF-0,5%,1/16W,EMPTY,A    I63 @S9S_MB_2U_LIB.S9S_MB_2U(SCH_1):PAGE264

PVCCD_HV_CPU0_LSET1 @S9S_MB_2U_LIB.S9S_MB_2U(SCH_1):PVCCD_HV_CPU0_LSET1
PR2718    1      A Q_RES_0402LF-8.87K,1%,1/16W,EMA     I3 @S9S_MB_2U_LIB.S9S_MB_2U(SCH_1):PAGE265
  PU36   37   LSET ISL99390FRZTR5935-ISL99390FRZ-A     I8 @S9S_MB_2U_LIB.S9S_MB_2U(SCH_1):PAGE265

PVCCD_HV_CPU0_NVDIMM_ISENSE @S9S_MB_2U_LIB.S9S_MB_2U(SCH_1):PVCCD_HV_CPU0_NVDIMM_ISENSE
 PR409    2      B Q_RES_0402LF-0,5%,1/16W,EMPTY,A    I63 @S9S_MB_2U_LIB.S9S_MB_2U(SCH_1):PAGE264
  U102    3    OUT INA183A1IDBVR-INA183A1IDBVR,SMA    I29 @S9S_MB_2U_LIB.S9S_MB_2U(SCH_1):PAGE240

PVCCD_HV_CPU0_PIN_ALT @S9S_MB_2U_LIB.S9S_MB_2U(SCH_1):PVCCD_HV_CPU0_PIN_ALT
  PU35   15 NPINALERT#||NPSYSCRIT# ISL69260IRAZT-ISL69260IRAZ-T,SA    I53 @S9S_MB_2U_LIB.S9S_MB_2U(SCH_1):PAGE264
 PR370    2      B Q_RES_0402LF-1K,1%,1/16W,CHIP,A    I13 @S9S_MB_2U_LIB.S9S_MB_2U(SCH_1):PAGE264

PVCCD_HV_CPU0_VCC @S9S_MB_2U_LIB.S9S_MB_2U(SCH_1):PVCCD_HV_CPU0_VCC
 PC629    1      A Q_CAP_C0402-100NF,50V,10%,EMPTA    I72 @S9S_MB_2U_LIB.S9S_MB_2U(SCH_1):PAGE264
  PU35   39    VCC ISL69260IRAZT-ISL69260IRAZ-T,SA    I53 @S9S_MB_2U_LIB.S9S_MB_2U(SCH_1):PAGE264
 PC632    1      A Q_CAP_C0402-1UF,16V,10%,X6S,CHA    I73 @S9S_MB_2U_LIB.S9S_MB_2U(SCH_1):PAGE264
 PR375    1      A Q_RES_0402LF-1,1%,1/16W,CHIP,CA    I80 @S9S_MB_2U_LIB.S9S_MB_2U(SCH_1):PAGE264
PC2365    1      A Q_CAP_0402-0.1UF,25V,10%,EMPTYA    I96 @S9S_MB_2U_LIB.S9S_MB_2U(SCH_1):PAGE264

PVCCD_HV_CPU0_VDD1 @S9S_MB_2U_LIB.S9S_MB_2U(SCH_1):PVCCD_HV_CPU0_VDD1
  PU36   35     EN ISL99390FRZTR5935-ISL99390FRZ-A     I8 @S9S_MB_2U_LIB.S9S_MB_2U(SCH_1):PAGE265
  PU36    3    VCC ISL99390FRZTR5935-ISL99390FRZ-A     I8 @S9S_MB_2U_LIB.S9S_MB_2U(SCH_1):PAGE265
 PC633    1      A Q_CAP_C0402-2.2UF,10V,10%,X6S,A    I11 @S9S_MB_2U_LIB.S9S_MB_2U(SCH_1):PAGE265
 PR380    2      B Q_RES_0402LF-2.2,1%,1/16W,CHIPA    I12 @S9S_MB_2U_LIB.S9S_MB_2U(SCH_1):PAGE265

PVCCD_HV_CPU0_VOS @S9S_MB_2U_LIB.S9S_MB_2U(SCH_1):PVCCD_HV_CPU0_VOS
  PU36    1    VOS ISL99390FRZTR5935-ISL99390FRZ-A     I8 @S9S_MB_2U_LIB.S9S_MB_2U(SCH_1):PAGE265
PR1785    1      A Q_RES_0402LF-0,5%,1/16W,CHIP,CA    I17 @S9S_MB_2U_LIB.S9S_MB_2U(SCH_1):PAGE265

PVCCD_HV_CPU0_VREF @S9S_MB_2U_LIB.S9S_MB_2U(SCH_1):PVCCD_HV_CPU0_VREF
  PU35   40   VCCS ISL69260IRAZT-ISL69260IRAZ-T,SA    I53 @S9S_MB_2U_LIB.S9S_MB_2U(SCH_1):PAGE264
  PU36   39  REFIN ISL99390FRZTR5935-ISL99390FRZ-A     I8 @S9S_MB_2U_LIB.S9S_MB_2U(SCH_1):PAGE265
PC1354    2      B Q_CAP_0402-0.1UF,25V,10%,X7R,CA     I7 @S9S_MB_2U_LIB.S9S_MB_2U(SCH_1):PAGE265
 PR357    1      A Q_RES_0402LF-28K,1%,1/16W,EMPTA     I5 @S9S_MB_2U_LIB.S9S_MB_2U(SCH_1):PAGE264
 PC630    1      A Q_CAP_C0402-10UF,6.3V,20%,X6S,B    I70 @S9S_MB_2U_LIB.S9S_MB_2U(SCH_1):PAGE264
PC1196    1      A Q_CAP_C0402-1UF,16V,10%,X6S,CHA    I71 @S9S_MB_2U_LIB.S9S_MB_2U(SCH_1):PAGE264

PVCCD_HV_CPU1 @S9S_MB_2U_LIB.S9S_MB_2U(SCH_1):PVCCD_HV_CPU1
    U1 AT36 VCCD_HV0 SOCKET4677_AZIF0045P001C01CS-SA     I8 @S9S_MB_2U_LIB.S9S_MB_2U(SCH_1):PAGE68
    U1 AT55 VCCD_HV1 SOCKET4677_AZIF0045P001C01CS-SA     I8 @S9S_MB_2U_LIB.S9S_MB_2U(SCH_1):PAGE68
    U1  AU3 VCCD_HV2 SOCKET4677_AZIF0045P001C01CS-SA     I8 @S9S_MB_2U_LIB.S9S_MB_2U(SCH_1):PAGE68
    U1 AU35 VCCD_HV3 SOCKET4677_AZIF0045P001C01CS-SA     I8 @S9S_MB_2U_LIB.S9S_MB_2U(SCH_1):PAGE68
    U1 AU54 VCCD_HV4 SOCKET4677_AZIF0045P001C01CS-SA     I8 @S9S_MB_2U_LIB.S9S_MB_2U(SCH_1):PAGE68
    U1  AU7 VCCD_HV5 SOCKET4677_AZIF0045P001C01CS-SA     I8 @S9S_MB_2U_LIB.S9S_MB_2U(SCH_1):PAGE68
    U1 AV34 VCCD_HV6 SOCKET4677_AZIF0045P001C01CS-SA     I8 @S9S_MB_2U_LIB.S9S_MB_2U(SCH_1):PAGE68
    U1 AV36 VCCD_HV7 SOCKET4677_AZIF0045P001C01CS-SA     I8 @S9S_MB_2U_LIB.S9S_MB_2U(SCH_1):PAGE68
    U1 AV53 VCCD_HV8 SOCKET4677_AZIF0045P001C01CS-SA     I8 @S9S_MB_2U_LIB.S9S_MB_2U(SCH_1):PAGE68
    U1 AV55 VCCD_HV9 SOCKET4677_AZIF0045P001C01CS-SA     I8 @S9S_MB_2U_LIB.S9S_MB_2U(SCH_1):PAGE68
    U1  BA3 VCCD_HV10 SOCKET4677_AZIF0045P001C01CS-SA     I8 @S9S_MB_2U_LIB.S9S_MB_2U(SCH_1):PAGE68
    U1  BA7 VCCD_HV11 SOCKET4677_AZIF0045P001C01CS-SA     I8 @S9S_MB_2U_LIB.S9S_MB_2U(SCH_1):PAGE68
    U1 BE11 VCCD_HV12 SOCKET4677_AZIF0045P001C01CS-SA     I8 @S9S_MB_2U_LIB.S9S_MB_2U(SCH_1):PAGE68
    U1  BE3 VCCD_HV13 SOCKET4677_AZIF0045P001C01CS-SA     I8 @S9S_MB_2U_LIB.S9S_MB_2U(SCH_1):PAGE68
    U1  BE7 VCCD_HV14 SOCKET4677_AZIF0045P001C01CS-SA     I8 @S9S_MB_2U_LIB.S9S_MB_2U(SCH_1):PAGE68
    U1 BJ11 VCCD_HV15 SOCKET4677_AZIF0045P001C01CS-SA     I8 @S9S_MB_2U_LIB.S9S_MB_2U(SCH_1):PAGE68
    U1  BJ3 VCCD_HV16 SOCKET4677_AZIF0045P001C01CS-SA     I8 @S9S_MB_2U_LIB.S9S_MB_2U(SCH_1):PAGE68
    U1  BJ7 VCCD_HV17 SOCKET4677_AZIF0045P001C01CS-SA     I8 @S9S_MB_2U_LIB.S9S_MB_2U(SCH_1):PAGE68
    U1  BN7 VCCD_HV18 SOCKET4677_AZIF0045P001C01CS-SA     I8 @S9S_MB_2U_LIB.S9S_MB_2U(SCH_1):PAGE68
    U1  CA7 VCCD_HV19 SOCKET4677_AZIF0045P001C01CS-SA     I8 @S9S_MB_2U_LIB.S9S_MB_2U(SCH_1):PAGE68
    U1  CE7 VCCD_HV20 SOCKET4677_AZIF0045P001C01CS-SA     I8 @S9S_MB_2U_LIB.S9S_MB_2U(SCH_1):PAGE68
    U1 CW35 VCCD_HV21 SOCKET4677_AZIF0045P001C01CS-SA     I8 @S9S_MB_2U_LIB.S9S_MB_2U(SCH_1):PAGE68
    U1 CW37 VCCD_HV22 SOCKET4677_AZIF0045P001C01CS-SA     I8 @S9S_MB_2U_LIB.S9S_MB_2U(SCH_1):PAGE68
    U1 CW52 VCCD_HV23 SOCKET4677_AZIF0045P001C01CS-SA     I8 @S9S_MB_2U_LIB.S9S_MB_2U(SCH_1):PAGE68
    U1 CW54 VCCD_HV24 SOCKET4677_AZIF0045P001C01CS-SA     I8 @S9S_MB_2U_LIB.S9S_MB_2U(SCH_1):PAGE68
    U1 CW56 VCCD_HV25 SOCKET4677_AZIF0045P001C01CS-SA     I8 @S9S_MB_2U_LIB.S9S_MB_2U(SCH_1):PAGE68
    U1 CY34 VCCD_HV26 SOCKET4677_AZIF0045P001C01CS-SA     I8 @S9S_MB_2U_LIB.S9S_MB_2U(SCH_1):PAGE68
    U1 CY36 VCCD_HV27 SOCKET4677_AZIF0045P001C01CS-SA     I8 @S9S_MB_2U_LIB.S9S_MB_2U(SCH_1):PAGE68
    U1 CY53 VCCD_HV28 SOCKET4677_AZIF0045P001C01CS-SA     I8 @S9S_MB_2U_LIB.S9S_MB_2U(SCH_1):PAGE68
  C423    1      A Q_CAP_C0402-22UF,4V,20%,X6S,CHA     I7 @S9S_MB_2U_LIB.S9S_MB_2U(SCH_1):PAGE77
  C425    1      A Q_CAP_C0402-22UF,4V,20%,X6S,CHA     I8 @S9S_MB_2U_LIB.S9S_MB_2U(SCH_1):PAGE77
  C427    1      A Q_CAP_C0402-22UF,4V,20%,X6S,CHA    I15 @S9S_MB_2U_LIB.S9S_MB_2U(SCH_1):PAGE77
  C429    1      A Q_CAP_C0402-22UF,4V,20%,X6S,CHA    I17 @S9S_MB_2U_LIB.S9S_MB_2U(SCH_1):PAGE77
  C451    1      A Q_CAP_C0805-47UF,4V,20%,X6S,CHA    I24 @S9S_MB_2U_LIB.S9S_MB_2U(SCH_1):PAGE78
  C474    1      A Q_CAP_C0805-47UF,4V,20%,X6S,CHA    I29 @S9S_MB_2U_LIB.S9S_MB_2U(SCH_1):PAGE78
  R153    2      B Q_RES_0402LF-100,1%,1/16W,CHIPA    I56 @S9S_MB_2U_LIB.S9S_MB_2U(SCH_1):PAGE125
  R151    2      B Q_RES_0402LF-100,1%,1/16W,CHIPA    I58 @S9S_MB_2U_LIB.S9S_MB_2U(SCH_1):PAGE125
  R137    2      B Q_RES_0402LF-100,1%,1/16W,CHIPA    I60 @S9S_MB_2U_LIB.S9S_MB_2U(SCH_1):PAGE125
  R135    2      B Q_RES_0402LF-100,1%,1/16W,CHIPA    I62 @S9S_MB_2U_LIB.S9S_MB_2U(SCH_1):PAGE125
  R820    1      A Q_RES_0402LF-1K,1%,1/16W,CHIP,A    I82 @S9S_MB_2U_LIB.S9S_MB_2U(SCH_1):PAGE130
  R821    1      A Q_RES_0402LF-1K,1%,1/16W,CHIP,A    I84 @S9S_MB_2U_LIB.S9S_MB_2U(SCH_1):PAGE130
  R822    1      A Q_RES_0402LF-1K,1%,1/16W,CHIP,A    I88 @S9S_MB_2U_LIB.S9S_MB_2U(SCH_1):PAGE130
  R819    1      A Q_RES_0402LF-1K,1%,1/16W,CHIP,A    I90 @S9S_MB_2U_LIB.S9S_MB_2U(SCH_1):PAGE130
 PC379    1      A Q_CAP_C0402-100NF,50V,10%,X7R,A    I27 @S9S_MB_2U_LIB.S9S_MB_2U(SCH_1):PAGE283
 PC381    1      A Q_CAP_C0805-22UF,4V,20%,X6S,CHA    I28 @S9S_MB_2U_LIB.S9S_MB_2U(SCH_1):PAGE283
  C447    1      A Q_CAP_C0805-47UF,4V,20%,X6S,CHA    I12 @S9S_MB_2U_LIB.S9S_MB_2U(SCH_1):PAGE78
  C471    1      A Q_CAP_C0805-47UF,4V,20%,X6S,CHA    I25 @S9S_MB_2U_LIB.S9S_MB_2U(SCH_1):PAGE78
  C455    1      A Q_CAP_C0805-47UF,4V,20%,X6S,CHA    I19 @S9S_MB_2U_LIB.S9S_MB_2U(SCH_1):PAGE79
  C459    1      A Q_CAP_C0805-47UF,4V,20%,X6S,CHA    I20 @S9S_MB_2U_LIB.S9S_MB_2U(SCH_1):PAGE79
  C463    1      A Q_CAP_C0805-47UF,4V,20%,X6S,CHA    I21 @S9S_MB_2U_LIB.S9S_MB_2U(SCH_1):PAGE79
  C467    1      A Q_CAP_C0805-47UF,4V,20%,X6S,CHA    I31 @S9S_MB_2U_LIB.S9S_MB_2U(SCH_1):PAGE79
PR1805    2      B Q_RES_0402LF-0,5%,1/16W,CHIP,CA    I12 @S9S_MB_2U_LIB.S9S_MB_2U(SCH_1):PAGE283
 PR559    2      B Q_RES_0402LF-100,1%,1/16W,CHIPA    I36 @S9S_MB_2U_LIB.S9S_MB_2U(SCH_1):PAGE282
  PL17    2      2 Q_INDUCTOR_SMLF-120NH/69A,IND,A    I14 @S9S_MB_2U_LIB.S9S_MB_2U(SCH_1):PAGE283
 PC382    1      A Q_CAP_C0805-22UF,4V,20%,X6S,CHA    I29 @S9S_MB_2U_LIB.S9S_MB_2U(SCH_1):PAGE283
   PC2    1      A Q_CAP_C0805-22UF,4V,20%,X6S,CHA    I30 @S9S_MB_2U_LIB.S9S_MB_2U(SCH_1):PAGE283
 PC385    1      A Q_CAPP_THLF-560UF,2.5V,20%,OSCA    I32 @S9S_MB_2U_LIB.S9S_MB_2U(SCH_1):PAGE283
PC1940    1      A Q_CAPP_SMLF-330UF,2V,35%,SPCAPA    I25 @S9S_MB_2U_LIB.S9S_MB_2U(SCH_1):PAGE283
 PC384    1      A Q_CAPP_THLF-560UF,2.5V,20%,OSCA    I26 @S9S_MB_2U_LIB.S9S_MB_2U(SCH_1):PAGE283
PR4258    1      A Q_RES_0402LF-499,1%,1/16W,CHIPA    I35 @S9S_MB_2U_LIB.S9S_MB_2U(SCH_1):PAGE283

PVCCD_HV_CPU1_ACSP1 @S9S_MB_2U_LIB.S9S_MB_2U(SCH_1):PVCCD_HV_CPU1_ACSP1
  PU18   23    CS7 ISL69260IRAZT-ISL69260IRAZ-T,SA    I53 @S9S_MB_2U_LIB.S9S_MB_2U(SCH_1):PAGE282
  PU17   38   IOUT ISL99390FRZTR5935-ISL99390FRZ-A    I10 @S9S_MB_2U_LIB.S9S_MB_2U(SCH_1):PAGE283

PVCCD_HV_CPU1_ADDR @S9S_MB_2U_LIB.S9S_MB_2U(SCH_1):PVCCD_HV_CPU1_ADDR
  PU18   34 ADDR_CFG ISL69260IRAZT-ISL69260IRAZ-T,SA    I53 @S9S_MB_2U_LIB.S9S_MB_2U(SCH_1):PAGE282
 PR202    2      B Q_RES_0402LF-28K,1%,1/16W,EMPTA     I8 @S9S_MB_2U_LIB.S9S_MB_2U(SCH_1):PAGE282
 PR203    2      B Q_RES_0402LF-24.3K,1%,1/16W,CHA    I95 @S9S_MB_2U_LIB.S9S_MB_2U(SCH_1):PAGE282

PVCCD_HV_CPU1_APWM1 @S9S_MB_2U_LIB.S9S_MB_2U(SCH_1):PVCCD_HV_CPU1_APWM1
  PU18    8   PWM7 ISL69260IRAZT-ISL69260IRAZ-T,SA    I53 @S9S_MB_2U_LIB.S9S_MB_2U(SCH_1):PAGE282
  PU17   34    PWM ISL99390FRZTR5935-ISL99390FRZ-A    I10 @S9S_MB_2U_LIB.S9S_MB_2U(SCH_1):PAGE283

PVCCD_HV_CPU1_ATSEN @S9S_MB_2U_LIB.S9S_MB_2U(SCH_1):PVCCD_HV_CPU1_ATSEN
  PU18   35  TEMP0 ISL69260IRAZT-ISL69260IRAZ-T,SA    I53 @S9S_MB_2U_LIB.S9S_MB_2U(SCH_1):PAGE282
 PR705    1      A Q_RES_0402LF-10K,1%,1/16W,EMPTA    I81 @S9S_MB_2U_LIB.S9S_MB_2U(SCH_1):PAGE282
  PU17   36 TOUT_FLT ISL99390FRZTR5935-ISL99390FRZ-A    I10 @S9S_MB_2U_LIB.S9S_MB_2U(SCH_1):PAGE283
 PC393    1      A Q_CAP_0402-470PF,50V,10%,X7R,TA    I57 @S9S_MB_2U_LIB.S9S_MB_2U(SCH_1):PAGE282

PVCCD_HV_CPU1_EN_R @S9S_MB_2U_LIB.S9S_MB_2U(SCH_1):PVCCD_HV_CPU1_EN_R
  PU18   13    EN0 ISL69260IRAZT-ISL69260IRAZ-T,SA    I53 @S9S_MB_2U_LIB.S9S_MB_2U(SCH_1):PAGE282
 R2577    2      B Q_RES_0402LF-0,5%,1/16W,CHIP,CA    I43 @S9S_MB_2U_LIB.S9S_MB_2U(SCH_1):PAGE282

PVCCD_HV_CPU1_FAULT @S9S_MB_2U_LIB.S9S_MB_2U(SCH_1):PVCCD_HV_CPU1_FAULT
  PU18   33    CFP ISL69260IRAZT-ISL69260IRAZ-T,SA    I53 @S9S_MB_2U_LIB.S9S_MB_2U(SCH_1):PAGE282
 PR217    2      B Q_RES_0402LF-1K,1%,1/16W,CHIP,A    I20 @S9S_MB_2U_LIB.S9S_MB_2U(SCH_1):PAGE282

PVCCD_HV_CPU1_ISENSE_N @S9S_MB_2U_LIB.S9S_MB_2U(SCH_1):PVCCD_HV_CPU1_ISENSE_N
 PR218    1      A Q_RES_0402LF-1K,1%,1/16W,EMPTYA    I48 @S9S_MB_2U_LIB.S9S_MB_2U(SCH_1):PAGE282
 PC390    1      A Q_CAP_0402-0.1UF,25V,10%,X7R,CA    I50 @S9S_MB_2U_LIB.S9S_MB_2U(SCH_1):PAGE282
  PU18   38 VINSEN||VSYS ISL69260IRAZT-ISL69260IRAZ-T,SA    I53 @S9S_MB_2U_LIB.S9S_MB_2U(SCH_1):PAGE282
 PC814    1      A Q_CAP_C0402-1UF,16V,10%,X6S,CHA    I51 @S9S_MB_2U_LIB.S9S_MB_2U(SCH_1):PAGE282
PR1410    2      B Q_RES_0402LF-49.9,1%,1/16W,CHIA    I10 @S9S_MB_2U_LIB.S9S_MB_2U(SCH_1):PAGE282

PVCCD_HV_CPU1_ISENSE_P @S9S_MB_2U_LIB.S9S_MB_2U(SCH_1):PVCCD_HV_CPU1_ISENSE_P
  PU18   37 VMON||IINSEN||VSYS||ISYS ISL69260IRAZT-ISL69260IRAZ-T,SA    I53 @S9S_MB_2U_LIB.S9S_MB_2U(SCH_1):PAGE282
 PC386    1      A Q_CAP_0402-0.1UF,25V,10%,X7R,CA    I13 @S9S_MB_2U_LIB.S9S_MB_2U(SCH_1):PAGE282
 PC814    2      B Q_CAP_C0402-1UF,16V,10%,X6S,CHA    I51 @S9S_MB_2U_LIB.S9S_MB_2U(SCH_1):PAGE282
PR1400    2      B Q_RES_0402LF-49.9,1%,1/16W,CHIA     I9 @S9S_MB_2U_LIB.S9S_MB_2U(SCH_1):PAGE282
 PR214    1      A Q_RES_0402LF-1K,1%,1/16W,EMPTYA    I11 @S9S_MB_2U_LIB.S9S_MB_2U(SCH_1):PAGE282

PVCCD_HV_CPU1_ISYS_R @S9S_MB_2U_LIB.S9S_MB_2U(SCH_1):PVCCD_HV_CPU1_ISYS_R
  PU18   36 TEMP1||ISYS ISL69260IRAZT-ISL69260IRAZ-T,SA    I53 @S9S_MB_2U_LIB.S9S_MB_2U(SCH_1):PAGE282
PR1315    1      A Q_RES_0402LF-0,5%,1/16W,CHIP,CA    I60 @S9S_MB_2U_LIB.S9S_MB_2U(SCH_1):PAGE282
 PR410    1      A Q_RES_0402LF-0,5%,1/16W,EMPTY,A    I61 @S9S_MB_2U_LIB.S9S_MB_2U(SCH_1):PAGE282

PVCCD_HV_CPU1_LSET1 @S9S_MB_2U_LIB.S9S_MB_2U(SCH_1):PVCCD_HV_CPU1_LSET1
PR1746    1      A Q_RES_0402LF-8.87K,1%,1/16W,EMA     I3 @S9S_MB_2U_LIB.S9S_MB_2U(SCH_1):PAGE283
  PU17   37   LSET ISL99390FRZTR5935-ISL99390FRZ-A    I10 @S9S_MB_2U_LIB.S9S_MB_2U(SCH_1):PAGE283

PVCCD_HV_CPU1_NVDIMM_ISENSE @S9S_MB_2U_LIB.S9S_MB_2U(SCH_1):PVCCD_HV_CPU1_NVDIMM_ISENSE
  U103    3    OUT INA183A1IDBVR-INA183A1IDBVR,SMA    I22 @S9S_MB_2U_LIB.S9S_MB_2U(SCH_1):PAGE240
 PR410    2      B Q_RES_0402LF-0,5%,1/16W,EMPTY,A    I61 @S9S_MB_2U_LIB.S9S_MB_2U(SCH_1):PAGE282

PVCCD_HV_CPU1_PIN_ALT @S9S_MB_2U_LIB.S9S_MB_2U(SCH_1):PVCCD_HV_CPU1_PIN_ALT
  PU18   15 NPINALERT#||NPSYSCRIT# ISL69260IRAZT-ISL69260IRAZ-T,SA    I53 @S9S_MB_2U_LIB.S9S_MB_2U(SCH_1):PAGE282
 PR215    2      B Q_RES_0402LF-1K,1%,1/16W,CHIP,A    I18 @S9S_MB_2U_LIB.S9S_MB_2U(SCH_1):PAGE282

PVCCD_HV_CPU1_VCC @S9S_MB_2U_LIB.S9S_MB_2U(SCH_1):PVCCD_HV_CPU1_VCC
  PU18   39    VCC ISL69260IRAZT-ISL69260IRAZ-T,SA    I53 @S9S_MB_2U_LIB.S9S_MB_2U(SCH_1):PAGE282
 PC391    1      A Q_CAP_C0402-100NF,50V,10%,EMPTA    I69 @S9S_MB_2U_LIB.S9S_MB_2U(SCH_1):PAGE282
 PC394    1      A Q_CAP_C0402-1UF,16V,10%,X6S,CHA    I77 @S9S_MB_2U_LIB.S9S_MB_2U(SCH_1):PAGE282
 PR220    1      A Q_RES_0402LF-1,1%,1/16W,CHIP,CA    I78 @S9S_MB_2U_LIB.S9S_MB_2U(SCH_1):PAGE282
PC2368    1      A Q_CAP_0402-0.1UF,25V,10%,EMPTYA    I96 @S9S_MB_2U_LIB.S9S_MB_2U(SCH_1):PAGE282

PVCCD_HV_CPU1_VDD1 @S9S_MB_2U_LIB.S9S_MB_2U(SCH_1):PVCCD_HV_CPU1_VDD1
 PC373    1      A Q_CAP_C0402-2.2UF,10V,10%,X6S,A    I15 @S9S_MB_2U_LIB.S9S_MB_2U(SCH_1):PAGE283
  PU17   35     EN ISL99390FRZTR5935-ISL99390FRZ-A    I10 @S9S_MB_2U_LIB.S9S_MB_2U(SCH_1):PAGE283
  PU17    3    VCC ISL99390FRZTR5935-ISL99390FRZ-A    I10 @S9S_MB_2U_LIB.S9S_MB_2U(SCH_1):PAGE283
 PR200    2      B Q_RES_0402LF-2.2,1%,1/16W,CHIPA    I16 @S9S_MB_2U_LIB.S9S_MB_2U(SCH_1):PAGE283

PVCCD_HV_CPU1_VOS @S9S_MB_2U_LIB.S9S_MB_2U(SCH_1):PVCCD_HV_CPU1_VOS
PR1805    1      A Q_RES_0402LF-0,5%,1/16W,CHIP,CA    I12 @S9S_MB_2U_LIB.S9S_MB_2U(SCH_1):PAGE283
  PU17    1    VOS ISL99390FRZTR5935-ISL99390FRZ-A    I10 @S9S_MB_2U_LIB.S9S_MB_2U(SCH_1):PAGE283

PVCCD_HV_CPU1_VREF @S9S_MB_2U_LIB.S9S_MB_2U(SCH_1):PVCCD_HV_CPU1_VREF
PC1371    2      B Q_CAP_0402-0.1UF,25V,10%,X7R,CA     I8 @S9S_MB_2U_LIB.S9S_MB_2U(SCH_1):PAGE283
  PU18   40   VCCS ISL69260IRAZT-ISL69260IRAZ-T,SA    I53 @S9S_MB_2U_LIB.S9S_MB_2U(SCH_1):PAGE282
  PU17   39  REFIN ISL99390FRZTR5935-ISL99390FRZ-A    I10 @S9S_MB_2U_LIB.S9S_MB_2U(SCH_1):PAGE283
 PC392    1      A Q_CAP_C0402-10UF,6.3V,20%,X6S,B    I68 @S9S_MB_2U_LIB.S9S_MB_2U(SCH_1):PAGE282
PC1289    1      A Q_CAP_C0402-1UF,16V,10%,X6S,CHA    I74 @S9S_MB_2U_LIB.S9S_MB_2U(SCH_1):PAGE282
 PR202    1      A Q_RES_0402LF-28K,1%,1/16W,EMPTA     I8 @S9S_MB_2U_LIB.S9S_MB_2U(SCH_1):PAGE282

PVCCFA_EHV_CPU0 @S9S_MB_2U_LIB.S9S_MB_2U(SCH_1):PVCCFA_EHV_CPU0
    U2  AA3 VCCFA_EHV0 SOCKET4677_AZIF0045P001C01CS-SA     I8 @S9S_MB_2U_LIB.S9S_MB_2U(SCH_1):PAGE37
    U2  AE3 VCCFA_EHV1 SOCKET4677_AZIF0045P001C01CS-SA     I8 @S9S_MB_2U_LIB.S9S_MB_2U(SCH_1):PAGE37
    U2  AJ3 VCCFA_EHV2 SOCKET4677_AZIF0045P001C01CS-SA     I8 @S9S_MB_2U_LIB.S9S_MB_2U(SCH_1):PAGE37
    U2  AN3 VCCFA_EHV3 SOCKET4677_AZIF0045P001C01CS-SA     I8 @S9S_MB_2U_LIB.S9S_MB_2U(SCH_1):PAGE37
    U2 AT61 VCCFA_EHV4 SOCKET4677_AZIF0045P001C01CS-SA     I8 @S9S_MB_2U_LIB.S9S_MB_2U(SCH_1):PAGE37
    U2 AU60 VCCFA_EHV5 SOCKET4677_AZIF0045P001C01CS-SA     I8 @S9S_MB_2U_LIB.S9S_MB_2U(SCH_1):PAGE37
    U2 AV61 VCCFA_EHV6 SOCKET4677_AZIF0045P001C01CS-SA     I8 @S9S_MB_2U_LIB.S9S_MB_2U(SCH_1):PAGE37
    U2 AW60 VCCFA_EHV7 SOCKET4677_AZIF0045P001C01CS-SA     I8 @S9S_MB_2U_LIB.S9S_MB_2U(SCH_1):PAGE37
    U2   N3 VCCFA_EHV8 SOCKET4677_AZIF0045P001C01CS-SA     I8 @S9S_MB_2U_LIB.S9S_MB_2U(SCH_1):PAGE37
    U2   U3 VCCFA_EHV9 SOCKET4677_AZIF0045P001C01CS-SA     I8 @S9S_MB_2U_LIB.S9S_MB_2U(SCH_1):PAGE37
  C419    1      A Q_CAP_C0402-22UF,4V,20%,X6S,CHA    I98 @S9S_MB_2U_LIB.S9S_MB_2U(SCH_1):PAGE74
  C421    1      A Q_CAP_C0402-22UF,4V,20%,X6S,CHA   I103 @S9S_MB_2U_LIB.S9S_MB_2U(SCH_1):PAGE74
 PC181    1      A Q_CAP_C0402-100NF,50V,10%,X7R,A    I28 @S9S_MB_2U_LIB.S9S_MB_2U(SCH_1):PAGE262
 PC184    1      A Q_CAP_C0805-22UF,4V,20%,X6S,CHA    I31 @S9S_MB_2U_LIB.S9S_MB_2U(SCH_1):PAGE262
  C420    1      A Q_CAP_C0402-22UF,4V,20%,X6S,CHA   I100 @S9S_MB_2U_LIB.S9S_MB_2U(SCH_1):PAGE74
  C422    1      A Q_CAP_C0402-22UF,4V,20%,X6S,CHA   I107 @S9S_MB_2U_LIB.S9S_MB_2U(SCH_1):PAGE74
  C492    1      A Q_CAP_C0805-47UF,4V,20%,X6S,CHA    I11 @S9S_MB_2U_LIB.S9S_MB_2U(SCH_1):PAGE75
  C496    1      A Q_CAP_C0805-47UF,4V,20%,X6S,CHA    I16 @S9S_MB_2U_LIB.S9S_MB_2U(SCH_1):PAGE75
  C500    1      A Q_CAP_C0805-47UF,4V,20%,X6S,CHA     I9 @S9S_MB_2U_LIB.S9S_MB_2U(SCH_1):PAGE76
  C504    1      A Q_CAP_C0805-47UF,4V,20%,X6S,CHA    I10 @S9S_MB_2U_LIB.S9S_MB_2U(SCH_1):PAGE76
  C508    1      A Q_CAP_C0805-47UF,4V,20%,X6S,CHA    I11 @S9S_MB_2U_LIB.S9S_MB_2U(SCH_1):PAGE76
  C512    1      A Q_CAP_C0805-47UF,4V,20%,X6S,CHA    I32 @S9S_MB_2U_LIB.S9S_MB_2U(SCH_1):PAGE76
  C516    1      A Q_CAP_C0603-47UF,2.5V,20%,X6S,A    I33 @S9S_MB_2U_LIB.S9S_MB_2U(SCH_1):PAGE76
  C519    1      A Q_CAP_C0603-47UF,2.5V,20%,X6S,A    I35 @S9S_MB_2U_LIB.S9S_MB_2U(SCH_1):PAGE76
 PR522    2      B Q_RES_0402LF-100,1%,1/16W,CHIPA    I40 @S9S_MB_2U_LIB.S9S_MB_2U(SCH_1):PAGE260
   PL3    2      2 Q_INDUCTOR_SMLF-300NH/33A,IND,A    I29 @S9S_MB_2U_LIB.S9S_MB_2U(SCH_1):PAGE262
PC2180    1      A Q_CAPP_THLF-560UF,2.5V,20%,OSCA    I33 @S9S_MB_2U_LIB.S9S_MB_2U(SCH_1):PAGE262
 PC186    1      A Q_CAP_C0805-22UF,4V,20%,X6S,CHA    I32 @S9S_MB_2U_LIB.S9S_MB_2U(SCH_1):PAGE262
PC1900    1      A Q_CAPP_SMLF-330UF,2.5V,+10/-35B    I34 @S9S_MB_2U_LIB.S9S_MB_2U(SCH_1):PAGE262
PR4229    1      A Q_RES_0402LF-499,1%,1/16W,CHIPA    I36 @S9S_MB_2U_LIB.S9S_MB_2U(SCH_1):PAGE262

PVCCFA_EHV_CPU0_BCSP1 @S9S_MB_2U_LIB.S9S_MB_2U(SCH_1):PVCCFA_EHV_CPU0_BCSP1
   PU5   30    CS0 ISL69260IRAZT-ISL69260IRAZ-T,SA    I65 @S9S_MB_2U_LIB.S9S_MB_2U(SCH_1):PAGE260
  PU42   25   IMON RAA2213404GNPHB0-RAA2213404GNPA    I14 @S9S_MB_2U_LIB.S9S_MB_2U(SCH_1):PAGE262

PVCCFA_EHV_CPU0_BPWM1 @S9S_MB_2U_LIB.S9S_MB_2U(SCH_1):PVCCFA_EHV_CPU0_BPWM1
   PU5    1   PWM0 ISL69260IRAZT-ISL69260IRAZ-T,SA    I65 @S9S_MB_2U_LIB.S9S_MB_2U(SCH_1):PAGE260
  PU42   21    PWM RAA2213404GNPHB0-RAA2213404GNPA    I14 @S9S_MB_2U_LIB.S9S_MB_2U(SCH_1):PAGE262

PVCCFA_EHV_CPU0_BTSEN @S9S_MB_2U_LIB.S9S_MB_2U(SCH_1):PVCCFA_EHV_CPU0_BTSEN
   PU5   36 TEMP1||ISYS ISL69260IRAZT-ISL69260IRAZ-T,SA    I65 @S9S_MB_2U_LIB.S9S_MB_2U(SCH_1):PAGE260
  PU42    1   TMON RAA2213404GNPHB0-RAA2213404GNPA    I14 @S9S_MB_2U_LIB.S9S_MB_2U(SCH_1):PAGE262
PC1271    1      A Q_CAP_0402-470PF,50V,10%,X7R,TA    I73 @S9S_MB_2U_LIB.S9S_MB_2U(SCH_1):PAGE260
 PR436    1      A Q_RES_0402LF-10K,1%,1/16W,EMPTA   I106 @S9S_MB_2U_LIB.S9S_MB_2U(SCH_1):PAGE260

PVCCFA_EHV_CPU0_EN_R @S9S_MB_2U_LIB.S9S_MB_2U(SCH_1):PVCCFA_EHV_CPU0_EN_R
   PU5   20    EN1 ISL69260IRAZT-ISL69260IRAZ-T,SA    I65 @S9S_MB_2U_LIB.S9S_MB_2U(SCH_1):PAGE260
 R2394    2      B Q_RES_0402LF-0,5%,1/16W,CHIP,CA    I14 @S9S_MB_2U_LIB.S9S_MB_2U(SCH_1):PAGE260
 C3275    1      A Q_CAP_0402-1000PF,50V,5%,X7R,TA    I23 @S9S_MB_2U_LIB.S9S_MB_2U(SCH_1):PAGE260

PVCCFA_EHV_CPU0_FAULT @S9S_MB_2U_LIB.S9S_MB_2U(SCH_1):PVCCFA_EHV_CPU0_FAULT
PR4228    1      A Q_RES_0402LF-0,5%,1/16W,EMPTY,A    I15 @S9S_MB_2U_LIB.S9S_MB_2U(SCH_1):PAGE262
  PU42    2 FAULT# RAA2213404GNPHB0-RAA2213404GNPA    I14 @S9S_MB_2U_LIB.S9S_MB_2U(SCH_1):PAGE262

PVCCFA_EHV_CPU0_LSET1 @S9S_MB_2U_LIB.S9S_MB_2U(SCH_1):PVCCFA_EHV_CPU0_LSET1
PR1709    1      A Q_RES_0402LF-8.87K,1%,1/16W,EMA     I2 @S9S_MB_2U_LIB.S9S_MB_2U(SCH_1):PAGE262
  PU42    5    GL1 RAA2213404GNPHB0-RAA2213404GNPA    I14 @S9S_MB_2U_LIB.S9S_MB_2U(SCH_1):PAGE262

PVCCFA_EHV_CPU0_NC1 @S9S_MB_2U_LIB.S9S_MB_2U(SCH_1):PVCCFA_EHV_CPU0_NC1
  PU42    3 LGCTRL RAA2213404GNPHB0-RAA2213404GNPA    I14 @S9S_MB_2U_LIB.S9S_MB_2U(SCH_1):PAGE262
PR1779    1      A Q_RES_0402LF-0,5%,1/16W,CHIP,CA    I16 @S9S_MB_2U_LIB.S9S_MB_2U(SCH_1):PAGE262

PVCCFA_EHV_CPU0_NC2 @S9S_MB_2U_LIB.S9S_MB_2U(SCH_1):PVCCFA_EHV_CPU0_NC2
PR4227    2      B Q_RES_0402LF-0,5%,1/16W,EMPTY,A    I13 @S9S_MB_2U_LIB.S9S_MB_2U(SCH_1):PAGE262
  PU42   22    NC1 RAA2213404GNPHB0-RAA2213404GNPA    I14 @S9S_MB_2U_LIB.S9S_MB_2U(SCH_1):PAGE262

PVCCFA_EHV_CPU0_PVCC @S9S_MB_2U_LIB.S9S_MB_2U(SCH_1):PVCCFA_EHV_CPU0_PVCC
  PR97    1      A Q_RES_0402LF-2.2,1%,1/16W,CHIPA    I21 @S9S_MB_2U_LIB.S9S_MB_2U(SCH_1):PAGE262
PU44_P0_2    4   PVCC ISL99390FRZTR5935-ISL99390FRZ-A    I12 @S9S_MB_2U_LIB.S9S_MB_2U(SCH_1):PAGE261
 PR101    1      A Q_RES_0402LF-2.2,1%,1/16W,CHIPA    I26 @S9S_MB_2U_LIB.S9S_MB_2U(SCH_1):PAGE261
  PU36    4   PVCC ISL99390FRZTR5935-ISL99390FRZ-A     I8 @S9S_MB_2U_LIB.S9S_MB_2U(SCH_1):PAGE265
 PR102    1      A Q_RES_0402LF-2.2,1%,1/16W,CHIPA    I14 @S9S_MB_2U_LIB.S9S_MB_2U(SCH_1):PAGE261
PC2947    1      A Q_CAP_C0402-2.2UF,10V,10%,X6S,A    I29 @S9S_MB_2U_LIB.S9S_MB_2U(SCH_1):PAGE261
PU43_P0_1    4   PVCC ISL99390FRZTR5935-ISL99390FRZ-A    I79 @S9S_MB_2U_LIB.S9S_MB_2U(SCH_1):PAGE261
 PR442    2      B Q_RES_0402LF-0,5%,1/16W,CHIP,CA     I8 @S9S_MB_2U_LIB.S9S_MB_2U(SCH_1):PAGE262
 PR380    1      A Q_RES_0402LF-2.2,1%,1/16W,CHIPA    I12 @S9S_MB_2U_LIB.S9S_MB_2U(SCH_1):PAGE265
PC2948    1      A Q_CAP_C0402-2.2UF,10V,10%,X6S,A    I14 @S9S_MB_2U_LIB.S9S_MB_2U(SCH_1):PAGE265
 PR443    2      B Q_RES_0402LF-0,5%,1/16W,EMPTY,A    I22 @S9S_MB_2U_LIB.S9S_MB_2U(SCH_1):PAGE262
PC2946    1      A Q_CAP_C0402-2.2UF,10V,10%,X6S,A    I16 @S9S_MB_2U_LIB.S9S_MB_2U(SCH_1):PAGE261

PVCCFA_EHV_CPU0_VDD1 @S9S_MB_2U_LIB.S9S_MB_2U(SCH_1):PVCCFA_EHV_CPU0_VDD1
  PR97    2      B Q_RES_0402LF-2.2,1%,1/16W,CHIPA    I21 @S9S_MB_2U_LIB.S9S_MB_2U(SCH_1):PAGE262
 PC175    1      A Q_CAP_C0402-2.2UF,10V,10%,X6S,A    I12 @S9S_MB_2U_LIB.S9S_MB_2U(SCH_1):PAGE262
PR4227    1      A Q_RES_0402LF-0,5%,1/16W,EMPTY,A    I13 @S9S_MB_2U_LIB.S9S_MB_2U(SCH_1):PAGE262
  PU42    4    VCC RAA2213404GNPHB0-RAA2213404GNPA    I14 @S9S_MB_2U_LIB.S9S_MB_2U(SCH_1):PAGE262
PR1779    2      B Q_RES_0402LF-0,5%,1/16W,CHIP,CA    I16 @S9S_MB_2U_LIB.S9S_MB_2U(SCH_1):PAGE262

PVCCFA_EHV_CPU1 @S9S_MB_2U_LIB.S9S_MB_2U(SCH_1):PVCCFA_EHV_CPU1
    U1  AA3 VCCFA_EHV0 SOCKET4677_AZIF0045P001C01CS-SA     I8 @S9S_MB_2U_LIB.S9S_MB_2U(SCH_1):PAGE68
    U1  AE3 VCCFA_EHV1 SOCKET4677_AZIF0045P001C01CS-SA     I8 @S9S_MB_2U_LIB.S9S_MB_2U(SCH_1):PAGE68
    U1  AJ3 VCCFA_EHV2 SOCKET4677_AZIF0045P001C01CS-SA     I8 @S9S_MB_2U_LIB.S9S_MB_2U(SCH_1):PAGE68
    U1  AN3 VCCFA_EHV3 SOCKET4677_AZIF0045P001C01CS-SA     I8 @S9S_MB_2U_LIB.S9S_MB_2U(SCH_1):PAGE68
    U1 AT61 VCCFA_EHV4 SOCKET4677_AZIF0045P001C01CS-SA     I8 @S9S_MB_2U_LIB.S9S_MB_2U(SCH_1):PAGE68
    U1 AU60 VCCFA_EHV5 SOCKET4677_AZIF0045P001C01CS-SA     I8 @S9S_MB_2U_LIB.S9S_MB_2U(SCH_1):PAGE68
    U1 AV61 VCCFA_EHV6 SOCKET4677_AZIF0045P001C01CS-SA     I8 @S9S_MB_2U_LIB.S9S_MB_2U(SCH_1):PAGE68
    U1 AW60 VCCFA_EHV7 SOCKET4677_AZIF0045P001C01CS-SA     I8 @S9S_MB_2U_LIB.S9S_MB_2U(SCH_1):PAGE68
    U1   N3 VCCFA_EHV8 SOCKET4677_AZIF0045P001C01CS-SA     I8 @S9S_MB_2U_LIB.S9S_MB_2U(SCH_1):PAGE68
    U1   U3 VCCFA_EHV9 SOCKET4677_AZIF0045P001C01CS-SA     I8 @S9S_MB_2U_LIB.S9S_MB_2U(SCH_1):PAGE68
  C444    1      A Q_CAP_C0402-22UF,4V,20%,X6S,CHA   I109 @S9S_MB_2U_LIB.S9S_MB_2U(SCH_1):PAGE77
  C445    1      A Q_CAP_C0402-22UF,4V,20%,X6S,CHA   I110 @S9S_MB_2U_LIB.S9S_MB_2U(SCH_1):PAGE77
  C446    1      A Q_CAP_C0402-22UF,4V,20%,X6S,CHA   I113 @S9S_MB_2U_LIB.S9S_MB_2U(SCH_1):PAGE77
  PL20    2      2 Q_INDUCTOR_SMLF-300NH/33A,IND,A    I23 @S9S_MB_2U_LIB.S9S_MB_2U(SCH_1):PAGE280
 PC435    1      A Q_CAP_C0805-22UF,4V,20%,X6S,CHA    I30 @S9S_MB_2U_LIB.S9S_MB_2U(SCH_1):PAGE280
 PC437    1      A Q_CAP_C0805-22UF,4V,20%,X6S,CHA    I31 @S9S_MB_2U_LIB.S9S_MB_2U(SCH_1):PAGE280
  C443    1      A Q_CAP_C0402-22UF,4V,20%,X6S,CHA    I67 @S9S_MB_2U_LIB.S9S_MB_2U(SCH_1):PAGE77
  C448    1      A Q_CAP_C0805-47UF,4V,20%,X6S,CHA    I10 @S9S_MB_2U_LIB.S9S_MB_2U(SCH_1):PAGE78
  C452    1      A Q_CAP_C0805-47UF,4V,20%,X6S,CHA    I21 @S9S_MB_2U_LIB.S9S_MB_2U(SCH_1):PAGE78
  C456    1      A Q_CAP_C0805-47UF,4V,20%,X6S,CHA    I15 @S9S_MB_2U_LIB.S9S_MB_2U(SCH_1):PAGE79
  C460    1      A Q_CAP_C0805-47UF,4V,20%,X6S,CHA    I16 @S9S_MB_2U_LIB.S9S_MB_2U(SCH_1):PAGE79
  C464    1      A Q_CAP_C0805-47UF,4V,20%,X6S,CHA    I17 @S9S_MB_2U_LIB.S9S_MB_2U(SCH_1):PAGE79
  C468    1      A Q_CAP_C0805-47UF,4V,20%,X6S,CHA    I26 @S9S_MB_2U_LIB.S9S_MB_2U(SCH_1):PAGE79
  C472    1      A Q_CAP_C0603-47UF,2.5V,20%,X6S,A    I27 @S9S_MB_2U_LIB.S9S_MB_2U(SCH_1):PAGE79
  C475    1      A Q_CAP_C0603-47UF,2.5V,20%,X6S,A    I29 @S9S_MB_2U_LIB.S9S_MB_2U(SCH_1):PAGE79
 PC434    1      A Q_CAP_C0402-100NF,50V,10%,X7R,A    I29 @S9S_MB_2U_LIB.S9S_MB_2U(SCH_1):PAGE280
PC2199    1      A Q_CAPP_THLF-560UF,2.5V,20%,OSCA    I32 @S9S_MB_2U_LIB.S9S_MB_2U(SCH_1):PAGE280
 PR569    2      B Q_RES_0402LF-100,1%,1/16W,CHIPA    I45 @S9S_MB_2U_LIB.S9S_MB_2U(SCH_1):PAGE278
PC1930    1      A Q_CAPP_SMLF-330UF,2.5V,+10/-35B    I33 @S9S_MB_2U_LIB.S9S_MB_2U(SCH_1):PAGE280
PR4250    1      A Q_RES_0402LF-499,1%,1/16W,CHIPA    I37 @S9S_MB_2U_LIB.S9S_MB_2U(SCH_1):PAGE280

PVCCFA_EHV_CPU1_BCSP1 @S9S_MB_2U_LIB.S9S_MB_2U(SCH_1):PVCCFA_EHV_CPU1_BCSP1
  PU49   25   IMON RAA2213404GNPHB0-RAA2213404GNPA    I14 @S9S_MB_2U_LIB.S9S_MB_2U(SCH_1):PAGE280
  PU22   30    CS0 ISL69260IRAZT-ISL69260IRAZ-T,SA    I38 @S9S_MB_2U_LIB.S9S_MB_2U(SCH_1):PAGE278

PVCCFA_EHV_CPU1_BPWM1 @S9S_MB_2U_LIB.S9S_MB_2U(SCH_1):PVCCFA_EHV_CPU1_BPWM1
  PU49   21    PWM RAA2213404GNPHB0-RAA2213404GNPA    I14 @S9S_MB_2U_LIB.S9S_MB_2U(SCH_1):PAGE280
  PU22    1   PWM0 ISL69260IRAZT-ISL69260IRAZ-T,SA    I38 @S9S_MB_2U_LIB.S9S_MB_2U(SCH_1):PAGE278

PVCCFA_EHV_CPU1_BTSEN @S9S_MB_2U_LIB.S9S_MB_2U(SCH_1):PVCCFA_EHV_CPU1_BTSEN
  PU49    1   TMON RAA2213404GNPHB0-RAA2213404GNPA    I14 @S9S_MB_2U_LIB.S9S_MB_2U(SCH_1):PAGE280
PC1292    1      A Q_CAP_0402-470PF,50V,10%,X7R,TA    I69 @S9S_MB_2U_LIB.S9S_MB_2U(SCH_1):PAGE278
  PU22   36 TEMP1||ISYS ISL69260IRAZT-ISL69260IRAZ-T,SA    I38 @S9S_MB_2U_LIB.S9S_MB_2U(SCH_1):PAGE278
 PR667    1      A Q_RES_0402LF-10K,1%,1/16W,EMPTA    I75 @S9S_MB_2U_LIB.S9S_MB_2U(SCH_1):PAGE278

PVCCFA_EHV_CPU1_EN_R @S9S_MB_2U_LIB.S9S_MB_2U(SCH_1):PVCCFA_EHV_CPU1_EN_R
 R2570    2      B Q_RES_0402LF-0,5%,1/16W,CHIP,CA    I31 @S9S_MB_2U_LIB.S9S_MB_2U(SCH_1):PAGE278
 C2452    1      A Q_CAP_0402-1000PF,50V,5%,X7R,TA    I33 @S9S_MB_2U_LIB.S9S_MB_2U(SCH_1):PAGE278
  PU22   20    EN1 ISL69260IRAZT-ISL69260IRAZ-T,SA    I38 @S9S_MB_2U_LIB.S9S_MB_2U(SCH_1):PAGE278

PVCCFA_EHV_CPU1_FAULT @S9S_MB_2U_LIB.S9S_MB_2U(SCH_1):PVCCFA_EHV_CPU1_FAULT
  PU49    2 FAULT# RAA2213404GNPHB0-RAA2213404GNPA    I14 @S9S_MB_2U_LIB.S9S_MB_2U(SCH_1):PAGE280
PR4249    1      A Q_RES_0402LF-0,5%,1/16W,EMPTY,A    I18 @S9S_MB_2U_LIB.S9S_MB_2U(SCH_1):PAGE280

PVCCFA_EHV_CPU1_LSET1 @S9S_MB_2U_LIB.S9S_MB_2U(SCH_1):PVCCFA_EHV_CPU1_LSET1
  PU49    5    GL1 RAA2213404GNPHB0-RAA2213404GNPA    I14 @S9S_MB_2U_LIB.S9S_MB_2U(SCH_1):PAGE280
PR1728    1      A Q_RES_0402LF-8.87K,1%,1/16W,EMA     I1 @S9S_MB_2U_LIB.S9S_MB_2U(SCH_1):PAGE280

PVCCFA_EHV_CPU1_NC1 @S9S_MB_2U_LIB.S9S_MB_2U(SCH_1):PVCCFA_EHV_CPU1_NC1
  PU49    3 LGCTRL RAA2213404GNPHB0-RAA2213404GNPA    I14 @S9S_MB_2U_LIB.S9S_MB_2U(SCH_1):PAGE280
PR1799    1      A Q_RES_0402LF-0,5%,1/16W,CHIP,CA    I20 @S9S_MB_2U_LIB.S9S_MB_2U(SCH_1):PAGE280

PVCCFA_EHV_CPU1_NC2 @S9S_MB_2U_LIB.S9S_MB_2U(SCH_1):PVCCFA_EHV_CPU1_NC2
  PU49   22    NC1 RAA2213404GNPHB0-RAA2213404GNPA    I14 @S9S_MB_2U_LIB.S9S_MB_2U(SCH_1):PAGE280
PR4248    1      A Q_RES_0402LF-0,5%,1/16W,EMPTY,A    I13 @S9S_MB_2U_LIB.S9S_MB_2U(SCH_1):PAGE280

PVCCFA_EHV_CPU1_PVCC @S9S_MB_2U_LIB.S9S_MB_2U(SCH_1):PVCCFA_EHV_CPU1_PVCC
 PR255    1      A Q_RES_0402LF-2.2,1%,1/16W,CHIPA    I11 @S9S_MB_2U_LIB.S9S_MB_2U(SCH_1):PAGE279
PU50_P1_1    4   PVCC ISL99390FRZTR5935-ISL99390FRZ-A    I38 @S9S_MB_2U_LIB.S9S_MB_2U(SCH_1):PAGE279
PC2951    1      A Q_CAP_C0402-2.2UF,10V,10%,X6S,A    I18 @S9S_MB_2U_LIB.S9S_MB_2U(SCH_1):PAGE283
 PR254    1      A Q_RES_0402LF-2.2,1%,1/16W,CHIPA    I25 @S9S_MB_2U_LIB.S9S_MB_2U(SCH_1):PAGE279
PU51_P1_2    4   PVCC ISL99390FRZTR5935-ISL99390FRZ-A    I29 @S9S_MB_2U_LIB.S9S_MB_2U(SCH_1):PAGE279
 PR678    2      B Q_RES_0402LF-0,5%,1/16W,CHIP,CA     I4 @S9S_MB_2U_LIB.S9S_MB_2U(SCH_1):PAGE280
 PR250    1      A Q_RES_0402LF-2.2,1%,1/16W,CHIPA    I15 @S9S_MB_2U_LIB.S9S_MB_2U(SCH_1):PAGE280
  PU17    4   PVCC ISL99390FRZTR5935-ISL99390FRZ-A    I10 @S9S_MB_2U_LIB.S9S_MB_2U(SCH_1):PAGE283
 PR200    1      A Q_RES_0402LF-2.2,1%,1/16W,CHIPA    I16 @S9S_MB_2U_LIB.S9S_MB_2U(SCH_1):PAGE283
PC2949    1      A Q_CAP_C0402-2.2UF,10V,10%,X6S,A    I13 @S9S_MB_2U_LIB.S9S_MB_2U(SCH_1):PAGE279
PC2950    1      A Q_CAP_C0402-2.2UF,10V,10%,X6S,A    I26 @S9S_MB_2U_LIB.S9S_MB_2U(SCH_1):PAGE279
 PR699    2      B Q_RES_0402LF-0,5%,1/16W,EMPTY,A    I16 @S9S_MB_2U_LIB.S9S_MB_2U(SCH_1):PAGE280

PVCCFA_EHV_CPU1_VDD1 @S9S_MB_2U_LIB.S9S_MB_2U(SCH_1):PVCCFA_EHV_CPU1_VDD1
  PU49    4    VCC RAA2213404GNPHB0-RAA2213404GNPA    I14 @S9S_MB_2U_LIB.S9S_MB_2U(SCH_1):PAGE280
 PR250    2      B Q_RES_0402LF-2.2,1%,1/16W,CHIPA    I15 @S9S_MB_2U_LIB.S9S_MB_2U(SCH_1):PAGE280
 PC428    1      A Q_CAP_C0402-2.2UF,10V,10%,X6S,A    I11 @S9S_MB_2U_LIB.S9S_MB_2U(SCH_1):PAGE280
PR4248    2      B Q_RES_0402LF-0,5%,1/16W,EMPTY,A    I13 @S9S_MB_2U_LIB.S9S_MB_2U(SCH_1):PAGE280
PR1799    2      B Q_RES_0402LF-0,5%,1/16W,CHIP,CA    I20 @S9S_MB_2U_LIB.S9S_MB_2U(SCH_1):PAGE280

PVCCFA_EHV_FIVRA_CPU0 @S9S_MB_2U_LIB.S9S_MB_2U(SCH_1):PVCCFA_EHV_FIVRA_CPU0
    U2 AA11 VCCFA_EHV_FIVRA0 SOCKET4677_AZIF0045P001C01CS-SA     I4 @S9S_MB_2U_LIB.S9S_MB_2U(SCH_1):PAGE38
    U2 AA15 VCCFA_EHV_FIVRA1 SOCKET4677_AZIF0045P001C01CS-SA     I4 @S9S_MB_2U_LIB.S9S_MB_2U(SCH_1):PAGE38
    U2  AA7 VCCFA_EHV_FIVRA2 SOCKET4677_AZIF0045P001C01CS-SA     I4 @S9S_MB_2U_LIB.S9S_MB_2U(SCH_1):PAGE38
    U2 AD85 VCCFA_EHV_FIVRA3 SOCKET4677_AZIF0045P001C01CS-SA     I4 @S9S_MB_2U_LIB.S9S_MB_2U(SCH_1):PAGE38
    U2 AD89 VCCFA_EHV_FIVRA4 SOCKET4677_AZIF0045P001C01CS-SA     I4 @S9S_MB_2U_LIB.S9S_MB_2U(SCH_1):PAGE38
    U2 AE11 VCCFA_EHV_FIVRA5 SOCKET4677_AZIF0045P001C01CS-SA     I4 @S9S_MB_2U_LIB.S9S_MB_2U(SCH_1):PAGE38
    U2 AE15 VCCFA_EHV_FIVRA6 SOCKET4677_AZIF0045P001C01CS-SA     I4 @S9S_MB_2U_LIB.S9S_MB_2U(SCH_1):PAGE38
    U2  AE7 VCCFA_EHV_FIVRA7 SOCKET4677_AZIF0045P001C01CS-SA     I4 @S9S_MB_2U_LIB.S9S_MB_2U(SCH_1):PAGE38
    U2 AF77 VCCFA_EHV_FIVRA8 SOCKET4677_AZIF0045P001C01CS-SA     I4 @S9S_MB_2U_LIB.S9S_MB_2U(SCH_1):PAGE38
    U2 AG78 VCCFA_EHV_FIVRA9 SOCKET4677_AZIF0045P001C01CS-SA     I4 @S9S_MB_2U_LIB.S9S_MB_2U(SCH_1):PAGE38
    U2 AH85 VCCFA_EHV_FIVRA10 SOCKET4677_AZIF0045P001C01CS-SA     I4 @S9S_MB_2U_LIB.S9S_MB_2U(SCH_1):PAGE38
    U2 AH89 VCCFA_EHV_FIVRA11 SOCKET4677_AZIF0045P001C01CS-SA     I4 @S9S_MB_2U_LIB.S9S_MB_2U(SCH_1):PAGE38
    U2 AJ11 VCCFA_EHV_FIVRA12 SOCKET4677_AZIF0045P001C01CS-SA     I4 @S9S_MB_2U_LIB.S9S_MB_2U(SCH_1):PAGE38
    U2 AJ15 VCCFA_EHV_FIVRA13 SOCKET4677_AZIF0045P001C01CS-SA     I4 @S9S_MB_2U_LIB.S9S_MB_2U(SCH_1):PAGE38
    U2  AJ7 VCCFA_EHV_FIVRA14 SOCKET4677_AZIF0045P001C01CS-SA     I4 @S9S_MB_2U_LIB.S9S_MB_2U(SCH_1):PAGE38
    U2 AM79 VCCFA_EHV_FIVRA15 SOCKET4677_AZIF0045P001C01CS-SA     I4 @S9S_MB_2U_LIB.S9S_MB_2U(SCH_1):PAGE38
    U2 AM85 VCCFA_EHV_FIVRA16 SOCKET4677_AZIF0045P001C01CS-SA     I4 @S9S_MB_2U_LIB.S9S_MB_2U(SCH_1):PAGE38
    U2 AM89 VCCFA_EHV_FIVRA17 SOCKET4677_AZIF0045P001C01CS-SA     I4 @S9S_MB_2U_LIB.S9S_MB_2U(SCH_1):PAGE38
    U2 AN11 VCCFA_EHV_FIVRA18 SOCKET4677_AZIF0045P001C01CS-SA     I4 @S9S_MB_2U_LIB.S9S_MB_2U(SCH_1):PAGE38
    U2 AN15 VCCFA_EHV_FIVRA19 SOCKET4677_AZIF0045P001C01CS-SA     I4 @S9S_MB_2U_LIB.S9S_MB_2U(SCH_1):PAGE38
    U2  AN7 VCCFA_EHV_FIVRA20 SOCKET4677_AZIF0045P001C01CS-SA     I4 @S9S_MB_2U_LIB.S9S_MB_2U(SCH_1):PAGE38
    U2 AN80 VCCFA_EHV_FIVRA21 SOCKET4677_AZIF0045P001C01CS-SA     I4 @S9S_MB_2U_LIB.S9S_MB_2U(SCH_1):PAGE38
    U2 AT73 VCCFA_EHV_FIVRA22 SOCKET4677_AZIF0045P001C01CS-SA     I4 @S9S_MB_2U_LIB.S9S_MB_2U(SCH_1):PAGE38
    U2 AT89 VCCFA_EHV_FIVRA23 SOCKET4677_AZIF0045P001C01CS-SA     I4 @S9S_MB_2U_LIB.S9S_MB_2U(SCH_1):PAGE38
    U2 AU15 VCCFA_EHV_FIVRA24 SOCKET4677_AZIF0045P001C01CS-SA     I4 @S9S_MB_2U_LIB.S9S_MB_2U(SCH_1):PAGE38
    U2 AW76 VCCFA_EHV_FIVRA25 SOCKET4677_AZIF0045P001C01CS-SA     I4 @S9S_MB_2U_LIB.S9S_MB_2U(SCH_1):PAGE38
    U2 AY89 VCCFA_EHV_FIVRA26 SOCKET4677_AZIF0045P001C01CS-SA     I4 @S9S_MB_2U_LIB.S9S_MB_2U(SCH_1):PAGE38
    U2 BE72 VCCFA_EHV_FIVRA27 SOCKET4677_AZIF0045P001C01CS-SA     I4 @S9S_MB_2U_LIB.S9S_MB_2U(SCH_1):PAGE38
    U2 BF77 VCCFA_EHV_FIVRA28 SOCKET4677_AZIF0045P001C01CS-SA     I4 @S9S_MB_2U_LIB.S9S_MB_2U(SCH_1):PAGE38
    U2 BH79 VCCFA_EHV_FIVRA29 SOCKET4677_AZIF0045P001C01CS-SA     I4 @S9S_MB_2U_LIB.S9S_MB_2U(SCH_1):PAGE38
    U2 BJ72 VCCFA_EHV_FIVRA30 SOCKET4677_AZIF0045P001C01CS-SA     I4 @S9S_MB_2U_LIB.S9S_MB_2U(SCH_1):PAGE38
    U2 BJ78 VCCFA_EHV_FIVRA31 SOCKET4677_AZIF0045P001C01CS-SA     I4 @S9S_MB_2U_LIB.S9S_MB_2U(SCH_1):PAGE38
    U2  C84 VCCFA_EHV_FIVRA32 SOCKET4677_AZIF0045P001C01CS-SA     I4 @S9S_MB_2U_LIB.S9S_MB_2U(SCH_1):PAGE38
    U2  C88 VCCFA_EHV_FIVRA33 SOCKET4677_AZIF0045P001C01CS-SA     I4 @S9S_MB_2U_LIB.S9S_MB_2U(SCH_1):PAGE38
    U2 CE74 VCCFA_EHV_FIVRA34 SOCKET4677_AZIF0045P001C01CS-SA     I4 @S9S_MB_2U_LIB.S9S_MB_2U(SCH_1):PAGE38
    U2 CK73 VCCFA_EHV_FIVRA35 SOCKET4677_AZIF0045P001C01CS-SA     I4 @S9S_MB_2U_LIB.S9S_MB_2U(SCH_1):PAGE38
    U2 CK79 VCCFA_EHV_FIVRA36 SOCKET4677_AZIF0045P001C01CS-SA     I4 @S9S_MB_2U_LIB.S9S_MB_2U(SCH_1):PAGE38
    U2 CM73 VCCFA_EHV_FIVRA37 SOCKET4677_AZIF0045P001C01CS-SA     I4 @S9S_MB_2U_LIB.S9S_MB_2U(SCH_1):PAGE38
    U2 CN78 VCCFA_EHV_FIVRA38 SOCKET4677_AZIF0045P001C01CS-SA     I4 @S9S_MB_2U_LIB.S9S_MB_2U(SCH_1):PAGE38
    U2 CP73 VCCFA_EHV_FIVRA39 SOCKET4677_AZIF0045P001C01CS-SA     I4 @S9S_MB_2U_LIB.S9S_MB_2U(SCH_1):PAGE38
    U2 CT77 VCCFA_EHV_FIVRA40 SOCKET4677_AZIF0045P001C01CS-SA     I4 @S9S_MB_2U_LIB.S9S_MB_2U(SCH_1):PAGE38
    U2 CT85 VCCFA_EHV_FIVRA41 SOCKET4677_AZIF0045P001C01CS-SA     I4 @S9S_MB_2U_LIB.S9S_MB_2U(SCH_1):PAGE38
    U2 CY75 VCCFA_EHV_FIVRA42 SOCKET4677_AZIF0045P001C01CS-SA     I4 @S9S_MB_2U_LIB.S9S_MB_2U(SCH_1):PAGE38
    U2 CY79 VCCFA_EHV_FIVRA43 SOCKET4677_AZIF0045P001C01CS-SA     I4 @S9S_MB_2U_LIB.S9S_MB_2U(SCH_1):PAGE38
    U2 CY85 VCCFA_EHV_FIVRA44 SOCKET4677_AZIF0045P001C01CS-SA     I4 @S9S_MB_2U_LIB.S9S_MB_2U(SCH_1):PAGE38
    U2 CY89 VCCFA_EHV_FIVRA45 SOCKET4677_AZIF0045P001C01CS-SA     I4 @S9S_MB_2U_LIB.S9S_MB_2U(SCH_1):PAGE38
    U2 DD77 VCCFA_EHV_FIVRA46 SOCKET4677_AZIF0045P001C01CS-SA     I4 @S9S_MB_2U_LIB.S9S_MB_2U(SCH_1):PAGE38
    U2 DD83 VCCFA_EHV_FIVRA47 SOCKET4677_AZIF0045P001C01CS-SA     I4 @S9S_MB_2U_LIB.S9S_MB_2U(SCH_1):PAGE38
    U2 DD85 VCCFA_EHV_FIVRA48 SOCKET4677_AZIF0045P001C01CS-SA     I4 @S9S_MB_2U_LIB.S9S_MB_2U(SCH_1):PAGE38
    U2 DD89 VCCFA_EHV_FIVRA49 SOCKET4677_AZIF0045P001C01CS-SA     I4 @S9S_MB_2U_LIB.S9S_MB_2U(SCH_1):PAGE38
    U2 DH89 VCCFA_EHV_FIVRA50 SOCKET4677_AZIF0045P001C01CS-SA     I4 @S9S_MB_2U_LIB.S9S_MB_2U(SCH_1):PAGE38
    U2 DM83 VCCFA_EHV_FIVRA51 SOCKET4677_AZIF0045P001C01CS-SA     I4 @S9S_MB_2U_LIB.S9S_MB_2U(SCH_1):PAGE38
    U2 DM85 VCCFA_EHV_FIVRA52 SOCKET4677_AZIF0045P001C01CS-SA     I4 @S9S_MB_2U_LIB.S9S_MB_2U(SCH_1):PAGE38
    U2 DM89 VCCFA_EHV_FIVRA53 SOCKET4677_AZIF0045P001C01CS-SA     I4 @S9S_MB_2U_LIB.S9S_MB_2U(SCH_1):PAGE38
    U2 DN11 VCCFA_EHV_FIVRA54 SOCKET4677_AZIF0045P001C01CS-SA     I4 @S9S_MB_2U_LIB.S9S_MB_2U(SCH_1):PAGE38
    U2 DN15 VCCFA_EHV_FIVRA55 SOCKET4677_AZIF0045P001C01CS-SA     I4 @S9S_MB_2U_LIB.S9S_MB_2U(SCH_1):PAGE38
    U2  DN3 VCCFA_EHV_FIVRA56 SOCKET4677_AZIF0045P001C01CS-SA     I4 @S9S_MB_2U_LIB.S9S_MB_2U(SCH_1):PAGE38
    U2  DN7 VCCFA_EHV_FIVRA57 SOCKET4677_AZIF0045P001C01CS-SA     I4 @S9S_MB_2U_LIB.S9S_MB_2U(SCH_1):PAGE38
    U2 DT79 VCCFA_EHV_FIVRA58 SOCKET4677_AZIF0045P001C01CS-SA     I4 @S9S_MB_2U_LIB.S9S_MB_2U(SCH_1):PAGE38
    U2 DT85 VCCFA_EHV_FIVRA59 SOCKET4677_AZIF0045P001C01CS-SA     I4 @S9S_MB_2U_LIB.S9S_MB_2U(SCH_1):PAGE38
    U2 DT89 VCCFA_EHV_FIVRA60 SOCKET4677_AZIF0045P001C01CS-SA     I4 @S9S_MB_2U_LIB.S9S_MB_2U(SCH_1):PAGE38
    U2 DU11 VCCFA_EHV_FIVRA61 SOCKET4677_AZIF0045P001C01CS-SA     I4 @S9S_MB_2U_LIB.S9S_MB_2U(SCH_1):PAGE38
    U2 DU15 VCCFA_EHV_FIVRA62 SOCKET4677_AZIF0045P001C01CS-SA     I4 @S9S_MB_2U_LIB.S9S_MB_2U(SCH_1):PAGE38
    U2  DU3 VCCFA_EHV_FIVRA63 SOCKET4677_AZIF0045P001C01CS-SA     I4 @S9S_MB_2U_LIB.S9S_MB_2U(SCH_1):PAGE38
    U2  DU7 VCCFA_EHV_FIVRA64 SOCKET4677_AZIF0045P001C01CS-SA     I4 @S9S_MB_2U_LIB.S9S_MB_2U(SCH_1):PAGE38
    U2 DY85 VCCFA_EHV_FIVRA65 SOCKET4677_AZIF0045P001C01CS-SA     I4 @S9S_MB_2U_LIB.S9S_MB_2U(SCH_1):PAGE38
    U2 DY89 VCCFA_EHV_FIVRA66 SOCKET4677_AZIF0045P001C01CS-SA     I4 @S9S_MB_2U_LIB.S9S_MB_2U(SCH_1):PAGE38
    U2 EA11 VCCFA_EHV_FIVRA67 SOCKET4677_AZIF0045P001C01CS-SA     I4 @S9S_MB_2U_LIB.S9S_MB_2U(SCH_1):PAGE38
    U2 EA15 VCCFA_EHV_FIVRA68 SOCKET4677_AZIF0045P001C01CS-SA     I4 @S9S_MB_2U_LIB.S9S_MB_2U(SCH_1):PAGE38
    U2  EA3 VCCFA_EHV_FIVRA69 SOCKET4677_AZIF0045P001C01CS-SA     I4 @S9S_MB_2U_LIB.S9S_MB_2U(SCH_1):PAGE38
    U2  EA7 VCCFA_EHV_FIVRA70 SOCKET4677_AZIF0045P001C01CS-SA     I4 @S9S_MB_2U_LIB.S9S_MB_2U(SCH_1):PAGE38
    U2 EC78 VCCFA_EHV_FIVRA71 SOCKET4677_AZIF0045P001C01CS-SA     I4 @S9S_MB_2U_LIB.S9S_MB_2U(SCH_1):PAGE38
    U2 ED79 VCCFA_EHV_FIVRA72 SOCKET4677_AZIF0045P001C01CS-SA     I4 @S9S_MB_2U_LIB.S9S_MB_2U(SCH_1):PAGE38
    U2 ED85 VCCFA_EHV_FIVRA73 SOCKET4677_AZIF0045P001C01CS-SA     I4 @S9S_MB_2U_LIB.S9S_MB_2U(SCH_1):PAGE38
    U2 ED89 VCCFA_EHV_FIVRA74 SOCKET4677_AZIF0045P001C01CS-SA     I4 @S9S_MB_2U_LIB.S9S_MB_2U(SCH_1):PAGE38
    U2 EE11 VCCFA_EHV_FIVRA75 SOCKET4677_AZIF0045P001C01CS-SA     I4 @S9S_MB_2U_LIB.S9S_MB_2U(SCH_1):PAGE38
    U2 EE15 VCCFA_EHV_FIVRA76 SOCKET4677_AZIF0045P001C01CS-SA     I4 @S9S_MB_2U_LIB.S9S_MB_2U(SCH_1):PAGE38
    U2  EE7 VCCFA_EHV_FIVRA77 SOCKET4677_AZIF0045P001C01CS-SA     I4 @S9S_MB_2U_LIB.S9S_MB_2U(SCH_1):PAGE38
    U2 EE84 VCCFA_EHV_FIVRA78 SOCKET4677_AZIF0045P001C01CS-SA     I4 @S9S_MB_2U_LIB.S9S_MB_2U(SCH_1):PAGE38
    U2 EF79 VCCFA_EHV_FIVRA79 SOCKET4677_AZIF0045P001C01CS-SA     I4 @S9S_MB_2U_LIB.S9S_MB_2U(SCH_1):PAGE38
    U2 EG80 VCCFA_EHV_FIVRA80 SOCKET4677_AZIF0045P001C01CS-SA     I4 @S9S_MB_2U_LIB.S9S_MB_2U(SCH_1):PAGE38
    U2 EJ15 VCCFA_EHV_FIVRA81 SOCKET4677_AZIF0045P001C01CS-SA     I4 @S9S_MB_2U_LIB.S9S_MB_2U(SCH_1):PAGE38
    U2 EJ84 VCCFA_EHV_FIVRA82 SOCKET4677_AZIF0045P001C01CS-SA     I4 @S9S_MB_2U_LIB.S9S_MB_2U(SCH_1):PAGE38
    U2 EN84 VCCFA_EHV_FIVRA83 SOCKET4677_AZIF0045P001C01CS-SA     I4 @S9S_MB_2U_LIB.S9S_MB_2U(SCH_1):PAGE38
    U2  H89 VCCFA_EHV_FIVRA84 SOCKET4677_AZIF0045P001C01CS-SA     I4 @S9S_MB_2U_LIB.S9S_MB_2U(SCH_1):PAGE38
    U2  J11 VCCFA_EHV_FIVRA85 SOCKET4677_AZIF0045P001C01CS-SA     I4 @S9S_MB_2U_LIB.S9S_MB_2U(SCH_1):PAGE38
    U2   J7 VCCFA_EHV_FIVRA86 SOCKET4677_AZIF0045P001C01CS-SA     I4 @S9S_MB_2U_LIB.S9S_MB_2U(SCH_1):PAGE38
    U2  J80 VCCFA_EHV_FIVRA87 SOCKET4677_AZIF0045P001C01CS-SA     I4 @S9S_MB_2U_LIB.S9S_MB_2U(SCH_1):PAGE38
    U2  K87 VCCFA_EHV_FIVRA88 SOCKET4677_AZIF0045P001C01CS-SA     I4 @S9S_MB_2U_LIB.S9S_MB_2U(SCH_1):PAGE38
    U2  L84 VCCFA_EHV_FIVRA89 SOCKET4677_AZIF0045P001C01CS-SA     I4 @S9S_MB_2U_LIB.S9S_MB_2U(SCH_1):PAGE38
    U2  M85 VCCFA_EHV_FIVRA90 SOCKET4677_AZIF0045P001C01CS-SA     I4 @S9S_MB_2U_LIB.S9S_MB_2U(SCH_1):PAGE38
    U2  M89 VCCFA_EHV_FIVRA91 SOCKET4677_AZIF0045P001C01CS-SA     I4 @S9S_MB_2U_LIB.S9S_MB_2U(SCH_1):PAGE38
    U2  N11 VCCFA_EHV_FIVRA92 SOCKET4677_AZIF0045P001C01CS-SA     I4 @S9S_MB_2U_LIB.S9S_MB_2U(SCH_1):PAGE38
    U2   N7 VCCFA_EHV_FIVRA93 SOCKET4677_AZIF0045P001C01CS-SA     I4 @S9S_MB_2U_LIB.S9S_MB_2U(SCH_1):PAGE38
    U2  P79 VCCFA_EHV_FIVRA94 SOCKET4677_AZIF0045P001C01CS-SA     I4 @S9S_MB_2U_LIB.S9S_MB_2U(SCH_1):PAGE38
    U2  R80 VCCFA_EHV_FIVRA95 SOCKET4677_AZIF0045P001C01CS-SA     I4 @S9S_MB_2U_LIB.S9S_MB_2U(SCH_1):PAGE38
    U2  T85 VCCFA_EHV_FIVRA96 SOCKET4677_AZIF0045P001C01CS-SA     I4 @S9S_MB_2U_LIB.S9S_MB_2U(SCH_1):PAGE38
    U2  T89 VCCFA_EHV_FIVRA97 SOCKET4677_AZIF0045P001C01CS-SA     I4 @S9S_MB_2U_LIB.S9S_MB_2U(SCH_1):PAGE38
    U2  U11 VCCFA_EHV_FIVRA98 SOCKET4677_AZIF0045P001C01CS-SA     I4 @S9S_MB_2U_LIB.S9S_MB_2U(SCH_1):PAGE38
    U2  U15 VCCFA_EHV_FIVRA99 SOCKET4677_AZIF0045P001C01CS-SA     I4 @S9S_MB_2U_LIB.S9S_MB_2U(SCH_1):PAGE38
    U2   U7 VCCFA_EHV_FIVRA100 SOCKET4677_AZIF0045P001C01CS-SA     I4 @S9S_MB_2U_LIB.S9S_MB_2U(SCH_1):PAGE38
    U2  W80 VCCFA_EHV_FIVRA101 SOCKET4677_AZIF0045P001C01CS-SA     I4 @S9S_MB_2U_LIB.S9S_MB_2U(SCH_1):PAGE38
    U2  Y79 VCCFA_EHV_FIVRA102 SOCKET4677_AZIF0045P001C01CS-SA     I4 @S9S_MB_2U_LIB.S9S_MB_2U(SCH_1):PAGE38
    U2  Y85 VCCFA_EHV_FIVRA103 SOCKET4677_AZIF0045P001C01CS-SA     I4 @S9S_MB_2U_LIB.S9S_MB_2U(SCH_1):PAGE38
    U2  Y89 VCCFA_EHV_FIVRA104 SOCKET4677_AZIF0045P001C01CS-SA     I4 @S9S_MB_2U_LIB.S9S_MB_2U(SCH_1):PAGE38
  C407    1      A Q_CAP_C0402-22UF,4V,20%,X6S,CHA     I7 @S9S_MB_2U_LIB.S9S_MB_2U(SCH_1):PAGE74
  C409    1      A Q_CAP_C0402-22UF,4V,20%,X6S,CHA     I8 @S9S_MB_2U_LIB.S9S_MB_2U(SCH_1):PAGE74
  C411    1      A Q_CAP_C0402-22UF,4V,20%,X6S,CHA     I9 @S9S_MB_2U_LIB.S9S_MB_2U(SCH_1):PAGE74
  C413    1      A Q_CAP_C0402-22UF,4V,20%,X6S,CHA    I10 @S9S_MB_2U_LIB.S9S_MB_2U(SCH_1):PAGE74
  C415    1      A Q_CAP_C0402-22UF,4V,20%,X6S,CHA    I64 @S9S_MB_2U_LIB.S9S_MB_2U(SCH_1):PAGE74
  C417    1      A Q_CAP_C0402-22UF,4V,20%,X6S,CHA    I65 @S9S_MB_2U_LIB.S9S_MB_2U(SCH_1):PAGE74
  C418    1      A Q_CAP_C0402-22UF,4V,20%,X6S,CHA    I68 @S9S_MB_2U_LIB.S9S_MB_2U(SCH_1):PAGE74
  C493    1      A Q_CAP_C0805-47UF,4V,20%,X6S,CHA     I1 @S9S_MB_2U_LIB.S9S_MB_2U(SCH_1):PAGE75
  C497    1      A Q_CAP_C0805-47UF,4V,20%,X6S,CHA     I3 @S9S_MB_2U_LIB.S9S_MB_2U(SCH_1):PAGE75
  C501    1      A Q_CAP_C0805-47UF,4V,20%,X6S,CHA     I4 @S9S_MB_2U_LIB.S9S_MB_2U(SCH_1):PAGE75
  C494    1      A Q_CAP_C0805-47UF,4V,20%,X6S,CHA     I1 @S9S_MB_2U_LIB.S9S_MB_2U(SCH_1):PAGE76
  C510    1      A Q_CAP_C0805-47UF,4V,20%,X6S,CHA    I27 @S9S_MB_2U_LIB.S9S_MB_2U(SCH_1):PAGE76
  C514    1      A Q_CAP_C0805-47UF,4V,20%,X6S,CHA    I28 @S9S_MB_2U_LIB.S9S_MB_2U(SCH_1):PAGE76
  C517    1      A Q_CAP_C0805-47UF,4V,20%,X6S,CHA    I29 @S9S_MB_2U_LIB.S9S_MB_2U(SCH_1):PAGE76
  C529    1      A Q_CAP_C0805-47UF,4V,20%,X6S,CHA    I41 @S9S_MB_2U_LIB.S9S_MB_2U(SCH_1):PAGE76
  PL34    2      2 Q_INDUCTOR_SMLF-130NH/106A,INDA    I49 @S9S_MB_2U_LIB.S9S_MB_2U(SCH_1):PAGE257
PR1323    2      B Q_RES_0402LF-0,5%,1/16W,CHIP,CA    I50 @S9S_MB_2U_LIB.S9S_MB_2U(SCH_1):PAGE257
PC618_P0_2    1      A Q_CAP_C0805-22UF,4V,20%,X6S,CHA    I59 @S9S_MB_2U_LIB.S9S_MB_2U(SCH_1):PAGE257
 PC621    1      A Q_CAPP_THLF-560UF,2.5V,20%,OSCA    I62 @S9S_MB_2U_LIB.S9S_MB_2U(SCH_1):PAGE257
 PL210    2      2 Q_INDUCTOR_SMLF-130NH/106A,INDA    I39 @S9S_MB_2U_LIB.S9S_MB_2U(SCH_1):PAGE258
PC1183_P0_4    1      A Q_CAP_C0402-100NF,50V,10%,X7R,A    I40 @S9S_MB_2U_LIB.S9S_MB_2U(SCH_1):PAGE258
PC1183_P0_3    1      A Q_CAP_C0402-1UF,16V,10%,X6S,CHA    I55 @S9S_MB_2U_LIB.S9S_MB_2U(SCH_1):PAGE258
PC1188_P0_4    1      A Q_CAP_C0805-22UF,4V,20%,X6S,CHA    I61 @S9S_MB_2U_LIB.S9S_MB_2U(SCH_1):PAGE258
PC1186    1      A Q_CAPP_THLF-560UF,2.5V,20%,OSCA    I68 @S9S_MB_2U_LIB.S9S_MB_2U(SCH_1):PAGE258
   PL2    2      2 Q_INDUCTOR_SMLF-130NH/106A,INDA    I51 @S9S_MB_2U_LIB.S9S_MB_2U(SCH_1):PAGE258
  C400    1      A Q_CAP_C0402-22UF,4V,20%,X6S,CHA     I1 @S9S_MB_2U_LIB.S9S_MB_2U(SCH_1):PAGE74
  C402    1      A Q_CAP_C0402-22UF,4V,20%,X6S,CHA     I3 @S9S_MB_2U_LIB.S9S_MB_2U(SCH_1):PAGE74
  C404    1      A Q_CAP_C0402-22UF,4V,20%,X6S,CHA     I4 @S9S_MB_2U_LIB.S9S_MB_2U(SCH_1):PAGE74
  C406    1      A Q_CAP_C0402-22UF,4V,20%,X6S,CHA     I5 @S9S_MB_2U_LIB.S9S_MB_2U(SCH_1):PAGE74
  C505    1      A Q_CAP_C0805-47UF,4V,20%,X6S,CHA     I6 @S9S_MB_2U_LIB.S9S_MB_2U(SCH_1):PAGE75
  C509    1      A Q_CAP_C0603-47UF,2.5V,20%,X6S,A     I8 @S9S_MB_2U_LIB.S9S_MB_2U(SCH_1):PAGE75
  C498    1      A Q_CAP_C0805-47UF,4V,20%,X6S,CHA     I2 @S9S_MB_2U_LIB.S9S_MB_2U(SCH_1):PAGE76
  C502    1      A Q_CAP_C0805-47UF,4V,20%,X6S,CHA     I3 @S9S_MB_2U_LIB.S9S_MB_2U(SCH_1):PAGE76
  C506    1      A Q_CAP_C0805-47UF,4V,20%,X6S,CHA    I26 @S9S_MB_2U_LIB.S9S_MB_2U(SCH_1):PAGE76
  C520    1      A Q_CAP_C0805-47UF,4V,20%,X6S,CHA    I36 @S9S_MB_2U_LIB.S9S_MB_2U(SCH_1):PAGE76
  C521    1      A Q_CAP_C0805-47UF,4V,20%,X6S,CHA    I37 @S9S_MB_2U_LIB.S9S_MB_2U(SCH_1):PAGE76
  C523    1      A Q_CAP_C0805-47UF,4V,20%,X6S,CHA    I38 @S9S_MB_2U_LIB.S9S_MB_2U(SCH_1):PAGE76
  C526    1      A Q_CAP_C0805-47UF,4V,20%,X6S,CHA    I39 @S9S_MB_2U_LIB.S9S_MB_2U(SCH_1):PAGE76
PC613_P0_2    1      A Q_CAP_C0402-1UF,16V,10%,X6S,CHA    I51 @S9S_MB_2U_LIB.S9S_MB_2U(SCH_1):PAGE257
PR1325    2      B Q_RES_0402LF-0,5%,1/16W,CHIP,CA    I38 @S9S_MB_2U_LIB.S9S_MB_2U(SCH_1):PAGE258
PC1185_P0_3    1      A Q_CAP_C0805-22UF,4V,20%,X6S,CHA    I72 @S9S_MB_2U_LIB.S9S_MB_2U(SCH_1):PAGE258
PR1322    2      B Q_RES_0402LF-0,5%,1/16W,CHIP,CA    I69 @S9S_MB_2U_LIB.S9S_MB_2U(SCH_1):PAGE257
PC615_P0_1    1      A Q_CAP_C0805-22UF,4V,20%,X6S,CHA    I77 @S9S_MB_2U_LIB.S9S_MB_2U(SCH_1):PAGE257
PR1324    2      B Q_RES_0402LF-0,5%,1/16W,CHIP,CA    I50 @S9S_MB_2U_LIB.S9S_MB_2U(SCH_1):PAGE258
PC1186_P0_4    1      A Q_CAP_C0805-22UF,4V,20%,X6S,CHA    I60 @S9S_MB_2U_LIB.S9S_MB_2U(SCH_1):PAGE258
PC616_P0_2    1      A Q_CAP_C0805-22UF,4V,20%,X6S,CHA    I52 @S9S_MB_2U_LIB.S9S_MB_2U(SCH_1):PAGE257
 PC619    1      A Q_CAPP_THLF-560UF,2.5V,20%,OSCA    I57 @S9S_MB_2U_LIB.S9S_MB_2U(SCH_1):PAGE257
 PC620    1      A Q_CAPP_THLF-560UF,2.5V,20%,OSCA    I58 @S9S_MB_2U_LIB.S9S_MB_2U(SCH_1):PAGE257
  PL33    2      2 Q_INDUCTOR_SMLF-130NH/106A,INDA    I70 @S9S_MB_2U_LIB.S9S_MB_2U(SCH_1):PAGE257
PR4265    1      A Q_RES_0402LF-499,1%,1/16W,CHIPA    I60 @S9S_MB_2U_LIB.S9S_MB_2U(SCH_1):PAGE257
 PC623    1      A Q_CAPP_SMLF-330UF,2.5V,+10/-35B    I63 @S9S_MB_2U_LIB.S9S_MB_2U(SCH_1):PAGE257
PC2645    1      A Q_CAPP_SMLF-330UF,2.5V,+10/-35B    I67 @S9S_MB_2U_LIB.S9S_MB_2U(SCH_1):PAGE257
PC612_P0_1    1      A Q_CAP_C0402-100NF,50V,10%,X7R,A    I75 @S9S_MB_2U_LIB.S9S_MB_2U(SCH_1):PAGE257
PC617_P0_1    1      A Q_CAP_C0805-22UF,4V,20%,X6S,CHA    I81 @S9S_MB_2U_LIB.S9S_MB_2U(SCH_1):PAGE257
PC1183    1      A Q_CAPP_THLF-560UF,2.5V,20%,OSCA    I64 @S9S_MB_2U_LIB.S9S_MB_2U(SCH_1):PAGE258
PC1185    1      A Q_CAPP_THLF-560UF,2.5V,20%,OSCA    I65 @S9S_MB_2U_LIB.S9S_MB_2U(SCH_1):PAGE258
PC1187    1      A Q_CAPP_SMLF-330UF,2.5V,+10/-35B    I69 @S9S_MB_2U_LIB.S9S_MB_2U(SCH_1):PAGE258
PC2170    1      A Q_CAPP_SMLF-330UF,2.5V,+10/-35B    I70 @S9S_MB_2U_LIB.S9S_MB_2U(SCH_1):PAGE258
PC1187_P0_3    1      A Q_CAP_C0805-22UF,4V,20%,X6S,CHA    I73 @S9S_MB_2U_LIB.S9S_MB_2U(SCH_1):PAGE258
 PR587    2      B Q_RES_0402LF-100,1%,1/16W,CHIPA    I25 @S9S_MB_2U_LIB.S9S_MB_2U(SCH_1):PAGE252

PVCCFA_EHV_FIVRA_CPU0_BTSEN @S9S_MB_2U_LIB.S9S_MB_2U(SCH_1):PVCCFA_EHV_FIVRA_CPU0_BTSEN
  PU14   44 TEMP1||ISYS RAA229126GNPHA0-RAA229126GNP#HA    I63 @S9S_MB_2U_LIB.S9S_MB_2U(SCH_1):PAGE252
PU70_P0_2   36 TOUT_FLT ISL99390FRZTR5935-ISL99390FRZ-A    I16 @S9S_MB_2U_LIB.S9S_MB_2U(SCH_1):PAGE257
PU71_P0_3   36 TOUT_FLT ISL99390FRZTR5935-ISL99390FRZ-A    I82 @S9S_MB_2U_LIB.S9S_MB_2U(SCH_1):PAGE258
PU69_P0_1   36 TOUT_FLT ISL99390FRZTR5935-ISL99390FRZ-A    I25 @S9S_MB_2U_LIB.S9S_MB_2U(SCH_1):PAGE257
PU72_P0_4   36 TOUT_FLT ISL99390FRZTR5935-ISL99390FRZ-A    I10 @S9S_MB_2U_LIB.S9S_MB_2U(SCH_1):PAGE258
 PC100    1      A Q_CAP_0402-470PF,50V,10%,X7R,TA   I116 @S9S_MB_2U_LIB.S9S_MB_2U(SCH_1):PAGE252
 PR451    1      A Q_RES_0402LF-10K,1%,1/16W,EMPTA   I121 @S9S_MB_2U_LIB.S9S_MB_2U(SCH_1):PAGE252

PVCCFA_EHV_FIVRA_CPU0_EN_R @S9S_MB_2U_LIB.S9S_MB_2U(SCH_1):PVCCFA_EHV_FIVRA_CPU0_EN_R
  PU14   24    EN1 RAA229126GNPHA0-RAA229126GNP#HA    I63 @S9S_MB_2U_LIB.S9S_MB_2U(SCH_1):PAGE252
 C3268    1      A Q_CAP_0402-1000PF,50V,5%,X7R,TA    I58 @S9S_MB_2U_LIB.S9S_MB_2U(SCH_1):PAGE252
 R4216    2      B Q_RES_0402LF-0,5%,1/16W,CHIP,CA    I56 @S9S_MB_2U_LIB.S9S_MB_2U(SCH_1):PAGE252

PVCCFA_EHV_FIVRA_CPU0_IMON1 @S9S_MB_2U_LIB.S9S_MB_2U(SCH_1):PVCCFA_EHV_FIVRA_CPU0_IMON1
  PU14   38    CS0 RAA229126GNPHA0-RAA229126GNP#HA    I63 @S9S_MB_2U_LIB.S9S_MB_2U(SCH_1):PAGE252
PU69_P0_1   38   IOUT ISL99390FRZTR5935-ISL99390FRZ-A    I25 @S9S_MB_2U_LIB.S9S_MB_2U(SCH_1):PAGE257

PVCCFA_EHV_FIVRA_CPU0_IMON2 @S9S_MB_2U_LIB.S9S_MB_2U(SCH_1):PVCCFA_EHV_FIVRA_CPU0_IMON2
  PU14   37    CS1 RAA229126GNPHA0-RAA229126GNP#HA    I63 @S9S_MB_2U_LIB.S9S_MB_2U(SCH_1):PAGE252
PU70_P0_2   38   IOUT ISL99390FRZTR5935-ISL99390FRZ-A    I16 @S9S_MB_2U_LIB.S9S_MB_2U(SCH_1):PAGE257

PVCCFA_EHV_FIVRA_CPU0_IMON3 @S9S_MB_2U_LIB.S9S_MB_2U(SCH_1):PVCCFA_EHV_FIVRA_CPU0_IMON3
  PU14   36    CS2 RAA229126GNPHA0-RAA229126GNP#HA    I63 @S9S_MB_2U_LIB.S9S_MB_2U(SCH_1):PAGE252
PU71_P0_3   38   IOUT ISL99390FRZTR5935-ISL99390FRZ-A    I82 @S9S_MB_2U_LIB.S9S_MB_2U(SCH_1):PAGE258
PR4218    1      A Q_RES_0402LF-0,5%,1/16W,EMPTY,A    I73 @S9S_MB_2U_LIB.S9S_MB_2U(SCH_1):PAGE252

PVCCFA_EHV_FIVRA_CPU0_IMON4 @S9S_MB_2U_LIB.S9S_MB_2U(SCH_1):PVCCFA_EHV_FIVRA_CPU0_IMON4
PR4217    1      A Q_RES_0402LF-0,5%,1/16W,EMPTY,A    I74 @S9S_MB_2U_LIB.S9S_MB_2U(SCH_1):PAGE252
  PU14   35    CS3 RAA229126GNPHA0-RAA229126GNP#HA    I63 @S9S_MB_2U_LIB.S9S_MB_2U(SCH_1):PAGE252
PU72_P0_4   38   IOUT ISL99390FRZTR5935-ISL99390FRZ-A    I10 @S9S_MB_2U_LIB.S9S_MB_2U(SCH_1):PAGE258

PVCCFA_EHV_FIVRA_CPU0_LSET1 @S9S_MB_2U_LIB.S9S_MB_2U(SCH_1):PVCCFA_EHV_FIVRA_CPU0_LSET1
 PR354    1      A Q_RES_0402LF-8.87K,1%,1/16W,EMA     I8 @S9S_MB_2U_LIB.S9S_MB_2U(SCH_1):PAGE257
PU69_P0_1   37   LSET ISL99390FRZTR5935-ISL99390FRZ-A    I25 @S9S_MB_2U_LIB.S9S_MB_2U(SCH_1):PAGE257

PVCCFA_EHV_FIVRA_CPU0_LSET2 @S9S_MB_2U_LIB.S9S_MB_2U(SCH_1):PVCCFA_EHV_FIVRA_CPU0_LSET2
 PR353    1      A Q_RES_0402LF-8.87K,1%,1/16W,EMA     I2 @S9S_MB_2U_LIB.S9S_MB_2U(SCH_1):PAGE257
PU70_P0_2   37   LSET ISL99390FRZTR5935-ISL99390FRZ-A    I16 @S9S_MB_2U_LIB.S9S_MB_2U(SCH_1):PAGE257

PVCCFA_EHV_FIVRA_CPU0_LSET3 @S9S_MB_2U_LIB.S9S_MB_2U(SCH_1):PVCCFA_EHV_FIVRA_CPU0_LSET3
PR1298    1      A Q_RES_0402LF-8.87K,1%,1/16W,EMA    I15 @S9S_MB_2U_LIB.S9S_MB_2U(SCH_1):PAGE258
PU71_P0_3   37   LSET ISL99390FRZTR5935-ISL99390FRZ-A    I82 @S9S_MB_2U_LIB.S9S_MB_2U(SCH_1):PAGE258

PVCCFA_EHV_FIVRA_CPU0_LSET4 @S9S_MB_2U_LIB.S9S_MB_2U(SCH_1):PVCCFA_EHV_FIVRA_CPU0_LSET4
PR1297    1      A Q_RES_0402LF-8.87K,1%,1/16W,EMA     I3 @S9S_MB_2U_LIB.S9S_MB_2U(SCH_1):PAGE258
PU72_P0_4   37   LSET ISL99390FRZTR5935-ISL99390FRZ-A    I10 @S9S_MB_2U_LIB.S9S_MB_2U(SCH_1):PAGE258

PVCCFA_EHV_FIVRA_CPU0_PVCC1 @S9S_MB_2U_LIB.S9S_MB_2U(SCH_1):PVCCFA_EHV_FIVRA_CPU0_PVCC1
 PR355    1      A Q_RES_0402LF-2.2,1%,1/16W,CHIPA    I39 @S9S_MB_2U_LIB.S9S_MB_2U(SCH_1):PAGE257
PU71_P0_3    4   PVCC ISL99390FRZTR5935-ISL99390FRZ-A    I82 @S9S_MB_2U_LIB.S9S_MB_2U(SCH_1):PAGE258
 PR444    2      B Q_RES_0402LF-0,5%,1/16W,CHIP,CA     I9 @S9S_MB_2U_LIB.S9S_MB_2U(SCH_1):PAGE257
PU69_P0_1    4   PVCC ISL99390FRZTR5935-ISL99390FRZ-A    I25 @S9S_MB_2U_LIB.S9S_MB_2U(SCH_1):PAGE257
 PR632    2      B Q_RES_0402LF-0,5%,1/16W,EMPTY,A    I40 @S9S_MB_2U_LIB.S9S_MB_2U(SCH_1):PAGE257
PC1211_P0_1    1      A Q_CAP_C0402-2.2UF,10V,10%,X6S,A    I42 @S9S_MB_2U_LIB.S9S_MB_2U(SCH_1):PAGE257
PR1299    1      A Q_RES_0402LF-2.2,1%,1/16W,CHIPA    I26 @S9S_MB_2U_LIB.S9S_MB_2U(SCH_1):PAGE258
PC1213_P0_3    1      A Q_CAP_C0402-2.2UF,10V,10%,X6S,A    I28 @S9S_MB_2U_LIB.S9S_MB_2U(SCH_1):PAGE258

PVCCFA_EHV_FIVRA_CPU0_PVCC2 @S9S_MB_2U_LIB.S9S_MB_2U(SCH_1):PVCCFA_EHV_FIVRA_CPU0_PVCC2
 PR633    2      B Q_RES_0402LF-0,5%,1/16W,EMPTY,A    I22 @S9S_MB_2U_LIB.S9S_MB_2U(SCH_1):PAGE257
PR1300    1      A Q_RES_0402LF-2.2,1%,1/16W,CHIPA    I11 @S9S_MB_2U_LIB.S9S_MB_2U(SCH_1):PAGE258
PU70_P0_2    4   PVCC ISL99390FRZTR5935-ISL99390FRZ-A    I16 @S9S_MB_2U_LIB.S9S_MB_2U(SCH_1):PAGE257
 PR447    2      B Q_RES_0402LF-0,5%,1/16W,CHIP,CA     I4 @S9S_MB_2U_LIB.S9S_MB_2U(SCH_1):PAGE257
 PR356    1      A Q_RES_0402LF-2.2,1%,1/16W,CHIPA    I19 @S9S_MB_2U_LIB.S9S_MB_2U(SCH_1):PAGE257
PC1212_P0_2    1      A Q_CAP_C0402-2.2UF,10V,10%,X6S,A    I21 @S9S_MB_2U_LIB.S9S_MB_2U(SCH_1):PAGE257
PU72_P0_4    4   PVCC ISL99390FRZTR5935-ISL99390FRZ-A    I10 @S9S_MB_2U_LIB.S9S_MB_2U(SCH_1):PAGE258
PC1214_P0_4    1      A Q_CAP_C0402-2.2UF,10V,10%,X6S,A    I18 @S9S_MB_2U_LIB.S9S_MB_2U(SCH_1):PAGE258

PVCCFA_EHV_FIVRA_CPU0_PWM1 @S9S_MB_2U_LIB.S9S_MB_2U(SCH_1):PVCCFA_EHV_FIVRA_CPU0_PWM1
  PU14    1   PWM0 RAA229126GNPHA0-RAA229126GNP#HA    I63 @S9S_MB_2U_LIB.S9S_MB_2U(SCH_1):PAGE252
PU69_P0_1   34    PWM ISL99390FRZTR5935-ISL99390FRZ-A    I25 @S9S_MB_2U_LIB.S9S_MB_2U(SCH_1):PAGE257

PVCCFA_EHV_FIVRA_CPU0_PWM2 @S9S_MB_2U_LIB.S9S_MB_2U(SCH_1):PVCCFA_EHV_FIVRA_CPU0_PWM2
  PU14    2   PWM1 RAA229126GNPHA0-RAA229126GNP#HA    I63 @S9S_MB_2U_LIB.S9S_MB_2U(SCH_1):PAGE252
PU70_P0_2   34    PWM ISL99390FRZTR5935-ISL99390FRZ-A    I16 @S9S_MB_2U_LIB.S9S_MB_2U(SCH_1):PAGE257

PVCCFA_EHV_FIVRA_CPU0_PWM3 @S9S_MB_2U_LIB.S9S_MB_2U(SCH_1):PVCCFA_EHV_FIVRA_CPU0_PWM3
  PU14    3   PWM2 RAA229126GNPHA0-RAA229126GNP#HA    I63 @S9S_MB_2U_LIB.S9S_MB_2U(SCH_1):PAGE252
PU71_P0_3   34    PWM ISL99390FRZTR5935-ISL99390FRZ-A    I82 @S9S_MB_2U_LIB.S9S_MB_2U(SCH_1):PAGE258

PVCCFA_EHV_FIVRA_CPU0_PWM4 @S9S_MB_2U_LIB.S9S_MB_2U(SCH_1):PVCCFA_EHV_FIVRA_CPU0_PWM4
  PU14    4   PWM3 RAA229126GNPHA0-RAA229126GNP#HA    I63 @S9S_MB_2U_LIB.S9S_MB_2U(SCH_1):PAGE252
PU72_P0_4   34    PWM ISL99390FRZTR5935-ISL99390FRZ-A    I10 @S9S_MB_2U_LIB.S9S_MB_2U(SCH_1):PAGE258

PVCCFA_EHV_FIVRA_CPU0_VDD1 @S9S_MB_2U_LIB.S9S_MB_2U(SCH_1):PVCCFA_EHV_FIVRA_CPU0_VDD1
 PR355    2      B Q_RES_0402LF-2.2,1%,1/16W,CHIPA    I39 @S9S_MB_2U_LIB.S9S_MB_2U(SCH_1):PAGE257
PU69_P0_1   35     EN ISL99390FRZTR5935-ISL99390FRZ-A    I25 @S9S_MB_2U_LIB.S9S_MB_2U(SCH_1):PAGE257
PU69_P0_1    3    VCC ISL99390FRZTR5935-ISL99390FRZ-A    I25 @S9S_MB_2U_LIB.S9S_MB_2U(SCH_1):PAGE257
 PC600    1      A Q_CAP_C0402-2.2UF,10V,10%,X6S,A    I37 @S9S_MB_2U_LIB.S9S_MB_2U(SCH_1):PAGE257

PVCCFA_EHV_FIVRA_CPU0_VDD2 @S9S_MB_2U_LIB.S9S_MB_2U(SCH_1):PVCCFA_EHV_FIVRA_CPU0_VDD2
PU70_P0_2   35     EN ISL99390FRZTR5935-ISL99390FRZ-A    I16 @S9S_MB_2U_LIB.S9S_MB_2U(SCH_1):PAGE257
PU70_P0_2    3    VCC ISL99390FRZTR5935-ISL99390FRZ-A    I16 @S9S_MB_2U_LIB.S9S_MB_2U(SCH_1):PAGE257
 PC601    1      A Q_CAP_C0402-2.2UF,10V,10%,X6S,A    I18 @S9S_MB_2U_LIB.S9S_MB_2U(SCH_1):PAGE257
 PR356    2      B Q_RES_0402LF-2.2,1%,1/16W,CHIPA    I19 @S9S_MB_2U_LIB.S9S_MB_2U(SCH_1):PAGE257

PVCCFA_EHV_FIVRA_CPU0_VDD3 @S9S_MB_2U_LIB.S9S_MB_2U(SCH_1):PVCCFA_EHV_FIVRA_CPU0_VDD3
PC1171    1      A Q_CAP_C0402-2.2UF,10V,10%,X6S,A    I23 @S9S_MB_2U_LIB.S9S_MB_2U(SCH_1):PAGE258
PU71_P0_3   35     EN ISL99390FRZTR5935-ISL99390FRZ-A    I82 @S9S_MB_2U_LIB.S9S_MB_2U(SCH_1):PAGE258
PU71_P0_3    3    VCC ISL99390FRZTR5935-ISL99390FRZ-A    I82 @S9S_MB_2U_LIB.S9S_MB_2U(SCH_1):PAGE258
PR1299    2      B Q_RES_0402LF-2.2,1%,1/16W,CHIPA    I26 @S9S_MB_2U_LIB.S9S_MB_2U(SCH_1):PAGE258

PVCCFA_EHV_FIVRA_CPU0_VDD4 @S9S_MB_2U_LIB.S9S_MB_2U(SCH_1):PVCCFA_EHV_FIVRA_CPU0_VDD4
PR1300    2      B Q_RES_0402LF-2.2,1%,1/16W,CHIPA    I11 @S9S_MB_2U_LIB.S9S_MB_2U(SCH_1):PAGE258
PU72_P0_4   35     EN ISL99390FRZTR5935-ISL99390FRZ-A    I10 @S9S_MB_2U_LIB.S9S_MB_2U(SCH_1):PAGE258
PU72_P0_4    3    VCC ISL99390FRZTR5935-ISL99390FRZ-A    I10 @S9S_MB_2U_LIB.S9S_MB_2U(SCH_1):PAGE258
PC1172    1      A Q_CAP_C0402-2.2UF,10V,10%,X6S,A    I13 @S9S_MB_2U_LIB.S9S_MB_2U(SCH_1):PAGE258

PVCCFA_EHV_FIVRA_CPU0_VOS1 @S9S_MB_2U_LIB.S9S_MB_2U(SCH_1):PVCCFA_EHV_FIVRA_CPU0_VOS1
PR1322    1      A Q_RES_0402LF-0,5%,1/16W,CHIP,CA    I69 @S9S_MB_2U_LIB.S9S_MB_2U(SCH_1):PAGE257
PU69_P0_1    1    VOS ISL99390FRZTR5935-ISL99390FRZ-A    I25 @S9S_MB_2U_LIB.S9S_MB_2U(SCH_1):PAGE257

PVCCFA_EHV_FIVRA_CPU0_VOS2 @S9S_MB_2U_LIB.S9S_MB_2U(SCH_1):PVCCFA_EHV_FIVRA_CPU0_VOS2
PR1323    1      A Q_RES_0402LF-0,5%,1/16W,CHIP,CA    I50 @S9S_MB_2U_LIB.S9S_MB_2U(SCH_1):PAGE257
PU70_P0_2    1    VOS ISL99390FRZTR5935-ISL99390FRZ-A    I16 @S9S_MB_2U_LIB.S9S_MB_2U(SCH_1):PAGE257

PVCCFA_EHV_FIVRA_CPU0_VOS3 @S9S_MB_2U_LIB.S9S_MB_2U(SCH_1):PVCCFA_EHV_FIVRA_CPU0_VOS3
PR1324    1      A Q_RES_0402LF-0,5%,1/16W,CHIP,CA    I50 @S9S_MB_2U_LIB.S9S_MB_2U(SCH_1):PAGE258
PU71_P0_3    1    VOS ISL99390FRZTR5935-ISL99390FRZ-A    I82 @S9S_MB_2U_LIB.S9S_MB_2U(SCH_1):PAGE258

PVCCFA_EHV_FIVRA_CPU0_VOS4 @S9S_MB_2U_LIB.S9S_MB_2U(SCH_1):PVCCFA_EHV_FIVRA_CPU0_VOS4
PR1325    1      A Q_RES_0402LF-0,5%,1/16W,CHIP,CA    I38 @S9S_MB_2U_LIB.S9S_MB_2U(SCH_1):PAGE258
PU72_P0_4    1    VOS ISL99390FRZTR5935-ISL99390FRZ-A    I10 @S9S_MB_2U_LIB.S9S_MB_2U(SCH_1):PAGE258

PVCCFA_EHV_FIVRA_CPU1 @S9S_MB_2U_LIB.S9S_MB_2U(SCH_1):PVCCFA_EHV_FIVRA_CPU1
    U1 AA11 VCCFA_EHV_FIVRA0 SOCKET4677_AZIF0045P001C01CS-SA     I1 @S9S_MB_2U_LIB.S9S_MB_2U(SCH_1):PAGE69
    U1 AA15 VCCFA_EHV_FIVRA1 SOCKET4677_AZIF0045P001C01CS-SA     I1 @S9S_MB_2U_LIB.S9S_MB_2U(SCH_1):PAGE69
    U1  AA7 VCCFA_EHV_FIVRA2 SOCKET4677_AZIF0045P001C01CS-SA     I1 @S9S_MB_2U_LIB.S9S_MB_2U(SCH_1):PAGE69
    U1 AD85 VCCFA_EHV_FIVRA3 SOCKET4677_AZIF0045P001C01CS-SA     I1 @S9S_MB_2U_LIB.S9S_MB_2U(SCH_1):PAGE69
    U1 AD89 VCCFA_EHV_FIVRA4 SOCKET4677_AZIF0045P001C01CS-SA     I1 @S9S_MB_2U_LIB.S9S_MB_2U(SCH_1):PAGE69
    U1 AE11 VCCFA_EHV_FIVRA5 SOCKET4677_AZIF0045P001C01CS-SA     I1 @S9S_MB_2U_LIB.S9S_MB_2U(SCH_1):PAGE69
    U1 AE15 VCCFA_EHV_FIVRA6 SOCKET4677_AZIF0045P001C01CS-SA     I1 @S9S_MB_2U_LIB.S9S_MB_2U(SCH_1):PAGE69
    U1  AE7 VCCFA_EHV_FIVRA7 SOCKET4677_AZIF0045P001C01CS-SA     I1 @S9S_MB_2U_LIB.S9S_MB_2U(SCH_1):PAGE69
    U1 AF77 VCCFA_EHV_FIVRA8 SOCKET4677_AZIF0045P001C01CS-SA     I1 @S9S_MB_2U_LIB.S9S_MB_2U(SCH_1):PAGE69
    U1 AG78 VCCFA_EHV_FIVRA9 SOCKET4677_AZIF0045P001C01CS-SA     I1 @S9S_MB_2U_LIB.S9S_MB_2U(SCH_1):PAGE69
    U1 AH85 VCCFA_EHV_FIVRA10 SOCKET4677_AZIF0045P001C01CS-SA     I1 @S9S_MB_2U_LIB.S9S_MB_2U(SCH_1):PAGE69
    U1 AH89 VCCFA_EHV_FIVRA11 SOCKET4677_AZIF0045P001C01CS-SA     I1 @S9S_MB_2U_LIB.S9S_MB_2U(SCH_1):PAGE69
    U1 AJ11 VCCFA_EHV_FIVRA12 SOCKET4677_AZIF0045P001C01CS-SA     I1 @S9S_MB_2U_LIB.S9S_MB_2U(SCH_1):PAGE69
    U1 AJ15 VCCFA_EHV_FIVRA13 SOCKET4677_AZIF0045P001C01CS-SA     I1 @S9S_MB_2U_LIB.S9S_MB_2U(SCH_1):PAGE69
    U1  AJ7 VCCFA_EHV_FIVRA14 SOCKET4677_AZIF0045P001C01CS-SA     I1 @S9S_MB_2U_LIB.S9S_MB_2U(SCH_1):PAGE69
    U1 AM79 VCCFA_EHV_FIVRA15 SOCKET4677_AZIF0045P001C01CS-SA     I1 @S9S_MB_2U_LIB.S9S_MB_2U(SCH_1):PAGE69
    U1 AM85 VCCFA_EHV_FIVRA16 SOCKET4677_AZIF0045P001C01CS-SA     I1 @S9S_MB_2U_LIB.S9S_MB_2U(SCH_1):PAGE69
    U1 AM89 VCCFA_EHV_FIVRA17 SOCKET4677_AZIF0045P001C01CS-SA     I1 @S9S_MB_2U_LIB.S9S_MB_2U(SCH_1):PAGE69
    U1 AN11 VCCFA_EHV_FIVRA18 SOCKET4677_AZIF0045P001C01CS-SA     I1 @S9S_MB_2U_LIB.S9S_MB_2U(SCH_1):PAGE69
    U1 AN15 VCCFA_EHV_FIVRA19 SOCKET4677_AZIF0045P001C01CS-SA     I1 @S9S_MB_2U_LIB.S9S_MB_2U(SCH_1):PAGE69
    U1  AN7 VCCFA_EHV_FIVRA20 SOCKET4677_AZIF0045P001C01CS-SA     I1 @S9S_MB_2U_LIB.S9S_MB_2U(SCH_1):PAGE69
    U1 AN80 VCCFA_EHV_FIVRA21 SOCKET4677_AZIF0045P001C01CS-SA     I1 @S9S_MB_2U_LIB.S9S_MB_2U(SCH_1):PAGE69
    U1 AT73 VCCFA_EHV_FIVRA22 SOCKET4677_AZIF0045P001C01CS-SA     I1 @S9S_MB_2U_LIB.S9S_MB_2U(SCH_1):PAGE69
    U1 AT89 VCCFA_EHV_FIVRA23 SOCKET4677_AZIF0045P001C01CS-SA     I1 @S9S_MB_2U_LIB.S9S_MB_2U(SCH_1):PAGE69
    U1 AU15 VCCFA_EHV_FIVRA24 SOCKET4677_AZIF0045P001C01CS-SA     I1 @S9S_MB_2U_LIB.S9S_MB_2U(SCH_1):PAGE69
    U1 AW76 VCCFA_EHV_FIVRA25 SOCKET4677_AZIF0045P001C01CS-SA     I1 @S9S_MB_2U_LIB.S9S_MB_2U(SCH_1):PAGE69
    U1 AY89 VCCFA_EHV_FIVRA26 SOCKET4677_AZIF0045P001C01CS-SA     I1 @S9S_MB_2U_LIB.S9S_MB_2U(SCH_1):PAGE69
    U1 BE72 VCCFA_EHV_FIVRA27 SOCKET4677_AZIF0045P001C01CS-SA     I1 @S9S_MB_2U_LIB.S9S_MB_2U(SCH_1):PAGE69
    U1 BF77 VCCFA_EHV_FIVRA28 SOCKET4677_AZIF0045P001C01CS-SA     I1 @S9S_MB_2U_LIB.S9S_MB_2U(SCH_1):PAGE69
    U1 BH79 VCCFA_EHV_FIVRA29 SOCKET4677_AZIF0045P001C01CS-SA     I1 @S9S_MB_2U_LIB.S9S_MB_2U(SCH_1):PAGE69
    U1 BJ72 VCCFA_EHV_FIVRA30 SOCKET4677_AZIF0045P001C01CS-SA     I1 @S9S_MB_2U_LIB.S9S_MB_2U(SCH_1):PAGE69
    U1 BJ78 VCCFA_EHV_FIVRA31 SOCKET4677_AZIF0045P001C01CS-SA     I1 @S9S_MB_2U_LIB.S9S_MB_2U(SCH_1):PAGE69
    U1  C84 VCCFA_EHV_FIVRA32 SOCKET4677_AZIF0045P001C01CS-SA     I1 @S9S_MB_2U_LIB.S9S_MB_2U(SCH_1):PAGE69
    U1  C88 VCCFA_EHV_FIVRA33 SOCKET4677_AZIF0045P001C01CS-SA     I1 @S9S_MB_2U_LIB.S9S_MB_2U(SCH_1):PAGE69
    U1 CE74 VCCFA_EHV_FIVRA34 SOCKET4677_AZIF0045P001C01CS-SA     I1 @S9S_MB_2U_LIB.S9S_MB_2U(SCH_1):PAGE69
    U1 CK73 VCCFA_EHV_FIVRA35 SOCKET4677_AZIF0045P001C01CS-SA     I1 @S9S_MB_2U_LIB.S9S_MB_2U(SCH_1):PAGE69
    U1 CK79 VCCFA_EHV_FIVRA36 SOCKET4677_AZIF0045P001C01CS-SA     I1 @S9S_MB_2U_LIB.S9S_MB_2U(SCH_1):PAGE69
    U1 CM73 VCCFA_EHV_FIVRA37 SOCKET4677_AZIF0045P001C01CS-SA     I1 @S9S_MB_2U_LIB.S9S_MB_2U(SCH_1):PAGE69
    U1 CN78 VCCFA_EHV_FIVRA38 SOCKET4677_AZIF0045P001C01CS-SA     I1 @S9S_MB_2U_LIB.S9S_MB_2U(SCH_1):PAGE69
    U1 CP73 VCCFA_EHV_FIVRA39 SOCKET4677_AZIF0045P001C01CS-SA     I1 @S9S_MB_2U_LIB.S9S_MB_2U(SCH_1):PAGE69
    U1 CT77 VCCFA_EHV_FIVRA40 SOCKET4677_AZIF0045P001C01CS-SA     I1 @S9S_MB_2U_LIB.S9S_MB_2U(SCH_1):PAGE69
    U1 CT85 VCCFA_EHV_FIVRA41 SOCKET4677_AZIF0045P001C01CS-SA     I1 @S9S_MB_2U_LIB.S9S_MB_2U(SCH_1):PAGE69
    U1 CY75 VCCFA_EHV_FIVRA42 SOCKET4677_AZIF0045P001C01CS-SA     I1 @S9S_MB_2U_LIB.S9S_MB_2U(SCH_1):PAGE69
    U1 CY79 VCCFA_EHV_FIVRA43 SOCKET4677_AZIF0045P001C01CS-SA     I1 @S9S_MB_2U_LIB.S9S_MB_2U(SCH_1):PAGE69
    U1 CY85 VCCFA_EHV_FIVRA44 SOCKET4677_AZIF0045P001C01CS-SA     I1 @S9S_MB_2U_LIB.S9S_MB_2U(SCH_1):PAGE69
    U1 CY89 VCCFA_EHV_FIVRA45 SOCKET4677_AZIF0045P001C01CS-SA     I1 @S9S_MB_2U_LIB.S9S_MB_2U(SCH_1):PAGE69
    U1 DD77 VCCFA_EHV_FIVRA46 SOCKET4677_AZIF0045P001C01CS-SA     I1 @S9S_MB_2U_LIB.S9S_MB_2U(SCH_1):PAGE69
    U1 DD83 VCCFA_EHV_FIVRA47 SOCKET4677_AZIF0045P001C01CS-SA     I1 @S9S_MB_2U_LIB.S9S_MB_2U(SCH_1):PAGE69
    U1 DD85 VCCFA_EHV_FIVRA48 SOCKET4677_AZIF0045P001C01CS-SA     I1 @S9S_MB_2U_LIB.S9S_MB_2U(SCH_1):PAGE69
    U1 DD89 VCCFA_EHV_FIVRA49 SOCKET4677_AZIF0045P001C01CS-SA     I1 @S9S_MB_2U_LIB.S9S_MB_2U(SCH_1):PAGE69
    U1 DH89 VCCFA_EHV_FIVRA50 SOCKET4677_AZIF0045P001C01CS-SA     I1 @S9S_MB_2U_LIB.S9S_MB_2U(SCH_1):PAGE69
    U1 DM83 VCCFA_EHV_FIVRA51 SOCKET4677_AZIF0045P001C01CS-SA     I1 @S9S_MB_2U_LIB.S9S_MB_2U(SCH_1):PAGE69
    U1 DM85 VCCFA_EHV_FIVRA52 SOCKET4677_AZIF0045P001C01CS-SA     I1 @S9S_MB_2U_LIB.S9S_MB_2U(SCH_1):PAGE69
    U1 DM89 VCCFA_EHV_FIVRA53 SOCKET4677_AZIF0045P001C01CS-SA     I1 @S9S_MB_2U_LIB.S9S_MB_2U(SCH_1):PAGE69
    U1 DN11 VCCFA_EHV_FIVRA54 SOCKET4677_AZIF0045P001C01CS-SA     I1 @S9S_MB_2U_LIB.S9S_MB_2U(SCH_1):PAGE69
    U1 DN15 VCCFA_EHV_FIVRA55 SOCKET4677_AZIF0045P001C01CS-SA     I1 @S9S_MB_2U_LIB.S9S_MB_2U(SCH_1):PAGE69
    U1  DN3 VCCFA_EHV_FIVRA56 SOCKET4677_AZIF0045P001C01CS-SA     I1 @S9S_MB_2U_LIB.S9S_MB_2U(SCH_1):PAGE69
    U1  DN7 VCCFA_EHV_FIVRA57 SOCKET4677_AZIF0045P001C01CS-SA     I1 @S9S_MB_2U_LIB.S9S_MB_2U(SCH_1):PAGE69
    U1 DT79 VCCFA_EHV_FIVRA58 SOCKET4677_AZIF0045P001C01CS-SA     I1 @S9S_MB_2U_LIB.S9S_MB_2U(SCH_1):PAGE69
    U1 DT85 VCCFA_EHV_FIVRA59 SOCKET4677_AZIF0045P001C01CS-SA     I1 @S9S_MB_2U_LIB.S9S_MB_2U(SCH_1):PAGE69
    U1 DT89 VCCFA_EHV_FIVRA60 SOCKET4677_AZIF0045P001C01CS-SA     I1 @S9S_MB_2U_LIB.S9S_MB_2U(SCH_1):PAGE69
    U1 DU11 VCCFA_EHV_FIVRA61 SOCKET4677_AZIF0045P001C01CS-SA     I1 @S9S_MB_2U_LIB.S9S_MB_2U(SCH_1):PAGE69
    U1 DU15 VCCFA_EHV_FIVRA62 SOCKET4677_AZIF0045P001C01CS-SA     I1 @S9S_MB_2U_LIB.S9S_MB_2U(SCH_1):PAGE69
    U1  DU3 VCCFA_EHV_FIVRA63 SOCKET4677_AZIF0045P001C01CS-SA     I1 @S9S_MB_2U_LIB.S9S_MB_2U(SCH_1):PAGE69
    U1  DU7 VCCFA_EHV_FIVRA64 SOCKET4677_AZIF0045P001C01CS-SA     I1 @S9S_MB_2U_LIB.S9S_MB_2U(SCH_1):PAGE69
    U1 DY85 VCCFA_EHV_FIVRA65 SOCKET4677_AZIF0045P001C01CS-SA     I1 @S9S_MB_2U_LIB.S9S_MB_2U(SCH_1):PAGE69
    U1 DY89 VCCFA_EHV_FIVRA66 SOCKET4677_AZIF0045P001C01CS-SA     I1 @S9S_MB_2U_LIB.S9S_MB_2U(SCH_1):PAGE69
    U1 EA11 VCCFA_EHV_FIVRA67 SOCKET4677_AZIF0045P001C01CS-SA     I1 @S9S_MB_2U_LIB.S9S_MB_2U(SCH_1):PAGE69
    U1 EA15 VCCFA_EHV_FIVRA68 SOCKET4677_AZIF0045P001C01CS-SA     I1 @S9S_MB_2U_LIB.S9S_MB_2U(SCH_1):PAGE69
    U1  EA3 VCCFA_EHV_FIVRA69 SOCKET4677_AZIF0045P001C01CS-SA     I1 @S9S_MB_2U_LIB.S9S_MB_2U(SCH_1):PAGE69
    U1  EA7 VCCFA_EHV_FIVRA70 SOCKET4677_AZIF0045P001C01CS-SA     I1 @S9S_MB_2U_LIB.S9S_MB_2U(SCH_1):PAGE69
    U1 EC78 VCCFA_EHV_FIVRA71 SOCKET4677_AZIF0045P001C01CS-SA     I1 @S9S_MB_2U_LIB.S9S_MB_2U(SCH_1):PAGE69
    U1 ED79 VCCFA_EHV_FIVRA72 SOCKET4677_AZIF0045P001C01CS-SA     I1 @S9S_MB_2U_LIB.S9S_MB_2U(SCH_1):PAGE69
    U1 ED85 VCCFA_EHV_FIVRA73 SOCKET4677_AZIF0045P001C01CS-SA     I1 @S9S_MB_2U_LIB.S9S_MB_2U(SCH_1):PAGE69
    U1 ED89 VCCFA_EHV_FIVRA74 SOCKET4677_AZIF0045P001C01CS-SA     I1 @S9S_MB_2U_LIB.S9S_MB_2U(SCH_1):PAGE69
    U1 EE11 VCCFA_EHV_FIVRA75 SOCKET4677_AZIF0045P001C01CS-SA     I1 @S9S_MB_2U_LIB.S9S_MB_2U(SCH_1):PAGE69
    U1 EE15 VCCFA_EHV_FIVRA76 SOCKET4677_AZIF0045P001C01CS-SA     I1 @S9S_MB_2U_LIB.S9S_MB_2U(SCH_1):PAGE69
    U1  EE7 VCCFA_EHV_FIVRA77 SOCKET4677_AZIF0045P001C01CS-SA     I1 @S9S_MB_2U_LIB.S9S_MB_2U(SCH_1):PAGE69
    U1 EE84 VCCFA_EHV_FIVRA78 SOCKET4677_AZIF0045P001C01CS-SA     I1 @S9S_MB_2U_LIB.S9S_MB_2U(SCH_1):PAGE69
    U1 EF79 VCCFA_EHV_FIVRA79 SOCKET4677_AZIF0045P001C01CS-SA     I1 @S9S_MB_2U_LIB.S9S_MB_2U(SCH_1):PAGE69
    U1 EG80 VCCFA_EHV_FIVRA80 SOCKET4677_AZIF0045P001C01CS-SA     I1 @S9S_MB_2U_LIB.S9S_MB_2U(SCH_1):PAGE69
    U1 EJ15 VCCFA_EHV_FIVRA81 SOCKET4677_AZIF0045P001C01CS-SA     I1 @S9S_MB_2U_LIB.S9S_MB_2U(SCH_1):PAGE69
    U1 EJ84 VCCFA_EHV_FIVRA82 SOCKET4677_AZIF0045P001C01CS-SA     I1 @S9S_MB_2U_LIB.S9S_MB_2U(SCH_1):PAGE69
    U1 EN84 VCCFA_EHV_FIVRA83 SOCKET4677_AZIF0045P001C01CS-SA     I1 @S9S_MB_2U_LIB.S9S_MB_2U(SCH_1):PAGE69
    U1  H89 VCCFA_EHV_FIVRA84 SOCKET4677_AZIF0045P001C01CS-SA     I1 @S9S_MB_2U_LIB.S9S_MB_2U(SCH_1):PAGE69
    U1  J11 VCCFA_EHV_FIVRA85 SOCKET4677_AZIF0045P001C01CS-SA     I1 @S9S_MB_2U_LIB.S9S_MB_2U(SCH_1):PAGE69
    U1   J7 VCCFA_EHV_FIVRA86 SOCKET4677_AZIF0045P001C01CS-SA     I1 @S9S_MB_2U_LIB.S9S_MB_2U(SCH_1):PAGE69
    U1  J80 VCCFA_EHV_FIVRA87 SOCKET4677_AZIF0045P001C01CS-SA     I1 @S9S_MB_2U_LIB.S9S_MB_2U(SCH_1):PAGE69
    U1  K87 VCCFA_EHV_FIVRA88 SOCKET4677_AZIF0045P001C01CS-SA     I1 @S9S_MB_2U_LIB.S9S_MB_2U(SCH_1):PAGE69
    U1  L84 VCCFA_EHV_FIVRA89 SOCKET4677_AZIF0045P001C01CS-SA     I1 @S9S_MB_2U_LIB.S9S_MB_2U(SCH_1):PAGE69
    U1  M85 VCCFA_EHV_FIVRA90 SOCKET4677_AZIF0045P001C01CS-SA     I1 @S9S_MB_2U_LIB.S9S_MB_2U(SCH_1):PAGE69
    U1  M89 VCCFA_EHV_FIVRA91 SOCKET4677_AZIF0045P001C01CS-SA     I1 @S9S_MB_2U_LIB.S9S_MB_2U(SCH_1):PAGE69
    U1  N11 VCCFA_EHV_FIVRA92 SOCKET4677_AZIF0045P001C01CS-SA     I1 @S9S_MB_2U_LIB.S9S_MB_2U(SCH_1):PAGE69
    U1   N7 VCCFA_EHV_FIVRA93 SOCKET4677_AZIF0045P001C01CS-SA     I1 @S9S_MB_2U_LIB.S9S_MB_2U(SCH_1):PAGE69
    U1  P79 VCCFA_EHV_FIVRA94 SOCKET4677_AZIF0045P001C01CS-SA     I1 @S9S_MB_2U_LIB.S9S_MB_2U(SCH_1):PAGE69
    U1  R80 VCCFA_EHV_FIVRA95 SOCKET4677_AZIF0045P001C01CS-SA     I1 @S9S_MB_2U_LIB.S9S_MB_2U(SCH_1):PAGE69
    U1  T85 VCCFA_EHV_FIVRA96 SOCKET4677_AZIF0045P001C01CS-SA     I1 @S9S_MB_2U_LIB.S9S_MB_2U(SCH_1):PAGE69
    U1  T89 VCCFA_EHV_FIVRA97 SOCKET4677_AZIF0045P001C01CS-SA     I1 @S9S_MB_2U_LIB.S9S_MB_2U(SCH_1):PAGE69
    U1  U11 VCCFA_EHV_FIVRA98 SOCKET4677_AZIF0045P001C01CS-SA     I1 @S9S_MB_2U_LIB.S9S_MB_2U(SCH_1):PAGE69
    U1  U15 VCCFA_EHV_FIVRA99 SOCKET4677_AZIF0045P001C01CS-SA     I1 @S9S_MB_2U_LIB.S9S_MB_2U(SCH_1):PAGE69
    U1   U7 VCCFA_EHV_FIVRA100 SOCKET4677_AZIF0045P001C01CS-SA     I1 @S9S_MB_2U_LIB.S9S_MB_2U(SCH_1):PAGE69
    U1  W80 VCCFA_EHV_FIVRA101 SOCKET4677_AZIF0045P001C01CS-SA     I1 @S9S_MB_2U_LIB.S9S_MB_2U(SCH_1):PAGE69
    U1  Y79 VCCFA_EHV_FIVRA102 SOCKET4677_AZIF0045P001C01CS-SA     I1 @S9S_MB_2U_LIB.S9S_MB_2U(SCH_1):PAGE69
    U1  Y85 VCCFA_EHV_FIVRA103 SOCKET4677_AZIF0045P001C01CS-SA     I1 @S9S_MB_2U_LIB.S9S_MB_2U(SCH_1):PAGE69
    U1  Y89 VCCFA_EHV_FIVRA104 SOCKET4677_AZIF0045P001C01CS-SA     I1 @S9S_MB_2U_LIB.S9S_MB_2U(SCH_1):PAGE69
  C424    1      A Q_CAP_C0402-22UF,4V,20%,X6S,CHA     I1 @S9S_MB_2U_LIB.S9S_MB_2U(SCH_1):PAGE77
  C428    1      A Q_CAP_C0402-22UF,4V,20%,X6S,CHA     I4 @S9S_MB_2U_LIB.S9S_MB_2U(SCH_1):PAGE77
  C430    1      A Q_CAP_C0402-22UF,4V,20%,X6S,CHA     I5 @S9S_MB_2U_LIB.S9S_MB_2U(SCH_1):PAGE77
  C431    1      A Q_CAP_C0402-22UF,4V,20%,X6S,CHA    I37 @S9S_MB_2U_LIB.S9S_MB_2U(SCH_1):PAGE77
  C433    1      A Q_CAP_C0402-22UF,4V,20%,X6S,CHA    I38 @S9S_MB_2U_LIB.S9S_MB_2U(SCH_1):PAGE77
  C435    1      A Q_CAP_C0402-22UF,4V,20%,X6S,CHA    I39 @S9S_MB_2U_LIB.S9S_MB_2U(SCH_1):PAGE77
  C439    1      A Q_CAP_C0402-22UF,4V,20%,X6S,CHA    I53 @S9S_MB_2U_LIB.S9S_MB_2U(SCH_1):PAGE77
  C441    1      A Q_CAP_C0402-22UF,4V,20%,X6S,CHA    I55 @S9S_MB_2U_LIB.S9S_MB_2U(SCH_1):PAGE77
  C442    1      A Q_CAP_C0402-22UF,4V,20%,X6S,CHA    I57 @S9S_MB_2U_LIB.S9S_MB_2U(SCH_1):PAGE77
  C453    1      A Q_CAP_C0805-47UF,4V,20%,X6S,CHA     I3 @S9S_MB_2U_LIB.S9S_MB_2U(SCH_1):PAGE78
  C461    1      A Q_CAP_C0805-47UF,4V,20%,X6S,CHA     I5 @S9S_MB_2U_LIB.S9S_MB_2U(SCH_1):PAGE78
  C465    1      A Q_CAP_C0603-47UF,2.5V,20%,X6S,A     I7 @S9S_MB_2U_LIB.S9S_MB_2U(SCH_1):PAGE78
  C450    1      A Q_CAP_C0805-47UF,4V,20%,X6S,CHA     I1 @S9S_MB_2U_LIB.S9S_MB_2U(SCH_1):PAGE79
  C454    1      A Q_CAP_C0805-47UF,4V,20%,X6S,CHA     I3 @S9S_MB_2U_LIB.S9S_MB_2U(SCH_1):PAGE79
  C458    1      A Q_CAP_C0805-47UF,4V,20%,X6S,CHA     I4 @S9S_MB_2U_LIB.S9S_MB_2U(SCH_1):PAGE79
  C462    1      A Q_CAP_C0805-47UF,4V,20%,X6S,CHA     I5 @S9S_MB_2U_LIB.S9S_MB_2U(SCH_1):PAGE79
  C466    1      A Q_CAP_C0805-47UF,4V,20%,X6S,CHA     I7 @S9S_MB_2U_LIB.S9S_MB_2U(SCH_1):PAGE79
  C470    1      A Q_CAP_C0805-47UF,4V,20%,X6S,CHA     I8 @S9S_MB_2U_LIB.S9S_MB_2U(SCH_1):PAGE79
  C473    1      A Q_CAP_C0805-47UF,4V,20%,X6S,CHA     I9 @S9S_MB_2U_LIB.S9S_MB_2U(SCH_1):PAGE79
 PL113    2      2 Q_INDUCTOR_SMLF-130NH/106A,INDA    I44 @S9S_MB_2U_LIB.S9S_MB_2U(SCH_1):PAGE276
PC1201    1      A Q_CAPP_THLF-560UF,2.5V,20%,OSCA    I55 @S9S_MB_2U_LIB.S9S_MB_2U(SCH_1):PAGE276
PC1204_P1_3    1      A Q_CAP_C0402-1UF,16V,10%,X6S,CHA    I56 @S9S_MB_2U_LIB.S9S_MB_2U(SCH_1):PAGE276
PC1203    1      A Q_CAPP_THLF-560UF,2.5V,20%,OSCA    I67 @S9S_MB_2U_LIB.S9S_MB_2U(SCH_1):PAGE276
PC1208_P1_3    1      A Q_CAP_C0805-22UF,4V,20%,X6S,CHA    I68 @S9S_MB_2U_LIB.S9S_MB_2U(SCH_1):PAGE276
  PL19    2      2 Q_INDUCTOR_SMLF-130NH/106A,INDA    I44 @S9S_MB_2U_LIB.S9S_MB_2U(SCH_1):PAGE275
PR1331    2      B Q_RES_0402LF-0,5%,1/16W,CHIP,CA    I53 @S9S_MB_2U_LIB.S9S_MB_2U(SCH_1):PAGE275
  PL18    2      2 Q_INDUCTOR_SMLF-130NH/106A,INDA    I55 @S9S_MB_2U_LIB.S9S_MB_2U(SCH_1):PAGE275
PC621_P1_1    1      A Q_CAP_C0402-100NF,50V,10%,X7R,A    I60 @S9S_MB_2U_LIB.S9S_MB_2U(SCH_1):PAGE275
PC413_P1_2    1      A Q_CAP_C0805-22UF,4V,20%,X6S,CHA    I63 @S9S_MB_2U_LIB.S9S_MB_2U(SCH_1):PAGE275
 PC416    1      A Q_CAPP_THLF-560UF,2.5V,20%,OSCA    I68 @S9S_MB_2U_LIB.S9S_MB_2U(SCH_1):PAGE275
  PL12    2      2 Q_INDUCTOR_SMLF-130NH/106A,INDA    I57 @S9S_MB_2U_LIB.S9S_MB_2U(SCH_1):PAGE276
  C426    1      A Q_CAP_C0402-22UF,4V,20%,X6S,CHA     I2 @S9S_MB_2U_LIB.S9S_MB_2U(SCH_1):PAGE77
  C437    1      A Q_CAP_C0402-22UF,4V,20%,X6S,CHA    I40 @S9S_MB_2U_LIB.S9S_MB_2U(SCH_1):PAGE77
  C449    1      A Q_CAP_C0805-47UF,4V,20%,X6S,CHA     I1 @S9S_MB_2U_LIB.S9S_MB_2U(SCH_1):PAGE78
  C457    1      A Q_CAP_C0805-47UF,4V,20%,X6S,CHA     I4 @S9S_MB_2U_LIB.S9S_MB_2U(SCH_1):PAGE78
  C476    1      A Q_CAP_C0805-47UF,4V,20%,X6S,CHA    I37 @S9S_MB_2U_LIB.S9S_MB_2U(SCH_1):PAGE79
  C477    1      A Q_CAP_C0805-47UF,4V,20%,X6S,CHA    I38 @S9S_MB_2U_LIB.S9S_MB_2U(SCH_1):PAGE79
  C479    1      A Q_CAP_C0805-47UF,4V,20%,X6S,CHA    I39 @S9S_MB_2U_LIB.S9S_MB_2U(SCH_1):PAGE79
  C482    1      A Q_CAP_C0805-47UF,4V,20%,X6S,CHA    I41 @S9S_MB_2U_LIB.S9S_MB_2U(SCH_1):PAGE79
  C485    1      A Q_CAP_C0805-47UF,4V,20%,X6S,CHA    I42 @S9S_MB_2U_LIB.S9S_MB_2U(SCH_1):PAGE79
PR1332    2      B Q_RES_0402LF-0,5%,1/16W,CHIP,CA    I41 @S9S_MB_2U_LIB.S9S_MB_2U(SCH_1):PAGE275
PC411_P1_2    1      A Q_CAP_C0805-22UF,4V,20%,X6S,CHA    I62 @S9S_MB_2U_LIB.S9S_MB_2U(SCH_1):PAGE275
PC1206_P1_3    1      A Q_CAP_C0805-22UF,4V,20%,X6S,CHA    I66 @S9S_MB_2U_LIB.S9S_MB_2U(SCH_1):PAGE276
PC408_P1_2    1      A Q_CAP_C0402-1UF,16V,10%,X6S,CHA    I61 @S9S_MB_2U_LIB.S9S_MB_2U(SCH_1):PAGE275
PR4241    1      A Q_RES_0402LF-499,1%,1/16W,CHIPA    I64 @S9S_MB_2U_LIB.S9S_MB_2U(SCH_1):PAGE275
 PC418    1      A Q_CAPP_SMLF-330UF,2.5V,+10/-35B    I70 @S9S_MB_2U_LIB.S9S_MB_2U(SCH_1):PAGE275
PC2172    1      A Q_CAPP_SMLF-330UF,2.5V,+10/-35B    I72 @S9S_MB_2U_LIB.S9S_MB_2U(SCH_1):PAGE275
PC1209_P1_4    1      A Q_CAP_C0805-22UF,4V,20%,X6S,CHA    I50 @S9S_MB_2U_LIB.S9S_MB_2U(SCH_1):PAGE276
PR1333    2      B Q_RES_0402LF-0,5%,1/16W,CHIP,CA    I54 @S9S_MB_2U_LIB.S9S_MB_2U(SCH_1):PAGE276
PC1204    1      A Q_CAPP_THLF-560UF,2.5V,20%,OSCA    I70 @S9S_MB_2U_LIB.S9S_MB_2U(SCH_1):PAGE276
PC1205    1      A Q_CAPP_SMLF-330UF,2.5V,+10/-35B    I72 @S9S_MB_2U_LIB.S9S_MB_2U(SCH_1):PAGE276
 PC414    1      A Q_CAPP_THLF-560UF,2.5V,20%,OSCA    I66 @S9S_MB_2U_LIB.S9S_MB_2U(SCH_1):PAGE275
 PC415    1      A Q_CAPP_THLF-560UF,2.5V,20%,OSCA    I67 @S9S_MB_2U_LIB.S9S_MB_2U(SCH_1):PAGE275
PC410_P1_1    1      A Q_CAP_C0805-22UF,4V,20%,X6S,CHA    I74 @S9S_MB_2U_LIB.S9S_MB_2U(SCH_1):PAGE275
PC412_P1_1    1      A Q_CAP_C0805-22UF,4V,20%,X6S,CHA    I75 @S9S_MB_2U_LIB.S9S_MB_2U(SCH_1):PAGE275
PR1334    2      B Q_RES_0402LF-0,5%,1/16W,CHIP,CA    I43 @S9S_MB_2U_LIB.S9S_MB_2U(SCH_1):PAGE276
PC1203_P1_4    1      A Q_CAP_C0402-100NF,50V,10%,X7R,A    I47 @S9S_MB_2U_LIB.S9S_MB_2U(SCH_1):PAGE276
PC1207_P1_4    1      A Q_CAP_C0805-22UF,4V,20%,X6S,CHA    I48 @S9S_MB_2U_LIB.S9S_MB_2U(SCH_1):PAGE276
PC2171    1      A Q_CAPP_SMLF-330UF,2.5V,+10/-35B    I73 @S9S_MB_2U_LIB.S9S_MB_2U(SCH_1):PAGE276
 PR561    2      B Q_RES_0402LF-100,1%,1/16W,CHIPA    I23 @S9S_MB_2U_LIB.S9S_MB_2U(SCH_1):PAGE270

PVCCFA_EHV_FIVRA_CPU1_BTSEN @S9S_MB_2U_LIB.S9S_MB_2U(SCH_1):PVCCFA_EHV_FIVRA_CPU1_BTSEN
PU76_P1_2   36 TOUT_FLT ISL99390FRZTR5935-ISL99390FRZ-A     I9 @S9S_MB_2U_LIB.S9S_MB_2U(SCH_1):PAGE275
PU78_P1_4   36 TOUT_FLT ISL99390FRZTR5935-ISL99390FRZ-A    I15 @S9S_MB_2U_LIB.S9S_MB_2U(SCH_1):PAGE276
PU77_P1_3   36 TOUT_FLT ISL99390FRZTR5935-ISL99390FRZ-A    I24 @S9S_MB_2U_LIB.S9S_MB_2U(SCH_1):PAGE276
PU75_P1_1   36 TOUT_FLT ISL99390FRZTR5935-ISL99390FRZ-A    I89 @S9S_MB_2U_LIB.S9S_MB_2U(SCH_1):PAGE275
  PU29   44 TEMP1||ISYS RAA229126GNPHA0-RAA229126GNP#HA    I33 @S9S_MB_2U_LIB.S9S_MB_2U(SCH_1):PAGE270
 PC101    1      A Q_CAP_0402-470PF,50V,10%,X7R,TA    I92 @S9S_MB_2U_LIB.S9S_MB_2U(SCH_1):PAGE270
 PR453    1      A Q_RES_0402LF-10K,1%,1/16W,EMPTA    I94 @S9S_MB_2U_LIB.S9S_MB_2U(SCH_1):PAGE270

PVCCFA_EHV_FIVRA_CPU1_EN_R @S9S_MB_2U_LIB.S9S_MB_2U(SCH_1):PVCCFA_EHV_FIVRA_CPU1_EN_R
 R2550    2      B Q_RES_0402LF-0,5%,1/16W,CHIP,CA    I19 @S9S_MB_2U_LIB.S9S_MB_2U(SCH_1):PAGE270
 C2446    1      A Q_CAP_0402-1000PF,50V,5%,X7R,TA    I34 @S9S_MB_2U_LIB.S9S_MB_2U(SCH_1):PAGE270
  PU29   24    EN1 RAA229126GNPHA0-RAA229126GNP#HA    I33 @S9S_MB_2U_LIB.S9S_MB_2U(SCH_1):PAGE270

PVCCFA_EHV_FIVRA_CPU1_IMON1 @S9S_MB_2U_LIB.S9S_MB_2U(SCH_1):PVCCFA_EHV_FIVRA_CPU1_IMON1
PU75_P1_1   38   IOUT ISL99390FRZTR5935-ISL99390FRZ-A    I89 @S9S_MB_2U_LIB.S9S_MB_2U(SCH_1):PAGE275
  PU29   38    CS0 RAA229126GNPHA0-RAA229126GNP#HA    I33 @S9S_MB_2U_LIB.S9S_MB_2U(SCH_1):PAGE270

PVCCFA_EHV_FIVRA_CPU1_IMON2 @S9S_MB_2U_LIB.S9S_MB_2U(SCH_1):PVCCFA_EHV_FIVRA_CPU1_IMON2
PU76_P1_2   38   IOUT ISL99390FRZTR5935-ISL99390FRZ-A     I9 @S9S_MB_2U_LIB.S9S_MB_2U(SCH_1):PAGE275
  PU29   37    CS1 RAA229126GNPHA0-RAA229126GNP#HA    I33 @S9S_MB_2U_LIB.S9S_MB_2U(SCH_1):PAGE270

PVCCFA_EHV_FIVRA_CPU1_IMON3 @S9S_MB_2U_LIB.S9S_MB_2U(SCH_1):PVCCFA_EHV_FIVRA_CPU1_IMON3
PU77_P1_3   38   IOUT ISL99390FRZTR5935-ISL99390FRZ-A    I24 @S9S_MB_2U_LIB.S9S_MB_2U(SCH_1):PAGE276
  PU29   36    CS2 RAA229126GNPHA0-RAA229126GNP#HA    I33 @S9S_MB_2U_LIB.S9S_MB_2U(SCH_1):PAGE270
PR4239    1      A Q_RES_0402LF-0,5%,1/16W,EMPTY,A    I80 @S9S_MB_2U_LIB.S9S_MB_2U(SCH_1):PAGE270

PVCCFA_EHV_FIVRA_CPU1_IMON4 @S9S_MB_2U_LIB.S9S_MB_2U(SCH_1):PVCCFA_EHV_FIVRA_CPU1_IMON4
PU78_P1_4   38   IOUT ISL99390FRZTR5935-ISL99390FRZ-A    I15 @S9S_MB_2U_LIB.S9S_MB_2U(SCH_1):PAGE276
PR4238    1      A Q_RES_0402LF-0,5%,1/16W,EMPTY,A    I81 @S9S_MB_2U_LIB.S9S_MB_2U(SCH_1):PAGE270
  PU29   35    CS3 RAA229126GNPHA0-RAA229126GNP#HA    I33 @S9S_MB_2U_LIB.S9S_MB_2U(SCH_1):PAGE270

PVCCFA_EHV_FIVRA_CPU1_LSET1 @S9S_MB_2U_LIB.S9S_MB_2U(SCH_1):PVCCFA_EHV_FIVRA_CPU1_LSET1
 PR225    1      A Q_RES_0402LF-8.87K,1%,1/16W,EMA    I20 @S9S_MB_2U_LIB.S9S_MB_2U(SCH_1):PAGE275
PU75_P1_1   37   LSET ISL99390FRZTR5935-ISL99390FRZ-A    I89 @S9S_MB_2U_LIB.S9S_MB_2U(SCH_1):PAGE275

PVCCFA_EHV_FIVRA_CPU1_LSET2 @S9S_MB_2U_LIB.S9S_MB_2U(SCH_1):PVCCFA_EHV_FIVRA_CPU1_LSET2
 PR224    1      A Q_RES_0402LF-8.87K,1%,1/16W,EMA     I2 @S9S_MB_2U_LIB.S9S_MB_2U(SCH_1):PAGE275
PU76_P1_2   37   LSET ISL99390FRZTR5935-ISL99390FRZ-A     I9 @S9S_MB_2U_LIB.S9S_MB_2U(SCH_1):PAGE275

PVCCFA_EHV_FIVRA_CPU1_LSET3 @S9S_MB_2U_LIB.S9S_MB_2U(SCH_1):PVCCFA_EHV_FIVRA_CPU1_LSET3
PU77_P1_3   37   LSET ISL99390FRZTR5935-ISL99390FRZ-A    I24 @S9S_MB_2U_LIB.S9S_MB_2U(SCH_1):PAGE276
PR1305    1      A Q_RES_0402LF-8.87K,1%,1/16W,EMA     I5 @S9S_MB_2U_LIB.S9S_MB_2U(SCH_1):PAGE276

PVCCFA_EHV_FIVRA_CPU1_LSET4 @S9S_MB_2U_LIB.S9S_MB_2U(SCH_1):PVCCFA_EHV_FIVRA_CPU1_LSET4
PR1304    1      A Q_RES_0402LF-8.87K,1%,1/16W,EMA     I2 @S9S_MB_2U_LIB.S9S_MB_2U(SCH_1):PAGE276
PU78_P1_4   37   LSET ISL99390FRZTR5935-ISL99390FRZ-A    I15 @S9S_MB_2U_LIB.S9S_MB_2U(SCH_1):PAGE276

PVCCFA_EHV_FIVRA_CPU1_PVCC1 @S9S_MB_2U_LIB.S9S_MB_2U(SCH_1):PVCCFA_EHV_FIVRA_CPU1_PVCC1
 PR701    2      B Q_RES_0402LF-0,5%,1/16W,CHIP,CA    I32 @S9S_MB_2U_LIB.S9S_MB_2U(SCH_1):PAGE275
 PR703    2      B Q_RES_0402LF-0,5%,1/16W,EMPTY,A    I34 @S9S_MB_2U_LIB.S9S_MB_2U(SCH_1):PAGE275
PU77_P1_3    4   PVCC ISL99390FRZTR5935-ISL99390FRZ-A    I24 @S9S_MB_2U_LIB.S9S_MB_2U(SCH_1):PAGE276
PC1244_P1_3    1      A Q_CAP_C0402-2.2UF,10V,10%,X6S,A    I31 @S9S_MB_2U_LIB.S9S_MB_2U(SCH_1):PAGE276
 PR226    1      A Q_RES_0402LF-2.2,1%,1/16W,CHIPA    I28 @S9S_MB_2U_LIB.S9S_MB_2U(SCH_1):PAGE275
PC1242_P1_1    1      A Q_CAP_C0402-2.2UF,10V,10%,X6S,A    I31 @S9S_MB_2U_LIB.S9S_MB_2U(SCH_1):PAGE275
PU75_P1_1    4   PVCC ISL99390FRZTR5935-ISL99390FRZ-A    I89 @S9S_MB_2U_LIB.S9S_MB_2U(SCH_1):PAGE275
PR1306    1      A Q_RES_0402LF-2.2,1%,1/16W,CHIPA    I29 @S9S_MB_2U_LIB.S9S_MB_2U(SCH_1):PAGE276

PVCCFA_EHV_FIVRA_CPU1_PVCC2 @S9S_MB_2U_LIB.S9S_MB_2U(SCH_1):PVCCFA_EHV_FIVRA_CPU1_PVCC2
PU76_P1_2    4   PVCC ISL99390FRZTR5935-ISL99390FRZ-A     I9 @S9S_MB_2U_LIB.S9S_MB_2U(SCH_1):PAGE275
PU78_P1_4    4   PVCC ISL99390FRZTR5935-ISL99390FRZ-A    I15 @S9S_MB_2U_LIB.S9S_MB_2U(SCH_1):PAGE276
PR1307    1      A Q_RES_0402LF-2.2,1%,1/16W,CHIPA    I18 @S9S_MB_2U_LIB.S9S_MB_2U(SCH_1):PAGE276
 PR227    1      A Q_RES_0402LF-2.2,1%,1/16W,CHIPA    I12 @S9S_MB_2U_LIB.S9S_MB_2U(SCH_1):PAGE275
 PR702    2      B Q_RES_0402LF-0,5%,1/16W,CHIP,CA    I13 @S9S_MB_2U_LIB.S9S_MB_2U(SCH_1):PAGE275
PC1243_P1_2    1      A Q_CAP_C0402-2.2UF,10V,10%,X6S,A    I16 @S9S_MB_2U_LIB.S9S_MB_2U(SCH_1):PAGE275
 PR704    2      B Q_RES_0402LF-0,5%,1/16W,EMPTY,A    I17 @S9S_MB_2U_LIB.S9S_MB_2U(SCH_1):PAGE275
PC1245_P1_4    1      A Q_CAP_C0402-2.2UF,10V,10%,X6S,A    I20 @S9S_MB_2U_LIB.S9S_MB_2U(SCH_1):PAGE276

PVCCFA_EHV_FIVRA_CPU1_PWM1 @S9S_MB_2U_LIB.S9S_MB_2U(SCH_1):PVCCFA_EHV_FIVRA_CPU1_PWM1
PU75_P1_1   34    PWM ISL99390FRZTR5935-ISL99390FRZ-A    I89 @S9S_MB_2U_LIB.S9S_MB_2U(SCH_1):PAGE275
  PU29    1   PWM0 RAA229126GNPHA0-RAA229126GNP#HA    I33 @S9S_MB_2U_LIB.S9S_MB_2U(SCH_1):PAGE270

PVCCFA_EHV_FIVRA_CPU1_PWM2 @S9S_MB_2U_LIB.S9S_MB_2U(SCH_1):PVCCFA_EHV_FIVRA_CPU1_PWM2
PU76_P1_2   34    PWM ISL99390FRZTR5935-ISL99390FRZ-A     I9 @S9S_MB_2U_LIB.S9S_MB_2U(SCH_1):PAGE275
  PU29    2   PWM1 RAA229126GNPHA0-RAA229126GNP#HA    I33 @S9S_MB_2U_LIB.S9S_MB_2U(SCH_1):PAGE270

PVCCFA_EHV_FIVRA_CPU1_PWM3 @S9S_MB_2U_LIB.S9S_MB_2U(SCH_1):PVCCFA_EHV_FIVRA_CPU1_PWM3
PU77_P1_3   34    PWM ISL99390FRZTR5935-ISL99390FRZ-A    I24 @S9S_MB_2U_LIB.S9S_MB_2U(SCH_1):PAGE276
  PU29    3   PWM2 RAA229126GNPHA0-RAA229126GNP#HA    I33 @S9S_MB_2U_LIB.S9S_MB_2U(SCH_1):PAGE270

PVCCFA_EHV_FIVRA_CPU1_PWM4 @S9S_MB_2U_LIB.S9S_MB_2U(SCH_1):PVCCFA_EHV_FIVRA_CPU1_PWM4
PU78_P1_4   34    PWM ISL99390FRZTR5935-ISL99390FRZ-A    I15 @S9S_MB_2U_LIB.S9S_MB_2U(SCH_1):PAGE276
  PU29    4   PWM3 RAA229126GNPHA0-RAA229126GNP#HA    I33 @S9S_MB_2U_LIB.S9S_MB_2U(SCH_1):PAGE270

PVCCFA_EHV_FIVRA_CPU1_VDD1 @S9S_MB_2U_LIB.S9S_MB_2U(SCH_1):PVCCFA_EHV_FIVRA_CPU1_VDD1
 PC395    1      A Q_CAP_C0402-2.2UF,10V,10%,X6S,A    I27 @S9S_MB_2U_LIB.S9S_MB_2U(SCH_1):PAGE275
 PR226    2      B Q_RES_0402LF-2.2,1%,1/16W,CHIPA    I28 @S9S_MB_2U_LIB.S9S_MB_2U(SCH_1):PAGE275
PU75_P1_1   35     EN ISL99390FRZTR5935-ISL99390FRZ-A    I89 @S9S_MB_2U_LIB.S9S_MB_2U(SCH_1):PAGE275
PU75_P1_1    3    VCC ISL99390FRZTR5935-ISL99390FRZ-A    I89 @S9S_MB_2U_LIB.S9S_MB_2U(SCH_1):PAGE275

PVCCFA_EHV_FIVRA_CPU1_VDD2 @S9S_MB_2U_LIB.S9S_MB_2U(SCH_1):PVCCFA_EHV_FIVRA_CPU1_VDD2
PU76_P1_2   35     EN ISL99390FRZTR5935-ISL99390FRZ-A     I9 @S9S_MB_2U_LIB.S9S_MB_2U(SCH_1):PAGE275
PU76_P1_2    3    VCC ISL99390FRZTR5935-ISL99390FRZ-A     I9 @S9S_MB_2U_LIB.S9S_MB_2U(SCH_1):PAGE275
 PC396    1      A Q_CAP_C0402-2.2UF,10V,10%,X6S,A    I11 @S9S_MB_2U_LIB.S9S_MB_2U(SCH_1):PAGE275
 PR227    2      B Q_RES_0402LF-2.2,1%,1/16W,CHIPA    I12 @S9S_MB_2U_LIB.S9S_MB_2U(SCH_1):PAGE275

PVCCFA_EHV_FIVRA_CPU1_VDD3 @S9S_MB_2U_LIB.S9S_MB_2U(SCH_1):PVCCFA_EHV_FIVRA_CPU1_VDD3
PC1191    1      A Q_CAP_C0402-2.2UF,10V,10%,X6S,A    I27 @S9S_MB_2U_LIB.S9S_MB_2U(SCH_1):PAGE276
PU77_P1_3   35     EN ISL99390FRZTR5935-ISL99390FRZ-A    I24 @S9S_MB_2U_LIB.S9S_MB_2U(SCH_1):PAGE276
PU77_P1_3    3    VCC ISL99390FRZTR5935-ISL99390FRZ-A    I24 @S9S_MB_2U_LIB.S9S_MB_2U(SCH_1):PAGE276
PR1306    2      B Q_RES_0402LF-2.2,1%,1/16W,CHIPA    I29 @S9S_MB_2U_LIB.S9S_MB_2U(SCH_1):PAGE276

PVCCFA_EHV_FIVRA_CPU1_VDD4 @S9S_MB_2U_LIB.S9S_MB_2U(SCH_1):PVCCFA_EHV_FIVRA_CPU1_VDD4
PU78_P1_4   35     EN ISL99390FRZTR5935-ISL99390FRZ-A    I15 @S9S_MB_2U_LIB.S9S_MB_2U(SCH_1):PAGE276
PU78_P1_4    3    VCC ISL99390FRZTR5935-ISL99390FRZ-A    I15 @S9S_MB_2U_LIB.S9S_MB_2U(SCH_1):PAGE276
PR1307    2      B Q_RES_0402LF-2.2,1%,1/16W,CHIPA    I18 @S9S_MB_2U_LIB.S9S_MB_2U(SCH_1):PAGE276
PC1192    1      A Q_CAP_C0402-2.2UF,10V,10%,X6S,A    I12 @S9S_MB_2U_LIB.S9S_MB_2U(SCH_1):PAGE276

PVCCFA_EHV_FIVRA_CPU1_VOS1 @S9S_MB_2U_LIB.S9S_MB_2U(SCH_1):PVCCFA_EHV_FIVRA_CPU1_VOS1
PR1331    1      A Q_RES_0402LF-0,5%,1/16W,CHIP,CA    I53 @S9S_MB_2U_LIB.S9S_MB_2U(SCH_1):PAGE275
PU75_P1_1    1    VOS ISL99390FRZTR5935-ISL99390FRZ-A    I89 @S9S_MB_2U_LIB.S9S_MB_2U(SCH_1):PAGE275

PVCCFA_EHV_FIVRA_CPU1_VOS2 @S9S_MB_2U_LIB.S9S_MB_2U(SCH_1):PVCCFA_EHV_FIVRA_CPU1_VOS2
PU76_P1_2    1    VOS ISL99390FRZTR5935-ISL99390FRZ-A     I9 @S9S_MB_2U_LIB.S9S_MB_2U(SCH_1):PAGE275
PR1332    1      A Q_RES_0402LF-0,5%,1/16W,CHIP,CA    I41 @S9S_MB_2U_LIB.S9S_MB_2U(SCH_1):PAGE275

PVCCFA_EHV_FIVRA_CPU1_VOS3 @S9S_MB_2U_LIB.S9S_MB_2U(SCH_1):PVCCFA_EHV_FIVRA_CPU1_VOS3
PU77_P1_3    1    VOS ISL99390FRZTR5935-ISL99390FRZ-A    I24 @S9S_MB_2U_LIB.S9S_MB_2U(SCH_1):PAGE276
PR1333    1      A Q_RES_0402LF-0,5%,1/16W,CHIP,CA    I54 @S9S_MB_2U_LIB.S9S_MB_2U(SCH_1):PAGE276

PVCCFA_EHV_FIVRA_CPU1_VOS4 @S9S_MB_2U_LIB.S9S_MB_2U(SCH_1):PVCCFA_EHV_FIVRA_CPU1_VOS4
PU78_P1_4    1    VOS ISL99390FRZTR5935-ISL99390FRZ-A    I15 @S9S_MB_2U_LIB.S9S_MB_2U(SCH_1):PAGE276
PR1334    1      A Q_RES_0402LF-0,5%,1/16W,CHIP,CA    I43 @S9S_MB_2U_LIB.S9S_MB_2U(SCH_1):PAGE276

PVCCINFAON_CPU0 @S9S_MB_2U_LIB.S9S_MB_2U(SCH_1):PVCCINFAON_CPU0
    U2 AY18 VCCINFAON33 SOCKET4677_AZIF0045P001C01CS-SA     I7 @S9S_MB_2U_LIB.S9S_MB_2U(SCH_1):PAGE37
    U2 BA15 VCCINFAON34 SOCKET4677_AZIF0045P001C01CS-SA     I7 @S9S_MB_2U_LIB.S9S_MB_2U(SCH_1):PAGE37
    U2 BC60 VCCINFAON35 SOCKET4677_AZIF0045P001C01CS-SA     I7 @S9S_MB_2U_LIB.S9S_MB_2U(SCH_1):PAGE37
    U2 BE15 VCCINFAON36 SOCKET4677_AZIF0045P001C01CS-SA     I7 @S9S_MB_2U_LIB.S9S_MB_2U(SCH_1):PAGE37
    U2 BE60 VCCINFAON37 SOCKET4677_AZIF0045P001C01CS-SA     I7 @S9S_MB_2U_LIB.S9S_MB_2U(SCH_1):PAGE37
    U2 BG60 VCCINFAON38 SOCKET4677_AZIF0045P001C01CS-SA     I7 @S9S_MB_2U_LIB.S9S_MB_2U(SCH_1):PAGE37
    U2 BJ15 VCCINFAON39 SOCKET4677_AZIF0045P001C01CS-SA     I7 @S9S_MB_2U_LIB.S9S_MB_2U(SCH_1):PAGE37
    U2 BJ60 VCCINFAON40 SOCKET4677_AZIF0045P001C01CS-SA     I7 @S9S_MB_2U_LIB.S9S_MB_2U(SCH_1):PAGE37
    U2 BK61 VCCINFAON41 SOCKET4677_AZIF0045P001C01CS-SA     I7 @S9S_MB_2U_LIB.S9S_MB_2U(SCH_1):PAGE37
    U2 BN15 VCCINFAON42 SOCKET4677_AZIF0045P001C01CS-SA     I7 @S9S_MB_2U_LIB.S9S_MB_2U(SCH_1):PAGE37
    U2 CA15 VCCINFAON43 SOCKET4677_AZIF0045P001C01CS-SA     I7 @S9S_MB_2U_LIB.S9S_MB_2U(SCH_1):PAGE37
    U2 CE19 VCCINFAON44 SOCKET4677_AZIF0045P001C01CS-SA     I7 @S9S_MB_2U_LIB.S9S_MB_2U(SCH_1):PAGE37
    U2 CJ11 VCCINFAON45 SOCKET4677_AZIF0045P001C01CS-SA     I7 @S9S_MB_2U_LIB.S9S_MB_2U(SCH_1):PAGE37
    U2 CJ19 VCCINFAON46 SOCKET4677_AZIF0045P001C01CS-SA     I7 @S9S_MB_2U_LIB.S9S_MB_2U(SCH_1):PAGE37
    U2 CN19 VCCINFAON47 SOCKET4677_AZIF0045P001C01CS-SA     I7 @S9S_MB_2U_LIB.S9S_MB_2U(SCH_1):PAGE37
    U2 CP63 VCCINFAON48 SOCKET4677_AZIF0045P001C01CS-SA     I7 @S9S_MB_2U_LIB.S9S_MB_2U(SCH_1):PAGE37
    U2 CT63 VCCINFAON49 SOCKET4677_AZIF0045P001C01CS-SA     I7 @S9S_MB_2U_LIB.S9S_MB_2U(SCH_1):PAGE37
    U2 CV61 VCCINFAON50 SOCKET4677_AZIF0045P001C01CS-SA     I7 @S9S_MB_2U_LIB.S9S_MB_2U(SCH_1):PAGE37
    U2 CV63 VCCINFAON51 SOCKET4677_AZIF0045P001C01CS-SA     I7 @S9S_MB_2U_LIB.S9S_MB_2U(SCH_1):PAGE37
    U2 CW62 VCCINFAON52 SOCKET4677_AZIF0045P001C01CS-SA     I7 @S9S_MB_2U_LIB.S9S_MB_2U(SCH_1):PAGE37
    U2 DA21 VCCINFAON53 SOCKET4677_AZIF0045P001C01CS-SA     I7 @S9S_MB_2U_LIB.S9S_MB_2U(SCH_1):PAGE37
    U2 CE15 VCCINFAON0 SOCKET4677_AZIF0045P001C01CS-SA     I8 @S9S_MB_2U_LIB.S9S_MB_2U(SCH_1):PAGE37
    U2 CJ15 VCCINFAON1 SOCKET4677_AZIF0045P001C01CS-SA     I8 @S9S_MB_2U_LIB.S9S_MB_2U(SCH_1):PAGE37
    U2  CJ3 VCCINFAON2 SOCKET4677_AZIF0045P001C01CS-SA     I8 @S9S_MB_2U_LIB.S9S_MB_2U(SCH_1):PAGE37
    U2  CJ7 VCCINFAON3 SOCKET4677_AZIF0045P001C01CS-SA     I8 @S9S_MB_2U_LIB.S9S_MB_2U(SCH_1):PAGE37
    U2 CN11 VCCINFAON4 SOCKET4677_AZIF0045P001C01CS-SA     I8 @S9S_MB_2U_LIB.S9S_MB_2U(SCH_1):PAGE37
    U2 CN15 VCCINFAON5 SOCKET4677_AZIF0045P001C01CS-SA     I8 @S9S_MB_2U_LIB.S9S_MB_2U(SCH_1):PAGE37
    U2  CN3 VCCINFAON6 SOCKET4677_AZIF0045P001C01CS-SA     I8 @S9S_MB_2U_LIB.S9S_MB_2U(SCH_1):PAGE37
    U2 CN64 VCCINFAON7 SOCKET4677_AZIF0045P001C01CS-SA     I8 @S9S_MB_2U_LIB.S9S_MB_2U(SCH_1):PAGE37
    U2 CN66 VCCINFAON8 SOCKET4677_AZIF0045P001C01CS-SA     I8 @S9S_MB_2U_LIB.S9S_MB_2U(SCH_1):PAGE37
    U2  CN7 VCCINFAON9 SOCKET4677_AZIF0045P001C01CS-SA     I8 @S9S_MB_2U_LIB.S9S_MB_2U(SCH_1):PAGE37
    U2 CP65 VCCINFAON10 SOCKET4677_AZIF0045P001C01CS-SA     I8 @S9S_MB_2U_LIB.S9S_MB_2U(SCH_1):PAGE37
    U2 CP67 VCCINFAON11 SOCKET4677_AZIF0045P001C01CS-SA     I8 @S9S_MB_2U_LIB.S9S_MB_2U(SCH_1):PAGE37
    U2 CT65 VCCINFAON12 SOCKET4677_AZIF0045P001C01CS-SA     I8 @S9S_MB_2U_LIB.S9S_MB_2U(SCH_1):PAGE37
    U2 CT67 VCCINFAON13 SOCKET4677_AZIF0045P001C01CS-SA     I8 @S9S_MB_2U_LIB.S9S_MB_2U(SCH_1):PAGE37
    U2 CU11 VCCINFAON14 SOCKET4677_AZIF0045P001C01CS-SA     I8 @S9S_MB_2U_LIB.S9S_MB_2U(SCH_1):PAGE37
    U2 CU15 VCCINFAON15 SOCKET4677_AZIF0045P001C01CS-SA     I8 @S9S_MB_2U_LIB.S9S_MB_2U(SCH_1):PAGE37
    U2  CU3 VCCINFAON16 SOCKET4677_AZIF0045P001C01CS-SA     I8 @S9S_MB_2U_LIB.S9S_MB_2U(SCH_1):PAGE37
    U2 CU64 VCCINFAON17 SOCKET4677_AZIF0045P001C01CS-SA     I8 @S9S_MB_2U_LIB.S9S_MB_2U(SCH_1):PAGE37
    U2  CU7 VCCINFAON18 SOCKET4677_AZIF0045P001C01CS-SA     I8 @S9S_MB_2U_LIB.S9S_MB_2U(SCH_1):PAGE37
    U2 CV65 VCCINFAON19 SOCKET4677_AZIF0045P001C01CS-SA     I8 @S9S_MB_2U_LIB.S9S_MB_2U(SCH_1):PAGE37
    U2 CV67 VCCINFAON20 SOCKET4677_AZIF0045P001C01CS-SA     I8 @S9S_MB_2U_LIB.S9S_MB_2U(SCH_1):PAGE37
    U2 CW66 VCCINFAON21 SOCKET4677_AZIF0045P001C01CS-SA     I8 @S9S_MB_2U_LIB.S9S_MB_2U(SCH_1):PAGE37
    U2 CY65 VCCINFAON22 SOCKET4677_AZIF0045P001C01CS-SA     I8 @S9S_MB_2U_LIB.S9S_MB_2U(SCH_1):PAGE37
    U2 CY67 VCCINFAON23 SOCKET4677_AZIF0045P001C01CS-SA     I8 @S9S_MB_2U_LIB.S9S_MB_2U(SCH_1):PAGE37
    U2 DA11 VCCINFAON24 SOCKET4677_AZIF0045P001C01CS-SA     I8 @S9S_MB_2U_LIB.S9S_MB_2U(SCH_1):PAGE37
    U2 DA15 VCCINFAON25 SOCKET4677_AZIF0045P001C01CS-SA     I8 @S9S_MB_2U_LIB.S9S_MB_2U(SCH_1):PAGE37
    U2 DA64 VCCINFAON26 SOCKET4677_AZIF0045P001C01CS-SA     I8 @S9S_MB_2U_LIB.S9S_MB_2U(SCH_1):PAGE37
    U2 DE11 VCCINFAON27 SOCKET4677_AZIF0045P001C01CS-SA     I8 @S9S_MB_2U_LIB.S9S_MB_2U(SCH_1):PAGE37
    U2 DE15 VCCINFAON28 SOCKET4677_AZIF0045P001C01CS-SA     I8 @S9S_MB_2U_LIB.S9S_MB_2U(SCH_1):PAGE37
    U2  DE3 VCCINFAON29 SOCKET4677_AZIF0045P001C01CS-SA     I8 @S9S_MB_2U_LIB.S9S_MB_2U(SCH_1):PAGE37
    U2 DJ15 VCCINFAON30 SOCKET4677_AZIF0045P001C01CS-SA     I8 @S9S_MB_2U_LIB.S9S_MB_2U(SCH_1):PAGE37
    U2  DJ3 VCCINFAON31 SOCKET4677_AZIF0045P001C01CS-SA     I8 @S9S_MB_2U_LIB.S9S_MB_2U(SCH_1):PAGE37
    U2  DJ7 VCCINFAON32 SOCKET4677_AZIF0045P001C01CS-SA     I8 @S9S_MB_2U_LIB.S9S_MB_2U(SCH_1):PAGE37
    U2 CR66 VCCINFAON54 SOCKET4677_AZIF0045P001C01CS-SA     I8 @S9S_MB_2U_LIB.S9S_MB_2U(SCH_1):PAGE37
    U2 CW64 VCCINFAON55 SOCKET4677_AZIF0045P001C01CS-SA     I8 @S9S_MB_2U_LIB.S9S_MB_2U(SCH_1):PAGE37
    U2  DA3 VCCINFAON56 SOCKET4677_AZIF0045P001C01CS-SA     I8 @S9S_MB_2U_LIB.S9S_MB_2U(SCH_1):PAGE37
    U2  DA7 VCCINFAON57 SOCKET4677_AZIF0045P001C01CS-SA     I8 @S9S_MB_2U_LIB.S9S_MB_2U(SCH_1):PAGE37
    U2  DE7 VCCINFAON58 SOCKET4677_AZIF0045P001C01CS-SA     I8 @S9S_MB_2U_LIB.S9S_MB_2U(SCH_1):PAGE37
    U2 DJ11 VCCINFAON59 SOCKET4677_AZIF0045P001C01CS-SA     I8 @S9S_MB_2U_LIB.S9S_MB_2U(SCH_1):PAGE37
  C410    1      A Q_CAP_C0402-22UF,4V,20%,X6S,CHA    I41 @S9S_MB_2U_LIB.S9S_MB_2U(SCH_1):PAGE74
  C412    1      A Q_CAP_C0402-22UF,4V,20%,X6S,CHA    I42 @S9S_MB_2U_LIB.S9S_MB_2U(SCH_1):PAGE74
  C414    1      A Q_CAP_C0402-22UF,4V,20%,X6S,CHA    I70 @S9S_MB_2U_LIB.S9S_MB_2U(SCH_1):PAGE74
  C416    1      A Q_CAP_C0402-22UF,4V,20%,X6S,CHA    I72 @S9S_MB_2U_LIB.S9S_MB_2U(SCH_1):PAGE74
  C408    1      A Q_CAP_C0402-22UF,4V,20%,X6S,CHA   I142 @S9S_MB_2U_LIB.S9S_MB_2U(SCH_1):PAGE74
  C532    1      A Q_CAP_C0603-47UF,2.5V,20%,X6S,A    I14 @S9S_MB_2U_LIB.S9S_MB_2U(SCH_1):PAGE75
  C528    1      A Q_CAP_C0805-47UF,4V,20%,X6S,CHA     I6 @S9S_MB_2U_LIB.S9S_MB_2U(SCH_1):PAGE76
  C530    1      A Q_CAP_C0805-47UF,4V,20%,X6S,CHA     I7 @S9S_MB_2U_LIB.S9S_MB_2U(SCH_1):PAGE76
  C531    1      A Q_CAP_C0805-47UF,4V,20%,X6S,CHA    I31 @S9S_MB_2U_LIB.S9S_MB_2U(SCH_1):PAGE76
  C522    1      A Q_CAP_C0805-47UF,4V,20%,X6S,CHA     I9 @S9S_MB_2U_LIB.S9S_MB_2U(SCH_1):PAGE75
  C533    1      A Q_CAP_C0603-47UF,2.5V,20%,X6S,A    I17 @S9S_MB_2U_LIB.S9S_MB_2U(SCH_1):PAGE75
  C534    1      A Q_CAP_C0402-22UF,4V,20%,X6S,CHA    I29 @S9S_MB_2U_LIB.S9S_MB_2U(SCH_1):PAGE75
  C525    1      A Q_CAP_C0805-47UF,4V,20%,X6S,CHA     I5 @S9S_MB_2U_LIB.S9S_MB_2U(SCH_1):PAGE76
  R323    1      A Q_RES_1206LF-0,,1/2W,EMPTY,CS0A    I13 @S9S_MB_2U_LIB.S9S_MB_2U(SCH_1):PAGE80
 PR521    2      B Q_RES_0402LF-100,1%,1/16W,CHIPA    I44 @S9S_MB_2U_LIB.S9S_MB_2U(SCH_1):PAGE260
PR1777    2      B Q_RES_0402LF-0,5%,1/16W,CHIP,CA    I31 @S9S_MB_2U_LIB.S9S_MB_2U(SCH_1):PAGE261
   PL5    2      2 Q_INDUCTOR_SMLF-120NH/69A,IND,A    I39 @S9S_MB_2U_LIB.S9S_MB_2U(SCH_1):PAGE261
PC203_P0_2    1      A Q_CAP_C0805-22UF,4V,20%,X6S,CHA    I40 @S9S_MB_2U_LIB.S9S_MB_2U(SCH_1):PAGE261
PR1776    2      B Q_RES_0402LF-0,5%,1/16W,CHIP,CA    I46 @S9S_MB_2U_LIB.S9S_MB_2U(SCH_1):PAGE261
   PL4    2      2 Q_INDUCTOR_SMLF-120NH/69A,IND,A    I52 @S9S_MB_2U_LIB.S9S_MB_2U(SCH_1):PAGE261
PC202_P0_1    1      A Q_CAP_C0805-22UF,4V,20%,X6S,CHA    I56 @S9S_MB_2U_LIB.S9S_MB_2U(SCH_1):PAGE261
PC1574    1      A Q_CAPP_THLF-560UF,2.5V,20%,OSCA    I66 @S9S_MB_2U_LIB.S9S_MB_2U(SCH_1):PAGE261
PC1576    1      A Q_CAPP_THLF-560UF,2.5V,20%,OSCA    I67 @S9S_MB_2U_LIB.S9S_MB_2U(SCH_1):PAGE261
PC1573    1      A Q_CAPP_SMLF-330UF,2V,35%,SPCAPA    I68 @S9S_MB_2U_LIB.S9S_MB_2U(SCH_1):PAGE261
PC205_P0_2    1      A Q_CAP_C0805-22UF,4V,20%,X6S,CHA    I41 @S9S_MB_2U_LIB.S9S_MB_2U(SCH_1):PAGE261
PC1575    1      A Q_CAPP_SMLF-330UF,2V,35%,SPCAPA    I69 @S9S_MB_2U_LIB.S9S_MB_2U(SCH_1):PAGE261
PC199_P0_1    1      A Q_CAP_C0402-100NF,50V,10%,X7R,A    I54 @S9S_MB_2U_LIB.S9S_MB_2U(SCH_1):PAGE261
PC204_P0_1    1      A Q_CAP_C0805-22UF,4V,20%,X6S,CHA    I57 @S9S_MB_2U_LIB.S9S_MB_2U(SCH_1):PAGE261
PR4226    1      A Q_RES_0402LF-499,1%,1/16W,CHIPA    I63 @S9S_MB_2U_LIB.S9S_MB_2U(SCH_1):PAGE261
PC1579    1      A Q_CAPP_THLF-560UF,2.5V,20%,OSCA    I70 @S9S_MB_2U_LIB.S9S_MB_2U(SCH_1):PAGE261

PVCCINFAON_CPU0_ACSP1 @S9S_MB_2U_LIB.S9S_MB_2U(SCH_1):PVCCINFAON_CPU0_ACSP1
   PU5   23    CS7 ISL69260IRAZT-ISL69260IRAZ-T,SA    I65 @S9S_MB_2U_LIB.S9S_MB_2U(SCH_1):PAGE260
PU43_P0_1   38   IOUT ISL99390FRZTR5935-ISL99390FRZ-A    I79 @S9S_MB_2U_LIB.S9S_MB_2U(SCH_1):PAGE261

PVCCINFAON_CPU0_ACSP2 @S9S_MB_2U_LIB.S9S_MB_2U(SCH_1):PVCCINFAON_CPU0_ACSP2
   PU5   24    CS6 ISL69260IRAZT-ISL69260IRAZ-T,SA    I65 @S9S_MB_2U_LIB.S9S_MB_2U(SCH_1):PAGE260
PU44_P0_2   38   IOUT ISL99390FRZTR5935-ISL99390FRZ-A    I12 @S9S_MB_2U_LIB.S9S_MB_2U(SCH_1):PAGE261

PVCCINFAON_CPU0_ADDR @S9S_MB_2U_LIB.S9S_MB_2U(SCH_1):PVCCINFAON_CPU0_ADDR
   PU5   34 ADDR_CFG ISL69260IRAZT-ISL69260IRAZ-T,SA    I65 @S9S_MB_2U_LIB.S9S_MB_2U(SCH_1):PAGE260
 PR105    2      B Q_RES_0402LF-28K,1%,1/16W,EMPTA     I7 @S9S_MB_2U_LIB.S9S_MB_2U(SCH_1):PAGE260
 PR106    1      A Q_RES_0402LF-681,1%,1/16W,CHIPA   I109 @S9S_MB_2U_LIB.S9S_MB_2U(SCH_1):PAGE260

PVCCINFAON_CPU0_APWM1 @S9S_MB_2U_LIB.S9S_MB_2U(SCH_1):PVCCINFAON_CPU0_APWM1
   PU5    8   PWM7 ISL69260IRAZT-ISL69260IRAZ-T,SA    I65 @S9S_MB_2U_LIB.S9S_MB_2U(SCH_1):PAGE260
PU43_P0_1   34    PWM ISL99390FRZTR5935-ISL99390FRZ-A    I79 @S9S_MB_2U_LIB.S9S_MB_2U(SCH_1):PAGE261

PVCCINFAON_CPU0_APWM2 @S9S_MB_2U_LIB.S9S_MB_2U(SCH_1):PVCCINFAON_CPU0_APWM2
   PU5    7   PWM6 ISL69260IRAZT-ISL69260IRAZ-T,SA    I65 @S9S_MB_2U_LIB.S9S_MB_2U(SCH_1):PAGE260
PU44_P0_2   34    PWM ISL99390FRZTR5935-ISL99390FRZ-A    I12 @S9S_MB_2U_LIB.S9S_MB_2U(SCH_1):PAGE261

PVCCINFAON_CPU0_ATSEN @S9S_MB_2U_LIB.S9S_MB_2U(SCH_1):PVCCINFAON_CPU0_ATSEN
   PU5   35  TEMP0 ISL69260IRAZT-ISL69260IRAZ-T,SA    I65 @S9S_MB_2U_LIB.S9S_MB_2U(SCH_1):PAGE260
PU44_P0_2   36 TOUT_FLT ISL99390FRZTR5935-ISL99390FRZ-A    I12 @S9S_MB_2U_LIB.S9S_MB_2U(SCH_1):PAGE261
PU43_P0_1   36 TOUT_FLT ISL99390FRZTR5935-ISL99390FRZ-A    I79 @S9S_MB_2U_LIB.S9S_MB_2U(SCH_1):PAGE261
 PC222    1      A Q_CAP_0402-470PF,50V,10%,X7R,TA    I69 @S9S_MB_2U_LIB.S9S_MB_2U(SCH_1):PAGE260
 PR435    1      A Q_RES_0402LF-10K,1%,1/16W,EMPTA    I71 @S9S_MB_2U_LIB.S9S_MB_2U(SCH_1):PAGE260

PVCCINFAON_CPU0_CSPIN @S9S_MB_2U_LIB.S9S_MB_2U(SCH_1):PVCCINFAON_CPU0_CSPIN
   PU5   37 VMON||IINSEN||VSYS||ISYS ISL69260IRAZT-ISL69260IRAZ-T,SA    I65 @S9S_MB_2U_LIB.S9S_MB_2U(SCH_1):PAGE260
 PR107    2      B Q_RES_0402LF-0,5%,1/16W,EMPTY,A    I10 @S9S_MB_2U_LIB.S9S_MB_2U(SCH_1):PAGE260
PR4220    1      A Q_RES_0402LF-0,5%,1/16W,CHIP,CA    I19 @S9S_MB_2U_LIB.S9S_MB_2U(SCH_1):PAGE260
 PC214    1      A Q_CAP_0402-0.1UF,25V,10%,EMPTYA    I20 @S9S_MB_2U_LIB.S9S_MB_2U(SCH_1):PAGE260

PVCCINFAON_CPU0_EN_R @S9S_MB_2U_LIB.S9S_MB_2U(SCH_1):PVCCINFAON_CPU0_EN_R
 C3274    1      A Q_CAP_0402-1000PF,50V,5%,X7R,TA    I60 @S9S_MB_2U_LIB.S9S_MB_2U(SCH_1):PAGE260
   PU5   13    EN0 ISL69260IRAZT-ISL69260IRAZ-T,SA    I65 @S9S_MB_2U_LIB.S9S_MB_2U(SCH_1):PAGE260
 R2594    2      B Q_RES_0402LF-0,5%,1/16W,CHIP,CA    I55 @S9S_MB_2U_LIB.S9S_MB_2U(SCH_1):PAGE260

PVCCINFAON_CPU0_LSET1 @S9S_MB_2U_LIB.S9S_MB_2U(SCH_1):PVCCINFAON_CPU0_LSET1
PU43_P0_1   37   LSET ISL99390FRZTR5935-ISL99390FRZ-A    I79 @S9S_MB_2U_LIB.S9S_MB_2U(SCH_1):PAGE261
PR1708    1      A Q_RES_0402LF-8.87K,1%,1/16W,EMA     I5 @S9S_MB_2U_LIB.S9S_MB_2U(SCH_1):PAGE261

PVCCINFAON_CPU0_LSET2 @S9S_MB_2U_LIB.S9S_MB_2U(SCH_1):PVCCINFAON_CPU0_LSET2
PU44_P0_2   37   LSET ISL99390FRZTR5935-ISL99390FRZ-A    I12 @S9S_MB_2U_LIB.S9S_MB_2U(SCH_1):PAGE261
PR1707    1      A Q_RES_0402LF-8.87K,1%,1/16W,EMA     I2 @S9S_MB_2U_LIB.S9S_MB_2U(SCH_1):PAGE261

PVCCINFAON_CPU0_PIN_ALERT @S9S_MB_2U_LIB.S9S_MB_2U(SCH_1):PVCCINFAON_CPU0_PIN_ALERT
   PU5   15 NPINALERT#||NPSYSCRIT# ISL69260IRAZT-ISL69260IRAZ-T,SA    I65 @S9S_MB_2U_LIB.S9S_MB_2U(SCH_1):PAGE260
 R2393    2      B Q_RES_0402LF-1K,1%,1/16W,CHIP,A    I17 @S9S_MB_2U_LIB.S9S_MB_2U(SCH_1):PAGE260

PVCCINFAON_CPU0_VCC @S9S_MB_2U_LIB.S9S_MB_2U(SCH_1):PVCCINFAON_CPU0_VCC
   PU5   39    VCC ISL69260IRAZT-ISL69260IRAZ-T,SA    I65 @S9S_MB_2U_LIB.S9S_MB_2U(SCH_1):PAGE260
 PC223    1      A Q_CAP_C0402-100NF,50V,10%,EMPTA    I98 @S9S_MB_2U_LIB.S9S_MB_2U(SCH_1):PAGE260
 PC225    1      A Q_CAP_C0402-1UF,16V,10%,X6S,CHA    I99 @S9S_MB_2U_LIB.S9S_MB_2U(SCH_1):PAGE260
 PR130    1      A Q_RES_0402LF-1,1%,1/16W,CHIP,CA   I100 @S9S_MB_2U_LIB.S9S_MB_2U(SCH_1):PAGE260
PC2362    1      A Q_CAP_0402-0.1UF,25V,10%,EMPTYA   I110 @S9S_MB_2U_LIB.S9S_MB_2U(SCH_1):PAGE260

PVCCINFAON_CPU0_VDD1 @S9S_MB_2U_LIB.S9S_MB_2U(SCH_1):PVCCINFAON_CPU0_VDD1
 PR101    2      B Q_RES_0402LF-2.2,1%,1/16W,CHIPA    I26 @S9S_MB_2U_LIB.S9S_MB_2U(SCH_1):PAGE261
PU43_P0_1   35     EN ISL99390FRZTR5935-ISL99390FRZ-A    I79 @S9S_MB_2U_LIB.S9S_MB_2U(SCH_1):PAGE261
PU43_P0_1    3    VCC ISL99390FRZTR5935-ISL99390FRZ-A    I79 @S9S_MB_2U_LIB.S9S_MB_2U(SCH_1):PAGE261
 PC187    1      A Q_CAP_C0402-2.2UF,10V,10%,X6S,A    I24 @S9S_MB_2U_LIB.S9S_MB_2U(SCH_1):PAGE261

PVCCINFAON_CPU0_VDD2 @S9S_MB_2U_LIB.S9S_MB_2U(SCH_1):PVCCINFAON_CPU0_VDD2
PU44_P0_2   35     EN ISL99390FRZTR5935-ISL99390FRZ-A    I12 @S9S_MB_2U_LIB.S9S_MB_2U(SCH_1):PAGE261
PU44_P0_2    3    VCC ISL99390FRZTR5935-ISL99390FRZ-A    I12 @S9S_MB_2U_LIB.S9S_MB_2U(SCH_1):PAGE261
 PR102    2      B Q_RES_0402LF-2.2,1%,1/16W,CHIPA    I14 @S9S_MB_2U_LIB.S9S_MB_2U(SCH_1):PAGE261
 PC188    1      A Q_CAP_C0402-2.2UF,10V,10%,X6S,A    I13 @S9S_MB_2U_LIB.S9S_MB_2U(SCH_1):PAGE261

PVCCINFAON_CPU0_VIN_CSNIN @S9S_MB_2U_LIB.S9S_MB_2U(SCH_1):PVCCINFAON_CPU0_VIN_CSNIN
   PU5   38 VINSEN||VSYS ISL69260IRAZT-ISL69260IRAZ-T,SA    I65 @S9S_MB_2U_LIB.S9S_MB_2U(SCH_1):PAGE260
 PC221    1      A Q_CAP_0402-0.1UF,25V,10%,X7R,CA    I63 @S9S_MB_2U_LIB.S9S_MB_2U(SCH_1):PAGE260
 PR108    2      B Q_RES_0402LF-0,5%,1/16W,CHIP,CA     I9 @S9S_MB_2U_LIB.S9S_MB_2U(SCH_1):PAGE260
 PR123    1      A Q_RES_0402LF-1K,1%,1/16W,EMPTYA    I21 @S9S_MB_2U_LIB.S9S_MB_2U(SCH_1):PAGE260

PVCCINFAON_CPU0_VOS1 @S9S_MB_2U_LIB.S9S_MB_2U(SCH_1):PVCCINFAON_CPU0_VOS1
PR1776    1      A Q_RES_0402LF-0,5%,1/16W,CHIP,CA    I46 @S9S_MB_2U_LIB.S9S_MB_2U(SCH_1):PAGE261
PU43_P0_1    1    VOS ISL99390FRZTR5935-ISL99390FRZ-A    I79 @S9S_MB_2U_LIB.S9S_MB_2U(SCH_1):PAGE261

PVCCINFAON_CPU0_VOS2 @S9S_MB_2U_LIB.S9S_MB_2U(SCH_1):PVCCINFAON_CPU0_VOS2
PU44_P0_2    1    VOS ISL99390FRZTR5935-ISL99390FRZ-A    I12 @S9S_MB_2U_LIB.S9S_MB_2U(SCH_1):PAGE261
PR1777    1      A Q_RES_0402LF-0,5%,1/16W,CHIP,CA    I31 @S9S_MB_2U_LIB.S9S_MB_2U(SCH_1):PAGE261

PVCCINFAON_CPU0_VREF @S9S_MB_2U_LIB.S9S_MB_2U(SCH_1):PVCCINFAON_CPU0_VREF
   PU5   40   VCCS ISL69260IRAZT-ISL69260IRAZ-T,SA    I65 @S9S_MB_2U_LIB.S9S_MB_2U(SCH_1):PAGE260
PU44_P0_2   39  REFIN ISL99390FRZTR5935-ISL99390FRZ-A    I12 @S9S_MB_2U_LIB.S9S_MB_2U(SCH_1):PAGE261
PC1347    2      B Q_CAP_0402-0.1UF,25V,10%,X7R,CA    I25 @S9S_MB_2U_LIB.S9S_MB_2U(SCH_1):PAGE261
PU43_P0_1   39  REFIN ISL99390FRZTR5935-ISL99390FRZ-A    I79 @S9S_MB_2U_LIB.S9S_MB_2U(SCH_1):PAGE261
 PC224    1      A Q_CAP_C0402-10UF,6.3V,20%,X6S,B    I92 @S9S_MB_2U_LIB.S9S_MB_2U(SCH_1):PAGE260
PC1348    2      B Q_CAP_0402-0.1UF,25V,10%,X7R,CA    I10 @S9S_MB_2U_LIB.S9S_MB_2U(SCH_1):PAGE262
  PU42   24  REFIN RAA2213404GNPHB0-RAA2213404GNPA    I14 @S9S_MB_2U_LIB.S9S_MB_2U(SCH_1):PAGE262
PC1346    2      B Q_CAP_0402-0.1UF,25V,10%,X7R,CA    I11 @S9S_MB_2U_LIB.S9S_MB_2U(SCH_1):PAGE261
 PR105    1      A Q_RES_0402LF-28K,1%,1/16W,EMPTA     I7 @S9S_MB_2U_LIB.S9S_MB_2U(SCH_1):PAGE260
PC1372    1      A Q_CAP_C0402-1UF,16V,10%,X6S,CHA    I95 @S9S_MB_2U_LIB.S9S_MB_2U(SCH_1):PAGE260

PVCCINFAON_CPU0_VR_FAULT @S9S_MB_2U_LIB.S9S_MB_2U(SCH_1):PVCCINFAON_CPU0_VR_FAULT
   PU5   33    CFP ISL69260IRAZT-ISL69260IRAZ-T,SA    I65 @S9S_MB_2U_LIB.S9S_MB_2U(SCH_1):PAGE260
 R2392    2      B Q_RES_0402LF-1K,1%,1/16W,CHIP,A    I18 @S9S_MB_2U_LIB.S9S_MB_2U(SCH_1):PAGE260

PVCCINFAON_CPU1 @S9S_MB_2U_LIB.S9S_MB_2U(SCH_1):PVCCINFAON_CPU1
    U1 AY18 VCCINFAON33 SOCKET4677_AZIF0045P001C01CS-SA     I1 @S9S_MB_2U_LIB.S9S_MB_2U(SCH_1):PAGE68
    U1 BA15 VCCINFAON34 SOCKET4677_AZIF0045P001C01CS-SA     I1 @S9S_MB_2U_LIB.S9S_MB_2U(SCH_1):PAGE68
    U1 BC60 VCCINFAON35 SOCKET4677_AZIF0045P001C01CS-SA     I1 @S9S_MB_2U_LIB.S9S_MB_2U(SCH_1):PAGE68
    U1 BE15 VCCINFAON36 SOCKET4677_AZIF0045P001C01CS-SA     I1 @S9S_MB_2U_LIB.S9S_MB_2U(SCH_1):PAGE68
    U1 BE60 VCCINFAON37 SOCKET4677_AZIF0045P001C01CS-SA     I1 @S9S_MB_2U_LIB.S9S_MB_2U(SCH_1):PAGE68
    U1 BG60 VCCINFAON38 SOCKET4677_AZIF0045P001C01CS-SA     I1 @S9S_MB_2U_LIB.S9S_MB_2U(SCH_1):PAGE68
    U1 BJ15 VCCINFAON39 SOCKET4677_AZIF0045P001C01CS-SA     I1 @S9S_MB_2U_LIB.S9S_MB_2U(SCH_1):PAGE68
    U1 BJ60 VCCINFAON40 SOCKET4677_AZIF0045P001C01CS-SA     I1 @S9S_MB_2U_LIB.S9S_MB_2U(SCH_1):PAGE68
    U1 BK61 VCCINFAON41 SOCKET4677_AZIF0045P001C01CS-SA     I1 @S9S_MB_2U_LIB.S9S_MB_2U(SCH_1):PAGE68
    U1 BN15 VCCINFAON42 SOCKET4677_AZIF0045P001C01CS-SA     I1 @S9S_MB_2U_LIB.S9S_MB_2U(SCH_1):PAGE68
    U1 CA15 VCCINFAON43 SOCKET4677_AZIF0045P001C01CS-SA     I1 @S9S_MB_2U_LIB.S9S_MB_2U(SCH_1):PAGE68
    U1 CE19 VCCINFAON44 SOCKET4677_AZIF0045P001C01CS-SA     I1 @S9S_MB_2U_LIB.S9S_MB_2U(SCH_1):PAGE68
    U1 CJ11 VCCINFAON45 SOCKET4677_AZIF0045P001C01CS-SA     I1 @S9S_MB_2U_LIB.S9S_MB_2U(SCH_1):PAGE68
    U1 CJ19 VCCINFAON46 SOCKET4677_AZIF0045P001C01CS-SA     I1 @S9S_MB_2U_LIB.S9S_MB_2U(SCH_1):PAGE68
    U1 CN19 VCCINFAON47 SOCKET4677_AZIF0045P001C01CS-SA     I1 @S9S_MB_2U_LIB.S9S_MB_2U(SCH_1):PAGE68
    U1 CP63 VCCINFAON48 SOCKET4677_AZIF0045P001C01CS-SA     I1 @S9S_MB_2U_LIB.S9S_MB_2U(SCH_1):PAGE68
    U1 CT63 VCCINFAON49 SOCKET4677_AZIF0045P001C01CS-SA     I1 @S9S_MB_2U_LIB.S9S_MB_2U(SCH_1):PAGE68
    U1 CV61 VCCINFAON50 SOCKET4677_AZIF0045P001C01CS-SA     I1 @S9S_MB_2U_LIB.S9S_MB_2U(SCH_1):PAGE68
    U1 CV63 VCCINFAON51 SOCKET4677_AZIF0045P001C01CS-SA     I1 @S9S_MB_2U_LIB.S9S_MB_2U(SCH_1):PAGE68
    U1 CW62 VCCINFAON52 SOCKET4677_AZIF0045P001C01CS-SA     I1 @S9S_MB_2U_LIB.S9S_MB_2U(SCH_1):PAGE68
    U1 DA21 VCCINFAON53 SOCKET4677_AZIF0045P001C01CS-SA     I1 @S9S_MB_2U_LIB.S9S_MB_2U(SCH_1):PAGE68
    U1 CE15 VCCINFAON0 SOCKET4677_AZIF0045P001C01CS-SA     I8 @S9S_MB_2U_LIB.S9S_MB_2U(SCH_1):PAGE68
    U1 CJ15 VCCINFAON1 SOCKET4677_AZIF0045P001C01CS-SA     I8 @S9S_MB_2U_LIB.S9S_MB_2U(SCH_1):PAGE68
    U1  CJ3 VCCINFAON2 SOCKET4677_AZIF0045P001C01CS-SA     I8 @S9S_MB_2U_LIB.S9S_MB_2U(SCH_1):PAGE68
    U1  CJ7 VCCINFAON3 SOCKET4677_AZIF0045P001C01CS-SA     I8 @S9S_MB_2U_LIB.S9S_MB_2U(SCH_1):PAGE68
    U1 CN11 VCCINFAON4 SOCKET4677_AZIF0045P001C01CS-SA     I8 @S9S_MB_2U_LIB.S9S_MB_2U(SCH_1):PAGE68
    U1 CN15 VCCINFAON5 SOCKET4677_AZIF0045P001C01CS-SA     I8 @S9S_MB_2U_LIB.S9S_MB_2U(SCH_1):PAGE68
    U1  CN3 VCCINFAON6 SOCKET4677_AZIF0045P001C01CS-SA     I8 @S9S_MB_2U_LIB.S9S_MB_2U(SCH_1):PAGE68
    U1 CN64 VCCINFAON7 SOCKET4677_AZIF0045P001C01CS-SA     I8 @S9S_MB_2U_LIB.S9S_MB_2U(SCH_1):PAGE68
    U1 CN66 VCCINFAON8 SOCKET4677_AZIF0045P001C01CS-SA     I8 @S9S_MB_2U_LIB.S9S_MB_2U(SCH_1):PAGE68
    U1  CN7 VCCINFAON9 SOCKET4677_AZIF0045P001C01CS-SA     I8 @S9S_MB_2U_LIB.S9S_MB_2U(SCH_1):PAGE68
    U1 CP65 VCCINFAON10 SOCKET4677_AZIF0045P001C01CS-SA     I8 @S9S_MB_2U_LIB.S9S_MB_2U(SCH_1):PAGE68
    U1 CP67 VCCINFAON11 SOCKET4677_AZIF0045P001C01CS-SA     I8 @S9S_MB_2U_LIB.S9S_MB_2U(SCH_1):PAGE68
    U1 CT65 VCCINFAON12 SOCKET4677_AZIF0045P001C01CS-SA     I8 @S9S_MB_2U_LIB.S9S_MB_2U(SCH_1):PAGE68
    U1 CT67 VCCINFAON13 SOCKET4677_AZIF0045P001C01CS-SA     I8 @S9S_MB_2U_LIB.S9S_MB_2U(SCH_1):PAGE68
    U1 CU11 VCCINFAON14 SOCKET4677_AZIF0045P001C01CS-SA     I8 @S9S_MB_2U_LIB.S9S_MB_2U(SCH_1):PAGE68
    U1 CU15 VCCINFAON15 SOCKET4677_AZIF0045P001C01CS-SA     I8 @S9S_MB_2U_LIB.S9S_MB_2U(SCH_1):PAGE68
    U1  CU3 VCCINFAON16 SOCKET4677_AZIF0045P001C01CS-SA     I8 @S9S_MB_2U_LIB.S9S_MB_2U(SCH_1):PAGE68
    U1 CU64 VCCINFAON17 SOCKET4677_AZIF0045P001C01CS-SA     I8 @S9S_MB_2U_LIB.S9S_MB_2U(SCH_1):PAGE68
    U1  CU7 VCCINFAON18 SOCKET4677_AZIF0045P001C01CS-SA     I8 @S9S_MB_2U_LIB.S9S_MB_2U(SCH_1):PAGE68
    U1 CV65 VCCINFAON19 SOCKET4677_AZIF0045P001C01CS-SA     I8 @S9S_MB_2U_LIB.S9S_MB_2U(SCH_1):PAGE68
    U1 CV67 VCCINFAON20 SOCKET4677_AZIF0045P001C01CS-SA     I8 @S9S_MB_2U_LIB.S9S_MB_2U(SCH_1):PAGE68
    U1 CW66 VCCINFAON21 SOCKET4677_AZIF0045P001C01CS-SA     I8 @S9S_MB_2U_LIB.S9S_MB_2U(SCH_1):PAGE68
    U1 CY65 VCCINFAON22 SOCKET4677_AZIF0045P001C01CS-SA     I8 @S9S_MB_2U_LIB.S9S_MB_2U(SCH_1):PAGE68
    U1 CY67 VCCINFAON23 SOCKET4677_AZIF0045P001C01CS-SA     I8 @S9S_MB_2U_LIB.S9S_MB_2U(SCH_1):PAGE68
    U1 DA11 VCCINFAON24 SOCKET4677_AZIF0045P001C01CS-SA     I8 @S9S_MB_2U_LIB.S9S_MB_2U(SCH_1):PAGE68
    U1 DA15 VCCINFAON25 SOCKET4677_AZIF0045P001C01CS-SA     I8 @S9S_MB_2U_LIB.S9S_MB_2U(SCH_1):PAGE68
    U1 DA64 VCCINFAON26 SOCKET4677_AZIF0045P001C01CS-SA     I8 @S9S_MB_2U_LIB.S9S_MB_2U(SCH_1):PAGE68
    U1 DE11 VCCINFAON27 SOCKET4677_AZIF0045P001C01CS-SA     I8 @S9S_MB_2U_LIB.S9S_MB_2U(SCH_1):PAGE68
    U1 DE15 VCCINFAON28 SOCKET4677_AZIF0045P001C01CS-SA     I8 @S9S_MB_2U_LIB.S9S_MB_2U(SCH_1):PAGE68
    U1  DE3 VCCINFAON29 SOCKET4677_AZIF0045P001C01CS-SA     I8 @S9S_MB_2U_LIB.S9S_MB_2U(SCH_1):PAGE68
    U1 DJ15 VCCINFAON30 SOCKET4677_AZIF0045P001C01CS-SA     I8 @S9S_MB_2U_LIB.S9S_MB_2U(SCH_1):PAGE68
    U1  DJ3 VCCINFAON31 SOCKET4677_AZIF0045P001C01CS-SA     I8 @S9S_MB_2U_LIB.S9S_MB_2U(SCH_1):PAGE68
    U1  DJ7 VCCINFAON32 SOCKET4677_AZIF0045P001C01CS-SA     I8 @S9S_MB_2U_LIB.S9S_MB_2U(SCH_1):PAGE68
    U1 CR66 VCCINFAON54 SOCKET4677_AZIF0045P001C01CS-SA     I8 @S9S_MB_2U_LIB.S9S_MB_2U(SCH_1):PAGE68
    U1 CW64 VCCINFAON55 SOCKET4677_AZIF0045P001C01CS-SA     I8 @S9S_MB_2U_LIB.S9S_MB_2U(SCH_1):PAGE68
    U1  DA3 VCCINFAON56 SOCKET4677_AZIF0045P001C01CS-SA     I8 @S9S_MB_2U_LIB.S9S_MB_2U(SCH_1):PAGE68
    U1  DA7 VCCINFAON57 SOCKET4677_AZIF0045P001C01CS-SA     I8 @S9S_MB_2U_LIB.S9S_MB_2U(SCH_1):PAGE68
    U1  DE7 VCCINFAON58 SOCKET4677_AZIF0045P001C01CS-SA     I8 @S9S_MB_2U_LIB.S9S_MB_2U(SCH_1):PAGE68
    U1 DJ11 VCCINFAON59 SOCKET4677_AZIF0045P001C01CS-SA     I8 @S9S_MB_2U_LIB.S9S_MB_2U(SCH_1):PAGE68
  C432    1      A Q_CAP_C0402-22UF,4V,20%,X6S,CHA    I42 @S9S_MB_2U_LIB.S9S_MB_2U(SCH_1):PAGE77
  C434    1      A Q_CAP_C0402-22UF,4V,20%,X6S,CHA    I47 @S9S_MB_2U_LIB.S9S_MB_2U(SCH_1):PAGE77
  C436    1      A Q_CAP_C0402-22UF,4V,20%,X6S,CHA    I49 @S9S_MB_2U_LIB.S9S_MB_2U(SCH_1):PAGE77
  C438    1      A Q_CAP_C0402-22UF,4V,20%,X6S,CHA    I58 @S9S_MB_2U_LIB.S9S_MB_2U(SCH_1):PAGE77
  C440    1      A Q_CAP_C0402-22UF,4V,20%,X6S,CHA    I61 @S9S_MB_2U_LIB.S9S_MB_2U(SCH_1):PAGE77
  C490    1      A Q_CAP_C0402-22UF,4V,20%,X6S,CHA    I23 @S9S_MB_2U_LIB.S9S_MB_2U(SCH_1):PAGE78
  C487    1      A Q_CAP_C0805-47UF,4V,20%,X6S,CHA    I10 @S9S_MB_2U_LIB.S9S_MB_2U(SCH_1):PAGE79
  C486    1      A Q_CAP_C0805-47UF,4V,20%,X6S,CHA    I11 @S9S_MB_2U_LIB.S9S_MB_2U(SCH_1):PAGE79
PC458_P1_2    1      A Q_CAP_C0805-22UF,4V,20%,X6S,CHA    I33 @S9S_MB_2U_LIB.S9S_MB_2U(SCH_1):PAGE279
PR4247    1      A Q_RES_0402LF-499,1%,1/16W,CHIPA    I34 @S9S_MB_2U_LIB.S9S_MB_2U(SCH_1):PAGE279
PC1593    1      A Q_CAPP_THLF-560UF,2.5V,20%,OSCA    I59 @S9S_MB_2U_LIB.S9S_MB_2U(SCH_1):PAGE279
PC1594    1      A Q_CAPP_SMLF-330UF,2V,35%,SPCAPA    I62 @S9S_MB_2U_LIB.S9S_MB_2U(SCH_1):PAGE279
  C478    1      A Q_CAP_C0805-47UF,4V,20%,X6S,CHA     I8 @S9S_MB_2U_LIB.S9S_MB_2U(SCH_1):PAGE78
  C488    1      A Q_CAP_C0603-47UF,2.5V,20%,X6S,A    I18 @S9S_MB_2U_LIB.S9S_MB_2U(SCH_1):PAGE78
  C489    1      A Q_CAP_C0603-47UF,2.5V,20%,X6S,A    I19 @S9S_MB_2U_LIB.S9S_MB_2U(SCH_1):PAGE78
  C484    1      A Q_CAP_C0805-47UF,4V,20%,X6S,CHA    I12 @S9S_MB_2U_LIB.S9S_MB_2U(SCH_1):PAGE79
  C481    1      A Q_CAP_C0805-47UF,4V,20%,X6S,CHA    I13 @S9S_MB_2U_LIB.S9S_MB_2U(SCH_1):PAGE79
  R329    1      A Q_RES_1206LF-0,,1/2W,EMPTY,CS0A    I35 @S9S_MB_2U_LIB.S9S_MB_2U(SCH_1):PAGE80
 PR568    2      B Q_RES_0402LF-100,1%,1/16W,CHIPA    I55 @S9S_MB_2U_LIB.S9S_MB_2U(SCH_1):PAGE278
PC456_P1_2    1      A Q_CAP_C0805-22UF,4V,20%,X6S,CHA    I32 @S9S_MB_2U_LIB.S9S_MB_2U(SCH_1):PAGE279
  PL22    2      2 Q_INDUCTOR_SMLF-120NH/69A,IND,A    I46 @S9S_MB_2U_LIB.S9S_MB_2U(SCH_1):PAGE279
PC1595    1      A Q_CAPP_THLF-560UF,2.5V,20%,OSCA    I60 @S9S_MB_2U_LIB.S9S_MB_2U(SCH_1):PAGE279
PC1588    1      A Q_CAPP_SMLF-330UF,2V,35%,SPCAPA    I61 @S9S_MB_2U_LIB.S9S_MB_2U(SCH_1):PAGE279
PC455_P1_1    1      A Q_CAP_C0805-22UF,4V,20%,X6S,CHA    I63 @S9S_MB_2U_LIB.S9S_MB_2U(SCH_1):PAGE279
PR1797    2      B Q_RES_0402LF-0,5%,1/16W,CHIP,CA    I31 @S9S_MB_2U_LIB.S9S_MB_2U(SCH_1):PAGE279
PR1796    2      B Q_RES_0402LF-0,5%,1/16W,CHIP,CA    I49 @S9S_MB_2U_LIB.S9S_MB_2U(SCH_1):PAGE279
  PL21    2      2 Q_INDUCTOR_SMLF-120NH/69A,IND,A    I54 @S9S_MB_2U_LIB.S9S_MB_2U(SCH_1):PAGE279
PC452_P1_1    1      A Q_CAP_C0402-100NF,50V,10%,X7R,A    I55 @S9S_MB_2U_LIB.S9S_MB_2U(SCH_1):PAGE279
PC457_P1_1    1      A Q_CAP_C0805-22UF,4V,20%,X6S,CHA    I65 @S9S_MB_2U_LIB.S9S_MB_2U(SCH_1):PAGE279
PC1596    1      A Q_CAPP_THLF-560UF,2.5V,20%,OSCA    I71 @S9S_MB_2U_LIB.S9S_MB_2U(SCH_1):PAGE279

PVCCINFAON_CPU1_ACSP1 @S9S_MB_2U_LIB.S9S_MB_2U(SCH_1):PVCCINFAON_CPU1_ACSP1
PU50_P1_1   38   IOUT ISL99390FRZTR5935-ISL99390FRZ-A    I38 @S9S_MB_2U_LIB.S9S_MB_2U(SCH_1):PAGE279
  PU22   23    CS7 ISL69260IRAZT-ISL69260IRAZ-T,SA    I38 @S9S_MB_2U_LIB.S9S_MB_2U(SCH_1):PAGE278

PVCCINFAON_CPU1_ACSP2 @S9S_MB_2U_LIB.S9S_MB_2U(SCH_1):PVCCINFAON_CPU1_ACSP2
PU51_P1_2   38   IOUT ISL99390FRZTR5935-ISL99390FRZ-A    I29 @S9S_MB_2U_LIB.S9S_MB_2U(SCH_1):PAGE279
  PU22   24    CS6 ISL69260IRAZT-ISL69260IRAZ-T,SA    I38 @S9S_MB_2U_LIB.S9S_MB_2U(SCH_1):PAGE278

PVCCINFAON_CPU1_ADDR @S9S_MB_2U_LIB.S9S_MB_2U(SCH_1):PVCCINFAON_CPU1_ADDR
 PR258    2      B Q_RES_0402LF-28K,1%,1/16W,EMPTA    I23 @S9S_MB_2U_LIB.S9S_MB_2U(SCH_1):PAGE278
  PU22   34 ADDR_CFG ISL69260IRAZT-ISL69260IRAZ-T,SA    I38 @S9S_MB_2U_LIB.S9S_MB_2U(SCH_1):PAGE278
 PR259    1      A Q_RES_0402LF-8.45K,1%,1/16W,CHA   I110 @S9S_MB_2U_LIB.S9S_MB_2U(SCH_1):PAGE278

PVCCINFAON_CPU1_APWM1 @S9S_MB_2U_LIB.S9S_MB_2U(SCH_1):PVCCINFAON_CPU1_APWM1
PU50_P1_1   34    PWM ISL99390FRZTR5935-ISL99390FRZ-A    I38 @S9S_MB_2U_LIB.S9S_MB_2U(SCH_1):PAGE279
  PU22    8   PWM7 ISL69260IRAZT-ISL69260IRAZ-T,SA    I38 @S9S_MB_2U_LIB.S9S_MB_2U(SCH_1):PAGE278

PVCCINFAON_CPU1_APWM2 @S9S_MB_2U_LIB.S9S_MB_2U(SCH_1):PVCCINFAON_CPU1_APWM2
PU51_P1_2   34    PWM ISL99390FRZTR5935-ISL99390FRZ-A    I29 @S9S_MB_2U_LIB.S9S_MB_2U(SCH_1):PAGE279
  PU22    7   PWM6 ISL69260IRAZT-ISL69260IRAZ-T,SA    I38 @S9S_MB_2U_LIB.S9S_MB_2U(SCH_1):PAGE278

PVCCINFAON_CPU1_ATSEN @S9S_MB_2U_LIB.S9S_MB_2U(SCH_1):PVCCINFAON_CPU1_ATSEN
PU50_P1_1   36 TOUT_FLT ISL99390FRZTR5935-ISL99390FRZ-A    I38 @S9S_MB_2U_LIB.S9S_MB_2U(SCH_1):PAGE279
 PC475    1      A Q_CAP_0402-470PF,50V,10%,X7R,TA    I66 @S9S_MB_2U_LIB.S9S_MB_2U(SCH_1):PAGE278
PU51_P1_2   36 TOUT_FLT ISL99390FRZTR5935-ISL99390FRZ-A    I29 @S9S_MB_2U_LIB.S9S_MB_2U(SCH_1):PAGE279
  PU22   35  TEMP0 ISL69260IRAZT-ISL69260IRAZ-T,SA    I38 @S9S_MB_2U_LIB.S9S_MB_2U(SCH_1):PAGE278
 PR665    1      A Q_RES_0402LF-10K,1%,1/16W,EMPTA    I67 @S9S_MB_2U_LIB.S9S_MB_2U(SCH_1):PAGE278

PVCCINFAON_CPU1_CSPIN @S9S_MB_2U_LIB.S9S_MB_2U(SCH_1):PVCCINFAON_CPU1_CSPIN
 PR260    2      B Q_RES_0402LF-0,5%,1/16W,EMPTY,A    I22 @S9S_MB_2U_LIB.S9S_MB_2U(SCH_1):PAGE278
 PR275    1      A Q_RES_0402LF-0,5%,1/16W,CHIP,CA    I26 @S9S_MB_2U_LIB.S9S_MB_2U(SCH_1):PAGE278
 PC467    1      A Q_CAP_0402-0.1UF,25V,10%,EMPTYA    I28 @S9S_MB_2U_LIB.S9S_MB_2U(SCH_1):PAGE278
  PU22   37 VMON||IINSEN||VSYS||ISYS ISL69260IRAZT-ISL69260IRAZ-T,SA    I38 @S9S_MB_2U_LIB.S9S_MB_2U(SCH_1):PAGE278

PVCCINFAON_CPU1_EN_R @S9S_MB_2U_LIB.S9S_MB_2U(SCH_1):PVCCINFAON_CPU1_EN_R
  PU22   13    EN0 ISL69260IRAZT-ISL69260IRAZ-T,SA    I38 @S9S_MB_2U_LIB.S9S_MB_2U(SCH_1):PAGE278
 C2451    1      A Q_CAP_0402-1000PF,50V,5%,X7R,TA    I63 @S9S_MB_2U_LIB.S9S_MB_2U(SCH_1):PAGE278
 R2558    2      B Q_RES_0402LF-0,5%,1/16W,CHIP,CA   I104 @S9S_MB_2U_LIB.S9S_MB_2U(SCH_1):PAGE278

PVCCINFAON_CPU1_LSET1 @S9S_MB_2U_LIB.S9S_MB_2U(SCH_1):PVCCINFAON_CPU1_LSET1
PU50_P1_1   37   LSET ISL99390FRZTR5935-ISL99390FRZ-A    I38 @S9S_MB_2U_LIB.S9S_MB_2U(SCH_1):PAGE279
PR1726    1      A Q_RES_0402LF-8.87K,1%,1/16W,EMA    I16 @S9S_MB_2U_LIB.S9S_MB_2U(SCH_1):PAGE279

PVCCINFAON_CPU1_LSET2 @S9S_MB_2U_LIB.S9S_MB_2U(SCH_1):PVCCINFAON_CPU1_LSET2
PU51_P1_2   37   LSET ISL99390FRZTR5935-ISL99390FRZ-A    I29 @S9S_MB_2U_LIB.S9S_MB_2U(SCH_1):PAGE279
PR1727    1      A Q_RES_0402LF-8.87K,1%,1/16W,EMA     I3 @S9S_MB_2U_LIB.S9S_MB_2U(SCH_1):PAGE279

PVCCINFAON_CPU1_PIN_ALERT @S9S_MB_2U_LIB.S9S_MB_2U(SCH_1):PVCCINFAON_CPU1_PIN_ALERT
  PU22   15 NPINALERT#||NPSYSCRIT# ISL69260IRAZT-ISL69260IRAZ-T,SA    I38 @S9S_MB_2U_LIB.S9S_MB_2U(SCH_1):PAGE278
 R2569    2      B Q_RES_0402LF-1K,1%,1/16W,CHIP,A    I49 @S9S_MB_2U_LIB.S9S_MB_2U(SCH_1):PAGE278

PVCCINFAON_CPU1_VCC @S9S_MB_2U_LIB.S9S_MB_2U(SCH_1):PVCCINFAON_CPU1_VCC
 PC476    1      A Q_CAP_C0402-100NF,50V,10%,EMPTA    I93 @S9S_MB_2U_LIB.S9S_MB_2U(SCH_1):PAGE278
 PC478    1      A Q_CAP_C0402-1UF,16V,10%,X6S,CHA    I97 @S9S_MB_2U_LIB.S9S_MB_2U(SCH_1):PAGE278
  PU22   39    VCC ISL69260IRAZT-ISL69260IRAZ-T,SA    I38 @S9S_MB_2U_LIB.S9S_MB_2U(SCH_1):PAGE278
 PR283    1      A Q_RES_0402LF-1,1%,1/16W,CHIP,CA   I108 @S9S_MB_2U_LIB.S9S_MB_2U(SCH_1):PAGE278
PC2367    1      A Q_CAP_0402-0.1UF,25V,10%,EMPTYA   I111 @S9S_MB_2U_LIB.S9S_MB_2U(SCH_1):PAGE278

PVCCINFAON_CPU1_VDD1 @S9S_MB_2U_LIB.S9S_MB_2U(SCH_1):PVCCINFAON_CPU1_VDD1
PU50_P1_1   35     EN ISL99390FRZTR5935-ISL99390FRZ-A    I38 @S9S_MB_2U_LIB.S9S_MB_2U(SCH_1):PAGE279
PU50_P1_1    3    VCC ISL99390FRZTR5935-ISL99390FRZ-A    I38 @S9S_MB_2U_LIB.S9S_MB_2U(SCH_1):PAGE279
 PR254    2      B Q_RES_0402LF-2.2,1%,1/16W,CHIPA    I25 @S9S_MB_2U_LIB.S9S_MB_2U(SCH_1):PAGE279
 PC440    1      A Q_CAP_C0402-2.2UF,10V,10%,X6S,A    I24 @S9S_MB_2U_LIB.S9S_MB_2U(SCH_1):PAGE279

PVCCINFAON_CPU1_VDD2 @S9S_MB_2U_LIB.S9S_MB_2U(SCH_1):PVCCINFAON_CPU1_VDD2
 PR255    2      B Q_RES_0402LF-2.2,1%,1/16W,CHIPA    I11 @S9S_MB_2U_LIB.S9S_MB_2U(SCH_1):PAGE279
PU51_P1_2   35     EN ISL99390FRZTR5935-ISL99390FRZ-A    I29 @S9S_MB_2U_LIB.S9S_MB_2U(SCH_1):PAGE279
PU51_P1_2    3    VCC ISL99390FRZTR5935-ISL99390FRZ-A    I29 @S9S_MB_2U_LIB.S9S_MB_2U(SCH_1):PAGE279
 PC441    1      A Q_CAP_C0402-2.2UF,10V,10%,X6S,A    I10 @S9S_MB_2U_LIB.S9S_MB_2U(SCH_1):PAGE279

PVCCINFAON_CPU1_VIN_CSNIN @S9S_MB_2U_LIB.S9S_MB_2U(SCH_1):PVCCINFAON_CPU1_VIN_CSNIN
 PR261    2      B Q_RES_0402LF-0,5%,1/16W,CHIP,CA    I21 @S9S_MB_2U_LIB.S9S_MB_2U(SCH_1):PAGE278
 PR276    1      A Q_RES_0402LF-1K,1%,1/16W,EMPTYA    I35 @S9S_MB_2U_LIB.S9S_MB_2U(SCH_1):PAGE278
 PC474    1      A Q_CAP_0402-0.1UF,25V,10%,X7R,CA    I36 @S9S_MB_2U_LIB.S9S_MB_2U(SCH_1):PAGE278
  PU22   38 VINSEN||VSYS ISL69260IRAZT-ISL69260IRAZ-T,SA    I38 @S9S_MB_2U_LIB.S9S_MB_2U(SCH_1):PAGE278

PVCCINFAON_CPU1_VOS1 @S9S_MB_2U_LIB.S9S_MB_2U(SCH_1):PVCCINFAON_CPU1_VOS1
PU50_P1_1    1    VOS ISL99390FRZTR5935-ISL99390FRZ-A    I38 @S9S_MB_2U_LIB.S9S_MB_2U(SCH_1):PAGE279
PR1796    1      A Q_RES_0402LF-0,5%,1/16W,CHIP,CA    I49 @S9S_MB_2U_LIB.S9S_MB_2U(SCH_1):PAGE279

PVCCINFAON_CPU1_VOS2 @S9S_MB_2U_LIB.S9S_MB_2U(SCH_1):PVCCINFAON_CPU1_VOS2
PU51_P1_2    1    VOS ISL99390FRZTR5935-ISL99390FRZ-A    I29 @S9S_MB_2U_LIB.S9S_MB_2U(SCH_1):PAGE279
PR1797    1      A Q_RES_0402LF-0,5%,1/16W,CHIP,CA    I31 @S9S_MB_2U_LIB.S9S_MB_2U(SCH_1):PAGE279

PVCCINFAON_CPU1_VREF @S9S_MB_2U_LIB.S9S_MB_2U(SCH_1):PVCCINFAON_CPU1_VREF
PU50_P1_1   39  REFIN ISL99390FRZTR5935-ISL99390FRZ-A    I38 @S9S_MB_2U_LIB.S9S_MB_2U(SCH_1):PAGE279
  PU49   24  REFIN RAA2213404GNPHB0-RAA2213404GNPA    I14 @S9S_MB_2U_LIB.S9S_MB_2U(SCH_1):PAGE280
PU51_P1_2   39  REFIN ISL99390FRZTR5935-ISL99390FRZ-A    I29 @S9S_MB_2U_LIB.S9S_MB_2U(SCH_1):PAGE279
PC1366    2      B Q_CAP_0402-0.1UF,25V,10%,X7R,CA     I9 @S9S_MB_2U_LIB.S9S_MB_2U(SCH_1):PAGE280
 PR258    1      A Q_RES_0402LF-28K,1%,1/16W,EMPTA    I23 @S9S_MB_2U_LIB.S9S_MB_2U(SCH_1):PAGE278
  PU22   40   VCCS ISL69260IRAZT-ISL69260IRAZ-T,SA    I38 @S9S_MB_2U_LIB.S9S_MB_2U(SCH_1):PAGE278
 PC477    1      A Q_CAP_C0402-10UF,6.3V,20%,X6S,B    I92 @S9S_MB_2U_LIB.S9S_MB_2U(SCH_1):PAGE278
PC1193    1      A Q_CAP_C0402-1UF,16V,10%,X6S,CHA    I96 @S9S_MB_2U_LIB.S9S_MB_2U(SCH_1):PAGE278
PC1365    2      B Q_CAP_0402-0.1UF,25V,10%,X7R,CA     I6 @S9S_MB_2U_LIB.S9S_MB_2U(SCH_1):PAGE279
PC1364    2      B Q_CAP_0402-0.1UF,25V,10%,X7R,CA    I20 @S9S_MB_2U_LIB.S9S_MB_2U(SCH_1):PAGE279

PVCCINFAON_CPU1_VR_FAULT @S9S_MB_2U_LIB.S9S_MB_2U(SCH_1):PVCCINFAON_CPU1_VR_FAULT
  PU22   33    CFP ISL69260IRAZT-ISL69260IRAZ-T,SA    I38 @S9S_MB_2U_LIB.S9S_MB_2U(SCH_1):PAGE278
 R2568    2      B Q_RES_0402LF-1K,1%,1/16W,CHIP,A    I50 @S9S_MB_2U_LIB.S9S_MB_2U(SCH_1):PAGE278

PVCCIN_CPU0 @S9S_MB_2U_LIB.S9S_MB_2U(SCH_1):PVCCIN_CPU0
    U2 BW80 VCCIN190 SOCKET4677_AZIF0045P001C01CS-SA     I1 @S9S_MB_2U_LIB.S9S_MB_2U(SCH_1):PAGE36
    U2 BW82 VCCIN191 SOCKET4677_AZIF0045P001C01CS-SA     I1 @S9S_MB_2U_LIB.S9S_MB_2U(SCH_1):PAGE36
    U2 BW84 VCCIN192 SOCKET4677_AZIF0045P001C01CS-SA     I1 @S9S_MB_2U_LIB.S9S_MB_2U(SCH_1):PAGE36
    U2 BW86 VCCIN193 SOCKET4677_AZIF0045P001C01CS-SA     I1 @S9S_MB_2U_LIB.S9S_MB_2U(SCH_1):PAGE36
    U2 BW88 VCCIN194 SOCKET4677_AZIF0045P001C01CS-SA     I1 @S9S_MB_2U_LIB.S9S_MB_2U(SCH_1):PAGE36
    U2 BW90 VCCIN195 SOCKET4677_AZIF0045P001C01CS-SA     I1 @S9S_MB_2U_LIB.S9S_MB_2U(SCH_1):PAGE36
    U2 BY32 VCCIN196 SOCKET4677_AZIF0045P001C01CS-SA     I1 @S9S_MB_2U_LIB.S9S_MB_2U(SCH_1):PAGE36
    U2 BY34 VCCIN197 SOCKET4677_AZIF0045P001C01CS-SA     I1 @S9S_MB_2U_LIB.S9S_MB_2U(SCH_1):PAGE36
    U2 BY36 VCCIN198 SOCKET4677_AZIF0045P001C01CS-SA     I1 @S9S_MB_2U_LIB.S9S_MB_2U(SCH_1):PAGE36
    U2 BY38 VCCIN199 SOCKET4677_AZIF0045P001C01CS-SA     I1 @S9S_MB_2U_LIB.S9S_MB_2U(SCH_1):PAGE36
    U2 BY40 VCCIN200 SOCKET4677_AZIF0045P001C01CS-SA     I1 @S9S_MB_2U_LIB.S9S_MB_2U(SCH_1):PAGE36
    U2 BY42 VCCIN201 SOCKET4677_AZIF0045P001C01CS-SA     I1 @S9S_MB_2U_LIB.S9S_MB_2U(SCH_1):PAGE36
    U2 BY44 VCCIN202 SOCKET4677_AZIF0045P001C01CS-SA     I1 @S9S_MB_2U_LIB.S9S_MB_2U(SCH_1):PAGE36
    U2 BY47 VCCIN203 SOCKET4677_AZIF0045P001C01CS-SA     I1 @S9S_MB_2U_LIB.S9S_MB_2U(SCH_1):PAGE36
    U2 BY49 VCCIN204 SOCKET4677_AZIF0045P001C01CS-SA     I1 @S9S_MB_2U_LIB.S9S_MB_2U(SCH_1):PAGE36
    U2 BY51 VCCIN205 SOCKET4677_AZIF0045P001C01CS-SA     I1 @S9S_MB_2U_LIB.S9S_MB_2U(SCH_1):PAGE36
    U2 BY53 VCCIN206 SOCKET4677_AZIF0045P001C01CS-SA     I1 @S9S_MB_2U_LIB.S9S_MB_2U(SCH_1):PAGE36
    U2 BY55 VCCIN207 SOCKET4677_AZIF0045P001C01CS-SA     I1 @S9S_MB_2U_LIB.S9S_MB_2U(SCH_1):PAGE36
    U2 BY57 VCCIN208 SOCKET4677_AZIF0045P001C01CS-SA     I1 @S9S_MB_2U_LIB.S9S_MB_2U(SCH_1):PAGE36
    U2 BY59 VCCIN209 SOCKET4677_AZIF0045P001C01CS-SA     I1 @S9S_MB_2U_LIB.S9S_MB_2U(SCH_1):PAGE36
    U2 BY61 VCCIN210 SOCKET4677_AZIF0045P001C01CS-SA     I1 @S9S_MB_2U_LIB.S9S_MB_2U(SCH_1):PAGE36
    U2 BY63 VCCIN211 SOCKET4677_AZIF0045P001C01CS-SA     I1 @S9S_MB_2U_LIB.S9S_MB_2U(SCH_1):PAGE36
    U2 BY65 VCCIN212 SOCKET4677_AZIF0045P001C01CS-SA     I1 @S9S_MB_2U_LIB.S9S_MB_2U(SCH_1):PAGE36
    U2 BY67 VCCIN213 SOCKET4677_AZIF0045P001C01CS-SA     I1 @S9S_MB_2U_LIB.S9S_MB_2U(SCH_1):PAGE36
    U2 BY69 VCCIN214 SOCKET4677_AZIF0045P001C01CS-SA     I1 @S9S_MB_2U_LIB.S9S_MB_2U(SCH_1):PAGE36
    U2 BY71 VCCIN215 SOCKET4677_AZIF0045P001C01CS-SA     I1 @S9S_MB_2U_LIB.S9S_MB_2U(SCH_1):PAGE36
    U2 BY73 VCCIN216 SOCKET4677_AZIF0045P001C01CS-SA     I1 @S9S_MB_2U_LIB.S9S_MB_2U(SCH_1):PAGE36
    U2 BY75 VCCIN217 SOCKET4677_AZIF0045P001C01CS-SA     I1 @S9S_MB_2U_LIB.S9S_MB_2U(SCH_1):PAGE36
    U2 BY77 VCCIN218 SOCKET4677_AZIF0045P001C01CS-SA     I1 @S9S_MB_2U_LIB.S9S_MB_2U(SCH_1):PAGE36
    U2 BY79 VCCIN219 SOCKET4677_AZIF0045P001C01CS-SA     I1 @S9S_MB_2U_LIB.S9S_MB_2U(SCH_1):PAGE36
    U2 BY81 VCCIN220 SOCKET4677_AZIF0045P001C01CS-SA     I1 @S9S_MB_2U_LIB.S9S_MB_2U(SCH_1):PAGE36
    U2 BY83 VCCIN221 SOCKET4677_AZIF0045P001C01CS-SA     I1 @S9S_MB_2U_LIB.S9S_MB_2U(SCH_1):PAGE36
    U2 BY85 VCCIN222 SOCKET4677_AZIF0045P001C01CS-SA     I1 @S9S_MB_2U_LIB.S9S_MB_2U(SCH_1):PAGE36
    U2 BY87 VCCIN223 SOCKET4677_AZIF0045P001C01CS-SA     I1 @S9S_MB_2U_LIB.S9S_MB_2U(SCH_1):PAGE36
    U2 BY89 VCCIN224 SOCKET4677_AZIF0045P001C01CS-SA     I1 @S9S_MB_2U_LIB.S9S_MB_2U(SCH_1):PAGE36
    U2 CA33 VCCIN225 SOCKET4677_AZIF0045P001C01CS-SA     I1 @S9S_MB_2U_LIB.S9S_MB_2U(SCH_1):PAGE36
    U2 CA35 VCCIN226 SOCKET4677_AZIF0045P001C01CS-SA     I1 @S9S_MB_2U_LIB.S9S_MB_2U(SCH_1):PAGE36
    U2 CA37 VCCIN227 SOCKET4677_AZIF0045P001C01CS-SA     I1 @S9S_MB_2U_LIB.S9S_MB_2U(SCH_1):PAGE36
    U2 CA39 VCCIN228 SOCKET4677_AZIF0045P001C01CS-SA     I1 @S9S_MB_2U_LIB.S9S_MB_2U(SCH_1):PAGE36
    U2 CA41 VCCIN229 SOCKET4677_AZIF0045P001C01CS-SA     I1 @S9S_MB_2U_LIB.S9S_MB_2U(SCH_1):PAGE36
    U2 CA43 VCCIN230 SOCKET4677_AZIF0045P001C01CS-SA     I1 @S9S_MB_2U_LIB.S9S_MB_2U(SCH_1):PAGE36
    U2 CA45 VCCIN231 SOCKET4677_AZIF0045P001C01CS-SA     I1 @S9S_MB_2U_LIB.S9S_MB_2U(SCH_1):PAGE36
    U2 CA48 VCCIN232 SOCKET4677_AZIF0045P001C01CS-SA     I1 @S9S_MB_2U_LIB.S9S_MB_2U(SCH_1):PAGE36
    U2 CA50 VCCIN233 SOCKET4677_AZIF0045P001C01CS-SA     I1 @S9S_MB_2U_LIB.S9S_MB_2U(SCH_1):PAGE36
    U2 CA52 VCCIN234 SOCKET4677_AZIF0045P001C01CS-SA     I1 @S9S_MB_2U_LIB.S9S_MB_2U(SCH_1):PAGE36
    U2 CA54 VCCIN235 SOCKET4677_AZIF0045P001C01CS-SA     I1 @S9S_MB_2U_LIB.S9S_MB_2U(SCH_1):PAGE36
    U2 CA56 VCCIN236 SOCKET4677_AZIF0045P001C01CS-SA     I1 @S9S_MB_2U_LIB.S9S_MB_2U(SCH_1):PAGE36
    U2 CA58 VCCIN237 SOCKET4677_AZIF0045P001C01CS-SA     I1 @S9S_MB_2U_LIB.S9S_MB_2U(SCH_1):PAGE36
    U2 CA60 VCCIN238 SOCKET4677_AZIF0045P001C01CS-SA     I1 @S9S_MB_2U_LIB.S9S_MB_2U(SCH_1):PAGE36
    U2 CA62 VCCIN239 SOCKET4677_AZIF0045P001C01CS-SA     I1 @S9S_MB_2U_LIB.S9S_MB_2U(SCH_1):PAGE36
    U2 CA64 VCCIN240 SOCKET4677_AZIF0045P001C01CS-SA     I1 @S9S_MB_2U_LIB.S9S_MB_2U(SCH_1):PAGE36
    U2 CA66 VCCIN241 SOCKET4677_AZIF0045P001C01CS-SA     I1 @S9S_MB_2U_LIB.S9S_MB_2U(SCH_1):PAGE36
    U2 CA68 VCCIN242 SOCKET4677_AZIF0045P001C01CS-SA     I1 @S9S_MB_2U_LIB.S9S_MB_2U(SCH_1):PAGE36
    U2 CA70 VCCIN243 SOCKET4677_AZIF0045P001C01CS-SA     I1 @S9S_MB_2U_LIB.S9S_MB_2U(SCH_1):PAGE36
    U2 CA72 VCCIN244 SOCKET4677_AZIF0045P001C01CS-SA     I1 @S9S_MB_2U_LIB.S9S_MB_2U(SCH_1):PAGE36
    U2 CA74 VCCIN245 SOCKET4677_AZIF0045P001C01CS-SA     I1 @S9S_MB_2U_LIB.S9S_MB_2U(SCH_1):PAGE36
    U2 CA76 VCCIN246 SOCKET4677_AZIF0045P001C01CS-SA     I1 @S9S_MB_2U_LIB.S9S_MB_2U(SCH_1):PAGE36
    U2 CA78 VCCIN247 SOCKET4677_AZIF0045P001C01CS-SA     I1 @S9S_MB_2U_LIB.S9S_MB_2U(SCH_1):PAGE36
    U2 CA80 VCCIN248 SOCKET4677_AZIF0045P001C01CS-SA     I1 @S9S_MB_2U_LIB.S9S_MB_2U(SCH_1):PAGE36
    U2 CA82 VCCIN249 SOCKET4677_AZIF0045P001C01CS-SA     I1 @S9S_MB_2U_LIB.S9S_MB_2U(SCH_1):PAGE36
    U2 CA84 VCCIN250 SOCKET4677_AZIF0045P001C01CS-SA     I1 @S9S_MB_2U_LIB.S9S_MB_2U(SCH_1):PAGE36
    U2 CA86 VCCIN251 SOCKET4677_AZIF0045P001C01CS-SA     I1 @S9S_MB_2U_LIB.S9S_MB_2U(SCH_1):PAGE36
    U2 CA88 VCCIN252 SOCKET4677_AZIF0045P001C01CS-SA     I1 @S9S_MB_2U_LIB.S9S_MB_2U(SCH_1):PAGE36
    U2 CA90 VCCIN253 SOCKET4677_AZIF0045P001C01CS-SA     I1 @S9S_MB_2U_LIB.S9S_MB_2U(SCH_1):PAGE36
    U2 CB61 VCCIN254 SOCKET4677_AZIF0045P001C01CS-SA     I1 @S9S_MB_2U_LIB.S9S_MB_2U(SCH_1):PAGE36
    U2 CB75 VCCIN255 SOCKET4677_AZIF0045P001C01CS-SA     I1 @S9S_MB_2U_LIB.S9S_MB_2U(SCH_1):PAGE36
    U2 CB77 VCCIN256 SOCKET4677_AZIF0045P001C01CS-SA     I1 @S9S_MB_2U_LIB.S9S_MB_2U(SCH_1):PAGE36
    U2 CC33 VCCIN257 SOCKET4677_AZIF0045P001C01CS-SA     I1 @S9S_MB_2U_LIB.S9S_MB_2U(SCH_1):PAGE36
    U2 CC35 VCCIN258 SOCKET4677_AZIF0045P001C01CS-SA     I1 @S9S_MB_2U_LIB.S9S_MB_2U(SCH_1):PAGE36
    U2 CC37 VCCIN259 SOCKET4677_AZIF0045P001C01CS-SA     I1 @S9S_MB_2U_LIB.S9S_MB_2U(SCH_1):PAGE36
    U2 CC39 VCCIN260 SOCKET4677_AZIF0045P001C01CS-SA     I1 @S9S_MB_2U_LIB.S9S_MB_2U(SCH_1):PAGE36
    U2 CC41 VCCIN261 SOCKET4677_AZIF0045P001C01CS-SA     I1 @S9S_MB_2U_LIB.S9S_MB_2U(SCH_1):PAGE36
    U2 CC43 VCCIN262 SOCKET4677_AZIF0045P001C01CS-SA     I1 @S9S_MB_2U_LIB.S9S_MB_2U(SCH_1):PAGE36
    U2 CC45 VCCIN263 SOCKET4677_AZIF0045P001C01CS-SA     I1 @S9S_MB_2U_LIB.S9S_MB_2U(SCH_1):PAGE36
    U2 CC48 VCCIN264 SOCKET4677_AZIF0045P001C01CS-SA     I1 @S9S_MB_2U_LIB.S9S_MB_2U(SCH_1):PAGE36
    U2 CC50 VCCIN265 SOCKET4677_AZIF0045P001C01CS-SA     I1 @S9S_MB_2U_LIB.S9S_MB_2U(SCH_1):PAGE36
    U2 CC52 VCCIN266 SOCKET4677_AZIF0045P001C01CS-SA     I1 @S9S_MB_2U_LIB.S9S_MB_2U(SCH_1):PAGE36
    U2 CC54 VCCIN267 SOCKET4677_AZIF0045P001C01CS-SA     I1 @S9S_MB_2U_LIB.S9S_MB_2U(SCH_1):PAGE36
    U2 CC56 VCCIN268 SOCKET4677_AZIF0045P001C01CS-SA     I1 @S9S_MB_2U_LIB.S9S_MB_2U(SCH_1):PAGE36
    U2 CC58 VCCIN269 SOCKET4677_AZIF0045P001C01CS-SA     I1 @S9S_MB_2U_LIB.S9S_MB_2U(SCH_1):PAGE36
    U2 CC60 VCCIN270 SOCKET4677_AZIF0045P001C01CS-SA     I1 @S9S_MB_2U_LIB.S9S_MB_2U(SCH_1):PAGE36
    U2 CC76 VCCIN271 SOCKET4677_AZIF0045P001C01CS-SA     I1 @S9S_MB_2U_LIB.S9S_MB_2U(SCH_1):PAGE36
    U2 CC78 VCCIN272 SOCKET4677_AZIF0045P001C01CS-SA     I1 @S9S_MB_2U_LIB.S9S_MB_2U(SCH_1):PAGE36
    U2 CC80 VCCIN273 SOCKET4677_AZIF0045P001C01CS-SA     I1 @S9S_MB_2U_LIB.S9S_MB_2U(SCH_1):PAGE36
    U2 CC82 VCCIN274 SOCKET4677_AZIF0045P001C01CS-SA     I1 @S9S_MB_2U_LIB.S9S_MB_2U(SCH_1):PAGE36
    U2 CC84 VCCIN275 SOCKET4677_AZIF0045P001C01CS-SA     I1 @S9S_MB_2U_LIB.S9S_MB_2U(SCH_1):PAGE36
    U2 CC86 VCCIN276 SOCKET4677_AZIF0045P001C01CS-SA     I1 @S9S_MB_2U_LIB.S9S_MB_2U(SCH_1):PAGE36
    U2 CC88 VCCIN277 SOCKET4677_AZIF0045P001C01CS-SA     I1 @S9S_MB_2U_LIB.S9S_MB_2U(SCH_1):PAGE36
    U2 CC90 VCCIN278 SOCKET4677_AZIF0045P001C01CS-SA     I1 @S9S_MB_2U_LIB.S9S_MB_2U(SCH_1):PAGE36
    U2 CD32 VCCIN279 SOCKET4677_AZIF0045P001C01CS-SA     I1 @S9S_MB_2U_LIB.S9S_MB_2U(SCH_1):PAGE36
    U2 CD34 VCCIN280 SOCKET4677_AZIF0045P001C01CS-SA     I1 @S9S_MB_2U_LIB.S9S_MB_2U(SCH_1):PAGE36
    U2 CD36 VCCIN281 SOCKET4677_AZIF0045P001C01CS-SA     I1 @S9S_MB_2U_LIB.S9S_MB_2U(SCH_1):PAGE36
    U2 CD38 VCCIN282 SOCKET4677_AZIF0045P001C01CS-SA     I1 @S9S_MB_2U_LIB.S9S_MB_2U(SCH_1):PAGE36
    U2 CD40 VCCIN283 SOCKET4677_AZIF0045P001C01CS-SA     I1 @S9S_MB_2U_LIB.S9S_MB_2U(SCH_1):PAGE36
    U2 CD42 VCCIN284 SOCKET4677_AZIF0045P001C01CS-SA     I1 @S9S_MB_2U_LIB.S9S_MB_2U(SCH_1):PAGE36
    U2 CD44 VCCIN285 SOCKET4677_AZIF0045P001C01CS-SA     I1 @S9S_MB_2U_LIB.S9S_MB_2U(SCH_1):PAGE36
    U2 CD47 VCCIN286 SOCKET4677_AZIF0045P001C01CS-SA     I1 @S9S_MB_2U_LIB.S9S_MB_2U(SCH_1):PAGE36
    U2 CD49 VCCIN287 SOCKET4677_AZIF0045P001C01CS-SA     I1 @S9S_MB_2U_LIB.S9S_MB_2U(SCH_1):PAGE36
    U2 CD51 VCCIN288 SOCKET4677_AZIF0045P001C01CS-SA     I1 @S9S_MB_2U_LIB.S9S_MB_2U(SCH_1):PAGE36
    U2 CD53 VCCIN289 SOCKET4677_AZIF0045P001C01CS-SA     I1 @S9S_MB_2U_LIB.S9S_MB_2U(SCH_1):PAGE36
    U2 CD55 VCCIN290 SOCKET4677_AZIF0045P001C01CS-SA     I1 @S9S_MB_2U_LIB.S9S_MB_2U(SCH_1):PAGE36
    U2 CD57 VCCIN291 SOCKET4677_AZIF0045P001C01CS-SA     I1 @S9S_MB_2U_LIB.S9S_MB_2U(SCH_1):PAGE36
    U2 CD59 VCCIN292 SOCKET4677_AZIF0045P001C01CS-SA     I1 @S9S_MB_2U_LIB.S9S_MB_2U(SCH_1):PAGE36
    U2 CD79 VCCIN293 SOCKET4677_AZIF0045P001C01CS-SA     I1 @S9S_MB_2U_LIB.S9S_MB_2U(SCH_1):PAGE36
    U2 CD81 VCCIN294 SOCKET4677_AZIF0045P001C01CS-SA     I1 @S9S_MB_2U_LIB.S9S_MB_2U(SCH_1):PAGE36
    U2 CD83 VCCIN295 SOCKET4677_AZIF0045P001C01CS-SA     I1 @S9S_MB_2U_LIB.S9S_MB_2U(SCH_1):PAGE36
    U2 CD85 VCCIN296 SOCKET4677_AZIF0045P001C01CS-SA     I1 @S9S_MB_2U_LIB.S9S_MB_2U(SCH_1):PAGE36
    U2 CD87 VCCIN297 SOCKET4677_AZIF0045P001C01CS-SA     I1 @S9S_MB_2U_LIB.S9S_MB_2U(SCH_1):PAGE36
    U2 CD89 VCCIN298 SOCKET4677_AZIF0045P001C01CS-SA     I1 @S9S_MB_2U_LIB.S9S_MB_2U(SCH_1):PAGE36
    U2 CE80 VCCIN299 SOCKET4677_AZIF0045P001C01CS-SA     I1 @S9S_MB_2U_LIB.S9S_MB_2U(SCH_1):PAGE36
    U2 CE82 VCCIN300 SOCKET4677_AZIF0045P001C01CS-SA     I1 @S9S_MB_2U_LIB.S9S_MB_2U(SCH_1):PAGE36
    U2 CE84 VCCIN301 SOCKET4677_AZIF0045P001C01CS-SA     I1 @S9S_MB_2U_LIB.S9S_MB_2U(SCH_1):PAGE36
    U2 CE86 VCCIN302 SOCKET4677_AZIF0045P001C01CS-SA     I1 @S9S_MB_2U_LIB.S9S_MB_2U(SCH_1):PAGE36
    U2 CE88 VCCIN303 SOCKET4677_AZIF0045P001C01CS-SA     I1 @S9S_MB_2U_LIB.S9S_MB_2U(SCH_1):PAGE36
    U2 CE90 VCCIN304 SOCKET4677_AZIF0045P001C01CS-SA     I1 @S9S_MB_2U_LIB.S9S_MB_2U(SCH_1):PAGE36
    U2 CF79 VCCIN305 SOCKET4677_AZIF0045P001C01CS-SA     I1 @S9S_MB_2U_LIB.S9S_MB_2U(SCH_1):PAGE36
    U2 CF81 VCCIN306 SOCKET4677_AZIF0045P001C01CS-SA     I1 @S9S_MB_2U_LIB.S9S_MB_2U(SCH_1):PAGE36
    U2 CF83 VCCIN307 SOCKET4677_AZIF0045P001C01CS-SA     I1 @S9S_MB_2U_LIB.S9S_MB_2U(SCH_1):PAGE36
    U2 CF85 VCCIN308 SOCKET4677_AZIF0045P001C01CS-SA     I1 @S9S_MB_2U_LIB.S9S_MB_2U(SCH_1):PAGE36
    U2 CF87 VCCIN309 SOCKET4677_AZIF0045P001C01CS-SA     I1 @S9S_MB_2U_LIB.S9S_MB_2U(SCH_1):PAGE36
    U2 CF89 VCCIN310 SOCKET4677_AZIF0045P001C01CS-SA     I1 @S9S_MB_2U_LIB.S9S_MB_2U(SCH_1):PAGE36
    U2 CF91 VCCIN311 SOCKET4677_AZIF0045P001C01CS-SA     I1 @S9S_MB_2U_LIB.S9S_MB_2U(SCH_1):PAGE36
    U2 CG80 VCCIN312 SOCKET4677_AZIF0045P001C01CS-SA     I1 @S9S_MB_2U_LIB.S9S_MB_2U(SCH_1):PAGE36
    U2 CG82 VCCIN313 SOCKET4677_AZIF0045P001C01CS-SA     I1 @S9S_MB_2U_LIB.S9S_MB_2U(SCH_1):PAGE36
    U2 CG84 VCCIN314 SOCKET4677_AZIF0045P001C01CS-SA     I1 @S9S_MB_2U_LIB.S9S_MB_2U(SCH_1):PAGE36
    U2 CG86 VCCIN315 SOCKET4677_AZIF0045P001C01CS-SA     I1 @S9S_MB_2U_LIB.S9S_MB_2U(SCH_1):PAGE36
    U2 CG88 VCCIN316 SOCKET4677_AZIF0045P001C01CS-SA     I1 @S9S_MB_2U_LIB.S9S_MB_2U(SCH_1):PAGE36
    U2 CG90 VCCIN317 SOCKET4677_AZIF0045P001C01CS-SA     I1 @S9S_MB_2U_LIB.S9S_MB_2U(SCH_1):PAGE36
    U2 CH81 VCCIN318 SOCKET4677_AZIF0045P001C01CS-SA     I1 @S9S_MB_2U_LIB.S9S_MB_2U(SCH_1):PAGE36
    U2 CH91 VCCIN319 SOCKET4677_AZIF0045P001C01CS-SA     I1 @S9S_MB_2U_LIB.S9S_MB_2U(SCH_1):PAGE36
    U2 CJ82 VCCIN320 SOCKET4677_AZIF0045P001C01CS-SA     I1 @S9S_MB_2U_LIB.S9S_MB_2U(SCH_1):PAGE36
    U2 CJ84 VCCIN321 SOCKET4677_AZIF0045P001C01CS-SA     I1 @S9S_MB_2U_LIB.S9S_MB_2U(SCH_1):PAGE36
    U2 CJ86 VCCIN322 SOCKET4677_AZIF0045P001C01CS-SA     I1 @S9S_MB_2U_LIB.S9S_MB_2U(SCH_1):PAGE36
    U2 CJ88 VCCIN323 SOCKET4677_AZIF0045P001C01CS-SA     I1 @S9S_MB_2U_LIB.S9S_MB_2U(SCH_1):PAGE36
    U2 CJ90 VCCIN324 SOCKET4677_AZIF0045P001C01CS-SA     I1 @S9S_MB_2U_LIB.S9S_MB_2U(SCH_1):PAGE36
    U2 CK83 VCCIN325 SOCKET4677_AZIF0045P001C01CS-SA     I1 @S9S_MB_2U_LIB.S9S_MB_2U(SCH_1):PAGE36
    U2 CK85 VCCIN326 SOCKET4677_AZIF0045P001C01CS-SA     I1 @S9S_MB_2U_LIB.S9S_MB_2U(SCH_1):PAGE36
    U2 CK87 VCCIN327 SOCKET4677_AZIF0045P001C01CS-SA     I1 @S9S_MB_2U_LIB.S9S_MB_2U(SCH_1):PAGE36
    U2 CK89 VCCIN328 SOCKET4677_AZIF0045P001C01CS-SA     I1 @S9S_MB_2U_LIB.S9S_MB_2U(SCH_1):PAGE36
    U2 CK91 VCCIN329 SOCKET4677_AZIF0045P001C01CS-SA     I1 @S9S_MB_2U_LIB.S9S_MB_2U(SCH_1):PAGE36
    U2 CL84 VCCIN330 SOCKET4677_AZIF0045P001C01CS-SA     I1 @S9S_MB_2U_LIB.S9S_MB_2U(SCH_1):PAGE36
    U2 CL86 VCCIN331 SOCKET4677_AZIF0045P001C01CS-SA     I1 @S9S_MB_2U_LIB.S9S_MB_2U(SCH_1):PAGE36
    U2 CL88 VCCIN332 SOCKET4677_AZIF0045P001C01CS-SA     I1 @S9S_MB_2U_LIB.S9S_MB_2U(SCH_1):PAGE36
    U2 CL90 VCCIN333 SOCKET4677_AZIF0045P001C01CS-SA     I1 @S9S_MB_2U_LIB.S9S_MB_2U(SCH_1):PAGE36
    U2 CM87 VCCIN334 SOCKET4677_AZIF0045P001C01CS-SA     I1 @S9S_MB_2U_LIB.S9S_MB_2U(SCH_1):PAGE36
    U2 CM91 VCCIN335 SOCKET4677_AZIF0045P001C01CS-SA     I1 @S9S_MB_2U_LIB.S9S_MB_2U(SCH_1):PAGE36
    U2 CN88 VCCIN336 SOCKET4677_AZIF0045P001C01CS-SA     I1 @S9S_MB_2U_LIB.S9S_MB_2U(SCH_1):PAGE36
    U2 CN90 VCCIN337 SOCKET4677_AZIF0045P001C01CS-SA     I1 @S9S_MB_2U_LIB.S9S_MB_2U(SCH_1):PAGE36
    U2 CP89 VCCIN338 SOCKET4677_AZIF0045P001C01CS-SA     I1 @S9S_MB_2U_LIB.S9S_MB_2U(SCH_1):PAGE36
    U2 CM89 VCCIN339 SOCKET4677_AZIF0045P001C01CS-SA     I1 @S9S_MB_2U_LIB.S9S_MB_2U(SCH_1):PAGE36
    U2 BN43 VCCIN40 SOCKET4677_AZIF0045P001C01CS-SA     I7 @S9S_MB_2U_LIB.S9S_MB_2U(SCH_1):PAGE36
    U2 BN45 VCCIN41 SOCKET4677_AZIF0045P001C01CS-SA     I7 @S9S_MB_2U_LIB.S9S_MB_2U(SCH_1):PAGE36
    U2 BN48 VCCIN42 SOCKET4677_AZIF0045P001C01CS-SA     I7 @S9S_MB_2U_LIB.S9S_MB_2U(SCH_1):PAGE36
    U2 BN50 VCCIN43 SOCKET4677_AZIF0045P001C01CS-SA     I7 @S9S_MB_2U_LIB.S9S_MB_2U(SCH_1):PAGE36
    U2 BN52 VCCIN44 SOCKET4677_AZIF0045P001C01CS-SA     I7 @S9S_MB_2U_LIB.S9S_MB_2U(SCH_1):PAGE36
    U2 BN54 VCCIN45 SOCKET4677_AZIF0045P001C01CS-SA     I7 @S9S_MB_2U_LIB.S9S_MB_2U(SCH_1):PAGE36
    U2 BN56 VCCIN46 SOCKET4677_AZIF0045P001C01CS-SA     I7 @S9S_MB_2U_LIB.S9S_MB_2U(SCH_1):PAGE36
    U2 BN58 VCCIN47 SOCKET4677_AZIF0045P001C01CS-SA     I7 @S9S_MB_2U_LIB.S9S_MB_2U(SCH_1):PAGE36
    U2 BN60 VCCIN48 SOCKET4677_AZIF0045P001C01CS-SA     I7 @S9S_MB_2U_LIB.S9S_MB_2U(SCH_1):PAGE36
    U2 BN78 VCCIN49 SOCKET4677_AZIF0045P001C01CS-SA     I7 @S9S_MB_2U_LIB.S9S_MB_2U(SCH_1):PAGE36
    U2 BN80 VCCIN50 SOCKET4677_AZIF0045P001C01CS-SA     I7 @S9S_MB_2U_LIB.S9S_MB_2U(SCH_1):PAGE36
    U2 BN82 VCCIN51 SOCKET4677_AZIF0045P001C01CS-SA     I7 @S9S_MB_2U_LIB.S9S_MB_2U(SCH_1):PAGE36
    U2 BN84 VCCIN52 SOCKET4677_AZIF0045P001C01CS-SA     I7 @S9S_MB_2U_LIB.S9S_MB_2U(SCH_1):PAGE36
    U2 BN86 VCCIN53 SOCKET4677_AZIF0045P001C01CS-SA     I7 @S9S_MB_2U_LIB.S9S_MB_2U(SCH_1):PAGE36
    U2 BN88 VCCIN54 SOCKET4677_AZIF0045P001C01CS-SA     I7 @S9S_MB_2U_LIB.S9S_MB_2U(SCH_1):PAGE36
    U2 BN90 VCCIN55 SOCKET4677_AZIF0045P001C01CS-SA     I7 @S9S_MB_2U_LIB.S9S_MB_2U(SCH_1):PAGE36
    U2 BP32 VCCIN56 SOCKET4677_AZIF0045P001C01CS-SA     I7 @S9S_MB_2U_LIB.S9S_MB_2U(SCH_1):PAGE36
    U2 BP34 VCCIN57 SOCKET4677_AZIF0045P001C01CS-SA     I7 @S9S_MB_2U_LIB.S9S_MB_2U(SCH_1):PAGE36
    U2 BP36 VCCIN58 SOCKET4677_AZIF0045P001C01CS-SA     I7 @S9S_MB_2U_LIB.S9S_MB_2U(SCH_1):PAGE36
    U2 BP38 VCCIN59 SOCKET4677_AZIF0045P001C01CS-SA     I7 @S9S_MB_2U_LIB.S9S_MB_2U(SCH_1):PAGE36
    U2 BP40 VCCIN60 SOCKET4677_AZIF0045P001C01CS-SA     I7 @S9S_MB_2U_LIB.S9S_MB_2U(SCH_1):PAGE36
    U2 BP42 VCCIN61 SOCKET4677_AZIF0045P001C01CS-SA     I7 @S9S_MB_2U_LIB.S9S_MB_2U(SCH_1):PAGE36
    U2 BP44 VCCIN62 SOCKET4677_AZIF0045P001C01CS-SA     I7 @S9S_MB_2U_LIB.S9S_MB_2U(SCH_1):PAGE36
    U2 BP47 VCCIN63 SOCKET4677_AZIF0045P001C01CS-SA     I7 @S9S_MB_2U_LIB.S9S_MB_2U(SCH_1):PAGE36
    U2 BP49 VCCIN64 SOCKET4677_AZIF0045P001C01CS-SA     I7 @S9S_MB_2U_LIB.S9S_MB_2U(SCH_1):PAGE36
    U2 BP51 VCCIN65 SOCKET4677_AZIF0045P001C01CS-SA     I7 @S9S_MB_2U_LIB.S9S_MB_2U(SCH_1):PAGE36
    U2 BP53 VCCIN66 SOCKET4677_AZIF0045P001C01CS-SA     I7 @S9S_MB_2U_LIB.S9S_MB_2U(SCH_1):PAGE36
    U2 BP55 VCCIN67 SOCKET4677_AZIF0045P001C01CS-SA     I7 @S9S_MB_2U_LIB.S9S_MB_2U(SCH_1):PAGE36
    U2 BP57 VCCIN68 SOCKET4677_AZIF0045P001C01CS-SA     I7 @S9S_MB_2U_LIB.S9S_MB_2U(SCH_1):PAGE36
    U2 BP59 VCCIN69 SOCKET4677_AZIF0045P001C01CS-SA     I7 @S9S_MB_2U_LIB.S9S_MB_2U(SCH_1):PAGE36
    U2 BP61 VCCIN70 SOCKET4677_AZIF0045P001C01CS-SA     I7 @S9S_MB_2U_LIB.S9S_MB_2U(SCH_1):PAGE36
    U2 BP79 VCCIN71 SOCKET4677_AZIF0045P001C01CS-SA     I7 @S9S_MB_2U_LIB.S9S_MB_2U(SCH_1):PAGE36
    U2 BP81 VCCIN72 SOCKET4677_AZIF0045P001C01CS-SA     I7 @S9S_MB_2U_LIB.S9S_MB_2U(SCH_1):PAGE36
    U2 BP83 VCCIN73 SOCKET4677_AZIF0045P001C01CS-SA     I7 @S9S_MB_2U_LIB.S9S_MB_2U(SCH_1):PAGE36
    U2 BP85 VCCIN74 SOCKET4677_AZIF0045P001C01CS-SA     I7 @S9S_MB_2U_LIB.S9S_MB_2U(SCH_1):PAGE36
    U2 BP87 VCCIN75 SOCKET4677_AZIF0045P001C01CS-SA     I7 @S9S_MB_2U_LIB.S9S_MB_2U(SCH_1):PAGE36
    U2 BP89 VCCIN76 SOCKET4677_AZIF0045P001C01CS-SA     I7 @S9S_MB_2U_LIB.S9S_MB_2U(SCH_1):PAGE36
    U2 BR60 VCCIN77 SOCKET4677_AZIF0045P001C01CS-SA     I7 @S9S_MB_2U_LIB.S9S_MB_2U(SCH_1):PAGE36
    U2 BR62 VCCIN78 SOCKET4677_AZIF0045P001C01CS-SA     I7 @S9S_MB_2U_LIB.S9S_MB_2U(SCH_1):PAGE36
    U2 BR78 VCCIN79 SOCKET4677_AZIF0045P001C01CS-SA     I7 @S9S_MB_2U_LIB.S9S_MB_2U(SCH_1):PAGE36
    U2 BT32 VCCIN80 SOCKET4677_AZIF0045P001C01CS-SA     I7 @S9S_MB_2U_LIB.S9S_MB_2U(SCH_1):PAGE36
    U2 BT34 VCCIN81 SOCKET4677_AZIF0045P001C01CS-SA     I7 @S9S_MB_2U_LIB.S9S_MB_2U(SCH_1):PAGE36
    U2 BT36 VCCIN82 SOCKET4677_AZIF0045P001C01CS-SA     I7 @S9S_MB_2U_LIB.S9S_MB_2U(SCH_1):PAGE36
    U2 BT38 VCCIN83 SOCKET4677_AZIF0045P001C01CS-SA     I7 @S9S_MB_2U_LIB.S9S_MB_2U(SCH_1):PAGE36
    U2 BT40 VCCIN84 SOCKET4677_AZIF0045P001C01CS-SA     I7 @S9S_MB_2U_LIB.S9S_MB_2U(SCH_1):PAGE36
    U2 BT42 VCCIN85 SOCKET4677_AZIF0045P001C01CS-SA     I7 @S9S_MB_2U_LIB.S9S_MB_2U(SCH_1):PAGE36
    U2 BT44 VCCIN86 SOCKET4677_AZIF0045P001C01CS-SA     I7 @S9S_MB_2U_LIB.S9S_MB_2U(SCH_1):PAGE36
    U2 BT47 VCCIN87 SOCKET4677_AZIF0045P001C01CS-SA     I7 @S9S_MB_2U_LIB.S9S_MB_2U(SCH_1):PAGE36
    U2 BT49 VCCIN88 SOCKET4677_AZIF0045P001C01CS-SA     I7 @S9S_MB_2U_LIB.S9S_MB_2U(SCH_1):PAGE36
    U2 BT51 VCCIN89 SOCKET4677_AZIF0045P001C01CS-SA     I7 @S9S_MB_2U_LIB.S9S_MB_2U(SCH_1):PAGE36
    U2 BT53 VCCIN90 SOCKET4677_AZIF0045P001C01CS-SA     I7 @S9S_MB_2U_LIB.S9S_MB_2U(SCH_1):PAGE36
    U2 BT55 VCCIN91 SOCKET4677_AZIF0045P001C01CS-SA     I7 @S9S_MB_2U_LIB.S9S_MB_2U(SCH_1):PAGE36
    U2 BT57 VCCIN92 SOCKET4677_AZIF0045P001C01CS-SA     I7 @S9S_MB_2U_LIB.S9S_MB_2U(SCH_1):PAGE36
    U2 BT59 VCCIN93 SOCKET4677_AZIF0045P001C01CS-SA     I7 @S9S_MB_2U_LIB.S9S_MB_2U(SCH_1):PAGE36
    U2 BT61 VCCIN94 SOCKET4677_AZIF0045P001C01CS-SA     I7 @S9S_MB_2U_LIB.S9S_MB_2U(SCH_1):PAGE36
    U2 BT63 VCCIN95 SOCKET4677_AZIF0045P001C01CS-SA     I7 @S9S_MB_2U_LIB.S9S_MB_2U(SCH_1):PAGE36
    U2 BT65 VCCIN96 SOCKET4677_AZIF0045P001C01CS-SA     I7 @S9S_MB_2U_LIB.S9S_MB_2U(SCH_1):PAGE36
    U2 BT67 VCCIN97 SOCKET4677_AZIF0045P001C01CS-SA     I7 @S9S_MB_2U_LIB.S9S_MB_2U(SCH_1):PAGE36
    U2 BT69 VCCIN98 SOCKET4677_AZIF0045P001C01CS-SA     I7 @S9S_MB_2U_LIB.S9S_MB_2U(SCH_1):PAGE36
    U2 BT71 VCCIN99 SOCKET4677_AZIF0045P001C01CS-SA     I7 @S9S_MB_2U_LIB.S9S_MB_2U(SCH_1):PAGE36
    U2 BT73 VCCIN100 SOCKET4677_AZIF0045P001C01CS-SA     I7 @S9S_MB_2U_LIB.S9S_MB_2U(SCH_1):PAGE36
    U2 BT75 VCCIN101 SOCKET4677_AZIF0045P001C01CS-SA     I7 @S9S_MB_2U_LIB.S9S_MB_2U(SCH_1):PAGE36
    U2 BT77 VCCIN102 SOCKET4677_AZIF0045P001C01CS-SA     I7 @S9S_MB_2U_LIB.S9S_MB_2U(SCH_1):PAGE36
    U2 BT79 VCCIN103 SOCKET4677_AZIF0045P001C01CS-SA     I7 @S9S_MB_2U_LIB.S9S_MB_2U(SCH_1):PAGE36
    U2 BT81 VCCIN104 SOCKET4677_AZIF0045P001C01CS-SA     I7 @S9S_MB_2U_LIB.S9S_MB_2U(SCH_1):PAGE36
    U2 BT83 VCCIN105 SOCKET4677_AZIF0045P001C01CS-SA     I7 @S9S_MB_2U_LIB.S9S_MB_2U(SCH_1):PAGE36
    U2 BT85 VCCIN106 SOCKET4677_AZIF0045P001C01CS-SA     I7 @S9S_MB_2U_LIB.S9S_MB_2U(SCH_1):PAGE36
    U2 BT87 VCCIN107 SOCKET4677_AZIF0045P001C01CS-SA     I7 @S9S_MB_2U_LIB.S9S_MB_2U(SCH_1):PAGE36
    U2 BT89 VCCIN108 SOCKET4677_AZIF0045P001C01CS-SA     I7 @S9S_MB_2U_LIB.S9S_MB_2U(SCH_1):PAGE36
    U2 BU33 VCCIN109 SOCKET4677_AZIF0045P001C01CS-SA     I7 @S9S_MB_2U_LIB.S9S_MB_2U(SCH_1):PAGE36
    U2 BU35 VCCIN110 SOCKET4677_AZIF0045P001C01CS-SA     I7 @S9S_MB_2U_LIB.S9S_MB_2U(SCH_1):PAGE36
    U2 BU37 VCCIN111 SOCKET4677_AZIF0045P001C01CS-SA     I7 @S9S_MB_2U_LIB.S9S_MB_2U(SCH_1):PAGE36
    U2 BU39 VCCIN112 SOCKET4677_AZIF0045P001C01CS-SA     I7 @S9S_MB_2U_LIB.S9S_MB_2U(SCH_1):PAGE36
    U2 BU41 VCCIN113 SOCKET4677_AZIF0045P001C01CS-SA     I7 @S9S_MB_2U_LIB.S9S_MB_2U(SCH_1):PAGE36
    U2 BU43 VCCIN114 SOCKET4677_AZIF0045P001C01CS-SA     I7 @S9S_MB_2U_LIB.S9S_MB_2U(SCH_1):PAGE36
    U2 BU45 VCCIN115 SOCKET4677_AZIF0045P001C01CS-SA     I7 @S9S_MB_2U_LIB.S9S_MB_2U(SCH_1):PAGE36
    U2 BU48 VCCIN116 SOCKET4677_AZIF0045P001C01CS-SA     I7 @S9S_MB_2U_LIB.S9S_MB_2U(SCH_1):PAGE36
    U2 BU50 VCCIN117 SOCKET4677_AZIF0045P001C01CS-SA     I7 @S9S_MB_2U_LIB.S9S_MB_2U(SCH_1):PAGE36
    U2 BU52 VCCIN118 SOCKET4677_AZIF0045P001C01CS-SA     I7 @S9S_MB_2U_LIB.S9S_MB_2U(SCH_1):PAGE36
    U2 BU54 VCCIN119 SOCKET4677_AZIF0045P001C01CS-SA     I7 @S9S_MB_2U_LIB.S9S_MB_2U(SCH_1):PAGE36
    U2 BU56 VCCIN120 SOCKET4677_AZIF0045P001C01CS-SA     I7 @S9S_MB_2U_LIB.S9S_MB_2U(SCH_1):PAGE36
    U2 BU58 VCCIN121 SOCKET4677_AZIF0045P001C01CS-SA     I7 @S9S_MB_2U_LIB.S9S_MB_2U(SCH_1):PAGE36
    U2 BU60 VCCIN122 SOCKET4677_AZIF0045P001C01CS-SA     I7 @S9S_MB_2U_LIB.S9S_MB_2U(SCH_1):PAGE36
    U2 BU62 VCCIN123 SOCKET4677_AZIF0045P001C01CS-SA     I7 @S9S_MB_2U_LIB.S9S_MB_2U(SCH_1):PAGE36
    U2 BU64 VCCIN124 SOCKET4677_AZIF0045P001C01CS-SA     I7 @S9S_MB_2U_LIB.S9S_MB_2U(SCH_1):PAGE36
    U2 BU66 VCCIN125 SOCKET4677_AZIF0045P001C01CS-SA     I7 @S9S_MB_2U_LIB.S9S_MB_2U(SCH_1):PAGE36
    U2 BU68 VCCIN126 SOCKET4677_AZIF0045P001C01CS-SA     I7 @S9S_MB_2U_LIB.S9S_MB_2U(SCH_1):PAGE36
    U2 BU70 VCCIN127 SOCKET4677_AZIF0045P001C01CS-SA     I7 @S9S_MB_2U_LIB.S9S_MB_2U(SCH_1):PAGE36
    U2 BU72 VCCIN128 SOCKET4677_AZIF0045P001C01CS-SA     I7 @S9S_MB_2U_LIB.S9S_MB_2U(SCH_1):PAGE36
    U2 BU74 VCCIN129 SOCKET4677_AZIF0045P001C01CS-SA     I7 @S9S_MB_2U_LIB.S9S_MB_2U(SCH_1):PAGE36
    U2 BU76 VCCIN130 SOCKET4677_AZIF0045P001C01CS-SA     I7 @S9S_MB_2U_LIB.S9S_MB_2U(SCH_1):PAGE36
    U2 BU78 VCCIN131 SOCKET4677_AZIF0045P001C01CS-SA     I7 @S9S_MB_2U_LIB.S9S_MB_2U(SCH_1):PAGE36
    U2 BU80 VCCIN132 SOCKET4677_AZIF0045P001C01CS-SA     I7 @S9S_MB_2U_LIB.S9S_MB_2U(SCH_1):PAGE36
    U2 BU82 VCCIN133 SOCKET4677_AZIF0045P001C01CS-SA     I7 @S9S_MB_2U_LIB.S9S_MB_2U(SCH_1):PAGE36
    U2 BU84 VCCIN134 SOCKET4677_AZIF0045P001C01CS-SA     I7 @S9S_MB_2U_LIB.S9S_MB_2U(SCH_1):PAGE36
    U2 BU86 VCCIN135 SOCKET4677_AZIF0045P001C01CS-SA     I7 @S9S_MB_2U_LIB.S9S_MB_2U(SCH_1):PAGE36
    U2 BU88 VCCIN136 SOCKET4677_AZIF0045P001C01CS-SA     I7 @S9S_MB_2U_LIB.S9S_MB_2U(SCH_1):PAGE36
    U2 BU90 VCCIN137 SOCKET4677_AZIF0045P001C01CS-SA     I7 @S9S_MB_2U_LIB.S9S_MB_2U(SCH_1):PAGE36
    U2 BV32 VCCIN138 SOCKET4677_AZIF0045P001C01CS-SA     I7 @S9S_MB_2U_LIB.S9S_MB_2U(SCH_1):PAGE36
    U2 BV34 VCCIN139 SOCKET4677_AZIF0045P001C01CS-SA     I7 @S9S_MB_2U_LIB.S9S_MB_2U(SCH_1):PAGE36
    U2 BV36 VCCIN140 SOCKET4677_AZIF0045P001C01CS-SA     I7 @S9S_MB_2U_LIB.S9S_MB_2U(SCH_1):PAGE36
    U2 BV38 VCCIN141 SOCKET4677_AZIF0045P001C01CS-SA     I7 @S9S_MB_2U_LIB.S9S_MB_2U(SCH_1):PAGE36
    U2 BV40 VCCIN142 SOCKET4677_AZIF0045P001C01CS-SA     I7 @S9S_MB_2U_LIB.S9S_MB_2U(SCH_1):PAGE36
    U2 BV42 VCCIN143 SOCKET4677_AZIF0045P001C01CS-SA     I7 @S9S_MB_2U_LIB.S9S_MB_2U(SCH_1):PAGE36
    U2 BV44 VCCIN144 SOCKET4677_AZIF0045P001C01CS-SA     I7 @S9S_MB_2U_LIB.S9S_MB_2U(SCH_1):PAGE36
    U2 BV47 VCCIN145 SOCKET4677_AZIF0045P001C01CS-SA     I7 @S9S_MB_2U_LIB.S9S_MB_2U(SCH_1):PAGE36
    U2 BV49 VCCIN146 SOCKET4677_AZIF0045P001C01CS-SA     I7 @S9S_MB_2U_LIB.S9S_MB_2U(SCH_1):PAGE36
    U2 BV51 VCCIN147 SOCKET4677_AZIF0045P001C01CS-SA     I7 @S9S_MB_2U_LIB.S9S_MB_2U(SCH_1):PAGE36
    U2 BV53 VCCIN148 SOCKET4677_AZIF0045P001C01CS-SA     I7 @S9S_MB_2U_LIB.S9S_MB_2U(SCH_1):PAGE36
    U2 BV55 VCCIN149 SOCKET4677_AZIF0045P001C01CS-SA     I7 @S9S_MB_2U_LIB.S9S_MB_2U(SCH_1):PAGE36
    U2 BV57 VCCIN150 SOCKET4677_AZIF0045P001C01CS-SA     I7 @S9S_MB_2U_LIB.S9S_MB_2U(SCH_1):PAGE36
    U2 BV59 VCCIN151 SOCKET4677_AZIF0045P001C01CS-SA     I7 @S9S_MB_2U_LIB.S9S_MB_2U(SCH_1):PAGE36
    U2 BV61 VCCIN152 SOCKET4677_AZIF0045P001C01CS-SA     I7 @S9S_MB_2U_LIB.S9S_MB_2U(SCH_1):PAGE36
    U2 BV63 VCCIN153 SOCKET4677_AZIF0045P001C01CS-SA     I7 @S9S_MB_2U_LIB.S9S_MB_2U(SCH_1):PAGE36
    U2 BV65 VCCIN154 SOCKET4677_AZIF0045P001C01CS-SA     I7 @S9S_MB_2U_LIB.S9S_MB_2U(SCH_1):PAGE36
    U2 BV67 VCCIN155 SOCKET4677_AZIF0045P001C01CS-SA     I7 @S9S_MB_2U_LIB.S9S_MB_2U(SCH_1):PAGE36
    U2 BV69 VCCIN156 SOCKET4677_AZIF0045P001C01CS-SA     I7 @S9S_MB_2U_LIB.S9S_MB_2U(SCH_1):PAGE36
    U2 BV71 VCCIN157 SOCKET4677_AZIF0045P001C01CS-SA     I7 @S9S_MB_2U_LIB.S9S_MB_2U(SCH_1):PAGE36
    U2 BV73 VCCIN158 SOCKET4677_AZIF0045P001C01CS-SA     I7 @S9S_MB_2U_LIB.S9S_MB_2U(SCH_1):PAGE36
    U2 BV75 VCCIN159 SOCKET4677_AZIF0045P001C01CS-SA     I7 @S9S_MB_2U_LIB.S9S_MB_2U(SCH_1):PAGE36
    U2 BV77 VCCIN160 SOCKET4677_AZIF0045P001C01CS-SA     I7 @S9S_MB_2U_LIB.S9S_MB_2U(SCH_1):PAGE36
    U2 BV79 VCCIN161 SOCKET4677_AZIF0045P001C01CS-SA     I7 @S9S_MB_2U_LIB.S9S_MB_2U(SCH_1):PAGE36
    U2 BV81 VCCIN162 SOCKET4677_AZIF0045P001C01CS-SA     I7 @S9S_MB_2U_LIB.S9S_MB_2U(SCH_1):PAGE36
    U2 BV83 VCCIN163 SOCKET4677_AZIF0045P001C01CS-SA     I7 @S9S_MB_2U_LIB.S9S_MB_2U(SCH_1):PAGE36
    U2 BV85 VCCIN164 SOCKET4677_AZIF0045P001C01CS-SA     I7 @S9S_MB_2U_LIB.S9S_MB_2U(SCH_1):PAGE36
    U2 BV87 VCCIN165 SOCKET4677_AZIF0045P001C01CS-SA     I7 @S9S_MB_2U_LIB.S9S_MB_2U(SCH_1):PAGE36
    U2 BV89 VCCIN166 SOCKET4677_AZIF0045P001C01CS-SA     I7 @S9S_MB_2U_LIB.S9S_MB_2U(SCH_1):PAGE36
    U2 BW33 VCCIN167 SOCKET4677_AZIF0045P001C01CS-SA     I7 @S9S_MB_2U_LIB.S9S_MB_2U(SCH_1):PAGE36
    U2 BW35 VCCIN168 SOCKET4677_AZIF0045P001C01CS-SA     I7 @S9S_MB_2U_LIB.S9S_MB_2U(SCH_1):PAGE36
    U2 BW37 VCCIN169 SOCKET4677_AZIF0045P001C01CS-SA     I7 @S9S_MB_2U_LIB.S9S_MB_2U(SCH_1):PAGE36
    U2 BW39 VCCIN170 SOCKET4677_AZIF0045P001C01CS-SA     I7 @S9S_MB_2U_LIB.S9S_MB_2U(SCH_1):PAGE36
    U2 BW41 VCCIN171 SOCKET4677_AZIF0045P001C01CS-SA     I7 @S9S_MB_2U_LIB.S9S_MB_2U(SCH_1):PAGE36
    U2 BW43 VCCIN172 SOCKET4677_AZIF0045P001C01CS-SA     I7 @S9S_MB_2U_LIB.S9S_MB_2U(SCH_1):PAGE36
    U2 BW45 VCCIN173 SOCKET4677_AZIF0045P001C01CS-SA     I7 @S9S_MB_2U_LIB.S9S_MB_2U(SCH_1):PAGE36
    U2 BW48 VCCIN174 SOCKET4677_AZIF0045P001C01CS-SA     I7 @S9S_MB_2U_LIB.S9S_MB_2U(SCH_1):PAGE36
    U2 BW50 VCCIN175 SOCKET4677_AZIF0045P001C01CS-SA     I7 @S9S_MB_2U_LIB.S9S_MB_2U(SCH_1):PAGE36
    U2 BW52 VCCIN176 SOCKET4677_AZIF0045P001C01CS-SA     I7 @S9S_MB_2U_LIB.S9S_MB_2U(SCH_1):PAGE36
    U2 BW54 VCCIN177 SOCKET4677_AZIF0045P001C01CS-SA     I7 @S9S_MB_2U_LIB.S9S_MB_2U(SCH_1):PAGE36
    U2 BW56 VCCIN178 SOCKET4677_AZIF0045P001C01CS-SA     I7 @S9S_MB_2U_LIB.S9S_MB_2U(SCH_1):PAGE36
    U2 BW58 VCCIN179 SOCKET4677_AZIF0045P001C01CS-SA     I7 @S9S_MB_2U_LIB.S9S_MB_2U(SCH_1):PAGE36
    U2 BW60 VCCIN180 SOCKET4677_AZIF0045P001C01CS-SA     I7 @S9S_MB_2U_LIB.S9S_MB_2U(SCH_1):PAGE36
    U2 BW62 VCCIN181 SOCKET4677_AZIF0045P001C01CS-SA     I7 @S9S_MB_2U_LIB.S9S_MB_2U(SCH_1):PAGE36
    U2 BW64 VCCIN182 SOCKET4677_AZIF0045P001C01CS-SA     I7 @S9S_MB_2U_LIB.S9S_MB_2U(SCH_1):PAGE36
    U2 BW66 VCCIN183 SOCKET4677_AZIF0045P001C01CS-SA     I7 @S9S_MB_2U_LIB.S9S_MB_2U(SCH_1):PAGE36
    U2 BW68 VCCIN184 SOCKET4677_AZIF0045P001C01CS-SA     I7 @S9S_MB_2U_LIB.S9S_MB_2U(SCH_1):PAGE36
    U2 BW70 VCCIN185 SOCKET4677_AZIF0045P001C01CS-SA     I7 @S9S_MB_2U_LIB.S9S_MB_2U(SCH_1):PAGE36
    U2 BW72 VCCIN186 SOCKET4677_AZIF0045P001C01CS-SA     I7 @S9S_MB_2U_LIB.S9S_MB_2U(SCH_1):PAGE36
    U2 BW74 VCCIN187 SOCKET4677_AZIF0045P001C01CS-SA     I7 @S9S_MB_2U_LIB.S9S_MB_2U(SCH_1):PAGE36
    U2 BW76 VCCIN188 SOCKET4677_AZIF0045P001C01CS-SA     I7 @S9S_MB_2U_LIB.S9S_MB_2U(SCH_1):PAGE36
    U2 BW78 VCCIN189 SOCKET4677_AZIF0045P001C01CS-SA     I7 @S9S_MB_2U_LIB.S9S_MB_2U(SCH_1):PAGE36
    U2 BD91 VCCIN0 SOCKET4677_AZIF0045P001C01CS-SA     I7 @S9S_MB_2U_LIB.S9S_MB_2U(SCH_1):PAGE37
    U2 BE86 VCCIN1 SOCKET4677_AZIF0045P001C01CS-SA     I7 @S9S_MB_2U_LIB.S9S_MB_2U(SCH_1):PAGE37
    U2 BE88 VCCIN2 SOCKET4677_AZIF0045P001C01CS-SA     I7 @S9S_MB_2U_LIB.S9S_MB_2U(SCH_1):PAGE37
    U2 BE90 VCCIN3 SOCKET4677_AZIF0045P001C01CS-SA     I7 @S9S_MB_2U_LIB.S9S_MB_2U(SCH_1):PAGE37
    U2 BF85 VCCIN4 SOCKET4677_AZIF0045P001C01CS-SA     I7 @S9S_MB_2U_LIB.S9S_MB_2U(SCH_1):PAGE37
    U2 BF87 VCCIN5 SOCKET4677_AZIF0045P001C01CS-SA     I7 @S9S_MB_2U_LIB.S9S_MB_2U(SCH_1):PAGE37
    U2 BF89 VCCIN6 SOCKET4677_AZIF0045P001C01CS-SA     I7 @S9S_MB_2U_LIB.S9S_MB_2U(SCH_1):PAGE37
    U2 BF91 VCCIN7 SOCKET4677_AZIF0045P001C01CS-SA     I7 @S9S_MB_2U_LIB.S9S_MB_2U(SCH_1):PAGE37
    U2 BG84 VCCIN8 SOCKET4677_AZIF0045P001C01CS-SA     I7 @S9S_MB_2U_LIB.S9S_MB_2U(SCH_1):PAGE37
    U2 BG86 VCCIN9 SOCKET4677_AZIF0045P001C01CS-SA     I7 @S9S_MB_2U_LIB.S9S_MB_2U(SCH_1):PAGE37
    U2 BG88 VCCIN10 SOCKET4677_AZIF0045P001C01CS-SA     I7 @S9S_MB_2U_LIB.S9S_MB_2U(SCH_1):PAGE37
    U2 BG90 VCCIN11 SOCKET4677_AZIF0045P001C01CS-SA     I7 @S9S_MB_2U_LIB.S9S_MB_2U(SCH_1):PAGE37
    U2 BH85 VCCIN12 SOCKET4677_AZIF0045P001C01CS-SA     I7 @S9S_MB_2U_LIB.S9S_MB_2U(SCH_1):PAGE37
    U2 BH87 VCCIN13 SOCKET4677_AZIF0045P001C01CS-SA     I7 @S9S_MB_2U_LIB.S9S_MB_2U(SCH_1):PAGE37
    U2 BH89 VCCIN14 SOCKET4677_AZIF0045P001C01CS-SA     I7 @S9S_MB_2U_LIB.S9S_MB_2U(SCH_1):PAGE37
    U2 BH91 VCCIN15 SOCKET4677_AZIF0045P001C01CS-SA     I7 @S9S_MB_2U_LIB.S9S_MB_2U(SCH_1):PAGE37
    U2 BK81 VCCIN16 SOCKET4677_AZIF0045P001C01CS-SA     I7 @S9S_MB_2U_LIB.S9S_MB_2U(SCH_1):PAGE37
    U2 BK83 VCCIN17 SOCKET4677_AZIF0045P001C01CS-SA     I7 @S9S_MB_2U_LIB.S9S_MB_2U(SCH_1):PAGE37
    U2 BK85 VCCIN18 SOCKET4677_AZIF0045P001C01CS-SA     I7 @S9S_MB_2U_LIB.S9S_MB_2U(SCH_1):PAGE37
    U2 BK87 VCCIN19 SOCKET4677_AZIF0045P001C01CS-SA     I7 @S9S_MB_2U_LIB.S9S_MB_2U(SCH_1):PAGE37
    U2 BK89 VCCIN20 SOCKET4677_AZIF0045P001C01CS-SA     I7 @S9S_MB_2U_LIB.S9S_MB_2U(SCH_1):PAGE37
    U2 BK91 VCCIN21 SOCKET4677_AZIF0045P001C01CS-SA     I7 @S9S_MB_2U_LIB.S9S_MB_2U(SCH_1):PAGE37
    U2 BL80 VCCIN22 SOCKET4677_AZIF0045P001C01CS-SA     I7 @S9S_MB_2U_LIB.S9S_MB_2U(SCH_1):PAGE37
    U2 BL82 VCCIN23 SOCKET4677_AZIF0045P001C01CS-SA     I7 @S9S_MB_2U_LIB.S9S_MB_2U(SCH_1):PAGE37
    U2 BL84 VCCIN24 SOCKET4677_AZIF0045P001C01CS-SA     I7 @S9S_MB_2U_LIB.S9S_MB_2U(SCH_1):PAGE37
    U2 BL86 VCCIN25 SOCKET4677_AZIF0045P001C01CS-SA     I7 @S9S_MB_2U_LIB.S9S_MB_2U(SCH_1):PAGE37
    U2 BL88 VCCIN26 SOCKET4677_AZIF0045P001C01CS-SA     I7 @S9S_MB_2U_LIB.S9S_MB_2U(SCH_1):PAGE37
    U2 BL90 VCCIN27 SOCKET4677_AZIF0045P001C01CS-SA     I7 @S9S_MB_2U_LIB.S9S_MB_2U(SCH_1):PAGE37
    U2 BM79 VCCIN28 SOCKET4677_AZIF0045P001C01CS-SA     I7 @S9S_MB_2U_LIB.S9S_MB_2U(SCH_1):PAGE37
    U2 BM81 VCCIN29 SOCKET4677_AZIF0045P001C01CS-SA     I7 @S9S_MB_2U_LIB.S9S_MB_2U(SCH_1):PAGE37
    U2 BM83 VCCIN30 SOCKET4677_AZIF0045P001C01CS-SA     I7 @S9S_MB_2U_LIB.S9S_MB_2U(SCH_1):PAGE37
    U2 BM85 VCCIN31 SOCKET4677_AZIF0045P001C01CS-SA     I7 @S9S_MB_2U_LIB.S9S_MB_2U(SCH_1):PAGE37
    U2 BM87 VCCIN32 SOCKET4677_AZIF0045P001C01CS-SA     I7 @S9S_MB_2U_LIB.S9S_MB_2U(SCH_1):PAGE37
    U2 BM89 VCCIN33 SOCKET4677_AZIF0045P001C01CS-SA     I7 @S9S_MB_2U_LIB.S9S_MB_2U(SCH_1):PAGE37
    U2 BM91 VCCIN34 SOCKET4677_AZIF0045P001C01CS-SA     I7 @S9S_MB_2U_LIB.S9S_MB_2U(SCH_1):PAGE37
    U2 BN33 VCCIN35 SOCKET4677_AZIF0045P001C01CS-SA     I7 @S9S_MB_2U_LIB.S9S_MB_2U(SCH_1):PAGE37
    U2 BN35 VCCIN36 SOCKET4677_AZIF0045P001C01CS-SA     I7 @S9S_MB_2U_LIB.S9S_MB_2U(SCH_1):PAGE37
    U2 BN37 VCCIN37 SOCKET4677_AZIF0045P001C01CS-SA     I7 @S9S_MB_2U_LIB.S9S_MB_2U(SCH_1):PAGE37
    U2 BN39 VCCIN38 SOCKET4677_AZIF0045P001C01CS-SA     I7 @S9S_MB_2U_LIB.S9S_MB_2U(SCH_1):PAGE37
    U2 BN41 VCCIN39 SOCKET4677_AZIF0045P001C01CS-SA     I7 @S9S_MB_2U_LIB.S9S_MB_2U(SCH_1):PAGE37
  C101    1      A Q_CAP_C0805-47UF,4V,20%,X6S,CHA    I13 @S9S_MB_2U_LIB.S9S_MB_2U(SCH_1):PAGE74
  C969    1      A Q_CAP_C0402-10UF,6.3V,20%,X6S,B    I15 @S9S_MB_2U_LIB.S9S_MB_2U(SCH_1):PAGE74
  C212    1      A Q_CAP_C0805-47UF,4V,20%,X6S,CHA    I18 @S9S_MB_2U_LIB.S9S_MB_2U(SCH_1):PAGE74
  C213    1      A Q_CAP_C0805-47UF,4V,20%,X6S,CHA    I20 @S9S_MB_2U_LIB.S9S_MB_2U(SCH_1):PAGE74
  C973    1      A Q_CAP_C0402-10UF,6.3V,20%,X6S,B    I21 @S9S_MB_2U_LIB.S9S_MB_2U(SCH_1):PAGE74
  C977    1      A Q_CAP_C0402-10UF,6.3V,20%,X6S,B    I22 @S9S_MB_2U_LIB.S9S_MB_2U(SCH_1):PAGE74
  C968    1      A Q_CAP_C0402-10UF,6.3V,20%,X6S,B    I23 @S9S_MB_2U_LIB.S9S_MB_2U(SCH_1):PAGE74
  C976    1      A Q_CAP_C0402-10UF,6.3V,20%,X6S,B    I29 @S9S_MB_2U_LIB.S9S_MB_2U(SCH_1):PAGE74
  C971    1      A Q_CAP_C0402-10UF,6.3V,20%,X6S,B    I30 @S9S_MB_2U_LIB.S9S_MB_2U(SCH_1):PAGE74
  C975    1      A Q_CAP_C0402-10UF,6.3V,20%,X6S,B    I32 @S9S_MB_2U_LIB.S9S_MB_2U(SCH_1):PAGE74
  C974    1      A Q_CAP_C0402-10UF,6.3V,20%,X6S,B    I33 @S9S_MB_2U_LIB.S9S_MB_2U(SCH_1):PAGE74
  C214    1      A Q_CAP_C0805-47UF,4V,20%,X6S,CHA    I35 @S9S_MB_2U_LIB.S9S_MB_2U(SCH_1):PAGE74
  C215    1      A Q_CAP_C0805-47UF,4V,20%,X6S,CHA    I36 @S9S_MB_2U_LIB.S9S_MB_2U(SCH_1):PAGE74
  C981    1      A Q_CAP_C0402-10UF,6.3V,20%,X6S,B    I37 @S9S_MB_2U_LIB.S9S_MB_2U(SCH_1):PAGE74
  C985    1      A Q_CAP_C0402-10UF,6.3V,20%,X6S,B    I38 @S9S_MB_2U_LIB.S9S_MB_2U(SCH_1):PAGE74
  C216    1      A Q_CAP_C0805-47UF,4V,20%,X6S,CHA    I40 @S9S_MB_2U_LIB.S9S_MB_2U(SCH_1):PAGE74
  C218    1      A Q_CAP_C0805-47UF,4V,20%,X6S,CHA    I44 @S9S_MB_2U_LIB.S9S_MB_2U(SCH_1):PAGE74
  C993    1      A Q_CAP_C0402-10UF,6.3V,20%,X6S,B    I46 @S9S_MB_2U_LIB.S9S_MB_2U(SCH_1):PAGE74
  C997    1      A Q_CAP_C0402-10UF,6.3V,20%,X6S,B    I47 @S9S_MB_2U_LIB.S9S_MB_2U(SCH_1):PAGE74
  C980    1      A Q_CAP_C0402-10UF,6.3V,20%,X6S,B    I48 @S9S_MB_2U_LIB.S9S_MB_2U(SCH_1):PAGE74
  C984    1      A Q_CAP_C0402-10UF,6.3V,20%,X6S,B    I49 @S9S_MB_2U_LIB.S9S_MB_2U(SCH_1):PAGE74
  C979    1      A Q_CAP_C0402-10UF,6.3V,20%,X6S,B    I50 @S9S_MB_2U_LIB.S9S_MB_2U(SCH_1):PAGE74
  C978    1      A Q_CAP_C0402-10UF,6.3V,20%,X6S,B    I51 @S9S_MB_2U_LIB.S9S_MB_2U(SCH_1):PAGE74
  C983    1      A Q_CAP_C0402-10UF,6.3V,20%,X6S,B    I52 @S9S_MB_2U_LIB.S9S_MB_2U(SCH_1):PAGE74
  C982    1      A Q_CAP_C0402-10UF,6.3V,20%,X6S,B    I53 @S9S_MB_2U_LIB.S9S_MB_2U(SCH_1):PAGE74
  C988    1      A Q_CAP_C0402-10UF,6.3V,20%,X6S,B    I54 @S9S_MB_2U_LIB.S9S_MB_2U(SCH_1):PAGE74
  C996    1      A Q_CAP_C0402-10UF,6.3V,20%,X6S,B    I56 @S9S_MB_2U_LIB.S9S_MB_2U(SCH_1):PAGE74
  C986    1      A Q_CAP_C0402-10UF,6.3V,20%,X6S,B    I58 @S9S_MB_2U_LIB.S9S_MB_2U(SCH_1):PAGE74
  C991    1      A Q_CAP_C0402-10UF,6.3V,20%,X6S,B    I59 @S9S_MB_2U_LIB.S9S_MB_2U(SCH_1):PAGE74
  C990    1      A Q_CAP_C0402-10UF,6.3V,20%,X6S,B    I60 @S9S_MB_2U_LIB.S9S_MB_2U(SCH_1):PAGE74
  C995    1      A Q_CAP_C0402-10UF,6.3V,20%,X6S,B    I61 @S9S_MB_2U_LIB.S9S_MB_2U(SCH_1):PAGE74
  C219    1      A Q_CAP_C0805-47UF,4V,20%,X6S,CHA    I71 @S9S_MB_2U_LIB.S9S_MB_2U(SCH_1):PAGE74
  C220    1      A Q_CAP_C0805-47UF,4V,20%,X6S,CHA    I74 @S9S_MB_2U_LIB.S9S_MB_2U(SCH_1):PAGE74
 C1001    1      A Q_CAP_C0402-10UF,6.3V,20%,X6S,B    I75 @S9S_MB_2U_LIB.S9S_MB_2U(SCH_1):PAGE74
 C1005    1      A Q_CAP_C0402-10UF,6.3V,20%,X6S,B    I77 @S9S_MB_2U_LIB.S9S_MB_2U(SCH_1):PAGE74
 C1009    1      A Q_CAP_C0402-22UF,4V,20%,X6S,CHA    I78 @S9S_MB_2U_LIB.S9S_MB_2U(SCH_1):PAGE74
 C1013    1      A Q_CAP_C0402-22UF,4V,20%,X6S,CHA    I80 @S9S_MB_2U_LIB.S9S_MB_2U(SCH_1):PAGE74
 C1000    1      A Q_CAP_C0402-10UF,6.3V,20%,X6S,B    I81 @S9S_MB_2U_LIB.S9S_MB_2U(SCH_1):PAGE74
  C999    1      A Q_CAP_C0402-10UF,6.3V,20%,X6S,B    I85 @S9S_MB_2U_LIB.S9S_MB_2U(SCH_1):PAGE74
  C998    1      A Q_CAP_C0402-10UF,6.3V,20%,X6S,B    I86 @S9S_MB_2U_LIB.S9S_MB_2U(SCH_1):PAGE74
 C1003    1      A Q_CAP_C0402-10UF,6.3V,20%,X6S,B    I87 @S9S_MB_2U_LIB.S9S_MB_2U(SCH_1):PAGE74
 C1002    1      A Q_CAP_C0402-10UF,6.3V,20%,X6S,B    I89 @S9S_MB_2U_LIB.S9S_MB_2U(SCH_1):PAGE74
 C1008    1      A Q_CAP_C0402-22UF,4V,20%,X6S,CHA    I90 @S9S_MB_2U_LIB.S9S_MB_2U(SCH_1):PAGE74
 C1012    1      A Q_CAP_C0402-22UF,4V,20%,X6S,CHA    I92 @S9S_MB_2U_LIB.S9S_MB_2U(SCH_1):PAGE74
 C1007    1      A Q_CAP_C0402-22UF,4V,20%,X6S,CHA    I93 @S9S_MB_2U_LIB.S9S_MB_2U(SCH_1):PAGE74
 C1006    1      A Q_CAP_C0402-22UF,4V,20%,X6S,CHA    I95 @S9S_MB_2U_LIB.S9S_MB_2U(SCH_1):PAGE74
 C1011    1      A Q_CAP_C0402-22UF,4V,20%,X6S,CHA    I96 @S9S_MB_2U_LIB.S9S_MB_2U(SCH_1):PAGE74
 C1010    1      A Q_CAP_C0402-22UF,4V,20%,X6S,CHA    I97 @S9S_MB_2U_LIB.S9S_MB_2U(SCH_1):PAGE74
 C1017    1      A Q_CAP_C0402-22UF,4V,20%,X6S,CHA   I105 @S9S_MB_2U_LIB.S9S_MB_2U(SCH_1):PAGE74
 C1016    1      A Q_CAP_C0402-22UF,4V,20%,X6S,CHA   I111 @S9S_MB_2U_LIB.S9S_MB_2U(SCH_1):PAGE74
 C1020    1      A Q_CAP_C0402-22UF,4V,20%,X6S,CHA   I112 @S9S_MB_2U_LIB.S9S_MB_2U(SCH_1):PAGE74
 C1015    1      A Q_CAP_C0402-22UF,4V,20%,X6S,CHA   I113 @S9S_MB_2U_LIB.S9S_MB_2U(SCH_1):PAGE74
 C1014    1      A Q_CAP_C0402-22UF,4V,20%,X6S,CHA   I114 @S9S_MB_2U_LIB.S9S_MB_2U(SCH_1):PAGE74
 C1019    1      A Q_CAP_C0402-22UF,4V,20%,X6S,CHA   I115 @S9S_MB_2U_LIB.S9S_MB_2U(SCH_1):PAGE74
 C1036    1      A Q_CAP_C0402-22UF,4V,20%,X6S,CHA   I131 @S9S_MB_2U_LIB.S9S_MB_2U(SCH_1):PAGE74
 C1040    1      A Q_CAP_C0402-22UF,4V,20%,X6S,CHA   I132 @S9S_MB_2U_LIB.S9S_MB_2U(SCH_1):PAGE74
 C1035    1      A Q_CAP_C0402-22UF,4V,20%,X6S,CHA   I133 @S9S_MB_2U_LIB.S9S_MB_2U(SCH_1):PAGE74
 C1034    1      A Q_CAP_C0402-22UF,4V,20%,X6S,CHA   I134 @S9S_MB_2U_LIB.S9S_MB_2U(SCH_1):PAGE74
 C1039    1      A Q_CAP_C0402-22UF,4V,20%,X6S,CHA   I135 @S9S_MB_2U_LIB.S9S_MB_2U(SCH_1):PAGE74
 C1038    1      A Q_CAP_C0402-22UF,4V,20%,X6S,CHA   I137 @S9S_MB_2U_LIB.S9S_MB_2U(SCH_1):PAGE74
 C1044    1      A Q_CAP_C0402-22UF,4V,20%,X6S,CHA   I139 @S9S_MB_2U_LIB.S9S_MB_2U(SCH_1):PAGE74
 C1043    1      A Q_CAP_C0402-22UF,4V,20%,X6S,CHA   I141 @S9S_MB_2U_LIB.S9S_MB_2U(SCH_1):PAGE74
  C359    1      A Q_CAP_C0805-47UF,4V,20%,X6S,CHA    I25 @S9S_MB_2U_LIB.S9S_MB_2U(SCH_1):PAGE75
  C362    1      A Q_CAP_C0805-47UF,4V,20%,X6S,CHA    I26 @S9S_MB_2U_LIB.S9S_MB_2U(SCH_1):PAGE75
  C358    1      A Q_CAP_C0805-47UF,4V,20%,X6S,CHA    I27 @S9S_MB_2U_LIB.S9S_MB_2U(SCH_1):PAGE75
  C361    1      A Q_CAP_C0805-47UF,4V,20%,X6S,CHA    I28 @S9S_MB_2U_LIB.S9S_MB_2U(SCH_1):PAGE75
  C368    1      A Q_CAP_C0805-47UF,4V,20%,X6S,CHA    I33 @S9S_MB_2U_LIB.S9S_MB_2U(SCH_1):PAGE75
  C391    1      A Q_CAP_C0805-47UF,4V,20%,X6S,CHA    I49 @S9S_MB_2U_LIB.S9S_MB_2U(SCH_1):PAGE75
  C379    1      A Q_CAP_C0805-47UF,4V,20%,X6S,CHA    I50 @S9S_MB_2U_LIB.S9S_MB_2U(SCH_1):PAGE75
  C393    1      A Q_CAP_C0805-47UF,4V,20%,X6S,CHA    I52 @S9S_MB_2U_LIB.S9S_MB_2U(SCH_1):PAGE75
  C360    1      A Q_CAP_C0805-47UF,4V,20%,X6S,CHA    I54 @S9S_MB_2U_LIB.S9S_MB_2U(SCH_1):PAGE75
  C381    1      A Q_CAP_C0805-47UF,4V,20%,X6S,CHA    I67 @S9S_MB_2U_LIB.S9S_MB_2U(SCH_1):PAGE75
  C396    1      A Q_CAP_C0805-47UF,4V,20%,X6S,CHA    I46 @S9S_MB_2U_LIB.S9S_MB_2U(SCH_1):PAGE76
  C398    1      A Q_CAP_C0805-47UF,4V,20%,X6S,CHA    I47 @S9S_MB_2U_LIB.S9S_MB_2U(SCH_1):PAGE76
 PL114    4      4 Q_INDUCTOR4P_14-150NH,SMLF,INDA    I46 @S9S_MB_2U_LIB.S9S_MB_2U(SCH_1):PAGE253
  PC16    1      A Q_CAPP_THLF-560UF,2.5V,20%,OSCA    I56 @S9S_MB_2U_LIB.S9S_MB_2U(SCH_1):PAGE253
 PC319    1      A Q_CAPP_THLF-560UF,2.5V,20%,OSCA    I62 @S9S_MB_2U_LIB.S9S_MB_2U(SCH_1):PAGE253
PC310_P0_1    1      A Q_CAP_C0402-1UF,16V,10%,X6S,CHA    I84 @S9S_MB_2U_LIB.S9S_MB_2U(SCH_1):PAGE253
 PL112    4      4 Q_INDUCTOR4P_14-150NH,SMLF,INDA    I50 @S9S_MB_2U_LIB.S9S_MB_2U(SCH_1):PAGE254
   PL9    4      4 Q_INDUCTOR4P_14-150NH,SMLF,INDA    I32 @S9S_MB_2U_LIB.S9S_MB_2U(SCH_1):PAGE255
 PR142    2      B Q_RES_0402LF-0,5%,1/16W,CHIP,CA    I40 @S9S_MB_2U_LIB.S9S_MB_2U(SCH_1):PAGE255
PC266_P0_6    1      A Q_CAP_C0805-22UF,4V,20%,X6S,CHA    I42 @S9S_MB_2U_LIB.S9S_MB_2U(SCH_1):PAGE255
PC268_P0_6    1      A Q_CAP_C0805-22UF,4V,20%,X6S,CHA    I59 @S9S_MB_2U_LIB.S9S_MB_2U(SCH_1):PAGE255
PC242_P0_8    1      A Q_CAP_C0402-1UF,16V,10%,X6S,CHA    I52 @S9S_MB_2U_LIB.S9S_MB_2U(SCH_1):PAGE256
 PR137    2      B Q_RES_0402LF-0,5%,1/16W,CHIP,CA    I57 @S9S_MB_2U_LIB.S9S_MB_2U(SCH_1):PAGE256
   PL8    4      4 Q_INDUCTOR4P_14-150NH,SMLF,INDA    I58 @S9S_MB_2U_LIB.S9S_MB_2U(SCH_1):PAGE256
  C967    1      A Q_CAP_C0402-10UF,6.3V,20%,X6S,B    I25 @S9S_MB_2U_LIB.S9S_MB_2U(SCH_1):PAGE74
  C966    1      A Q_CAP_C0402-10UF,6.3V,20%,X6S,B    I27 @S9S_MB_2U_LIB.S9S_MB_2U(SCH_1):PAGE74
  C972    1      A Q_CAP_C0402-10UF,6.3V,20%,X6S,B    I28 @S9S_MB_2U_LIB.S9S_MB_2U(SCH_1):PAGE74
  C970    1      A Q_CAP_C0402-10UF,6.3V,20%,X6S,B    I31 @S9S_MB_2U_LIB.S9S_MB_2U(SCH_1):PAGE74
  C217    1      A Q_CAP_C0805-47UF,4V,20%,X6S,CHA    I43 @S9S_MB_2U_LIB.S9S_MB_2U(SCH_1):PAGE74
  C989    1      A Q_CAP_C0402-10UF,6.3V,20%,X6S,B    I45 @S9S_MB_2U_LIB.S9S_MB_2U(SCH_1):PAGE74
  C992    1      A Q_CAP_C0402-10UF,6.3V,20%,X6S,B    I55 @S9S_MB_2U_LIB.S9S_MB_2U(SCH_1):PAGE74
  C987    1      A Q_CAP_C0402-10UF,6.3V,20%,X6S,B    I57 @S9S_MB_2U_LIB.S9S_MB_2U(SCH_1):PAGE74
  C994    1      A Q_CAP_C0402-10UF,6.3V,20%,X6S,B    I62 @S9S_MB_2U_LIB.S9S_MB_2U(SCH_1):PAGE74
 C1004    1      A Q_CAP_C0402-10UF,6.3V,20%,X6S,B    I83 @S9S_MB_2U_LIB.S9S_MB_2U(SCH_1):PAGE74
 C1021    1      A Q_CAP_C0402-22UF,4V,20%,X6S,CHA   I106 @S9S_MB_2U_LIB.S9S_MB_2U(SCH_1):PAGE74
 C1025    1      A Q_CAP_C0402-22UF,4V,20%,X6S,CHA   I108 @S9S_MB_2U_LIB.S9S_MB_2U(SCH_1):PAGE74
 C1029    1      A Q_CAP_C0402-22UF,4V,20%,X6S,CHA   I109 @S9S_MB_2U_LIB.S9S_MB_2U(SCH_1):PAGE74
 C1033    1      A Q_CAP_C0402-22UF,4V,20%,X6S,CHA   I110 @S9S_MB_2U_LIB.S9S_MB_2U(SCH_1):PAGE74
 C1018    1      A Q_CAP_C0402-22UF,4V,20%,X6S,CHA   I116 @S9S_MB_2U_LIB.S9S_MB_2U(SCH_1):PAGE74
 C1024    1      A Q_CAP_C0402-22UF,4V,20%,X6S,CHA   I117 @S9S_MB_2U_LIB.S9S_MB_2U(SCH_1):PAGE74
 C1028    1      A Q_CAP_C0402-22UF,4V,20%,X6S,CHA   I118 @S9S_MB_2U_LIB.S9S_MB_2U(SCH_1):PAGE74
 C1032    1      A Q_CAP_C0402-22UF,4V,20%,X6S,CHA   I119 @S9S_MB_2U_LIB.S9S_MB_2U(SCH_1):PAGE74
 C1023    1      A Q_CAP_C0402-22UF,4V,20%,X6S,CHA   I120 @S9S_MB_2U_LIB.S9S_MB_2U(SCH_1):PAGE74
 C1027    1      A Q_CAP_C0402-22UF,4V,20%,X6S,CHA   I121 @S9S_MB_2U_LIB.S9S_MB_2U(SCH_1):PAGE74
 C1022    1      A Q_CAP_C0402-22UF,4V,20%,X6S,CHA   I122 @S9S_MB_2U_LIB.S9S_MB_2U(SCH_1):PAGE74
 C1026    1      A Q_CAP_C0402-22UF,4V,20%,X6S,CHA   I123 @S9S_MB_2U_LIB.S9S_MB_2U(SCH_1):PAGE74
 C1031    1      A Q_CAP_C0402-22UF,4V,20%,X6S,CHA   I124 @S9S_MB_2U_LIB.S9S_MB_2U(SCH_1):PAGE74
 C1030    1      A Q_CAP_C0402-22UF,4V,20%,X6S,CHA   I125 @S9S_MB_2U_LIB.S9S_MB_2U(SCH_1):PAGE74
 C1037    1      A Q_CAP_C0402-22UF,4V,20%,X6S,CHA   I127 @S9S_MB_2U_LIB.S9S_MB_2U(SCH_1):PAGE74
 C1041    1      A Q_CAP_C0402-22UF,4V,20%,X6S,CHA   I128 @S9S_MB_2U_LIB.S9S_MB_2U(SCH_1):PAGE74
 C1045    1      A Q_CAP_C0402-22UF,4V,20%,X6S,CHA   I130 @S9S_MB_2U_LIB.S9S_MB_2U(SCH_1):PAGE74
  C356    1      A Q_CAP_C0805-47UF,4V,20%,X6S,CHA    I21 @S9S_MB_2U_LIB.S9S_MB_2U(SCH_1):PAGE75
  C355    1      A Q_CAP_C0805-47UF,4V,20%,X6S,CHA    I23 @S9S_MB_2U_LIB.S9S_MB_2U(SCH_1):PAGE75
  C365    1      A Q_CAP_C0805-47UF,4V,20%,X6S,CHA    I32 @S9S_MB_2U_LIB.S9S_MB_2U(SCH_1):PAGE75
  C364    1      A Q_CAP_C0805-47UF,4V,20%,X6S,CHA    I34 @S9S_MB_2U_LIB.S9S_MB_2U(SCH_1):PAGE75
  C367    1      A Q_CAP_C0805-47UF,4V,20%,X6S,CHA    I35 @S9S_MB_2U_LIB.S9S_MB_2U(SCH_1):PAGE75
  C371    1      A Q_CAP_C0805-47UF,4V,20%,X6S,CHA    I36 @S9S_MB_2U_LIB.S9S_MB_2U(SCH_1):PAGE75
  C397    1      A Q_CAP_C0805-47UF,4V,20%,X6S,CHA    I37 @S9S_MB_2U_LIB.S9S_MB_2U(SCH_1):PAGE75
  C357    1      A Q_CAP_C0805-47UF,4V,20%,X6S,CHA    I38 @S9S_MB_2U_LIB.S9S_MB_2U(SCH_1):PAGE75
  C370    1      A Q_CAP_C0805-47UF,4V,20%,X6S,CHA    I39 @S9S_MB_2U_LIB.S9S_MB_2U(SCH_1):PAGE75
  C373    1      A Q_CAP_C0805-47UF,4V,20%,X6S,CHA    I40 @S9S_MB_2U_LIB.S9S_MB_2U(SCH_1):PAGE75
  C376    1      A Q_CAP_C0805-47UF,4V,20%,X6S,CHA    I41 @S9S_MB_2U_LIB.S9S_MB_2U(SCH_1):PAGE75
  C389    1      A Q_CAP_C0805-47UF,4V,20%,X6S,CHA    I48 @S9S_MB_2U_LIB.S9S_MB_2U(SCH_1):PAGE75
  C382    1      A Q_CAP_C0805-47UF,4V,20%,X6S,CHA    I51 @S9S_MB_2U_LIB.S9S_MB_2U(SCH_1):PAGE75
  C385    1      A Q_CAP_C0805-47UF,4V,20%,X6S,CHA    I55 @S9S_MB_2U_LIB.S9S_MB_2U(SCH_1):PAGE75
  C387    1      A Q_CAP_C0805-47UF,4V,20%,X6S,CHA    I56 @S9S_MB_2U_LIB.S9S_MB_2U(SCH_1):PAGE75
  C363    1      A Q_CAP_C0805-47UF,4V,20%,X6S,CHA    I64 @S9S_MB_2U_LIB.S9S_MB_2U(SCH_1):PAGE75
  C527    1      A Q_CAP_C0805-47UF,4V,20%,X6S,CHA    I68 @S9S_MB_2U_LIB.S9S_MB_2U(SCH_1):PAGE75
  C386    1      A Q_CAP_C0805-47UF,4V,20%,X6S,CHA    I22 @S9S_MB_2U_LIB.S9S_MB_2U(SCH_1):PAGE76
  C388    1      A Q_CAP_C0805-47UF,4V,20%,X6S,CHA    I23 @S9S_MB_2U_LIB.S9S_MB_2U(SCH_1):PAGE76
  C390    1      A Q_CAP_C0805-47UF,4V,20%,X6S,CHA    I25 @S9S_MB_2U_LIB.S9S_MB_2U(SCH_1):PAGE76
  C392    1      A Q_CAP_C0805-47UF,4V,20%,X6S,CHA    I44 @S9S_MB_2U_LIB.S9S_MB_2U(SCH_1):PAGE76
  C394    1      A Q_CAP_C0805-47UF,4V,20%,X6S,CHA    I45 @S9S_MB_2U_LIB.S9S_MB_2U(SCH_1):PAGE76
  C366    1      A Q_CAP_C0805-47UF,4V,20%,X6S,CHA    I48 @S9S_MB_2U_LIB.S9S_MB_2U(SCH_1):PAGE76
  C369    1      A Q_CAP_C0805-47UF,4V,20%,X6S,CHA    I49 @S9S_MB_2U_LIB.S9S_MB_2U(SCH_1):PAGE76
  C372    1      A Q_CAP_C0805-47UF,4V,20%,X6S,CHA    I50 @S9S_MB_2U_LIB.S9S_MB_2U(SCH_1):PAGE76
  C374    1      A Q_CAP_C0805-47UF,4V,20%,X6S,CHA    I51 @S9S_MB_2U_LIB.S9S_MB_2U(SCH_1):PAGE76
  C377    1      A Q_CAP_C0805-47UF,4V,20%,X6S,CHA    I52 @S9S_MB_2U_LIB.S9S_MB_2U(SCH_1):PAGE76
  C380    1      A Q_CAP_C0805-47UF,4V,20%,X6S,CHA    I53 @S9S_MB_2U_LIB.S9S_MB_2U(SCH_1):PAGE76
  C383    1      A Q_CAP_C0805-47UF,4V,20%,X6S,CHA    I54 @S9S_MB_2U_LIB.S9S_MB_2U(SCH_1):PAGE76
 PR531    2      B Q_RES_0402LF-100,1%,1/16W,CHIPA    I38 @S9S_MB_2U_LIB.S9S_MB_2U(SCH_1):PAGE252
 PR154    2      B Q_RES_0402LF-0,5%,1/16W,CHIP,CA    I51 @S9S_MB_2U_LIB.S9S_MB_2U(SCH_1):PAGE253
 PC316    1      A Q_CAPP_THLF-560UF,2.5V,20%,OSCA    I61 @S9S_MB_2U_LIB.S9S_MB_2U(SCH_1):PAGE253
 PC323    1      A Q_CAPP_SMLF-330UF,2.5V,+10/-35A    I64 @S9S_MB_2U_LIB.S9S_MB_2U(SCH_1):PAGE253
 PC325    1      A Q_CAPP_THLF-560UF,2.5V,20%,OSCA    I70 @S9S_MB_2U_LIB.S9S_MB_2U(SCH_1):PAGE253
 PR155    2      B Q_RES_0402LF-0,5%,1/16W,CHIP,CA    I73 @S9S_MB_2U_LIB.S9S_MB_2U(SCH_1):PAGE253
PC314_P0_1    1      A Q_CAP_C0805-22UF,4V,20%,X6S,CHA    I86 @S9S_MB_2U_LIB.S9S_MB_2U(SCH_1):PAGE253
  PL11    4      4 Q_INDUCTOR4P_14-150NH,SMLF,INDA    I33 @S9S_MB_2U_LIB.S9S_MB_2U(SCH_1):PAGE254
 PR148    2      B Q_RES_0402LF-0,5%,1/16W,CHIP,CA    I41 @S9S_MB_2U_LIB.S9S_MB_2U(SCH_1):PAGE254
 PR149    2      B Q_RES_0402LF-0,5%,1/16W,CHIP,CA    I46 @S9S_MB_2U_LIB.S9S_MB_2U(SCH_1):PAGE254
PC289_P0_3    1      A Q_CAP_C0805-22UF,4V,20%,X6S,CHA    I59 @S9S_MB_2U_LIB.S9S_MB_2U(SCH_1):PAGE254
PC288_P0_4    1      A Q_CAP_C0805-22UF,4V,20%,X6S,CHA    I60 @S9S_MB_2U_LIB.S9S_MB_2U(SCH_1):PAGE254
PC290_P0_4    1      A Q_CAP_C0805-22UF,4V,20%,X6S,CHA    I61 @S9S_MB_2U_LIB.S9S_MB_2U(SCH_1):PAGE254
PC291_P0_3    1      A Q_CAP_C0805-22UF,4V,20%,X6S,CHA    I65 @S9S_MB_2U_LIB.S9S_MB_2U(SCH_1):PAGE254
 PR143    2      B Q_RES_0402LF-0,5%,1/16W,CHIP,CA    I46 @S9S_MB_2U_LIB.S9S_MB_2U(SCH_1):PAGE255
  PL10    4      4 Q_INDUCTOR4P_14-150NH,SMLF,INDA    I50 @S9S_MB_2U_LIB.S9S_MB_2U(SCH_1):PAGE255
PC267_P0_5    1      A Q_CAP_C0805-22UF,4V,20%,X6S,CHA    I63 @S9S_MB_2U_LIB.S9S_MB_2U(SCH_1):PAGE255
PC269_P0_5    1      A Q_CAP_C0805-22UF,4V,20%,X6S,CHA    I64 @S9S_MB_2U_LIB.S9S_MB_2U(SCH_1):PAGE255
   PL7    4      4 Q_INDUCTOR4P_14-150NH,SMLF,INDA    I44 @S9S_MB_2U_LIB.S9S_MB_2U(SCH_1):PAGE256
 PR136    2      B Q_RES_0402LF-0,5%,1/16W,CHIP,CA    I46 @S9S_MB_2U_LIB.S9S_MB_2U(SCH_1):PAGE256
PC244_P0_8    1      A Q_CAP_C0805-22UF,4V,20%,X6S,CHA    I53 @S9S_MB_2U_LIB.S9S_MB_2U(SCH_1):PAGE256
PC246_P0_8    1      A Q_CAP_C0805-22UF,4V,20%,X6S,CHA    I54 @S9S_MB_2U_LIB.S9S_MB_2U(SCH_1):PAGE256
PC243_P0_7    1      A Q_CAP_C0402-1UF,16V,10%,X6S,CHA    I62 @S9S_MB_2U_LIB.S9S_MB_2U(SCH_1):PAGE256
PC245_P0_7    1      A Q_CAP_C0805-22UF,4V,20%,X6S,CHA    I66 @S9S_MB_2U_LIB.S9S_MB_2U(SCH_1):PAGE256
PC247_P0_7    1      A Q_CAP_C0805-22UF,4V,20%,X6S,CHA    I67 @S9S_MB_2U_LIB.S9S_MB_2U(SCH_1):PAGE256
  PL13    4      4 Q_INDUCTOR4P_14-150NH,SMLF,INDA    I21 @S9S_MB_2U_LIB.S9S_MB_2U(SCH_1):PAGE253
PR4219    1      A Q_RES_0402LF-499,1%,1/16W,CHIPA    I59 @S9S_MB_2U_LIB.S9S_MB_2U(SCH_1):PAGE253
PC1920    1      A Q_CAPP_SMLF-330UF,2.5V,+10/-35A    I63 @S9S_MB_2U_LIB.S9S_MB_2U(SCH_1):PAGE253
 PC326    1      A Q_CAPP_SMLF-330UF,2.5V,+10/-35A    I66 @S9S_MB_2U_LIB.S9S_MB_2U(SCH_1):PAGE253
 PC322    1      A Q_CAPP_THLF-560UF,2.5V,20%,OSCA    I67 @S9S_MB_2U_LIB.S9S_MB_2U(SCH_1):PAGE253
PC311_P0_2    1      A Q_CAP_C0805-22UF,4V,20%,X6S,CHA    I57 @S9S_MB_2U_LIB.S9S_MB_2U(SCH_1):PAGE253
PC313_P0_2    1      A Q_CAP_C0805-22UF,4V,20%,X6S,CHA    I58 @S9S_MB_2U_LIB.S9S_MB_2U(SCH_1):PAGE253
PC2336    1      A Q_CAPP_SMLF-330UF,2.5V,+10/-35A    I60 @S9S_MB_2U_LIB.S9S_MB_2U(SCH_1):PAGE253
PC308_P0_1    1      A Q_CAP_C0402-100NF,50V,10%,X7R,A    I83 @S9S_MB_2U_LIB.S9S_MB_2U(SCH_1):PAGE253
PC312_P0_1    1      A Q_CAP_C0805-22UF,4V,20%,X6S,CHA    I85 @S9S_MB_2U_LIB.S9S_MB_2U(SCH_1):PAGE253

PVCCIN_CPU0_ADDR @S9S_MB_2U_LIB.S9S_MB_2U(SCH_1):PVCCIN_CPU0_ADDR
  PU14   42 ADDR_CFG RAA229126GNPHA0-RAA229126GNP#HA    I63 @S9S_MB_2U_LIB.S9S_MB_2U(SCH_1):PAGE252
 PR159    2      B Q_RES_0402LF-28K,1%,1/16W,EMPTA     I5 @S9S_MB_2U_LIB.S9S_MB_2U(SCH_1):PAGE252
 PR171    1      A Q_RES_0402LF-0,5%,1/16W,CHIP,CA     I8 @S9S_MB_2U_LIB.S9S_MB_2U(SCH_1):PAGE252

PVCCIN_CPU0_ATSEN @S9S_MB_2U_LIB.S9S_MB_2U(SCH_1):PVCCIN_CPU0_ATSEN
PU13_P0_1   36 TOUT_FLT ISL99390FRZTR5935-ISL99390FRZ-A    I40 @S9S_MB_2U_LIB.S9S_MB_2U(SCH_1):PAGE253
PU10_P0_4   36 TOUT_FLT ISL99390FRZTR5935-ISL99390FRZ-A    I13 @S9S_MB_2U_LIB.S9S_MB_2U(SCH_1):PAGE254
PU8_P0_6   36 TOUT_FLT ISL99390FRZTR5935-ISL99390FRZ-A    I12 @S9S_MB_2U_LIB.S9S_MB_2U(SCH_1):PAGE255
PU6_P0_8   36 TOUT_FLT ISL99390FRZTR5935-ISL99390FRZ-A     I2 @S9S_MB_2U_LIB.S9S_MB_2U(SCH_1):PAGE256
PU11_P0_3   36 TOUT_FLT ISL99390FRZTR5935-ISL99390FRZ-A    I20 @S9S_MB_2U_LIB.S9S_MB_2U(SCH_1):PAGE254
PU9_P0_5   36 TOUT_FLT ISL99390FRZTR5935-ISL99390FRZ-A    I66 @S9S_MB_2U_LIB.S9S_MB_2U(SCH_1):PAGE255
PU7_P0_7   36 TOUT_FLT ISL99390FRZTR5935-ISL99390FRZ-A    I32 @S9S_MB_2U_LIB.S9S_MB_2U(SCH_1):PAGE256
  PU14   43  TEMP0 RAA229126GNPHA0-RAA229126GNP#HA    I63 @S9S_MB_2U_LIB.S9S_MB_2U(SCH_1):PAGE252
PU12_P0_2   36 TOUT_FLT ISL99390FRZTR5935-ISL99390FRZ-A     I6 @S9S_MB_2U_LIB.S9S_MB_2U(SCH_1):PAGE253
 PC336    1      A Q_CAP_0402-470PF,50V,10%,X7R,TA    I70 @S9S_MB_2U_LIB.S9S_MB_2U(SCH_1):PAGE252
 PR400    1      A Q_RES_0402LF-10K,1%,1/16W,EMPTA    I72 @S9S_MB_2U_LIB.S9S_MB_2U(SCH_1):PAGE252

PVCCIN_CPU0_CSPIN @S9S_MB_2U_LIB.S9S_MB_2U(SCH_1):PVCCIN_CPU0_CSPIN
 PR158    1      A Q_RES_0402LF-0,5%,1/16W,CHIP,CA    I51 @S9S_MB_2U_LIB.S9S_MB_2U(SCH_1):PAGE252
  PU14   45 VMON||IINSEN||VSYS||ISYS RAA229126GNPHA0-RAA229126GNP#HA    I63 @S9S_MB_2U_LIB.S9S_MB_2U(SCH_1):PAGE252
 PR157    2      B Q_RES_0402LF-0,5%,1/16W,EMPTY,A    I11 @S9S_MB_2U_LIB.S9S_MB_2U(SCH_1):PAGE252
 PC329    1      A Q_CAP_0402-0.1UF,25V,10%,EMPTYA    I53 @S9S_MB_2U_LIB.S9S_MB_2U(SCH_1):PAGE252

PVCCIN_CPU0_EN_R @S9S_MB_2U_LIB.S9S_MB_2U(SCH_1):PVCCIN_CPU0_EN_R
  PU14   17    EN0 RAA229126GNPHA0-RAA229126GNP#HA    I63 @S9S_MB_2U_LIB.S9S_MB_2U(SCH_1):PAGE252
 R2591    2      B Q_RES_0402LF-0,5%,1/16W,CHIP,CA    I48 @S9S_MB_2U_LIB.S9S_MB_2U(SCH_1):PAGE252
 C3267    1      A Q_CAP_0402-1000PF,50V,5%,X7R,TA    I82 @S9S_MB_2U_LIB.S9S_MB_2U(SCH_1):PAGE252

PVCCIN_CPU0_IMON1 @S9S_MB_2U_LIB.S9S_MB_2U(SCH_1):PVCCIN_CPU0_IMON1
PU13_P0_1   38   IOUT ISL99390FRZTR5935-ISL99390FRZ-A    I40 @S9S_MB_2U_LIB.S9S_MB_2U(SCH_1):PAGE253
  PU14   27   CS11 RAA229126GNPHA0-RAA229126GNP#HA    I63 @S9S_MB_2U_LIB.S9S_MB_2U(SCH_1):PAGE252

PVCCIN_CPU0_IMON2 @S9S_MB_2U_LIB.S9S_MB_2U(SCH_1):PVCCIN_CPU0_IMON2
  PU14   28   CS10 RAA229126GNPHA0-RAA229126GNP#HA    I63 @S9S_MB_2U_LIB.S9S_MB_2U(SCH_1):PAGE252
PU12_P0_2   38   IOUT ISL99390FRZTR5935-ISL99390FRZ-A     I6 @S9S_MB_2U_LIB.S9S_MB_2U(SCH_1):PAGE253

PVCCIN_CPU0_IMON3 @S9S_MB_2U_LIB.S9S_MB_2U(SCH_1):PVCCIN_CPU0_IMON3
PU11_P0_3   38   IOUT ISL99390FRZTR5935-ISL99390FRZ-A    I20 @S9S_MB_2U_LIB.S9S_MB_2U(SCH_1):PAGE254
  PU14   29    CS9 RAA229126GNPHA0-RAA229126GNP#HA    I63 @S9S_MB_2U_LIB.S9S_MB_2U(SCH_1):PAGE252

PVCCIN_CPU0_IMON4 @S9S_MB_2U_LIB.S9S_MB_2U(SCH_1):PVCCIN_CPU0_IMON4
PU10_P0_4   38   IOUT ISL99390FRZTR5935-ISL99390FRZ-A    I13 @S9S_MB_2U_LIB.S9S_MB_2U(SCH_1):PAGE254
  PU14   30    CS8 RAA229126GNPHA0-RAA229126GNP#HA    I63 @S9S_MB_2U_LIB.S9S_MB_2U(SCH_1):PAGE252

PVCCIN_CPU0_IMON5 @S9S_MB_2U_LIB.S9S_MB_2U(SCH_1):PVCCIN_CPU0_IMON5
PU9_P0_5   38   IOUT ISL99390FRZTR5935-ISL99390FRZ-A    I66 @S9S_MB_2U_LIB.S9S_MB_2U(SCH_1):PAGE255
  PU14   31    CS7 RAA229126GNPHA0-RAA229126GNP#HA    I63 @S9S_MB_2U_LIB.S9S_MB_2U(SCH_1):PAGE252

PVCCIN_CPU0_IMON6 @S9S_MB_2U_LIB.S9S_MB_2U(SCH_1):PVCCIN_CPU0_IMON6
PU8_P0_6   38   IOUT ISL99390FRZTR5935-ISL99390FRZ-A    I12 @S9S_MB_2U_LIB.S9S_MB_2U(SCH_1):PAGE255
  PU14   32    CS6 RAA229126GNPHA0-RAA229126GNP#HA    I63 @S9S_MB_2U_LIB.S9S_MB_2U(SCH_1):PAGE252

PVCCIN_CPU0_IMON7 @S9S_MB_2U_LIB.S9S_MB_2U(SCH_1):PVCCIN_CPU0_IMON7
PU7_P0_7   38   IOUT ISL99390FRZTR5935-ISL99390FRZ-A    I32 @S9S_MB_2U_LIB.S9S_MB_2U(SCH_1):PAGE256
  PU14   33    CS5 RAA229126GNPHA0-RAA229126GNP#HA    I63 @S9S_MB_2U_LIB.S9S_MB_2U(SCH_1):PAGE252

PVCCIN_CPU0_IMON8 @S9S_MB_2U_LIB.S9S_MB_2U(SCH_1):PVCCIN_CPU0_IMON8
PU6_P0_8   38   IOUT ISL99390FRZTR5935-ISL99390FRZ-A     I2 @S9S_MB_2U_LIB.S9S_MB_2U(SCH_1):PAGE256
  PU14   34    CS4 RAA229126GNPHA0-RAA229126GNP#HA    I63 @S9S_MB_2U_LIB.S9S_MB_2U(SCH_1):PAGE252

PVCCIN_CPU0_LSET1 @S9S_MB_2U_LIB.S9S_MB_2U(SCH_1):PVCCIN_CPU0_LSET1
PU13_P0_1   37   LSET ISL99390FRZTR5935-ISL99390FRZ-A    I40 @S9S_MB_2U_LIB.S9S_MB_2U(SCH_1):PAGE253
 PR151    1      A Q_RES_0402LF-8.87K,1%,1/16W,EMA    I29 @S9S_MB_2U_LIB.S9S_MB_2U(SCH_1):PAGE253

PVCCIN_CPU0_LSET2 @S9S_MB_2U_LIB.S9S_MB_2U(SCH_1):PVCCIN_CPU0_LSET2
 PR150    1      A Q_RES_0402LF-8.87K,1%,1/16W,EMA     I2 @S9S_MB_2U_LIB.S9S_MB_2U(SCH_1):PAGE253
PU12_P0_2   37   LSET ISL99390FRZTR5935-ISL99390FRZ-A     I6 @S9S_MB_2U_LIB.S9S_MB_2U(SCH_1):PAGE253

PVCCIN_CPU0_LSET3 @S9S_MB_2U_LIB.S9S_MB_2U(SCH_1):PVCCIN_CPU0_LSET3
 PR145    1      A Q_RES_0402LF-8.87K,1%,1/16W,EMA     I4 @S9S_MB_2U_LIB.S9S_MB_2U(SCH_1):PAGE254
PU11_P0_3   37   LSET ISL99390FRZTR5935-ISL99390FRZ-A    I20 @S9S_MB_2U_LIB.S9S_MB_2U(SCH_1):PAGE254

PVCCIN_CPU0_LSET4 @S9S_MB_2U_LIB.S9S_MB_2U(SCH_1):PVCCIN_CPU0_LSET4
 PR144    1      A Q_RES_0402LF-8.87K,1%,1/16W,EMA     I2 @S9S_MB_2U_LIB.S9S_MB_2U(SCH_1):PAGE254
PU10_P0_4   37   LSET ISL99390FRZTR5935-ISL99390FRZ-A    I13 @S9S_MB_2U_LIB.S9S_MB_2U(SCH_1):PAGE254

PVCCIN_CPU0_LSET5 @S9S_MB_2U_LIB.S9S_MB_2U(SCH_1):PVCCIN_CPU0_LSET5
 PR139    1      A Q_RES_0402LF-8.87K,1%,1/16W,EMA     I4 @S9S_MB_2U_LIB.S9S_MB_2U(SCH_1):PAGE255
PU9_P0_5   37   LSET ISL99390FRZTR5935-ISL99390FRZ-A    I66 @S9S_MB_2U_LIB.S9S_MB_2U(SCH_1):PAGE255

PVCCIN_CPU0_LSET6 @S9S_MB_2U_LIB.S9S_MB_2U(SCH_1):PVCCIN_CPU0_LSET6
 PR138    1      A Q_RES_0402LF-8.87K,1%,1/16W,EMA     I2 @S9S_MB_2U_LIB.S9S_MB_2U(SCH_1):PAGE255
PU8_P0_6   37   LSET ISL99390FRZTR5935-ISL99390FRZ-A    I12 @S9S_MB_2U_LIB.S9S_MB_2U(SCH_1):PAGE255

PVCCIN_CPU0_LSET7 @S9S_MB_2U_LIB.S9S_MB_2U(SCH_1):PVCCIN_CPU0_LSET7
 PR133    1      A Q_RES_0402LF-8.87K,1%,1/16W,EMA    I23 @S9S_MB_2U_LIB.S9S_MB_2U(SCH_1):PAGE256
PU7_P0_7   37   LSET ISL99390FRZTR5935-ISL99390FRZ-A    I32 @S9S_MB_2U_LIB.S9S_MB_2U(SCH_1):PAGE256

PVCCIN_CPU0_LSET8 @S9S_MB_2U_LIB.S9S_MB_2U(SCH_1):PVCCIN_CPU0_LSET8
PU6_P0_8   37   LSET ISL99390FRZTR5935-ISL99390FRZ-A     I2 @S9S_MB_2U_LIB.S9S_MB_2U(SCH_1):PAGE256
 PR132    1      A Q_RES_0402LF-8.87K,1%,1/16W,EMA     I4 @S9S_MB_2U_LIB.S9S_MB_2U(SCH_1):PAGE256

PVCCIN_CPU0_PIN_ALERT @S9S_MB_2U_LIB.S9S_MB_2U(SCH_1):PVCCIN_CPU0_PIN_ALERT
 R2375    2      B Q_RES_0402LF-1K,1%,1/16W,CHIP,A    I19 @S9S_MB_2U_LIB.S9S_MB_2U(SCH_1):PAGE252
  PU14   19 NPINALERT||NPSYS_CRIT RAA229126GNPHA0-RAA229126GNP#HA    I63 @S9S_MB_2U_LIB.S9S_MB_2U(SCH_1):PAGE252
 R2376    2      B Q_RES_0402LF-0,5%,1/16W,CHIP,CA    I17 @S9S_MB_2U_LIB.S9S_MB_2U(SCH_1):PAGE252

PVCCIN_CPU0_PVCC @S9S_MB_2U_LIB.S9S_MB_2U(SCH_1):PVCCIN_CPU0_PVCC
PC295_P0_1    1      A Q_CAP_C0402-2.2UF,10V,10%,X6S,A    I39 @S9S_MB_2U_LIB.S9S_MB_2U(SCH_1):PAGE253
PU13_P0_1    4   PVCC ISL99390FRZTR5935-ISL99390FRZ-A    I40 @S9S_MB_2U_LIB.S9S_MB_2U(SCH_1):PAGE253
PU10_P0_4    4   PVCC ISL99390FRZTR5935-ISL99390FRZ-A    I13 @S9S_MB_2U_LIB.S9S_MB_2U(SCH_1):PAGE254
 PR146    1      A Q_RES_0402LF-2.2,1%,1/16W,CHIPA    I14 @S9S_MB_2U_LIB.S9S_MB_2U(SCH_1):PAGE254
PC272_P0_4    1      A Q_CAP_C0402-2.2UF,10V,10%,X6S,A    I17 @S9S_MB_2U_LIB.S9S_MB_2U(SCH_1):PAGE254
 PR147    1      A Q_RES_0402LF-2.2,1%,1/16W,CHIPA    I27 @S9S_MB_2U_LIB.S9S_MB_2U(SCH_1):PAGE254
PC273_P0_3    1      A Q_CAP_C0402-2.2UF,10V,10%,X6S,A    I30 @S9S_MB_2U_LIB.S9S_MB_2U(SCH_1):PAGE254
PU8_P0_6    4   PVCC ISL99390FRZTR5935-ISL99390FRZ-A    I12 @S9S_MB_2U_LIB.S9S_MB_2U(SCH_1):PAGE255
PC250_P0_6    1      A Q_CAP_C0402-2.2UF,10V,10%,X6S,A    I17 @S9S_MB_2U_LIB.S9S_MB_2U(SCH_1):PAGE255
PU6_P0_8    4   PVCC ISL99390FRZTR5935-ISL99390FRZ-A     I2 @S9S_MB_2U_LIB.S9S_MB_2U(SCH_1):PAGE256
 PR135    1      A Q_RES_0402LF-2.2,1%,1/16W,CHIPA    I33 @S9S_MB_2U_LIB.S9S_MB_2U(SCH_1):PAGE256
PC229_P0_7    1      A Q_CAP_C0402-2.2UF,10V,10%,X6S,A    I36 @S9S_MB_2U_LIB.S9S_MB_2U(SCH_1):PAGE256
 PR153    1      A Q_RES_0402LF-2.2,1%,1/16W,CHIPA    I37 @S9S_MB_2U_LIB.S9S_MB_2U(SCH_1):PAGE253
PU11_P0_3    4   PVCC ISL99390FRZTR5935-ISL99390FRZ-A    I20 @S9S_MB_2U_LIB.S9S_MB_2U(SCH_1):PAGE254
 PR140    1      A Q_RES_0402LF-2.2,1%,1/16W,CHIPA    I14 @S9S_MB_2U_LIB.S9S_MB_2U(SCH_1):PAGE255
 PR141    1      A Q_RES_0402LF-2.2,1%,1/16W,CHIPA    I26 @S9S_MB_2U_LIB.S9S_MB_2U(SCH_1):PAGE255
PC251_P0_5    1      A Q_CAP_C0402-2.2UF,10V,10%,X6S,A    I29 @S9S_MB_2U_LIB.S9S_MB_2U(SCH_1):PAGE255
PU9_P0_5    4   PVCC ISL99390FRZTR5935-ISL99390FRZ-A    I66 @S9S_MB_2U_LIB.S9S_MB_2U(SCH_1):PAGE255
 PR134    1      A Q_RES_0402LF-2.2,1%,1/16W,CHIPA    I12 @S9S_MB_2U_LIB.S9S_MB_2U(SCH_1):PAGE256
PC228_P0_8    1      A Q_CAP_C0402-2.2UF,10V,10%,X6S,A    I15 @S9S_MB_2U_LIB.S9S_MB_2U(SCH_1):PAGE256
PU7_P0_7    4   PVCC ISL99390FRZTR5935-ISL99390FRZ-A    I32 @S9S_MB_2U_LIB.S9S_MB_2U(SCH_1):PAGE256
 PR402    2      B Q_RES_0402LF-0,5%,1/16W,CHIP,CA    I26 @S9S_MB_2U_LIB.S9S_MB_2U(SCH_1):PAGE253
PU12_P0_2    4   PVCC ISL99390FRZTR5935-ISL99390FRZ-A     I6 @S9S_MB_2U_LIB.S9S_MB_2U(SCH_1):PAGE253
 PR152    1      A Q_RES_0402LF-2.2,1%,1/16W,CHIPA    I12 @S9S_MB_2U_LIB.S9S_MB_2U(SCH_1):PAGE253
PC294_P0_2    1      A Q_CAP_C0402-2.2UF,10V,10%,X6S,A    I15 @S9S_MB_2U_LIB.S9S_MB_2U(SCH_1):PAGE253
 PR403    2      B Q_RES_0402LF-0,5%,1/16W,EMPTY,A    I42 @S9S_MB_2U_LIB.S9S_MB_2U(SCH_1):PAGE253

PVCCIN_CPU0_PWM1 @S9S_MB_2U_LIB.S9S_MB_2U(SCH_1):PVCCIN_CPU0_PWM1
PU13_P0_1   34    PWM ISL99390FRZTR5935-ISL99390FRZ-A    I40 @S9S_MB_2U_LIB.S9S_MB_2U(SCH_1):PAGE253
  PU14   12  PWM11 RAA229126GNPHA0-RAA229126GNP#HA    I63 @S9S_MB_2U_LIB.S9S_MB_2U(SCH_1):PAGE252

PVCCIN_CPU0_PWM2 @S9S_MB_2U_LIB.S9S_MB_2U(SCH_1):PVCCIN_CPU0_PWM2
  PU14   11  PWM10 RAA229126GNPHA0-RAA229126GNP#HA    I63 @S9S_MB_2U_LIB.S9S_MB_2U(SCH_1):PAGE252
PU12_P0_2   34    PWM ISL99390FRZTR5935-ISL99390FRZ-A     I6 @S9S_MB_2U_LIB.S9S_MB_2U(SCH_1):PAGE253

PVCCIN_CPU0_PWM3 @S9S_MB_2U_LIB.S9S_MB_2U(SCH_1):PVCCIN_CPU0_PWM3
PU11_P0_3   34    PWM ISL99390FRZTR5935-ISL99390FRZ-A    I20 @S9S_MB_2U_LIB.S9S_MB_2U(SCH_1):PAGE254
  PU14   10   PWM9 RAA229126GNPHA0-RAA229126GNP#HA    I63 @S9S_MB_2U_LIB.S9S_MB_2U(SCH_1):PAGE252

PVCCIN_CPU0_PWM4 @S9S_MB_2U_LIB.S9S_MB_2U(SCH_1):PVCCIN_CPU0_PWM4
PU10_P0_4   34    PWM ISL99390FRZTR5935-ISL99390FRZ-A    I13 @S9S_MB_2U_LIB.S9S_MB_2U(SCH_1):PAGE254
  PU14    9   PWM8 RAA229126GNPHA0-RAA229126GNP#HA    I63 @S9S_MB_2U_LIB.S9S_MB_2U(SCH_1):PAGE252

PVCCIN_CPU0_PWM5 @S9S_MB_2U_LIB.S9S_MB_2U(SCH_1):PVCCIN_CPU0_PWM5
PU9_P0_5   34    PWM ISL99390FRZTR5935-ISL99390FRZ-A    I66 @S9S_MB_2U_LIB.S9S_MB_2U(SCH_1):PAGE255
  PU14    8   PWM7 RAA229126GNPHA0-RAA229126GNP#HA    I63 @S9S_MB_2U_LIB.S9S_MB_2U(SCH_1):PAGE252

PVCCIN_CPU0_PWM6 @S9S_MB_2U_LIB.S9S_MB_2U(SCH_1):PVCCIN_CPU0_PWM6
PU8_P0_6   34    PWM ISL99390FRZTR5935-ISL99390FRZ-A    I12 @S9S_MB_2U_LIB.S9S_MB_2U(SCH_1):PAGE255
  PU14    7   PWM6 RAA229126GNPHA0-RAA229126GNP#HA    I63 @S9S_MB_2U_LIB.S9S_MB_2U(SCH_1):PAGE252

PVCCIN_CPU0_PWM7 @S9S_MB_2U_LIB.S9S_MB_2U(SCH_1):PVCCIN_CPU0_PWM7
PU7_P0_7   34    PWM ISL99390FRZTR5935-ISL99390FRZ-A    I32 @S9S_MB_2U_LIB.S9S_MB_2U(SCH_1):PAGE256
  PU14    6   PWM5 RAA229126GNPHA0-RAA229126GNP#HA    I63 @S9S_MB_2U_LIB.S9S_MB_2U(SCH_1):PAGE252

PVCCIN_CPU0_PWM8 @S9S_MB_2U_LIB.S9S_MB_2U(SCH_1):PVCCIN_CPU0_PWM8
PU6_P0_8   34    PWM ISL99390FRZTR5935-ISL99390FRZ-A     I2 @S9S_MB_2U_LIB.S9S_MB_2U(SCH_1):PAGE256
  PU14    5   PWM4 RAA229126GNPHA0-RAA229126GNP#HA    I63 @S9S_MB_2U_LIB.S9S_MB_2U(SCH_1):PAGE252

PVCCIN_CPU0_VCC @S9S_MB_2U_LIB.S9S_MB_2U(SCH_1):PVCCIN_CPU0_VCC
  PU14   47    VCC RAA229126GNPHA0-RAA229126GNP#HA    I63 @S9S_MB_2U_LIB.S9S_MB_2U(SCH_1):PAGE252
 PR176    1      A Q_RES_0402LF-1,1%,1/16W,CHIP,CA   I133 @S9S_MB_2U_LIB.S9S_MB_2U(SCH_1):PAGE252
 PC334    1      A Q_CAP_0402-0.1UF,25V,10%,EMPTYA    I88 @S9S_MB_2U_LIB.S9S_MB_2U(SCH_1):PAGE252
 PC337    1      A Q_CAP_C0402-1UF,16V,10%,X6S,CHA    I89 @S9S_MB_2U_LIB.S9S_MB_2U(SCH_1):PAGE252
PC2361    1      A Q_CAP_0402-0.1UF,25V,10%,EMPTYA   I136 @S9S_MB_2U_LIB.S9S_MB_2U(SCH_1):PAGE252

PVCCIN_CPU0_VDD1 @S9S_MB_2U_LIB.S9S_MB_2U(SCH_1):PVCCIN_CPU0_VDD1
 PC293    1      A Q_CAP_C0402-2.2UF,10V,10%,X6S,A    I36 @S9S_MB_2U_LIB.S9S_MB_2U(SCH_1):PAGE253
PU13_P0_1   35     EN ISL99390FRZTR5935-ISL99390FRZ-A    I40 @S9S_MB_2U_LIB.S9S_MB_2U(SCH_1):PAGE253
PU13_P0_1    3    VCC ISL99390FRZTR5935-ISL99390FRZ-A    I40 @S9S_MB_2U_LIB.S9S_MB_2U(SCH_1):PAGE253
 PR153    2      B Q_RES_0402LF-2.2,1%,1/16W,CHIPA    I37 @S9S_MB_2U_LIB.S9S_MB_2U(SCH_1):PAGE253

PVCCIN_CPU0_VDD2 @S9S_MB_2U_LIB.S9S_MB_2U(SCH_1):PVCCIN_CPU0_VDD2
PU12_P0_2   35     EN ISL99390FRZTR5935-ISL99390FRZ-A     I6 @S9S_MB_2U_LIB.S9S_MB_2U(SCH_1):PAGE253
PU12_P0_2    3    VCC ISL99390FRZTR5935-ISL99390FRZ-A     I6 @S9S_MB_2U_LIB.S9S_MB_2U(SCH_1):PAGE253
 PC292    1      A Q_CAP_C0402-2.2UF,10V,10%,X6S,A     I9 @S9S_MB_2U_LIB.S9S_MB_2U(SCH_1):PAGE253
 PR152    2      B Q_RES_0402LF-2.2,1%,1/16W,CHIPA    I12 @S9S_MB_2U_LIB.S9S_MB_2U(SCH_1):PAGE253

PVCCIN_CPU0_VDD3 @S9S_MB_2U_LIB.S9S_MB_2U(SCH_1):PVCCIN_CPU0_VDD3
 PR147    2      B Q_RES_0402LF-2.2,1%,1/16W,CHIPA    I27 @S9S_MB_2U_LIB.S9S_MB_2U(SCH_1):PAGE254
PU11_P0_3   35     EN ISL99390FRZTR5935-ISL99390FRZ-A    I20 @S9S_MB_2U_LIB.S9S_MB_2U(SCH_1):PAGE254
PU11_P0_3    3    VCC ISL99390FRZTR5935-ISL99390FRZ-A    I20 @S9S_MB_2U_LIB.S9S_MB_2U(SCH_1):PAGE254
 PC271    1      A Q_CAP_C0402-2.2UF,10V,10%,X6S,A    I25 @S9S_MB_2U_LIB.S9S_MB_2U(SCH_1):PAGE254

PVCCIN_CPU0_VDD4 @S9S_MB_2U_LIB.S9S_MB_2U(SCH_1):PVCCIN_CPU0_VDD4
PU10_P0_4   35     EN ISL99390FRZTR5935-ISL99390FRZ-A    I13 @S9S_MB_2U_LIB.S9S_MB_2U(SCH_1):PAGE254
PU10_P0_4    3    VCC ISL99390FRZTR5935-ISL99390FRZ-A    I13 @S9S_MB_2U_LIB.S9S_MB_2U(SCH_1):PAGE254
 PR146    2      B Q_RES_0402LF-2.2,1%,1/16W,CHIPA    I14 @S9S_MB_2U_LIB.S9S_MB_2U(SCH_1):PAGE254
 PC270    1      A Q_CAP_C0402-2.2UF,10V,10%,X6S,A    I11 @S9S_MB_2U_LIB.S9S_MB_2U(SCH_1):PAGE254

PVCCIN_CPU0_VDD5 @S9S_MB_2U_LIB.S9S_MB_2U(SCH_1):PVCCIN_CPU0_VDD5
 PC249    1      A Q_CAP_C0402-2.2UF,10V,10%,X6S,A    I24 @S9S_MB_2U_LIB.S9S_MB_2U(SCH_1):PAGE255
 PR141    2      B Q_RES_0402LF-2.2,1%,1/16W,CHIPA    I26 @S9S_MB_2U_LIB.S9S_MB_2U(SCH_1):PAGE255
PU9_P0_5   35     EN ISL99390FRZTR5935-ISL99390FRZ-A    I66 @S9S_MB_2U_LIB.S9S_MB_2U(SCH_1):PAGE255
PU9_P0_5    3    VCC ISL99390FRZTR5935-ISL99390FRZ-A    I66 @S9S_MB_2U_LIB.S9S_MB_2U(SCH_1):PAGE255

PVCCIN_CPU0_VDD6 @S9S_MB_2U_LIB.S9S_MB_2U(SCH_1):PVCCIN_CPU0_VDD6
PU8_P0_6   35     EN ISL99390FRZTR5935-ISL99390FRZ-A    I12 @S9S_MB_2U_LIB.S9S_MB_2U(SCH_1):PAGE255
PU8_P0_6    3    VCC ISL99390FRZTR5935-ISL99390FRZ-A    I12 @S9S_MB_2U_LIB.S9S_MB_2U(SCH_1):PAGE255
 PC248    1      A Q_CAP_C0402-2.2UF,10V,10%,X6S,A    I13 @S9S_MB_2U_LIB.S9S_MB_2U(SCH_1):PAGE255
 PR140    2      B Q_RES_0402LF-2.2,1%,1/16W,CHIPA    I14 @S9S_MB_2U_LIB.S9S_MB_2U(SCH_1):PAGE255

PVCCIN_CPU0_VDD7 @S9S_MB_2U_LIB.S9S_MB_2U(SCH_1):PVCCIN_CPU0_VDD7
 PR135    2      B Q_RES_0402LF-2.2,1%,1/16W,CHIPA    I33 @S9S_MB_2U_LIB.S9S_MB_2U(SCH_1):PAGE256
 PC227    1      A Q_CAP_C0402-2.2UF,10V,10%,X6S,A    I31 @S9S_MB_2U_LIB.S9S_MB_2U(SCH_1):PAGE256
PU7_P0_7   35     EN ISL99390FRZTR5935-ISL99390FRZ-A    I32 @S9S_MB_2U_LIB.S9S_MB_2U(SCH_1):PAGE256
PU7_P0_7    3    VCC ISL99390FRZTR5935-ISL99390FRZ-A    I32 @S9S_MB_2U_LIB.S9S_MB_2U(SCH_1):PAGE256

PVCCIN_CPU0_VDD8 @S9S_MB_2U_LIB.S9S_MB_2U(SCH_1):PVCCIN_CPU0_VDD8
PU6_P0_8   35     EN ISL99390FRZTR5935-ISL99390FRZ-A     I2 @S9S_MB_2U_LIB.S9S_MB_2U(SCH_1):PAGE256
PU6_P0_8    3    VCC ISL99390FRZTR5935-ISL99390FRZ-A     I2 @S9S_MB_2U_LIB.S9S_MB_2U(SCH_1):PAGE256
 PC226    1      A Q_CAP_C0402-2.2UF,10V,10%,X6S,A    I11 @S9S_MB_2U_LIB.S9S_MB_2U(SCH_1):PAGE256
 PR134    2      B Q_RES_0402LF-2.2,1%,1/16W,CHIPA    I12 @S9S_MB_2U_LIB.S9S_MB_2U(SCH_1):PAGE256

PVCCIN_CPU0_VIN_CSNIN @S9S_MB_2U_LIB.S9S_MB_2U(SCH_1):PVCCIN_CPU0_VIN_CSNIN
  PU14   46 VINSEN||VSYS RAA229126GNPHA0-RAA229126GNP#HA    I63 @S9S_MB_2U_LIB.S9S_MB_2U(SCH_1):PAGE252
 PR156    2      B Q_RES_0402LF-0,5%,1/16W,CHIP,CA    I10 @S9S_MB_2U_LIB.S9S_MB_2U(SCH_1):PAGE252
 PR166    1      A Q_RES_0402LF-1K,1%,1/16W,EMPTYA    I60 @S9S_MB_2U_LIB.S9S_MB_2U(SCH_1):PAGE252
 PC330    1      A Q_CAP_0402-0.1UF,25V,10%,X7R,CA    I61 @S9S_MB_2U_LIB.S9S_MB_2U(SCH_1):PAGE252

PVCCIN_CPU0_VOS1 @S9S_MB_2U_LIB.S9S_MB_2U(SCH_1):PVCCIN_CPU0_VOS1
PU13_P0_1    1    VOS ISL99390FRZTR5935-ISL99390FRZ-A    I40 @S9S_MB_2U_LIB.S9S_MB_2U(SCH_1):PAGE253
 PR155    1      A Q_RES_0402LF-0,5%,1/16W,CHIP,CA    I73 @S9S_MB_2U_LIB.S9S_MB_2U(SCH_1):PAGE253

PVCCIN_CPU0_VOS2 @S9S_MB_2U_LIB.S9S_MB_2U(SCH_1):PVCCIN_CPU0_VOS2
 PR154    1      A Q_RES_0402LF-0,5%,1/16W,CHIP,CA    I51 @S9S_MB_2U_LIB.S9S_MB_2U(SCH_1):PAGE253
PU12_P0_2    1    VOS ISL99390FRZTR5935-ISL99390FRZ-A     I6 @S9S_MB_2U_LIB.S9S_MB_2U(SCH_1):PAGE253

PVCCIN_CPU0_VOS3 @S9S_MB_2U_LIB.S9S_MB_2U(SCH_1):PVCCIN_CPU0_VOS3
PU11_P0_3    1    VOS ISL99390FRZTR5935-ISL99390FRZ-A    I20 @S9S_MB_2U_LIB.S9S_MB_2U(SCH_1):PAGE254
 PR149    1      A Q_RES_0402LF-0,5%,1/16W,CHIP,CA    I46 @S9S_MB_2U_LIB.S9S_MB_2U(SCH_1):PAGE254

PVCCIN_CPU0_VOS4 @S9S_MB_2U_LIB.S9S_MB_2U(SCH_1):PVCCIN_CPU0_VOS4
PU10_P0_4    1    VOS ISL99390FRZTR5935-ISL99390FRZ-A    I13 @S9S_MB_2U_LIB.S9S_MB_2U(SCH_1):PAGE254
 PR148    1      A Q_RES_0402LF-0,5%,1/16W,CHIP,CA    I41 @S9S_MB_2U_LIB.S9S_MB_2U(SCH_1):PAGE254

PVCCIN_CPU0_VOS5 @S9S_MB_2U_LIB.S9S_MB_2U(SCH_1):PVCCIN_CPU0_VOS5
 PR143    1      A Q_RES_0402LF-0,5%,1/16W,CHIP,CA    I46 @S9S_MB_2U_LIB.S9S_MB_2U(SCH_1):PAGE255
PU9_P0_5    1    VOS ISL99390FRZTR5935-ISL99390FRZ-A    I66 @S9S_MB_2U_LIB.S9S_MB_2U(SCH_1):PAGE255

PVCCIN_CPU0_VOS6 @S9S_MB_2U_LIB.S9S_MB_2U(SCH_1):PVCCIN_CPU0_VOS6
PU8_P0_6    1    VOS ISL99390FRZTR5935-ISL99390FRZ-A    I12 @S9S_MB_2U_LIB.S9S_MB_2U(SCH_1):PAGE255
 PR142    1      A Q_RES_0402LF-0,5%,1/16W,CHIP,CA    I40 @S9S_MB_2U_LIB.S9S_MB_2U(SCH_1):PAGE255

PVCCIN_CPU0_VOS7 @S9S_MB_2U_LIB.S9S_MB_2U(SCH_1):PVCCIN_CPU0_VOS7
 PR137    1      A Q_RES_0402LF-0,5%,1/16W,CHIP,CA    I57 @S9S_MB_2U_LIB.S9S_MB_2U(SCH_1):PAGE256
PU7_P0_7    1    VOS ISL99390FRZTR5935-ISL99390FRZ-A    I32 @S9S_MB_2U_LIB.S9S_MB_2U(SCH_1):PAGE256

PVCCIN_CPU0_VOS8 @S9S_MB_2U_LIB.S9S_MB_2U(SCH_1):PVCCIN_CPU0_VOS8
PU6_P0_8    1    VOS ISL99390FRZTR5935-ISL99390FRZ-A     I2 @S9S_MB_2U_LIB.S9S_MB_2U(SCH_1):PAGE256
 PR136    1      A Q_RES_0402LF-0,5%,1/16W,CHIP,CA    I46 @S9S_MB_2U_LIB.S9S_MB_2U(SCH_1):PAGE256

PVCCIN_CPU0_VREF @S9S_MB_2U_LIB.S9S_MB_2U(SCH_1):PVCCIN_CPU0_VREF
PC1355    2      B Q_CAP_0402-0.1UF,25V,10%,X7R,CA    I11 @S9S_MB_2U_LIB.S9S_MB_2U(SCH_1):PAGE253
PU13_P0_1   39  REFIN ISL99390FRZTR5935-ISL99390FRZ-A    I40 @S9S_MB_2U_LIB.S9S_MB_2U(SCH_1):PAGE253
PU10_P0_4   39  REFIN ISL99390FRZTR5935-ISL99390FRZ-A    I13 @S9S_MB_2U_LIB.S9S_MB_2U(SCH_1):PAGE254
PC1341    2      B Q_CAP_0402-0.1UF,25V,10%,X7R,CA    I26 @S9S_MB_2U_LIB.S9S_MB_2U(SCH_1):PAGE254
PC1342    2      B Q_CAP_0402-0.1UF,25V,10%,X7R,CA    I11 @S9S_MB_2U_LIB.S9S_MB_2U(SCH_1):PAGE255
PU8_P0_6   39  REFIN ISL99390FRZTR5935-ISL99390FRZ-A    I12 @S9S_MB_2U_LIB.S9S_MB_2U(SCH_1):PAGE255
PU6_P0_8   39  REFIN ISL99390FRZTR5935-ISL99390FRZ-A     I2 @S9S_MB_2U_LIB.S9S_MB_2U(SCH_1):PAGE256
PC1340    2      B Q_CAP_0402-0.1UF,25V,10%,X7R,CA    I12 @S9S_MB_2U_LIB.S9S_MB_2U(SCH_1):PAGE254
PU11_P0_3   39  REFIN ISL99390FRZTR5935-ISL99390FRZ-A    I20 @S9S_MB_2U_LIB.S9S_MB_2U(SCH_1):PAGE254
PC1343    2      B Q_CAP_0402-0.1UF,25V,10%,X7R,CA    I25 @S9S_MB_2U_LIB.S9S_MB_2U(SCH_1):PAGE255
PU9_P0_5   39  REFIN ISL99390FRZTR5935-ISL99390FRZ-A    I66 @S9S_MB_2U_LIB.S9S_MB_2U(SCH_1):PAGE255
PC1344    2      B Q_CAP_0402-0.1UF,25V,10%,X7R,CA     I7 @S9S_MB_2U_LIB.S9S_MB_2U(SCH_1):PAGE256
PC1345    2      B Q_CAP_0402-0.1UF,25V,10%,X7R,CA    I29 @S9S_MB_2U_LIB.S9S_MB_2U(SCH_1):PAGE256
PU7_P0_7   39  REFIN ISL99390FRZTR5935-ISL99390FRZ-A    I32 @S9S_MB_2U_LIB.S9S_MB_2U(SCH_1):PAGE256
PC1351    2      B Q_CAP_0402-0.1UF,25V,10%,X7R,CA    I25 @S9S_MB_2U_LIB.S9S_MB_2U(SCH_1):PAGE258
  PU14   48   VCCS RAA229126GNPHA0-RAA229126GNP#HA    I63 @S9S_MB_2U_LIB.S9S_MB_2U(SCH_1):PAGE252
PC1356    2      B Q_CAP_0402-0.1UF,25V,10%,X7R,CA    I34 @S9S_MB_2U_LIB.S9S_MB_2U(SCH_1):PAGE253
PU70_P0_2   39  REFIN ISL99390FRZTR5935-ISL99390FRZ-A    I16 @S9S_MB_2U_LIB.S9S_MB_2U(SCH_1):PAGE257
PU71_P0_3   39  REFIN ISL99390FRZTR5935-ISL99390FRZ-A    I82 @S9S_MB_2U_LIB.S9S_MB_2U(SCH_1):PAGE258
 PR159    1      A Q_RES_0402LF-28K,1%,1/16W,EMPTA     I5 @S9S_MB_2U_LIB.S9S_MB_2U(SCH_1):PAGE252
 PC335    1      A Q_CAP_C0402-10UF,6.3V,20%,X6S,B    I86 @S9S_MB_2U_LIB.S9S_MB_2U(SCH_1):PAGE252
PC1350    2      B Q_CAP_0402-0.1UF,25V,10%,X7R,CA    I15 @S9S_MB_2U_LIB.S9S_MB_2U(SCH_1):PAGE257
PU12_P0_2   39  REFIN ISL99390FRZTR5935-ISL99390FRZ-A     I6 @S9S_MB_2U_LIB.S9S_MB_2U(SCH_1):PAGE253
PU69_P0_1   39  REFIN ISL99390FRZTR5935-ISL99390FRZ-A    I25 @S9S_MB_2U_LIB.S9S_MB_2U(SCH_1):PAGE257
PC1349    2      B Q_CAP_0402-0.1UF,25V,10%,X7R,CA    I35 @S9S_MB_2U_LIB.S9S_MB_2U(SCH_1):PAGE257
PC1352    2      B Q_CAP_0402-0.1UF,25V,10%,X7R,CA     I9 @S9S_MB_2U_LIB.S9S_MB_2U(SCH_1):PAGE258
PU72_P0_4   39  REFIN ISL99390FRZTR5935-ISL99390FRZ-A    I10 @S9S_MB_2U_LIB.S9S_MB_2U(SCH_1):PAGE258
PC1173    1      A Q_CAP_C0402-1UF,16V,10%,X6S,CHA    I87 @S9S_MB_2U_LIB.S9S_MB_2U(SCH_1):PAGE252

PVCCIN_CPU0_VR_FAULT @S9S_MB_2U_LIB.S9S_MB_2U(SCH_1):PVCCIN_CPU0_VR_FAULT
  PU14   41    CFP RAA229126GNPHA0-RAA229126GNP#HA    I63 @S9S_MB_2U_LIB.S9S_MB_2U(SCH_1):PAGE252
 R2589    2      B Q_RES_0402LF-1K,1%,1/16W,CHIP,A    I20 @S9S_MB_2U_LIB.S9S_MB_2U(SCH_1):PAGE252

PVCCIN_CPU1 @S9S_MB_2U_LIB.S9S_MB_2U(SCH_1):PVCCIN_CPU1
    U1 BW80 VCCIN190 SOCKET4677_AZIF0045P001C01CS-SA     I1 @S9S_MB_2U_LIB.S9S_MB_2U(SCH_1):PAGE67
    U1 BW82 VCCIN191 SOCKET4677_AZIF0045P001C01CS-SA     I1 @S9S_MB_2U_LIB.S9S_MB_2U(SCH_1):PAGE67
    U1 BW84 VCCIN192 SOCKET4677_AZIF0045P001C01CS-SA     I1 @S9S_MB_2U_LIB.S9S_MB_2U(SCH_1):PAGE67
    U1 BW86 VCCIN193 SOCKET4677_AZIF0045P001C01CS-SA     I1 @S9S_MB_2U_LIB.S9S_MB_2U(SCH_1):PAGE67
    U1 BW88 VCCIN194 SOCKET4677_AZIF0045P001C01CS-SA     I1 @S9S_MB_2U_LIB.S9S_MB_2U(SCH_1):PAGE67
    U1 BW90 VCCIN195 SOCKET4677_AZIF0045P001C01CS-SA     I1 @S9S_MB_2U_LIB.S9S_MB_2U(SCH_1):PAGE67
    U1 BY32 VCCIN196 SOCKET4677_AZIF0045P001C01CS-SA     I1 @S9S_MB_2U_LIB.S9S_MB_2U(SCH_1):PAGE67
    U1 BY34 VCCIN197 SOCKET4677_AZIF0045P001C01CS-SA     I1 @S9S_MB_2U_LIB.S9S_MB_2U(SCH_1):PAGE67
    U1 BY36 VCCIN198 SOCKET4677_AZIF0045P001C01CS-SA     I1 @S9S_MB_2U_LIB.S9S_MB_2U(SCH_1):PAGE67
    U1 BY38 VCCIN199 SOCKET4677_AZIF0045P001C01CS-SA     I1 @S9S_MB_2U_LIB.S9S_MB_2U(SCH_1):PAGE67
    U1 BY40 VCCIN200 SOCKET4677_AZIF0045P001C01CS-SA     I1 @S9S_MB_2U_LIB.S9S_MB_2U(SCH_1):PAGE67
    U1 BY42 VCCIN201 SOCKET4677_AZIF0045P001C01CS-SA     I1 @S9S_MB_2U_LIB.S9S_MB_2U(SCH_1):PAGE67
    U1 BY44 VCCIN202 SOCKET4677_AZIF0045P001C01CS-SA     I1 @S9S_MB_2U_LIB.S9S_MB_2U(SCH_1):PAGE67
    U1 BY47 VCCIN203 SOCKET4677_AZIF0045P001C01CS-SA     I1 @S9S_MB_2U_LIB.S9S_MB_2U(SCH_1):PAGE67
    U1 BY49 VCCIN204 SOCKET4677_AZIF0045P001C01CS-SA     I1 @S9S_MB_2U_LIB.S9S_MB_2U(SCH_1):PAGE67
    U1 BY51 VCCIN205 SOCKET4677_AZIF0045P001C01CS-SA     I1 @S9S_MB_2U_LIB.S9S_MB_2U(SCH_1):PAGE67
    U1 BY53 VCCIN206 SOCKET4677_AZIF0045P001C01CS-SA     I1 @S9S_MB_2U_LIB.S9S_MB_2U(SCH_1):PAGE67
    U1 BY55 VCCIN207 SOCKET4677_AZIF0045P001C01CS-SA     I1 @S9S_MB_2U_LIB.S9S_MB_2U(SCH_1):PAGE67
    U1 BY57 VCCIN208 SOCKET4677_AZIF0045P001C01CS-SA     I1 @S9S_MB_2U_LIB.S9S_MB_2U(SCH_1):PAGE67
    U1 BY59 VCCIN209 SOCKET4677_AZIF0045P001C01CS-SA     I1 @S9S_MB_2U_LIB.S9S_MB_2U(SCH_1):PAGE67
    U1 BY61 VCCIN210 SOCKET4677_AZIF0045P001C01CS-SA     I1 @S9S_MB_2U_LIB.S9S_MB_2U(SCH_1):PAGE67
    U1 BY63 VCCIN211 SOCKET4677_AZIF0045P001C01CS-SA     I1 @S9S_MB_2U_LIB.S9S_MB_2U(SCH_1):PAGE67
    U1 BY65 VCCIN212 SOCKET4677_AZIF0045P001C01CS-SA     I1 @S9S_MB_2U_LIB.S9S_MB_2U(SCH_1):PAGE67
    U1 BY67 VCCIN213 SOCKET4677_AZIF0045P001C01CS-SA     I1 @S9S_MB_2U_LIB.S9S_MB_2U(SCH_1):PAGE67
    U1 BY69 VCCIN214 SOCKET4677_AZIF0045P001C01CS-SA     I1 @S9S_MB_2U_LIB.S9S_MB_2U(SCH_1):PAGE67
    U1 BY71 VCCIN215 SOCKET4677_AZIF0045P001C01CS-SA     I1 @S9S_MB_2U_LIB.S9S_MB_2U(SCH_1):PAGE67
    U1 BY73 VCCIN216 SOCKET4677_AZIF0045P001C01CS-SA     I1 @S9S_MB_2U_LIB.S9S_MB_2U(SCH_1):PAGE67
    U1 BY75 VCCIN217 SOCKET4677_AZIF0045P001C01CS-SA     I1 @S9S_MB_2U_LIB.S9S_MB_2U(SCH_1):PAGE67
    U1 BY77 VCCIN218 SOCKET4677_AZIF0045P001C01CS-SA     I1 @S9S_MB_2U_LIB.S9S_MB_2U(SCH_1):PAGE67
    U1 BY79 VCCIN219 SOCKET4677_AZIF0045P001C01CS-SA     I1 @S9S_MB_2U_LIB.S9S_MB_2U(SCH_1):PAGE67
    U1 BY81 VCCIN220 SOCKET4677_AZIF0045P001C01CS-SA     I1 @S9S_MB_2U_LIB.S9S_MB_2U(SCH_1):PAGE67
    U1 BY83 VCCIN221 SOCKET4677_AZIF0045P001C01CS-SA     I1 @S9S_MB_2U_LIB.S9S_MB_2U(SCH_1):PAGE67
    U1 BY85 VCCIN222 SOCKET4677_AZIF0045P001C01CS-SA     I1 @S9S_MB_2U_LIB.S9S_MB_2U(SCH_1):PAGE67
    U1 BY87 VCCIN223 SOCKET4677_AZIF0045P001C01CS-SA     I1 @S9S_MB_2U_LIB.S9S_MB_2U(SCH_1):PAGE67
    U1 BY89 VCCIN224 SOCKET4677_AZIF0045P001C01CS-SA     I1 @S9S_MB_2U_LIB.S9S_MB_2U(SCH_1):PAGE67
    U1 CA33 VCCIN225 SOCKET4677_AZIF0045P001C01CS-SA     I1 @S9S_MB_2U_LIB.S9S_MB_2U(SCH_1):PAGE67
    U1 CA35 VCCIN226 SOCKET4677_AZIF0045P001C01CS-SA     I1 @S9S_MB_2U_LIB.S9S_MB_2U(SCH_1):PAGE67
    U1 CA37 VCCIN227 SOCKET4677_AZIF0045P001C01CS-SA     I1 @S9S_MB_2U_LIB.S9S_MB_2U(SCH_1):PAGE67
    U1 CA39 VCCIN228 SOCKET4677_AZIF0045P001C01CS-SA     I1 @S9S_MB_2U_LIB.S9S_MB_2U(SCH_1):PAGE67
    U1 CA41 VCCIN229 SOCKET4677_AZIF0045P001C01CS-SA     I1 @S9S_MB_2U_LIB.S9S_MB_2U(SCH_1):PAGE67
    U1 CA43 VCCIN230 SOCKET4677_AZIF0045P001C01CS-SA     I1 @S9S_MB_2U_LIB.S9S_MB_2U(SCH_1):PAGE67
    U1 CA45 VCCIN231 SOCKET4677_AZIF0045P001C01CS-SA     I1 @S9S_MB_2U_LIB.S9S_MB_2U(SCH_1):PAGE67
    U1 CA48 VCCIN232 SOCKET4677_AZIF0045P001C01CS-SA     I1 @S9S_MB_2U_LIB.S9S_MB_2U(SCH_1):PAGE67
    U1 CA50 VCCIN233 SOCKET4677_AZIF0045P001C01CS-SA     I1 @S9S_MB_2U_LIB.S9S_MB_2U(SCH_1):PAGE67
    U1 CA52 VCCIN234 SOCKET4677_AZIF0045P001C01CS-SA     I1 @S9S_MB_2U_LIB.S9S_MB_2U(SCH_1):PAGE67
    U1 CA54 VCCIN235 SOCKET4677_AZIF0045P001C01CS-SA     I1 @S9S_MB_2U_LIB.S9S_MB_2U(SCH_1):PAGE67
    U1 CA56 VCCIN236 SOCKET4677_AZIF0045P001C01CS-SA     I1 @S9S_MB_2U_LIB.S9S_MB_2U(SCH_1):PAGE67
    U1 CA58 VCCIN237 SOCKET4677_AZIF0045P001C01CS-SA     I1 @S9S_MB_2U_LIB.S9S_MB_2U(SCH_1):PAGE67
    U1 CA60 VCCIN238 SOCKET4677_AZIF0045P001C01CS-SA     I1 @S9S_MB_2U_LIB.S9S_MB_2U(SCH_1):PAGE67
    U1 CA62 VCCIN239 SOCKET4677_AZIF0045P001C01CS-SA     I1 @S9S_MB_2U_LIB.S9S_MB_2U(SCH_1):PAGE67
    U1 CA64 VCCIN240 SOCKET4677_AZIF0045P001C01CS-SA     I1 @S9S_MB_2U_LIB.S9S_MB_2U(SCH_1):PAGE67
    U1 CA66 VCCIN241 SOCKET4677_AZIF0045P001C01CS-SA     I1 @S9S_MB_2U_LIB.S9S_MB_2U(SCH_1):PAGE67
    U1 CA68 VCCIN242 SOCKET4677_AZIF0045P001C01CS-SA     I1 @S9S_MB_2U_LIB.S9S_MB_2U(SCH_1):PAGE67
    U1 CA70 VCCIN243 SOCKET4677_AZIF0045P001C01CS-SA     I1 @S9S_MB_2U_LIB.S9S_MB_2U(SCH_1):PAGE67
    U1 CA72 VCCIN244 SOCKET4677_AZIF0045P001C01CS-SA     I1 @S9S_MB_2U_LIB.S9S_MB_2U(SCH_1):PAGE67
    U1 CA74 VCCIN245 SOCKET4677_AZIF0045P001C01CS-SA     I1 @S9S_MB_2U_LIB.S9S_MB_2U(SCH_1):PAGE67
    U1 CA76 VCCIN246 SOCKET4677_AZIF0045P001C01CS-SA     I1 @S9S_MB_2U_LIB.S9S_MB_2U(SCH_1):PAGE67
    U1 CA78 VCCIN247 SOCKET4677_AZIF0045P001C01CS-SA     I1 @S9S_MB_2U_LIB.S9S_MB_2U(SCH_1):PAGE67
    U1 CA80 VCCIN248 SOCKET4677_AZIF0045P001C01CS-SA     I1 @S9S_MB_2U_LIB.S9S_MB_2U(SCH_1):PAGE67
    U1 CA82 VCCIN249 SOCKET4677_AZIF0045P001C01CS-SA     I1 @S9S_MB_2U_LIB.S9S_MB_2U(SCH_1):PAGE67
    U1 CA84 VCCIN250 SOCKET4677_AZIF0045P001C01CS-SA     I1 @S9S_MB_2U_LIB.S9S_MB_2U(SCH_1):PAGE67
    U1 CA86 VCCIN251 SOCKET4677_AZIF0045P001C01CS-SA     I1 @S9S_MB_2U_LIB.S9S_MB_2U(SCH_1):PAGE67
    U1 CA88 VCCIN252 SOCKET4677_AZIF0045P001C01CS-SA     I1 @S9S_MB_2U_LIB.S9S_MB_2U(SCH_1):PAGE67
    U1 CA90 VCCIN253 SOCKET4677_AZIF0045P001C01CS-SA     I1 @S9S_MB_2U_LIB.S9S_MB_2U(SCH_1):PAGE67
    U1 CB61 VCCIN254 SOCKET4677_AZIF0045P001C01CS-SA     I1 @S9S_MB_2U_LIB.S9S_MB_2U(SCH_1):PAGE67
    U1 CB75 VCCIN255 SOCKET4677_AZIF0045P001C01CS-SA     I1 @S9S_MB_2U_LIB.S9S_MB_2U(SCH_1):PAGE67
    U1 CB77 VCCIN256 SOCKET4677_AZIF0045P001C01CS-SA     I1 @S9S_MB_2U_LIB.S9S_MB_2U(SCH_1):PAGE67
    U1 CC33 VCCIN257 SOCKET4677_AZIF0045P001C01CS-SA     I1 @S9S_MB_2U_LIB.S9S_MB_2U(SCH_1):PAGE67
    U1 CC35 VCCIN258 SOCKET4677_AZIF0045P001C01CS-SA     I1 @S9S_MB_2U_LIB.S9S_MB_2U(SCH_1):PAGE67
    U1 CC37 VCCIN259 SOCKET4677_AZIF0045P001C01CS-SA     I1 @S9S_MB_2U_LIB.S9S_MB_2U(SCH_1):PAGE67
    U1 CC39 VCCIN260 SOCKET4677_AZIF0045P001C01CS-SA     I1 @S9S_MB_2U_LIB.S9S_MB_2U(SCH_1):PAGE67
    U1 CC41 VCCIN261 SOCKET4677_AZIF0045P001C01CS-SA     I1 @S9S_MB_2U_LIB.S9S_MB_2U(SCH_1):PAGE67
    U1 CC43 VCCIN262 SOCKET4677_AZIF0045P001C01CS-SA     I1 @S9S_MB_2U_LIB.S9S_MB_2U(SCH_1):PAGE67
    U1 CC45 VCCIN263 SOCKET4677_AZIF0045P001C01CS-SA     I1 @S9S_MB_2U_LIB.S9S_MB_2U(SCH_1):PAGE67
    U1 CC48 VCCIN264 SOCKET4677_AZIF0045P001C01CS-SA     I1 @S9S_MB_2U_LIB.S9S_MB_2U(SCH_1):PAGE67
    U1 CC50 VCCIN265 SOCKET4677_AZIF0045P001C01CS-SA     I1 @S9S_MB_2U_LIB.S9S_MB_2U(SCH_1):PAGE67
    U1 CC52 VCCIN266 SOCKET4677_AZIF0045P001C01CS-SA     I1 @S9S_MB_2U_LIB.S9S_MB_2U(SCH_1):PAGE67
    U1 CC54 VCCIN267 SOCKET4677_AZIF0045P001C01CS-SA     I1 @S9S_MB_2U_LIB.S9S_MB_2U(SCH_1):PAGE67
    U1 CC56 VCCIN268 SOCKET4677_AZIF0045P001C01CS-SA     I1 @S9S_MB_2U_LIB.S9S_MB_2U(SCH_1):PAGE67
    U1 CC58 VCCIN269 SOCKET4677_AZIF0045P001C01CS-SA     I1 @S9S_MB_2U_LIB.S9S_MB_2U(SCH_1):PAGE67
    U1 CC60 VCCIN270 SOCKET4677_AZIF0045P001C01CS-SA     I1 @S9S_MB_2U_LIB.S9S_MB_2U(SCH_1):PAGE67
    U1 CC76 VCCIN271 SOCKET4677_AZIF0045P001C01CS-SA     I1 @S9S_MB_2U_LIB.S9S_MB_2U(SCH_1):PAGE67
    U1 CC78 VCCIN272 SOCKET4677_AZIF0045P001C01CS-SA     I1 @S9S_MB_2U_LIB.S9S_MB_2U(SCH_1):PAGE67
    U1 CC80 VCCIN273 SOCKET4677_AZIF0045P001C01CS-SA     I1 @S9S_MB_2U_LIB.S9S_MB_2U(SCH_1):PAGE67
    U1 CC82 VCCIN274 SOCKET4677_AZIF0045P001C01CS-SA     I1 @S9S_MB_2U_LIB.S9S_MB_2U(SCH_1):PAGE67
    U1 CC84 VCCIN275 SOCKET4677_AZIF0045P001C01CS-SA     I1 @S9S_MB_2U_LIB.S9S_MB_2U(SCH_1):PAGE67
    U1 CC86 VCCIN276 SOCKET4677_AZIF0045P001C01CS-SA     I1 @S9S_MB_2U_LIB.S9S_MB_2U(SCH_1):PAGE67
    U1 CC88 VCCIN277 SOCKET4677_AZIF0045P001C01CS-SA     I1 @S9S_MB_2U_LIB.S9S_MB_2U(SCH_1):PAGE67
    U1 CC90 VCCIN278 SOCKET4677_AZIF0045P001C01CS-SA     I1 @S9S_MB_2U_LIB.S9S_MB_2U(SCH_1):PAGE67
    U1 CD32 VCCIN279 SOCKET4677_AZIF0045P001C01CS-SA     I1 @S9S_MB_2U_LIB.S9S_MB_2U(SCH_1):PAGE67
    U1 CD34 VCCIN280 SOCKET4677_AZIF0045P001C01CS-SA     I1 @S9S_MB_2U_LIB.S9S_MB_2U(SCH_1):PAGE67
    U1 CD36 VCCIN281 SOCKET4677_AZIF0045P001C01CS-SA     I1 @S9S_MB_2U_LIB.S9S_MB_2U(SCH_1):PAGE67
    U1 CD38 VCCIN282 SOCKET4677_AZIF0045P001C01CS-SA     I1 @S9S_MB_2U_LIB.S9S_MB_2U(SCH_1):PAGE67
    U1 CD40 VCCIN283 SOCKET4677_AZIF0045P001C01CS-SA     I1 @S9S_MB_2U_LIB.S9S_MB_2U(SCH_1):PAGE67
    U1 CD42 VCCIN284 SOCKET4677_AZIF0045P001C01CS-SA     I1 @S9S_MB_2U_LIB.S9S_MB_2U(SCH_1):PAGE67
    U1 CD44 VCCIN285 SOCKET4677_AZIF0045P001C01CS-SA     I1 @S9S_MB_2U_LIB.S9S_MB_2U(SCH_1):PAGE67
    U1 CD47 VCCIN286 SOCKET4677_AZIF0045P001C01CS-SA     I1 @S9S_MB_2U_LIB.S9S_MB_2U(SCH_1):PAGE67
    U1 CD49 VCCIN287 SOCKET4677_AZIF0045P001C01CS-SA     I1 @S9S_MB_2U_LIB.S9S_MB_2U(SCH_1):PAGE67
    U1 CD51 VCCIN288 SOCKET4677_AZIF0045P001C01CS-SA     I1 @S9S_MB_2U_LIB.S9S_MB_2U(SCH_1):PAGE67
    U1 CD53 VCCIN289 SOCKET4677_AZIF0045P001C01CS-SA     I1 @S9S_MB_2U_LIB.S9S_MB_2U(SCH_1):PAGE67
    U1 CD55 VCCIN290 SOCKET4677_AZIF0045P001C01CS-SA     I1 @S9S_MB_2U_LIB.S9S_MB_2U(SCH_1):PAGE67
    U1 CD57 VCCIN291 SOCKET4677_AZIF0045P001C01CS-SA     I1 @S9S_MB_2U_LIB.S9S_MB_2U(SCH_1):PAGE67
    U1 CD59 VCCIN292 SOCKET4677_AZIF0045P001C01CS-SA     I1 @S9S_MB_2U_LIB.S9S_MB_2U(SCH_1):PAGE67
    U1 CD79 VCCIN293 SOCKET4677_AZIF0045P001C01CS-SA     I1 @S9S_MB_2U_LIB.S9S_MB_2U(SCH_1):PAGE67
    U1 CD81 VCCIN294 SOCKET4677_AZIF0045P001C01CS-SA     I1 @S9S_MB_2U_LIB.S9S_MB_2U(SCH_1):PAGE67
    U1 CD83 VCCIN295 SOCKET4677_AZIF0045P001C01CS-SA     I1 @S9S_MB_2U_LIB.S9S_MB_2U(SCH_1):PAGE67
    U1 CD85 VCCIN296 SOCKET4677_AZIF0045P001C01CS-SA     I1 @S9S_MB_2U_LIB.S9S_MB_2U(SCH_1):PAGE67
    U1 CD87 VCCIN297 SOCKET4677_AZIF0045P001C01CS-SA     I1 @S9S_MB_2U_LIB.S9S_MB_2U(SCH_1):PAGE67
    U1 CD89 VCCIN298 SOCKET4677_AZIF0045P001C01CS-SA     I1 @S9S_MB_2U_LIB.S9S_MB_2U(SCH_1):PAGE67
    U1 CE80 VCCIN299 SOCKET4677_AZIF0045P001C01CS-SA     I1 @S9S_MB_2U_LIB.S9S_MB_2U(SCH_1):PAGE67
    U1 CE82 VCCIN300 SOCKET4677_AZIF0045P001C01CS-SA     I1 @S9S_MB_2U_LIB.S9S_MB_2U(SCH_1):PAGE67
    U1 CE84 VCCIN301 SOCKET4677_AZIF0045P001C01CS-SA     I1 @S9S_MB_2U_LIB.S9S_MB_2U(SCH_1):PAGE67
    U1 CE86 VCCIN302 SOCKET4677_AZIF0045P001C01CS-SA     I1 @S9S_MB_2U_LIB.S9S_MB_2U(SCH_1):PAGE67
    U1 CE88 VCCIN303 SOCKET4677_AZIF0045P001C01CS-SA     I1 @S9S_MB_2U_LIB.S9S_MB_2U(SCH_1):PAGE67
    U1 CE90 VCCIN304 SOCKET4677_AZIF0045P001C01CS-SA     I1 @S9S_MB_2U_LIB.S9S_MB_2U(SCH_1):PAGE67
    U1 CF79 VCCIN305 SOCKET4677_AZIF0045P001C01CS-SA     I1 @S9S_MB_2U_LIB.S9S_MB_2U(SCH_1):PAGE67
    U1 CF81 VCCIN306 SOCKET4677_AZIF0045P001C01CS-SA     I1 @S9S_MB_2U_LIB.S9S_MB_2U(SCH_1):PAGE67
    U1 CF83 VCCIN307 SOCKET4677_AZIF0045P001C01CS-SA     I1 @S9S_MB_2U_LIB.S9S_MB_2U(SCH_1):PAGE67
    U1 CF85 VCCIN308 SOCKET4677_AZIF0045P001C01CS-SA     I1 @S9S_MB_2U_LIB.S9S_MB_2U(SCH_1):PAGE67
    U1 CF87 VCCIN309 SOCKET4677_AZIF0045P001C01CS-SA     I1 @S9S_MB_2U_LIB.S9S_MB_2U(SCH_1):PAGE67
    U1 CF89 VCCIN310 SOCKET4677_AZIF0045P001C01CS-SA     I1 @S9S_MB_2U_LIB.S9S_MB_2U(SCH_1):PAGE67
    U1 CF91 VCCIN311 SOCKET4677_AZIF0045P001C01CS-SA     I1 @S9S_MB_2U_LIB.S9S_MB_2U(SCH_1):PAGE67
    U1 CG80 VCCIN312 SOCKET4677_AZIF0045P001C01CS-SA     I1 @S9S_MB_2U_LIB.S9S_MB_2U(SCH_1):PAGE67
    U1 CG82 VCCIN313 SOCKET4677_AZIF0045P001C01CS-SA     I1 @S9S_MB_2U_LIB.S9S_MB_2U(SCH_1):PAGE67
    U1 CG84 VCCIN314 SOCKET4677_AZIF0045P001C01CS-SA     I1 @S9S_MB_2U_LIB.S9S_MB_2U(SCH_1):PAGE67
    U1 CG86 VCCIN315 SOCKET4677_AZIF0045P001C01CS-SA     I1 @S9S_MB_2U_LIB.S9S_MB_2U(SCH_1):PAGE67
    U1 CG88 VCCIN316 SOCKET4677_AZIF0045P001C01CS-SA     I1 @S9S_MB_2U_LIB.S9S_MB_2U(SCH_1):PAGE67
    U1 CG90 VCCIN317 SOCKET4677_AZIF0045P001C01CS-SA     I1 @S9S_MB_2U_LIB.S9S_MB_2U(SCH_1):PAGE67
    U1 CH81 VCCIN318 SOCKET4677_AZIF0045P001C01CS-SA     I1 @S9S_MB_2U_LIB.S9S_MB_2U(SCH_1):PAGE67
    U1 CH91 VCCIN319 SOCKET4677_AZIF0045P001C01CS-SA     I1 @S9S_MB_2U_LIB.S9S_MB_2U(SCH_1):PAGE67
    U1 CJ82 VCCIN320 SOCKET4677_AZIF0045P001C01CS-SA     I1 @S9S_MB_2U_LIB.S9S_MB_2U(SCH_1):PAGE67
    U1 CJ84 VCCIN321 SOCKET4677_AZIF0045P001C01CS-SA     I1 @S9S_MB_2U_LIB.S9S_MB_2U(SCH_1):PAGE67
    U1 CJ86 VCCIN322 SOCKET4677_AZIF0045P001C01CS-SA     I1 @S9S_MB_2U_LIB.S9S_MB_2U(SCH_1):PAGE67
    U1 CJ88 VCCIN323 SOCKET4677_AZIF0045P001C01CS-SA     I1 @S9S_MB_2U_LIB.S9S_MB_2U(SCH_1):PAGE67
    U1 CJ90 VCCIN324 SOCKET4677_AZIF0045P001C01CS-SA     I1 @S9S_MB_2U_LIB.S9S_MB_2U(SCH_1):PAGE67
    U1 CK83 VCCIN325 SOCKET4677_AZIF0045P001C01CS-SA     I1 @S9S_MB_2U_LIB.S9S_MB_2U(SCH_1):PAGE67
    U1 CK85 VCCIN326 SOCKET4677_AZIF0045P001C01CS-SA     I1 @S9S_MB_2U_LIB.S9S_MB_2U(SCH_1):PAGE67
    U1 CK87 VCCIN327 SOCKET4677_AZIF0045P001C01CS-SA     I1 @S9S_MB_2U_LIB.S9S_MB_2U(SCH_1):PAGE67
    U1 CK89 VCCIN328 SOCKET4677_AZIF0045P001C01CS-SA     I1 @S9S_MB_2U_LIB.S9S_MB_2U(SCH_1):PAGE67
    U1 CK91 VCCIN329 SOCKET4677_AZIF0045P001C01CS-SA     I1 @S9S_MB_2U_LIB.S9S_MB_2U(SCH_1):PAGE67
    U1 CL84 VCCIN330 SOCKET4677_AZIF0045P001C01CS-SA     I1 @S9S_MB_2U_LIB.S9S_MB_2U(SCH_1):PAGE67
    U1 CL86 VCCIN331 SOCKET4677_AZIF0045P001C01CS-SA     I1 @S9S_MB_2U_LIB.S9S_MB_2U(SCH_1):PAGE67
    U1 CL88 VCCIN332 SOCKET4677_AZIF0045P001C01CS-SA     I1 @S9S_MB_2U_LIB.S9S_MB_2U(SCH_1):PAGE67
    U1 CL90 VCCIN333 SOCKET4677_AZIF0045P001C01CS-SA     I1 @S9S_MB_2U_LIB.S9S_MB_2U(SCH_1):PAGE67
    U1 CM87 VCCIN334 SOCKET4677_AZIF0045P001C01CS-SA     I1 @S9S_MB_2U_LIB.S9S_MB_2U(SCH_1):PAGE67
    U1 CM91 VCCIN335 SOCKET4677_AZIF0045P001C01CS-SA     I1 @S9S_MB_2U_LIB.S9S_MB_2U(SCH_1):PAGE67
    U1 CN88 VCCIN336 SOCKET4677_AZIF0045P001C01CS-SA     I1 @S9S_MB_2U_LIB.S9S_MB_2U(SCH_1):PAGE67
    U1 CN90 VCCIN337 SOCKET4677_AZIF0045P001C01CS-SA     I1 @S9S_MB_2U_LIB.S9S_MB_2U(SCH_1):PAGE67
    U1 CP89 VCCIN338 SOCKET4677_AZIF0045P001C01CS-SA     I1 @S9S_MB_2U_LIB.S9S_MB_2U(SCH_1):PAGE67
    U1 CM89 VCCIN339 SOCKET4677_AZIF0045P001C01CS-SA     I1 @S9S_MB_2U_LIB.S9S_MB_2U(SCH_1):PAGE67
    U1 BN43 VCCIN40 SOCKET4677_AZIF0045P001C01CS-SA     I3 @S9S_MB_2U_LIB.S9S_MB_2U(SCH_1):PAGE67
    U1 BN45 VCCIN41 SOCKET4677_AZIF0045P001C01CS-SA     I3 @S9S_MB_2U_LIB.S9S_MB_2U(SCH_1):PAGE67
    U1 BN48 VCCIN42 SOCKET4677_AZIF0045P001C01CS-SA     I3 @S9S_MB_2U_LIB.S9S_MB_2U(SCH_1):PAGE67
    U1 BN50 VCCIN43 SOCKET4677_AZIF0045P001C01CS-SA     I3 @S9S_MB_2U_LIB.S9S_MB_2U(SCH_1):PAGE67
    U1 BN52 VCCIN44 SOCKET4677_AZIF0045P001C01CS-SA     I3 @S9S_MB_2U_LIB.S9S_MB_2U(SCH_1):PAGE67
    U1 BN54 VCCIN45 SOCKET4677_AZIF0045P001C01CS-SA     I3 @S9S_MB_2U_LIB.S9S_MB_2U(SCH_1):PAGE67
    U1 BN56 VCCIN46 SOCKET4677_AZIF0045P001C01CS-SA     I3 @S9S_MB_2U_LIB.S9S_MB_2U(SCH_1):PAGE67
    U1 BN58 VCCIN47 SOCKET4677_AZIF0045P001C01CS-SA     I3 @S9S_MB_2U_LIB.S9S_MB_2U(SCH_1):PAGE67
    U1 BN60 VCCIN48 SOCKET4677_AZIF0045P001C01CS-SA     I3 @S9S_MB_2U_LIB.S9S_MB_2U(SCH_1):PAGE67
    U1 BN78 VCCIN49 SOCKET4677_AZIF0045P001C01CS-SA     I3 @S9S_MB_2U_LIB.S9S_MB_2U(SCH_1):PAGE67
    U1 BN80 VCCIN50 SOCKET4677_AZIF0045P001C01CS-SA     I3 @S9S_MB_2U_LIB.S9S_MB_2U(SCH_1):PAGE67
    U1 BN82 VCCIN51 SOCKET4677_AZIF0045P001C01CS-SA     I3 @S9S_MB_2U_LIB.S9S_MB_2U(SCH_1):PAGE67
    U1 BN84 VCCIN52 SOCKET4677_AZIF0045P001C01CS-SA     I3 @S9S_MB_2U_LIB.S9S_MB_2U(SCH_1):PAGE67
    U1 BN86 VCCIN53 SOCKET4677_AZIF0045P001C01CS-SA     I3 @S9S_MB_2U_LIB.S9S_MB_2U(SCH_1):PAGE67
    U1 BN88 VCCIN54 SOCKET4677_AZIF0045P001C01CS-SA     I3 @S9S_MB_2U_LIB.S9S_MB_2U(SCH_1):PAGE67
    U1 BN90 VCCIN55 SOCKET4677_AZIF0045P001C01CS-SA     I3 @S9S_MB_2U_LIB.S9S_MB_2U(SCH_1):PAGE67
    U1 BP32 VCCIN56 SOCKET4677_AZIF0045P001C01CS-SA     I3 @S9S_MB_2U_LIB.S9S_MB_2U(SCH_1):PAGE67
    U1 BP34 VCCIN57 SOCKET4677_AZIF0045P001C01CS-SA     I3 @S9S_MB_2U_LIB.S9S_MB_2U(SCH_1):PAGE67
    U1 BP36 VCCIN58 SOCKET4677_AZIF0045P001C01CS-SA     I3 @S9S_MB_2U_LIB.S9S_MB_2U(SCH_1):PAGE67
    U1 BP38 VCCIN59 SOCKET4677_AZIF0045P001C01CS-SA     I3 @S9S_MB_2U_LIB.S9S_MB_2U(SCH_1):PAGE67
    U1 BP40 VCCIN60 SOCKET4677_AZIF0045P001C01CS-SA     I3 @S9S_MB_2U_LIB.S9S_MB_2U(SCH_1):PAGE67
    U1 BP42 VCCIN61 SOCKET4677_AZIF0045P001C01CS-SA     I3 @S9S_MB_2U_LIB.S9S_MB_2U(SCH_1):PAGE67
    U1 BP44 VCCIN62 SOCKET4677_AZIF0045P001C01CS-SA     I3 @S9S_MB_2U_LIB.S9S_MB_2U(SCH_1):PAGE67
    U1 BP47 VCCIN63 SOCKET4677_AZIF0045P001C01CS-SA     I3 @S9S_MB_2U_LIB.S9S_MB_2U(SCH_1):PAGE67
    U1 BP49 VCCIN64 SOCKET4677_AZIF0045P001C01CS-SA     I3 @S9S_MB_2U_LIB.S9S_MB_2U(SCH_1):PAGE67
    U1 BP51 VCCIN65 SOCKET4677_AZIF0045P001C01CS-SA     I3 @S9S_MB_2U_LIB.S9S_MB_2U(SCH_1):PAGE67
    U1 BP53 VCCIN66 SOCKET4677_AZIF0045P001C01CS-SA     I3 @S9S_MB_2U_LIB.S9S_MB_2U(SCH_1):PAGE67
    U1 BP55 VCCIN67 SOCKET4677_AZIF0045P001C01CS-SA     I3 @S9S_MB_2U_LIB.S9S_MB_2U(SCH_1):PAGE67
    U1 BP57 VCCIN68 SOCKET4677_AZIF0045P001C01CS-SA     I3 @S9S_MB_2U_LIB.S9S_MB_2U(SCH_1):PAGE67
    U1 BP59 VCCIN69 SOCKET4677_AZIF0045P001C01CS-SA     I3 @S9S_MB_2U_LIB.S9S_MB_2U(SCH_1):PAGE67
    U1 BP61 VCCIN70 SOCKET4677_AZIF0045P001C01CS-SA     I3 @S9S_MB_2U_LIB.S9S_MB_2U(SCH_1):PAGE67
    U1 BP79 VCCIN71 SOCKET4677_AZIF0045P001C01CS-SA     I3 @S9S_MB_2U_LIB.S9S_MB_2U(SCH_1):PAGE67
    U1 BP81 VCCIN72 SOCKET4677_AZIF0045P001C01CS-SA     I3 @S9S_MB_2U_LIB.S9S_MB_2U(SCH_1):PAGE67
    U1 BP83 VCCIN73 SOCKET4677_AZIF0045P001C01CS-SA     I3 @S9S_MB_2U_LIB.S9S_MB_2U(SCH_1):PAGE67
    U1 BP85 VCCIN74 SOCKET4677_AZIF0045P001C01CS-SA     I3 @S9S_MB_2U_LIB.S9S_MB_2U(SCH_1):PAGE67
    U1 BP87 VCCIN75 SOCKET4677_AZIF0045P001C01CS-SA     I3 @S9S_MB_2U_LIB.S9S_MB_2U(SCH_1):PAGE67
    U1 BP89 VCCIN76 SOCKET4677_AZIF0045P001C01CS-SA     I3 @S9S_MB_2U_LIB.S9S_MB_2U(SCH_1):PAGE67
    U1 BR60 VCCIN77 SOCKET4677_AZIF0045P001C01CS-SA     I3 @S9S_MB_2U_LIB.S9S_MB_2U(SCH_1):PAGE67
    U1 BR62 VCCIN78 SOCKET4677_AZIF0045P001C01CS-SA     I3 @S9S_MB_2U_LIB.S9S_MB_2U(SCH_1):PAGE67
    U1 BR78 VCCIN79 SOCKET4677_AZIF0045P001C01CS-SA     I3 @S9S_MB_2U_LIB.S9S_MB_2U(SCH_1):PAGE67
    U1 BT32 VCCIN80 SOCKET4677_AZIF0045P001C01CS-SA     I3 @S9S_MB_2U_LIB.S9S_MB_2U(SCH_1):PAGE67
    U1 BT34 VCCIN81 SOCKET4677_AZIF0045P001C01CS-SA     I3 @S9S_MB_2U_LIB.S9S_MB_2U(SCH_1):PAGE67
    U1 BT36 VCCIN82 SOCKET4677_AZIF0045P001C01CS-SA     I3 @S9S_MB_2U_LIB.S9S_MB_2U(SCH_1):PAGE67
    U1 BT38 VCCIN83 SOCKET4677_AZIF0045P001C01CS-SA     I3 @S9S_MB_2U_LIB.S9S_MB_2U(SCH_1):PAGE67
    U1 BT40 VCCIN84 SOCKET4677_AZIF0045P001C01CS-SA     I3 @S9S_MB_2U_LIB.S9S_MB_2U(SCH_1):PAGE67
    U1 BT42 VCCIN85 SOCKET4677_AZIF0045P001C01CS-SA     I3 @S9S_MB_2U_LIB.S9S_MB_2U(SCH_1):PAGE67
    U1 BT44 VCCIN86 SOCKET4677_AZIF0045P001C01CS-SA     I3 @S9S_MB_2U_LIB.S9S_MB_2U(SCH_1):PAGE67
    U1 BT47 VCCIN87 SOCKET4677_AZIF0045P001C01CS-SA     I3 @S9S_MB_2U_LIB.S9S_MB_2U(SCH_1):PAGE67
    U1 BT49 VCCIN88 SOCKET4677_AZIF0045P001C01CS-SA     I3 @S9S_MB_2U_LIB.S9S_MB_2U(SCH_1):PAGE67
    U1 BT51 VCCIN89 SOCKET4677_AZIF0045P001C01CS-SA     I3 @S9S_MB_2U_LIB.S9S_MB_2U(SCH_1):PAGE67
    U1 BT53 VCCIN90 SOCKET4677_AZIF0045P001C01CS-SA     I3 @S9S_MB_2U_LIB.S9S_MB_2U(SCH_1):PAGE67
    U1 BT55 VCCIN91 SOCKET4677_AZIF0045P001C01CS-SA     I3 @S9S_MB_2U_LIB.S9S_MB_2U(SCH_1):PAGE67
    U1 BT57 VCCIN92 SOCKET4677_AZIF0045P001C01CS-SA     I3 @S9S_MB_2U_LIB.S9S_MB_2U(SCH_1):PAGE67
    U1 BT59 VCCIN93 SOCKET4677_AZIF0045P001C01CS-SA     I3 @S9S_MB_2U_LIB.S9S_MB_2U(SCH_1):PAGE67
    U1 BT61 VCCIN94 SOCKET4677_AZIF0045P001C01CS-SA     I3 @S9S_MB_2U_LIB.S9S_MB_2U(SCH_1):PAGE67
    U1 BT63 VCCIN95 SOCKET4677_AZIF0045P001C01CS-SA     I3 @S9S_MB_2U_LIB.S9S_MB_2U(SCH_1):PAGE67
    U1 BT65 VCCIN96 SOCKET4677_AZIF0045P001C01CS-SA     I3 @S9S_MB_2U_LIB.S9S_MB_2U(SCH_1):PAGE67
    U1 BT67 VCCIN97 SOCKET4677_AZIF0045P001C01CS-SA     I3 @S9S_MB_2U_LIB.S9S_MB_2U(SCH_1):PAGE67
    U1 BT69 VCCIN98 SOCKET4677_AZIF0045P001C01CS-SA     I3 @S9S_MB_2U_LIB.S9S_MB_2U(SCH_1):PAGE67
    U1 BT71 VCCIN99 SOCKET4677_AZIF0045P001C01CS-SA     I3 @S9S_MB_2U_LIB.S9S_MB_2U(SCH_1):PAGE67
    U1 BT73 VCCIN100 SOCKET4677_AZIF0045P001C01CS-SA     I3 @S9S_MB_2U_LIB.S9S_MB_2U(SCH_1):PAGE67
    U1 BT75 VCCIN101 SOCKET4677_AZIF0045P001C01CS-SA     I3 @S9S_MB_2U_LIB.S9S_MB_2U(SCH_1):PAGE67
    U1 BT77 VCCIN102 SOCKET4677_AZIF0045P001C01CS-SA     I3 @S9S_MB_2U_LIB.S9S_MB_2U(SCH_1):PAGE67
    U1 BT79 VCCIN103 SOCKET4677_AZIF0045P001C01CS-SA     I3 @S9S_MB_2U_LIB.S9S_MB_2U(SCH_1):PAGE67
    U1 BT81 VCCIN104 SOCKET4677_AZIF0045P001C01CS-SA     I3 @S9S_MB_2U_LIB.S9S_MB_2U(SCH_1):PAGE67
    U1 BT83 VCCIN105 SOCKET4677_AZIF0045P001C01CS-SA     I3 @S9S_MB_2U_LIB.S9S_MB_2U(SCH_1):PAGE67
    U1 BT85 VCCIN106 SOCKET4677_AZIF0045P001C01CS-SA     I3 @S9S_MB_2U_LIB.S9S_MB_2U(SCH_1):PAGE67
    U1 BT87 VCCIN107 SOCKET4677_AZIF0045P001C01CS-SA     I3 @S9S_MB_2U_LIB.S9S_MB_2U(SCH_1):PAGE67
    U1 BT89 VCCIN108 SOCKET4677_AZIF0045P001C01CS-SA     I3 @S9S_MB_2U_LIB.S9S_MB_2U(SCH_1):PAGE67
    U1 BU33 VCCIN109 SOCKET4677_AZIF0045P001C01CS-SA     I3 @S9S_MB_2U_LIB.S9S_MB_2U(SCH_1):PAGE67
    U1 BU35 VCCIN110 SOCKET4677_AZIF0045P001C01CS-SA     I3 @S9S_MB_2U_LIB.S9S_MB_2U(SCH_1):PAGE67
    U1 BU37 VCCIN111 SOCKET4677_AZIF0045P001C01CS-SA     I3 @S9S_MB_2U_LIB.S9S_MB_2U(SCH_1):PAGE67
    U1 BU39 VCCIN112 SOCKET4677_AZIF0045P001C01CS-SA     I3 @S9S_MB_2U_LIB.S9S_MB_2U(SCH_1):PAGE67
    U1 BU41 VCCIN113 SOCKET4677_AZIF0045P001C01CS-SA     I3 @S9S_MB_2U_LIB.S9S_MB_2U(SCH_1):PAGE67
    U1 BU43 VCCIN114 SOCKET4677_AZIF0045P001C01CS-SA     I3 @S9S_MB_2U_LIB.S9S_MB_2U(SCH_1):PAGE67
    U1 BU45 VCCIN115 SOCKET4677_AZIF0045P001C01CS-SA     I3 @S9S_MB_2U_LIB.S9S_MB_2U(SCH_1):PAGE67
    U1 BU48 VCCIN116 SOCKET4677_AZIF0045P001C01CS-SA     I3 @S9S_MB_2U_LIB.S9S_MB_2U(SCH_1):PAGE67
    U1 BU50 VCCIN117 SOCKET4677_AZIF0045P001C01CS-SA     I3 @S9S_MB_2U_LIB.S9S_MB_2U(SCH_1):PAGE67
    U1 BU52 VCCIN118 SOCKET4677_AZIF0045P001C01CS-SA     I3 @S9S_MB_2U_LIB.S9S_MB_2U(SCH_1):PAGE67
    U1 BU54 VCCIN119 SOCKET4677_AZIF0045P001C01CS-SA     I3 @S9S_MB_2U_LIB.S9S_MB_2U(SCH_1):PAGE67
    U1 BU56 VCCIN120 SOCKET4677_AZIF0045P001C01CS-SA     I3 @S9S_MB_2U_LIB.S9S_MB_2U(SCH_1):PAGE67
    U1 BU58 VCCIN121 SOCKET4677_AZIF0045P001C01CS-SA     I3 @S9S_MB_2U_LIB.S9S_MB_2U(SCH_1):PAGE67
    U1 BU60 VCCIN122 SOCKET4677_AZIF0045P001C01CS-SA     I3 @S9S_MB_2U_LIB.S9S_MB_2U(SCH_1):PAGE67
    U1 BU62 VCCIN123 SOCKET4677_AZIF0045P001C01CS-SA     I3 @S9S_MB_2U_LIB.S9S_MB_2U(SCH_1):PAGE67
    U1 BU64 VCCIN124 SOCKET4677_AZIF0045P001C01CS-SA     I3 @S9S_MB_2U_LIB.S9S_MB_2U(SCH_1):PAGE67
    U1 BU66 VCCIN125 SOCKET4677_AZIF0045P001C01CS-SA     I3 @S9S_MB_2U_LIB.S9S_MB_2U(SCH_1):PAGE67
    U1 BU68 VCCIN126 SOCKET4677_AZIF0045P001C01CS-SA     I3 @S9S_MB_2U_LIB.S9S_MB_2U(SCH_1):PAGE67
    U1 BU70 VCCIN127 SOCKET4677_AZIF0045P001C01CS-SA     I3 @S9S_MB_2U_LIB.S9S_MB_2U(SCH_1):PAGE67
    U1 BU72 VCCIN128 SOCKET4677_AZIF0045P001C01CS-SA     I3 @S9S_MB_2U_LIB.S9S_MB_2U(SCH_1):PAGE67
    U1 BU74 VCCIN129 SOCKET4677_AZIF0045P001C01CS-SA     I3 @S9S_MB_2U_LIB.S9S_MB_2U(SCH_1):PAGE67
    U1 BU76 VCCIN130 SOCKET4677_AZIF0045P001C01CS-SA     I3 @S9S_MB_2U_LIB.S9S_MB_2U(SCH_1):PAGE67
    U1 BU78 VCCIN131 SOCKET4677_AZIF0045P001C01CS-SA     I3 @S9S_MB_2U_LIB.S9S_MB_2U(SCH_1):PAGE67
    U1 BU80 VCCIN132 SOCKET4677_AZIF0045P001C01CS-SA     I3 @S9S_MB_2U_LIB.S9S_MB_2U(SCH_1):PAGE67
    U1 BU82 VCCIN133 SOCKET4677_AZIF0045P001C01CS-SA     I3 @S9S_MB_2U_LIB.S9S_MB_2U(SCH_1):PAGE67
    U1 BU84 VCCIN134 SOCKET4677_AZIF0045P001C01CS-SA     I3 @S9S_MB_2U_LIB.S9S_MB_2U(SCH_1):PAGE67
    U1 BU86 VCCIN135 SOCKET4677_AZIF0045P001C01CS-SA     I3 @S9S_MB_2U_LIB.S9S_MB_2U(SCH_1):PAGE67
    U1 BU88 VCCIN136 SOCKET4677_AZIF0045P001C01CS-SA     I3 @S9S_MB_2U_LIB.S9S_MB_2U(SCH_1):PAGE67
    U1 BU90 VCCIN137 SOCKET4677_AZIF0045P001C01CS-SA     I3 @S9S_MB_2U_LIB.S9S_MB_2U(SCH_1):PAGE67
    U1 BV32 VCCIN138 SOCKET4677_AZIF0045P001C01CS-SA     I3 @S9S_MB_2U_LIB.S9S_MB_2U(SCH_1):PAGE67
    U1 BV34 VCCIN139 SOCKET4677_AZIF0045P001C01CS-SA     I3 @S9S_MB_2U_LIB.S9S_MB_2U(SCH_1):PAGE67
    U1 BV36 VCCIN140 SOCKET4677_AZIF0045P001C01CS-SA     I3 @S9S_MB_2U_LIB.S9S_MB_2U(SCH_1):PAGE67
    U1 BV38 VCCIN141 SOCKET4677_AZIF0045P001C01CS-SA     I3 @S9S_MB_2U_LIB.S9S_MB_2U(SCH_1):PAGE67
    U1 BV40 VCCIN142 SOCKET4677_AZIF0045P001C01CS-SA     I3 @S9S_MB_2U_LIB.S9S_MB_2U(SCH_1):PAGE67
    U1 BV42 VCCIN143 SOCKET4677_AZIF0045P001C01CS-SA     I3 @S9S_MB_2U_LIB.S9S_MB_2U(SCH_1):PAGE67
    U1 BV44 VCCIN144 SOCKET4677_AZIF0045P001C01CS-SA     I3 @S9S_MB_2U_LIB.S9S_MB_2U(SCH_1):PAGE67
    U1 BV47 VCCIN145 SOCKET4677_AZIF0045P001C01CS-SA     I3 @S9S_MB_2U_LIB.S9S_MB_2U(SCH_1):PAGE67
    U1 BV49 VCCIN146 SOCKET4677_AZIF0045P001C01CS-SA     I3 @S9S_MB_2U_LIB.S9S_MB_2U(SCH_1):PAGE67
    U1 BV51 VCCIN147 SOCKET4677_AZIF0045P001C01CS-SA     I3 @S9S_MB_2U_LIB.S9S_MB_2U(SCH_1):PAGE67
    U1 BV53 VCCIN148 SOCKET4677_AZIF0045P001C01CS-SA     I3 @S9S_MB_2U_LIB.S9S_MB_2U(SCH_1):PAGE67
    U1 BV55 VCCIN149 SOCKET4677_AZIF0045P001C01CS-SA     I3 @S9S_MB_2U_LIB.S9S_MB_2U(SCH_1):PAGE67
    U1 BV57 VCCIN150 SOCKET4677_AZIF0045P001C01CS-SA     I3 @S9S_MB_2U_LIB.S9S_MB_2U(SCH_1):PAGE67
    U1 BV59 VCCIN151 SOCKET4677_AZIF0045P001C01CS-SA     I3 @S9S_MB_2U_LIB.S9S_MB_2U(SCH_1):PAGE67
    U1 BV61 VCCIN152 SOCKET4677_AZIF0045P001C01CS-SA     I3 @S9S_MB_2U_LIB.S9S_MB_2U(SCH_1):PAGE67
    U1 BV63 VCCIN153 SOCKET4677_AZIF0045P001C01CS-SA     I3 @S9S_MB_2U_LIB.S9S_MB_2U(SCH_1):PAGE67
    U1 BV65 VCCIN154 SOCKET4677_AZIF0045P001C01CS-SA     I3 @S9S_MB_2U_LIB.S9S_MB_2U(SCH_1):PAGE67
    U1 BV67 VCCIN155 SOCKET4677_AZIF0045P001C01CS-SA     I3 @S9S_MB_2U_LIB.S9S_MB_2U(SCH_1):PAGE67
    U1 BV69 VCCIN156 SOCKET4677_AZIF0045P001C01CS-SA     I3 @S9S_MB_2U_LIB.S9S_MB_2U(SCH_1):PAGE67
    U1 BV71 VCCIN157 SOCKET4677_AZIF0045P001C01CS-SA     I3 @S9S_MB_2U_LIB.S9S_MB_2U(SCH_1):PAGE67
    U1 BV73 VCCIN158 SOCKET4677_AZIF0045P001C01CS-SA     I3 @S9S_MB_2U_LIB.S9S_MB_2U(SCH_1):PAGE67
    U1 BV75 VCCIN159 SOCKET4677_AZIF0045P001C01CS-SA     I3 @S9S_MB_2U_LIB.S9S_MB_2U(SCH_1):PAGE67
    U1 BV77 VCCIN160 SOCKET4677_AZIF0045P001C01CS-SA     I3 @S9S_MB_2U_LIB.S9S_MB_2U(SCH_1):PAGE67
    U1 BV79 VCCIN161 SOCKET4677_AZIF0045P001C01CS-SA     I3 @S9S_MB_2U_LIB.S9S_MB_2U(SCH_1):PAGE67
    U1 BV81 VCCIN162 SOCKET4677_AZIF0045P001C01CS-SA     I3 @S9S_MB_2U_LIB.S9S_MB_2U(SCH_1):PAGE67
    U1 BV83 VCCIN163 SOCKET4677_AZIF0045P001C01CS-SA     I3 @S9S_MB_2U_LIB.S9S_MB_2U(SCH_1):PAGE67
    U1 BV85 VCCIN164 SOCKET4677_AZIF0045P001C01CS-SA     I3 @S9S_MB_2U_LIB.S9S_MB_2U(SCH_1):PAGE67
    U1 BV87 VCCIN165 SOCKET4677_AZIF0045P001C01CS-SA     I3 @S9S_MB_2U_LIB.S9S_MB_2U(SCH_1):PAGE67
    U1 BV89 VCCIN166 SOCKET4677_AZIF0045P001C01CS-SA     I3 @S9S_MB_2U_LIB.S9S_MB_2U(SCH_1):PAGE67
    U1 BW33 VCCIN167 SOCKET4677_AZIF0045P001C01CS-SA     I3 @S9S_MB_2U_LIB.S9S_MB_2U(SCH_1):PAGE67
    U1 BW35 VCCIN168 SOCKET4677_AZIF0045P001C01CS-SA     I3 @S9S_MB_2U_LIB.S9S_MB_2U(SCH_1):PAGE67
    U1 BW37 VCCIN169 SOCKET4677_AZIF0045P001C01CS-SA     I3 @S9S_MB_2U_LIB.S9S_MB_2U(SCH_1):PAGE67
    U1 BW39 VCCIN170 SOCKET4677_AZIF0045P001C01CS-SA     I3 @S9S_MB_2U_LIB.S9S_MB_2U(SCH_1):PAGE67
    U1 BW41 VCCIN171 SOCKET4677_AZIF0045P001C01CS-SA     I3 @S9S_MB_2U_LIB.S9S_MB_2U(SCH_1):PAGE67
    U1 BW43 VCCIN172 SOCKET4677_AZIF0045P001C01CS-SA     I3 @S9S_MB_2U_LIB.S9S_MB_2U(SCH_1):PAGE67
    U1 BW45 VCCIN173 SOCKET4677_AZIF0045P001C01CS-SA     I3 @S9S_MB_2U_LIB.S9S_MB_2U(SCH_1):PAGE67
    U1 BW48 VCCIN174 SOCKET4677_AZIF0045P001C01CS-SA     I3 @S9S_MB_2U_LIB.S9S_MB_2U(SCH_1):PAGE67
    U1 BW50 VCCIN175 SOCKET4677_AZIF0045P001C01CS-SA     I3 @S9S_MB_2U_LIB.S9S_MB_2U(SCH_1):PAGE67
    U1 BW52 VCCIN176 SOCKET4677_AZIF0045P001C01CS-SA     I3 @S9S_MB_2U_LIB.S9S_MB_2U(SCH_1):PAGE67
    U1 BW54 VCCIN177 SOCKET4677_AZIF0045P001C01CS-SA     I3 @S9S_MB_2U_LIB.S9S_MB_2U(SCH_1):PAGE67
    U1 BW56 VCCIN178 SOCKET4677_AZIF0045P001C01CS-SA     I3 @S9S_MB_2U_LIB.S9S_MB_2U(SCH_1):PAGE67
    U1 BW58 VCCIN179 SOCKET4677_AZIF0045P001C01CS-SA     I3 @S9S_MB_2U_LIB.S9S_MB_2U(SCH_1):PAGE67
    U1 BW60 VCCIN180 SOCKET4677_AZIF0045P001C01CS-SA     I3 @S9S_MB_2U_LIB.S9S_MB_2U(SCH_1):PAGE67
    U1 BW62 VCCIN181 SOCKET4677_AZIF0045P001C01CS-SA     I3 @S9S_MB_2U_LIB.S9S_MB_2U(SCH_1):PAGE67
    U1 BW64 VCCIN182 SOCKET4677_AZIF0045P001C01CS-SA     I3 @S9S_MB_2U_LIB.S9S_MB_2U(SCH_1):PAGE67
    U1 BW66 VCCIN183 SOCKET4677_AZIF0045P001C01CS-SA     I3 @S9S_MB_2U_LIB.S9S_MB_2U(SCH_1):PAGE67
    U1 BW68 VCCIN184 SOCKET4677_AZIF0045P001C01CS-SA     I3 @S9S_MB_2U_LIB.S9S_MB_2U(SCH_1):PAGE67
    U1 BW70 VCCIN185 SOCKET4677_AZIF0045P001C01CS-SA     I3 @S9S_MB_2U_LIB.S9S_MB_2U(SCH_1):PAGE67
    U1 BW72 VCCIN186 SOCKET4677_AZIF0045P001C01CS-SA     I3 @S9S_MB_2U_LIB.S9S_MB_2U(SCH_1):PAGE67
    U1 BW74 VCCIN187 SOCKET4677_AZIF0045P001C01CS-SA     I3 @S9S_MB_2U_LIB.S9S_MB_2U(SCH_1):PAGE67
    U1 BW76 VCCIN188 SOCKET4677_AZIF0045P001C01CS-SA     I3 @S9S_MB_2U_LIB.S9S_MB_2U(SCH_1):PAGE67
    U1 BW78 VCCIN189 SOCKET4677_AZIF0045P001C01CS-SA     I3 @S9S_MB_2U_LIB.S9S_MB_2U(SCH_1):PAGE67
    U1 BD91 VCCIN0 SOCKET4677_AZIF0045P001C01CS-SA     I1 @S9S_MB_2U_LIB.S9S_MB_2U(SCH_1):PAGE68
    U1 BE86 VCCIN1 SOCKET4677_AZIF0045P001C01CS-SA     I1 @S9S_MB_2U_LIB.S9S_MB_2U(SCH_1):PAGE68
    U1 BE88 VCCIN2 SOCKET4677_AZIF0045P001C01CS-SA     I1 @S9S_MB_2U_LIB.S9S_MB_2U(SCH_1):PAGE68
    U1 BE90 VCCIN3 SOCKET4677_AZIF0045P001C01CS-SA     I1 @S9S_MB_2U_LIB.S9S_MB_2U(SCH_1):PAGE68
    U1 BF85 VCCIN4 SOCKET4677_AZIF0045P001C01CS-SA     I1 @S9S_MB_2U_LIB.S9S_MB_2U(SCH_1):PAGE68
    U1 BF87 VCCIN5 SOCKET4677_AZIF0045P001C01CS-SA     I1 @S9S_MB_2U_LIB.S9S_MB_2U(SCH_1):PAGE68
    U1 BF89 VCCIN6 SOCKET4677_AZIF0045P001C01CS-SA     I1 @S9S_MB_2U_LIB.S9S_MB_2U(SCH_1):PAGE68
    U1 BF91 VCCIN7 SOCKET4677_AZIF0045P001C01CS-SA     I1 @S9S_MB_2U_LIB.S9S_MB_2U(SCH_1):PAGE68
    U1 BG84 VCCIN8 SOCKET4677_AZIF0045P001C01CS-SA     I1 @S9S_MB_2U_LIB.S9S_MB_2U(SCH_1):PAGE68
    U1 BG86 VCCIN9 SOCKET4677_AZIF0045P001C01CS-SA     I1 @S9S_MB_2U_LIB.S9S_MB_2U(SCH_1):PAGE68
    U1 BG88 VCCIN10 SOCKET4677_AZIF0045P001C01CS-SA     I1 @S9S_MB_2U_LIB.S9S_MB_2U(SCH_1):PAGE68
    U1 BG90 VCCIN11 SOCKET4677_AZIF0045P001C01CS-SA     I1 @S9S_MB_2U_LIB.S9S_MB_2U(SCH_1):PAGE68
    U1 BH85 VCCIN12 SOCKET4677_AZIF0045P001C01CS-SA     I1 @S9S_MB_2U_LIB.S9S_MB_2U(SCH_1):PAGE68
    U1 BH87 VCCIN13 SOCKET4677_AZIF0045P001C01CS-SA     I1 @S9S_MB_2U_LIB.S9S_MB_2U(SCH_1):PAGE68
    U1 BH89 VCCIN14 SOCKET4677_AZIF0045P001C01CS-SA     I1 @S9S_MB_2U_LIB.S9S_MB_2U(SCH_1):PAGE68
    U1 BH91 VCCIN15 SOCKET4677_AZIF0045P001C01CS-SA     I1 @S9S_MB_2U_LIB.S9S_MB_2U(SCH_1):PAGE68
    U1 BK81 VCCIN16 SOCKET4677_AZIF0045P001C01CS-SA     I1 @S9S_MB_2U_LIB.S9S_MB_2U(SCH_1):PAGE68
    U1 BK83 VCCIN17 SOCKET4677_AZIF0045P001C01CS-SA     I1 @S9S_MB_2U_LIB.S9S_MB_2U(SCH_1):PAGE68
    U1 BK85 VCCIN18 SOCKET4677_AZIF0045P001C01CS-SA     I1 @S9S_MB_2U_LIB.S9S_MB_2U(SCH_1):PAGE68
    U1 BK87 VCCIN19 SOCKET4677_AZIF0045P001C01CS-SA     I1 @S9S_MB_2U_LIB.S9S_MB_2U(SCH_1):PAGE68
    U1 BK89 VCCIN20 SOCKET4677_AZIF0045P001C01CS-SA     I1 @S9S_MB_2U_LIB.S9S_MB_2U(SCH_1):PAGE68
    U1 BK91 VCCIN21 SOCKET4677_AZIF0045P001C01CS-SA     I1 @S9S_MB_2U_LIB.S9S_MB_2U(SCH_1):PAGE68
    U1 BL80 VCCIN22 SOCKET4677_AZIF0045P001C01CS-SA     I1 @S9S_MB_2U_LIB.S9S_MB_2U(SCH_1):PAGE68
    U1 BL82 VCCIN23 SOCKET4677_AZIF0045P001C01CS-SA     I1 @S9S_MB_2U_LIB.S9S_MB_2U(SCH_1):PAGE68
    U1 BL84 VCCIN24 SOCKET4677_AZIF0045P001C01CS-SA     I1 @S9S_MB_2U_LIB.S9S_MB_2U(SCH_1):PAGE68
    U1 BL86 VCCIN25 SOCKET4677_AZIF0045P001C01CS-SA     I1 @S9S_MB_2U_LIB.S9S_MB_2U(SCH_1):PAGE68
    U1 BL88 VCCIN26 SOCKET4677_AZIF0045P001C01CS-SA     I1 @S9S_MB_2U_LIB.S9S_MB_2U(SCH_1):PAGE68
    U1 BL90 VCCIN27 SOCKET4677_AZIF0045P001C01CS-SA     I1 @S9S_MB_2U_LIB.S9S_MB_2U(SCH_1):PAGE68
    U1 BM79 VCCIN28 SOCKET4677_AZIF0045P001C01CS-SA     I1 @S9S_MB_2U_LIB.S9S_MB_2U(SCH_1):PAGE68
    U1 BM81 VCCIN29 SOCKET4677_AZIF0045P001C01CS-SA     I1 @S9S_MB_2U_LIB.S9S_MB_2U(SCH_1):PAGE68
    U1 BM83 VCCIN30 SOCKET4677_AZIF0045P001C01CS-SA     I1 @S9S_MB_2U_LIB.S9S_MB_2U(SCH_1):PAGE68
    U1 BM85 VCCIN31 SOCKET4677_AZIF0045P001C01CS-SA     I1 @S9S_MB_2U_LIB.S9S_MB_2U(SCH_1):PAGE68
    U1 BM87 VCCIN32 SOCKET4677_AZIF0045P001C01CS-SA     I1 @S9S_MB_2U_LIB.S9S_MB_2U(SCH_1):PAGE68
    U1 BM89 VCCIN33 SOCKET4677_AZIF0045P001C01CS-SA     I1 @S9S_MB_2U_LIB.S9S_MB_2U(SCH_1):PAGE68
    U1 BM91 VCCIN34 SOCKET4677_AZIF0045P001C01CS-SA     I1 @S9S_MB_2U_LIB.S9S_MB_2U(SCH_1):PAGE68
    U1 BN33 VCCIN35 SOCKET4677_AZIF0045P001C01CS-SA     I1 @S9S_MB_2U_LIB.S9S_MB_2U(SCH_1):PAGE68
    U1 BN35 VCCIN36 SOCKET4677_AZIF0045P001C01CS-SA     I1 @S9S_MB_2U_LIB.S9S_MB_2U(SCH_1):PAGE68
    U1 BN37 VCCIN37 SOCKET4677_AZIF0045P001C01CS-SA     I1 @S9S_MB_2U_LIB.S9S_MB_2U(SCH_1):PAGE68
    U1 BN39 VCCIN38 SOCKET4677_AZIF0045P001C01CS-SA     I1 @S9S_MB_2U_LIB.S9S_MB_2U(SCH_1):PAGE68
    U1 BN41 VCCIN39 SOCKET4677_AZIF0045P001C01CS-SA     I1 @S9S_MB_2U_LIB.S9S_MB_2U(SCH_1):PAGE68
  C225    1      A Q_CAP_C0805-47UF,4V,20%,X6S,CHA    I10 @S9S_MB_2U_LIB.S9S_MB_2U(SCH_1):PAGE77
  C230    1      A Q_CAP_C0805-47UF,4V,20%,X6S,CHA    I11 @S9S_MB_2U_LIB.S9S_MB_2U(SCH_1):PAGE77
  C224    1      A Q_CAP_C0402-10UF,6.3V,20%,X6S,B    I13 @S9S_MB_2U_LIB.S9S_MB_2U(SCH_1):PAGE77
  C240    1      A Q_CAP_C0805-47UF,4V,20%,X6S,CHA    I18 @S9S_MB_2U_LIB.S9S_MB_2U(SCH_1):PAGE77
  C234    1      A Q_CAP_C0402-10UF,6.3V,20%,X6S,B    I19 @S9S_MB_2U_LIB.S9S_MB_2U(SCH_1):PAGE77
  C239    1      A Q_CAP_C0402-10UF,6.3V,20%,X6S,B    I20 @S9S_MB_2U_LIB.S9S_MB_2U(SCH_1):PAGE77
  C223    1      A Q_CAP_C0402-10UF,6.3V,20%,X6S,B    I22 @S9S_MB_2U_LIB.S9S_MB_2U(SCH_1):PAGE77
  C228    1      A Q_CAP_C0402-10UF,6.3V,20%,X6S,B    I23 @S9S_MB_2U_LIB.S9S_MB_2U(SCH_1):PAGE77
  C222    1      A Q_CAP_C0402-10UF,6.3V,20%,X6S,B    I25 @S9S_MB_2U_LIB.S9S_MB_2U(SCH_1):PAGE77
  C221    1      A Q_CAP_C0402-10UF,6.3V,20%,X6S,B    I28 @S9S_MB_2U_LIB.S9S_MB_2U(SCH_1):PAGE77
  C226    1      A Q_CAP_C0402-10UF,6.3V,20%,X6S,B    I29 @S9S_MB_2U_LIB.S9S_MB_2U(SCH_1):PAGE77
  C233    1      A Q_CAP_C0402-10UF,6.3V,20%,X6S,B    I30 @S9S_MB_2U_LIB.S9S_MB_2U(SCH_1):PAGE77
  C238    1      A Q_CAP_C0402-10UF,6.3V,20%,X6S,B    I31 @S9S_MB_2U_LIB.S9S_MB_2U(SCH_1):PAGE77
  C232    1      A Q_CAP_C0402-10UF,6.3V,20%,X6S,B    I32 @S9S_MB_2U_LIB.S9S_MB_2U(SCH_1):PAGE77
  C231    1      A Q_CAP_C0402-10UF,6.3V,20%,X6S,B    I33 @S9S_MB_2U_LIB.S9S_MB_2U(SCH_1):PAGE77
  C237    1      A Q_CAP_C0402-10UF,6.3V,20%,X6S,B    I34 @S9S_MB_2U_LIB.S9S_MB_2U(SCH_1):PAGE77
  C236    1      A Q_CAP_C0402-10UF,6.3V,20%,X6S,B    I35 @S9S_MB_2U_LIB.S9S_MB_2U(SCH_1):PAGE77
  C245    1      A Q_CAP_C0805-47UF,4V,20%,X6S,CHA    I41 @S9S_MB_2U_LIB.S9S_MB_2U(SCH_1):PAGE77
  C250    1      A Q_CAP_C0805-47UF,4V,20%,X6S,CHA    I44 @S9S_MB_2U_LIB.S9S_MB_2U(SCH_1):PAGE77
  C244    1      A Q_CAP_C0402-10UF,6.3V,20%,X6S,B    I45 @S9S_MB_2U_LIB.S9S_MB_2U(SCH_1):PAGE77
  C249    1      A Q_CAP_C0402-10UF,6.3V,20%,X6S,B    I46 @S9S_MB_2U_LIB.S9S_MB_2U(SCH_1):PAGE77
  C255    1      A Q_CAP_C0805-47UF,4V,20%,X6S,CHA    I48 @S9S_MB_2U_LIB.S9S_MB_2U(SCH_1):PAGE77
  C260    1      A Q_CAP_C0805-47UF,4V,20%,X6S,CHA    I50 @S9S_MB_2U_LIB.S9S_MB_2U(SCH_1):PAGE77
  C254    1      A Q_CAP_C0402-10UF,6.3V,20%,X6S,B    I51 @S9S_MB_2U_LIB.S9S_MB_2U(SCH_1):PAGE77
  C259    1      A Q_CAP_C0402-10UF,6.3V,20%,X6S,B    I52 @S9S_MB_2U_LIB.S9S_MB_2U(SCH_1):PAGE77
  C265    1      A Q_CAP_C0805-47UF,4V,20%,X6S,CHA    I59 @S9S_MB_2U_LIB.S9S_MB_2U(SCH_1):PAGE77
  C270    1      A Q_CAP_C0805-47UF,4V,20%,X6S,CHA    I62 @S9S_MB_2U_LIB.S9S_MB_2U(SCH_1):PAGE77
  C264    1      A Q_CAP_C0402-10UF,6.3V,20%,X6S,B    I63 @S9S_MB_2U_LIB.S9S_MB_2U(SCH_1):PAGE77
  C274    1      A Q_CAP_C0402-22UF,4V,20%,X6S,CHA    I66 @S9S_MB_2U_LIB.S9S_MB_2U(SCH_1):PAGE77
  C278    1      A Q_CAP_C0402-22UF,4V,20%,X6S,CHA    I71 @S9S_MB_2U_LIB.S9S_MB_2U(SCH_1):PAGE77
  C282    1      A Q_CAP_C0402-22UF,4V,20%,X6S,CHA    I73 @S9S_MB_2U_LIB.S9S_MB_2U(SCH_1):PAGE77
  C248    1      A Q_CAP_C0402-10UF,6.3V,20%,X6S,B    I75 @S9S_MB_2U_LIB.S9S_MB_2U(SCH_1):PAGE77
  C242    1      A Q_CAP_C0402-10UF,6.3V,20%,X6S,B    I76 @S9S_MB_2U_LIB.S9S_MB_2U(SCH_1):PAGE77
  C247    1      A Q_CAP_C0402-10UF,6.3V,20%,X6S,B    I78 @S9S_MB_2U_LIB.S9S_MB_2U(SCH_1):PAGE77
  C246    1      A Q_CAP_C0402-10UF,6.3V,20%,X6S,B    I79 @S9S_MB_2U_LIB.S9S_MB_2U(SCH_1):PAGE77
  C258    1      A Q_CAP_C0402-10UF,6.3V,20%,X6S,B    I81 @S9S_MB_2U_LIB.S9S_MB_2U(SCH_1):PAGE77
  C251    1      A Q_CAP_C0402-10UF,6.3V,20%,X6S,B    I83 @S9S_MB_2U_LIB.S9S_MB_2U(SCH_1):PAGE77
  C257    1      A Q_CAP_C0402-10UF,6.3V,20%,X6S,B    I84 @S9S_MB_2U_LIB.S9S_MB_2U(SCH_1):PAGE77
  C263    1      A Q_CAP_C0402-10UF,6.3V,20%,X6S,B    I86 @S9S_MB_2U_LIB.S9S_MB_2U(SCH_1):PAGE77
  C268    1      A Q_CAP_C0402-10UF,6.3V,20%,X6S,B    I88 @S9S_MB_2U_LIB.S9S_MB_2U(SCH_1):PAGE77
  C262    1      A Q_CAP_C0402-10UF,6.3V,20%,X6S,B    I93 @S9S_MB_2U_LIB.S9S_MB_2U(SCH_1):PAGE77
  C261    1      A Q_CAP_C0402-10UF,6.3V,20%,X6S,B    I95 @S9S_MB_2U_LIB.S9S_MB_2U(SCH_1):PAGE77
  C272    1      A Q_CAP_C0402-22UF,4V,20%,X6S,CHA    I98 @S9S_MB_2U_LIB.S9S_MB_2U(SCH_1):PAGE77
  C271    1      A Q_CAP_C0402-22UF,4V,20%,X6S,CHA   I100 @S9S_MB_2U_LIB.S9S_MB_2U(SCH_1):PAGE77
  C277    1      A Q_CAP_C0402-22UF,4V,20%,X6S,CHA   I101 @S9S_MB_2U_LIB.S9S_MB_2U(SCH_1):PAGE77
  C281    1      A Q_CAP_C0402-22UF,4V,20%,X6S,CHA   I102 @S9S_MB_2U_LIB.S9S_MB_2U(SCH_1):PAGE77
  C276    1      A Q_CAP_C0402-22UF,4V,20%,X6S,CHA   I103 @S9S_MB_2U_LIB.S9S_MB_2U(SCH_1):PAGE77
  C275    1      A Q_CAP_C0402-22UF,4V,20%,X6S,CHA   I104 @S9S_MB_2U_LIB.S9S_MB_2U(SCH_1):PAGE77
  C280    1      A Q_CAP_C0402-22UF,4V,20%,X6S,CHA   I105 @S9S_MB_2U_LIB.S9S_MB_2U(SCH_1):PAGE77
  C279    1      A Q_CAP_C0402-22UF,4V,20%,X6S,CHA   I106 @S9S_MB_2U_LIB.S9S_MB_2U(SCH_1):PAGE77
  C286    1      A Q_CAP_C0402-22UF,4V,20%,X6S,CHA   I111 @S9S_MB_2U_LIB.S9S_MB_2U(SCH_1):PAGE77
  C290    1      A Q_CAP_C0402-22UF,4V,20%,X6S,CHA   I112 @S9S_MB_2U_LIB.S9S_MB_2U(SCH_1):PAGE77
  C294    1      A Q_CAP_C0402-22UF,4V,20%,X6S,CHA   I114 @S9S_MB_2U_LIB.S9S_MB_2U(SCH_1):PAGE77
  C298    1      A Q_CAP_C0402-22UF,4V,20%,X6S,CHA   I115 @S9S_MB_2U_LIB.S9S_MB_2U(SCH_1):PAGE77
  C302    1      A Q_CAP_C0402-22UF,4V,20%,X6S,CHA   I117 @S9S_MB_2U_LIB.S9S_MB_2U(SCH_1):PAGE77
  C306    1      A Q_CAP_C0402-22UF,4V,20%,X6S,CHA   I118 @S9S_MB_2U_LIB.S9S_MB_2U(SCH_1):PAGE77
  C285    1      A Q_CAP_C0402-22UF,4V,20%,X6S,CHA   I119 @S9S_MB_2U_LIB.S9S_MB_2U(SCH_1):PAGE77
  C289    1      A Q_CAP_C0402-22UF,4V,20%,X6S,CHA   I120 @S9S_MB_2U_LIB.S9S_MB_2U(SCH_1):PAGE77
  C284    1      A Q_CAP_C0402-22UF,4V,20%,X6S,CHA   I121 @S9S_MB_2U_LIB.S9S_MB_2U(SCH_1):PAGE77
  C283    1      A Q_CAP_C0402-22UF,4V,20%,X6S,CHA   I122 @S9S_MB_2U_LIB.S9S_MB_2U(SCH_1):PAGE77
  C288    1      A Q_CAP_C0402-22UF,4V,20%,X6S,CHA   I123 @S9S_MB_2U_LIB.S9S_MB_2U(SCH_1):PAGE77
  C293    1      A Q_CAP_C0402-22UF,4V,20%,X6S,CHA   I125 @S9S_MB_2U_LIB.S9S_MB_2U(SCH_1):PAGE77
  C297    1      A Q_CAP_C0402-22UF,4V,20%,X6S,CHA   I126 @S9S_MB_2U_LIB.S9S_MB_2U(SCH_1):PAGE77
  C296    1      A Q_CAP_C0402-22UF,4V,20%,X6S,CHA   I129 @S9S_MB_2U_LIB.S9S_MB_2U(SCH_1):PAGE77
  C295    1      A Q_CAP_C0402-22UF,4V,20%,X6S,CHA   I130 @S9S_MB_2U_LIB.S9S_MB_2U(SCH_1):PAGE77
  C299    1      A Q_CAP_C0402-22UF,4V,20%,X6S,CHA   I131 @S9S_MB_2U_LIB.S9S_MB_2U(SCH_1):PAGE77
  C300    1      A Q_CAP_C0402-22UF,4V,20%,X6S,CHA   I132 @S9S_MB_2U_LIB.S9S_MB_2U(SCH_1):PAGE77
  C301    1      A Q_CAP_C0402-22UF,4V,20%,X6S,CHA   I133 @S9S_MB_2U_LIB.S9S_MB_2U(SCH_1):PAGE77
  C305    1      A Q_CAP_C0402-22UF,4V,20%,X6S,CHA   I134 @S9S_MB_2U_LIB.S9S_MB_2U(SCH_1):PAGE77
  C309    1      A Q_CAP_C0402-22UF,4V,20%,X6S,CHA   I136 @S9S_MB_2U_LIB.S9S_MB_2U(SCH_1):PAGE77
  C304    1      A Q_CAP_C0402-22UF,4V,20%,X6S,CHA   I138 @S9S_MB_2U_LIB.S9S_MB_2U(SCH_1):PAGE77
  C308    1      A Q_CAP_C0402-22UF,4V,20%,X6S,CHA   I140 @S9S_MB_2U_LIB.S9S_MB_2U(SCH_1):PAGE77
  C318    1      A Q_CAP_C0805-47UF,4V,20%,X6S,CHA    I27 @S9S_MB_2U_LIB.S9S_MB_2U(SCH_1):PAGE78
  C327    1      A Q_CAP_C0805-47UF,4V,20%,X6S,CHA    I32 @S9S_MB_2U_LIB.S9S_MB_2U(SCH_1):PAGE78
  C336    1      A Q_CAP_C0805-47UF,4V,20%,X6S,CHA    I35 @S9S_MB_2U_LIB.S9S_MB_2U(SCH_1):PAGE78
  C314    1      A Q_CAP_C0805-47UF,4V,20%,X6S,CHA    I37 @S9S_MB_2U_LIB.S9S_MB_2U(SCH_1):PAGE78
  C320    1      A Q_CAP_C0805-47UF,4V,20%,X6S,CHA    I39 @S9S_MB_2U_LIB.S9S_MB_2U(SCH_1):PAGE78
  C323    1      A Q_CAP_C0805-47UF,4V,20%,X6S,CHA    I40 @S9S_MB_2U_LIB.S9S_MB_2U(SCH_1):PAGE78
  C326    1      A Q_CAP_C0805-47UF,4V,20%,X6S,CHA    I41 @S9S_MB_2U_LIB.S9S_MB_2U(SCH_1):PAGE78
  C313    1      A Q_CAP_C0805-47UF,4V,20%,X6S,CHA    I58 @S9S_MB_2U_LIB.S9S_MB_2U(SCH_1):PAGE78
  C316    1      A Q_CAP_C0805-47UF,4V,20%,X6S,CHA    I60 @S9S_MB_2U_LIB.S9S_MB_2U(SCH_1):PAGE78
  C353    1      A Q_CAP_C0805-47UF,4V,20%,X6S,CHA    I65 @S9S_MB_2U_LIB.S9S_MB_2U(SCH_1):PAGE78
  C337    1      A Q_CAP_C0805-47UF,4V,20%,X6S,CHA    I66 @S9S_MB_2U_LIB.S9S_MB_2U(SCH_1):PAGE78
  C483    1      A Q_CAP_C0805-47UF,4V,20%,X6S,CHA    I68 @S9S_MB_2U_LIB.S9S_MB_2U(SCH_1):PAGE78
PC1990    1      A Q_CAPP_SMLF-330UF,2.5V,+10/-35A    I61 @S9S_MB_2U_LIB.S9S_MB_2U(SCH_1):PAGE271
 PC587    1      A Q_CAPP_SMLF-330UF,2.5V,+10/-35A    I65 @S9S_MB_2U_LIB.S9S_MB_2U(SCH_1):PAGE271
 PC586    1      A Q_CAPP_THLF-560UF,2.5V,20%,OSCA    I69 @S9S_MB_2U_LIB.S9S_MB_2U(SCH_1):PAGE271
  PL31    4      4 Q_INDUCTOR4P_14-150NH,SMLF,INDA    I74 @S9S_MB_2U_LIB.S9S_MB_2U(SCH_1):PAGE271
PC572_P1_1    1      A Q_CAP_C0402-100NF,50V,10%,X7R,A    I84 @S9S_MB_2U_LIB.S9S_MB_2U(SCH_1):PAGE271
  PL26    4      4 Q_INDUCTOR4P_14-150NH,SMLF,INDA    I28 @S9S_MB_2U_LIB.S9S_MB_2U(SCH_1):PAGE273
  PL27    4      4 Q_INDUCTOR4P_14-150NH,SMLF,INDA    I48 @S9S_MB_2U_LIB.S9S_MB_2U(SCH_1):PAGE273
 PR296    2      B Q_RES_0402LF-0,5%,1/16W,CHIP,CA    I49 @S9S_MB_2U_LIB.S9S_MB_2U(SCH_1):PAGE273
PC519_P1_6    1      A Q_CAP_C0805-22UF,4V,20%,X6S,CHA    I54 @S9S_MB_2U_LIB.S9S_MB_2U(SCH_1):PAGE273
  PL24    4      4 Q_INDUCTOR4P_14-150NH,SMLF,INDA    I43 @S9S_MB_2U_LIB.S9S_MB_2U(SCH_1):PAGE274
 PR289    2      B Q_RES_0402LF-0,5%,1/16W,CHIP,CA    I44 @S9S_MB_2U_LIB.S9S_MB_2U(SCH_1):PAGE274
PC495_P1_8    1      A Q_CAP_C0402-1UF,16V,10%,X6S,CHA    I52 @S9S_MB_2U_LIB.S9S_MB_2U(SCH_1):PAGE274
PC497_P1_8    1      A Q_CAP_C0805-22UF,4V,20%,X6S,CHA    I53 @S9S_MB_2U_LIB.S9S_MB_2U(SCH_1):PAGE274
PC499_P1_8    1      A Q_CAP_C0805-22UF,4V,20%,X6S,CHA    I54 @S9S_MB_2U_LIB.S9S_MB_2U(SCH_1):PAGE274
  C229    1      A Q_CAP_C0402-10UF,6.3V,20%,X6S,B    I14 @S9S_MB_2U_LIB.S9S_MB_2U(SCH_1):PAGE77
  C235    1      A Q_CAP_C0805-47UF,4V,20%,X6S,CHA    I16 @S9S_MB_2U_LIB.S9S_MB_2U(SCH_1):PAGE77
  C227    1      A Q_CAP_C0402-10UF,6.3V,20%,X6S,B    I26 @S9S_MB_2U_LIB.S9S_MB_2U(SCH_1):PAGE77
  C269    1      A Q_CAP_C0402-10UF,6.3V,20%,X6S,B    I64 @S9S_MB_2U_LIB.S9S_MB_2U(SCH_1):PAGE77
  C243    1      A Q_CAP_C0402-10UF,6.3V,20%,X6S,B    I74 @S9S_MB_2U_LIB.S9S_MB_2U(SCH_1):PAGE77
  C241    1      A Q_CAP_C0402-10UF,6.3V,20%,X6S,B    I77 @S9S_MB_2U_LIB.S9S_MB_2U(SCH_1):PAGE77
  C253    1      A Q_CAP_C0402-10UF,6.3V,20%,X6S,B    I80 @S9S_MB_2U_LIB.S9S_MB_2U(SCH_1):PAGE77
  C252    1      A Q_CAP_C0402-10UF,6.3V,20%,X6S,B    I82 @S9S_MB_2U_LIB.S9S_MB_2U(SCH_1):PAGE77
  C256    1      A Q_CAP_C0402-10UF,6.3V,20%,X6S,B    I85 @S9S_MB_2U_LIB.S9S_MB_2U(SCH_1):PAGE77
  C273    1      A Q_CAP_C0402-22UF,4V,20%,X6S,CHA    I91 @S9S_MB_2U_LIB.S9S_MB_2U(SCH_1):PAGE77
  C267    1      A Q_CAP_C0402-10UF,6.3V,20%,X6S,B    I94 @S9S_MB_2U_LIB.S9S_MB_2U(SCH_1):PAGE77
  C266    1      A Q_CAP_C0402-10UF,6.3V,20%,X6S,B    I97 @S9S_MB_2U_LIB.S9S_MB_2U(SCH_1):PAGE77
  C287    1      A Q_CAP_C0402-22UF,4V,20%,X6S,CHA   I124 @S9S_MB_2U_LIB.S9S_MB_2U(SCH_1):PAGE77
  C292    1      A Q_CAP_C0402-22UF,4V,20%,X6S,CHA   I127 @S9S_MB_2U_LIB.S9S_MB_2U(SCH_1):PAGE77
  C291    1      A Q_CAP_C0402-22UF,4V,20%,X6S,CHA   I128 @S9S_MB_2U_LIB.S9S_MB_2U(SCH_1):PAGE77
  C303    1      A Q_CAP_C0402-22UF,4V,20%,X6S,CHA   I139 @S9S_MB_2U_LIB.S9S_MB_2U(SCH_1):PAGE77
  C307    1      A Q_CAP_C0402-22UF,4V,20%,X6S,CHA   I142 @S9S_MB_2U_LIB.S9S_MB_2U(SCH_1):PAGE77
  C312    1      A Q_CAP_C0805-47UF,4V,20%,X6S,CHA    I14 @S9S_MB_2U_LIB.S9S_MB_2U(SCH_1):PAGE78
  C311    1      A Q_CAP_C0805-47UF,4V,20%,X6S,CHA    I16 @S9S_MB_2U_LIB.S9S_MB_2U(SCH_1):PAGE78
  C315    1      A Q_CAP_C0805-47UF,4V,20%,X6S,CHA    I26 @S9S_MB_2U_LIB.S9S_MB_2U(SCH_1):PAGE78
  C321    1      A Q_CAP_C0805-47UF,4V,20%,X6S,CHA    I30 @S9S_MB_2U_LIB.S9S_MB_2U(SCH_1):PAGE78
  C324    1      A Q_CAP_C0805-47UF,4V,20%,X6S,CHA    I31 @S9S_MB_2U_LIB.S9S_MB_2U(SCH_1):PAGE78
  C330    1      A Q_CAP_C0805-47UF,4V,20%,X6S,CHA    I33 @S9S_MB_2U_LIB.S9S_MB_2U(SCH_1):PAGE78
  C333    1      A Q_CAP_C0805-47UF,4V,20%,X6S,CHA    I34 @S9S_MB_2U_LIB.S9S_MB_2U(SCH_1):PAGE78
  C339    1      A Q_CAP_C0805-47UF,4V,20%,X6S,CHA    I36 @S9S_MB_2U_LIB.S9S_MB_2U(SCH_1):PAGE78
  C317    1      A Q_CAP_C0805-47UF,4V,20%,X6S,CHA    I38 @S9S_MB_2U_LIB.S9S_MB_2U(SCH_1):PAGE78
  C329    1      A Q_CAP_C0805-47UF,4V,20%,X6S,CHA    I42 @S9S_MB_2U_LIB.S9S_MB_2U(SCH_1):PAGE78
  C332    1      A Q_CAP_C0805-47UF,4V,20%,X6S,CHA    I43 @S9S_MB_2U_LIB.S9S_MB_2U(SCH_1):PAGE78
  C335    1      A Q_CAP_C0805-47UF,4V,20%,X6S,CHA    I44 @S9S_MB_2U_LIB.S9S_MB_2U(SCH_1):PAGE78
  C338    1      A Q_CAP_C0805-47UF,4V,20%,X6S,CHA    I45 @S9S_MB_2U_LIB.S9S_MB_2U(SCH_1):PAGE78
  C349    1      A Q_CAP_C0805-47UF,4V,20%,X6S,CHA    I63 @S9S_MB_2U_LIB.S9S_MB_2U(SCH_1):PAGE78
  C351    1      A Q_CAP_C0805-47UF,4V,20%,X6S,CHA    I64 @S9S_MB_2U_LIB.S9S_MB_2U(SCH_1):PAGE78
  C342    1      A Q_CAP_C0805-47UF,4V,20%,X6S,CHA    I23 @S9S_MB_2U_LIB.S9S_MB_2U(SCH_1):PAGE79
  C344    1      A Q_CAP_C0805-47UF,4V,20%,X6S,CHA    I24 @S9S_MB_2U_LIB.S9S_MB_2U(SCH_1):PAGE79
  C346    1      A Q_CAP_C0805-47UF,4V,20%,X6S,CHA    I25 @S9S_MB_2U_LIB.S9S_MB_2U(SCH_1):PAGE79
  C348    1      A Q_CAP_C0805-47UF,4V,20%,X6S,CHA    I32 @S9S_MB_2U_LIB.S9S_MB_2U(SCH_1):PAGE79
  C350    1      A Q_CAP_C0805-47UF,4V,20%,X6S,CHA    I33 @S9S_MB_2U_LIB.S9S_MB_2U(SCH_1):PAGE79
  C352    1      A Q_CAP_C0805-47UF,4V,20%,X6S,CHA    I34 @S9S_MB_2U_LIB.S9S_MB_2U(SCH_1):PAGE79
  C354    1      A Q_CAP_C0805-47UF,4V,20%,X6S,CHA    I35 @S9S_MB_2U_LIB.S9S_MB_2U(SCH_1):PAGE79
  C322    1      A Q_CAP_C0805-47UF,4V,20%,X6S,CHA    I46 @S9S_MB_2U_LIB.S9S_MB_2U(SCH_1):PAGE79
  C325    1      A Q_CAP_C0805-47UF,4V,20%,X6S,CHA    I47 @S9S_MB_2U_LIB.S9S_MB_2U(SCH_1):PAGE79
  C328    1      A Q_CAP_C0805-47UF,4V,20%,X6S,CHA    I50 @S9S_MB_2U_LIB.S9S_MB_2U(SCH_1):PAGE79
  C341    1      A Q_CAP_C0805-47UF,4V,20%,X6S,CHA    I51 @S9S_MB_2U_LIB.S9S_MB_2U(SCH_1):PAGE79
  C343    1      A Q_CAP_C0805-47UF,4V,20%,X6S,CHA    I52 @S9S_MB_2U_LIB.S9S_MB_2U(SCH_1):PAGE79
  C345    1      A Q_CAP_C0805-47UF,4V,20%,X6S,CHA    I53 @S9S_MB_2U_LIB.S9S_MB_2U(SCH_1):PAGE79
  C347    1      A Q_CAP_C0805-47UF,4V,20%,X6S,CHA    I55 @S9S_MB_2U_LIB.S9S_MB_2U(SCH_1):PAGE79
PC575_P1_2    1      A Q_CAP_C0805-22UF,4V,20%,X6S,CHA    I57 @S9S_MB_2U_LIB.S9S_MB_2U(SCH_1):PAGE271
PC577_P1_2    1      A Q_CAP_C0805-22UF,4V,20%,X6S,CHA    I58 @S9S_MB_2U_LIB.S9S_MB_2U(SCH_1):PAGE271
PR4240    1      A Q_RES_0402LF-499,1%,1/16W,CHIPA    I59 @S9S_MB_2U_LIB.S9S_MB_2U(SCH_1):PAGE271
 PC580    1      A Q_CAPP_THLF-560UF,2.5V,20%,OSCA    I63 @S9S_MB_2U_LIB.S9S_MB_2U(SCH_1):PAGE271
 PC589    1      A Q_CAPP_THLF-560UF,2.5V,20%,OSCA    I72 @S9S_MB_2U_LIB.S9S_MB_2U(SCH_1):PAGE271
PC574_P1_1    1      A Q_CAP_C0402-1UF,16V,10%,X6S,CHA    I85 @S9S_MB_2U_LIB.S9S_MB_2U(SCH_1):PAGE271
  PL28    4      4 Q_INDUCTOR4P_14-150NH,SMLF,INDA    I37 @S9S_MB_2U_LIB.S9S_MB_2U(SCH_1):PAGE272
 PR301    2      B Q_RES_0402LF-0,5%,1/16W,CHIP,CA    I38 @S9S_MB_2U_LIB.S9S_MB_2U(SCH_1):PAGE272
 PR302    2      B Q_RES_0402LF-0,5%,1/16W,CHIP,CA    I45 @S9S_MB_2U_LIB.S9S_MB_2U(SCH_1):PAGE272
  PL29    4      4 Q_INDUCTOR4P_14-150NH,SMLF,INDA    I51 @S9S_MB_2U_LIB.S9S_MB_2U(SCH_1):PAGE272
PC541_P1_4    1      A Q_CAP_C0805-22UF,4V,20%,X6S,CHA    I58 @S9S_MB_2U_LIB.S9S_MB_2U(SCH_1):PAGE272
PC543_P1_4    1      A Q_CAP_C0805-22UF,4V,20%,X6S,CHA    I59 @S9S_MB_2U_LIB.S9S_MB_2U(SCH_1):PAGE272
PC542_P1_3    1      A Q_CAP_C0805-22UF,4V,20%,X6S,CHA    I63 @S9S_MB_2U_LIB.S9S_MB_2U(SCH_1):PAGE272
PC544_P1_3    1      A Q_CAP_C0805-22UF,4V,20%,X6S,CHA    I64 @S9S_MB_2U_LIB.S9S_MB_2U(SCH_1):PAGE272
 PR295    2      B Q_RES_0402LF-0,5%,1/16W,CHIP,CA    I27 @S9S_MB_2U_LIB.S9S_MB_2U(SCH_1):PAGE273
PC521_P1_6    1      A Q_CAP_C0805-22UF,4V,20%,X6S,CHA    I57 @S9S_MB_2U_LIB.S9S_MB_2U(SCH_1):PAGE273
PC520_P1_5    1      A Q_CAP_C0805-22UF,4V,20%,X6S,CHA    I64 @S9S_MB_2U_LIB.S9S_MB_2U(SCH_1):PAGE273
PC522_P1_5    1      A Q_CAP_C0805-22UF,4V,20%,X6S,CHA    I65 @S9S_MB_2U_LIB.S9S_MB_2U(SCH_1):PAGE273
 PR290    2      B Q_RES_0402LF-0,5%,1/16W,CHIP,CA    I50 @S9S_MB_2U_LIB.S9S_MB_2U(SCH_1):PAGE274
  PL25    4      4 Q_INDUCTOR4P_14-150NH,SMLF,INDA    I58 @S9S_MB_2U_LIB.S9S_MB_2U(SCH_1):PAGE274
PC496_P1_7    1      A Q_CAP_C0402-1UF,16V,10%,X6S,CHA    I64 @S9S_MB_2U_LIB.S9S_MB_2U(SCH_1):PAGE274
PC498_P1_7    1      A Q_CAP_C0805-22UF,4V,20%,X6S,CHA    I65 @S9S_MB_2U_LIB.S9S_MB_2U(SCH_1):PAGE274
PC500_P1_7    1      A Q_CAP_C0805-22UF,4V,20%,X6S,CHA    I66 @S9S_MB_2U_LIB.S9S_MB_2U(SCH_1):PAGE274
  PC83    1      A Q_CAPP_THLF-560UF,2.5V,20%,OSCA    I56 @S9S_MB_2U_LIB.S9S_MB_2U(SCH_1):PAGE271
 PC189    1      A Q_CAPP_SMLF-330UF,2.5V,+10/-35A    I62 @S9S_MB_2U_LIB.S9S_MB_2U(SCH_1):PAGE271
 PR330    2      B Q_RES_0402LF-0,5%,1/16W,CHIP,CA    I73 @S9S_MB_2U_LIB.S9S_MB_2U(SCH_1):PAGE271
PC576_P1_1    1      A Q_CAP_C0805-22UF,4V,20%,X6S,CHA    I88 @S9S_MB_2U_LIB.S9S_MB_2U(SCH_1):PAGE271
PC578_P1_1    1      A Q_CAP_C0805-22UF,4V,20%,X6S,CHA    I91 @S9S_MB_2U_LIB.S9S_MB_2U(SCH_1):PAGE271
 PR578    2      B Q_RES_0402LF-100,1%,1/16W,CHIPA    I49 @S9S_MB_2U_LIB.S9S_MB_2U(SCH_1):PAGE270
  PL30    4      4 Q_INDUCTOR4P_14-150NH,SMLF,INDA    I18 @S9S_MB_2U_LIB.S9S_MB_2U(SCH_1):PAGE271
 PR329    2      B Q_RES_0402LF-0,5%,1/16W,CHIP,CA    I51 @S9S_MB_2U_LIB.S9S_MB_2U(SCH_1):PAGE271
 PC583    1      A Q_CAPP_THLF-560UF,2.5V,20%,OSCA    I64 @S9S_MB_2U_LIB.S9S_MB_2U(SCH_1):PAGE271
 PC590    1      A Q_CAPP_SMLF-330UF,2.5V,+10/-35A    I68 @S9S_MB_2U_LIB.S9S_MB_2U(SCH_1):PAGE271

PVCCIN_CPU1_ADDR @S9S_MB_2U_LIB.S9S_MB_2U(SCH_1):PVCCIN_CPU1_ADDR
 PR306    2      B Q_RES_0402LF-28K,1%,1/16W,EMPTA     I4 @S9S_MB_2U_LIB.S9S_MB_2U(SCH_1):PAGE270
 PR318    1      A Q_RES_0402LF-5.23K,1%,1/16W,CHA     I6 @S9S_MB_2U_LIB.S9S_MB_2U(SCH_1):PAGE270
  PU29   42 ADDR_CFG RAA229126GNPHA0-RAA229126GNP#HA    I33 @S9S_MB_2U_LIB.S9S_MB_2U(SCH_1):PAGE270

PVCCIN_CPU1_ATSEN @S9S_MB_2U_LIB.S9S_MB_2U(SCH_1):PVCCIN_CPU1_ATSEN
PU26_P1_5   36 TOUT_FLT ISL99390FRZTR5935-ISL99390FRZ-A    I23 @S9S_MB_2U_LIB.S9S_MB_2U(SCH_1):PAGE273
 PR637    1      A Q_RES_0402LF-10K,1%,1/16W,EMPTA    I74 @S9S_MB_2U_LIB.S9S_MB_2U(SCH_1):PAGE270
PU27_P1_4   36 TOUT_FLT ISL99390FRZTR5935-ISL99390FRZ-A    I10 @S9S_MB_2U_LIB.S9S_MB_2U(SCH_1):PAGE272
PU28_P1_3   36 TOUT_FLT ISL99390FRZTR5935-ISL99390FRZ-A    I66 @S9S_MB_2U_LIB.S9S_MB_2U(SCH_1):PAGE272
PU25_P1_6   36 TOUT_FLT ISL99390FRZTR5935-ISL99390FRZ-A    I16 @S9S_MB_2U_LIB.S9S_MB_2U(SCH_1):PAGE273
PU23_P1_8   36 TOUT_FLT ISL99390FRZTR5935-ISL99390FRZ-A    I11 @S9S_MB_2U_LIB.S9S_MB_2U(SCH_1):PAGE274
PU24_P1_7   36 TOUT_FLT ISL99390FRZTR5935-ISL99390FRZ-A    I20 @S9S_MB_2U_LIB.S9S_MB_2U(SCH_1):PAGE274
PU31_P1_1   36 TOUT_FLT ISL99390FRZTR5935-ISL99390FRZ-A    I40 @S9S_MB_2U_LIB.S9S_MB_2U(SCH_1):PAGE271
PU30_P1_2   36 TOUT_FLT ISL99390FRZTR5935-ISL99390FRZ-A     I7 @S9S_MB_2U_LIB.S9S_MB_2U(SCH_1):PAGE271
  PU29   43  TEMP0 RAA229126GNPHA0-RAA229126GNP#HA    I33 @S9S_MB_2U_LIB.S9S_MB_2U(SCH_1):PAGE270
 PC554    1      A Q_CAP_0402-470PF,50V,10%,X7R,TA    I72 @S9S_MB_2U_LIB.S9S_MB_2U(SCH_1):PAGE270

PVCCIN_CPU1_CSPIN @S9S_MB_2U_LIB.S9S_MB_2U(SCH_1):PVCCIN_CPU1_CSPIN
 PC547    1      A Q_CAP_0402-0.1UF,25V,10%,EMPTYA    I28 @S9S_MB_2U_LIB.S9S_MB_2U(SCH_1):PAGE270
 PR304    2      B Q_RES_0402LF-0,5%,1/16W,EMPTY,A     I9 @S9S_MB_2U_LIB.S9S_MB_2U(SCH_1):PAGE270
 PR305    1      A Q_RES_0402LF-0,5%,1/16W,CHIP,CA    I27 @S9S_MB_2U_LIB.S9S_MB_2U(SCH_1):PAGE270
  PU29   45 VMON||IINSEN||VSYS||ISYS RAA229126GNPHA0-RAA229126GNP#HA    I33 @S9S_MB_2U_LIB.S9S_MB_2U(SCH_1):PAGE270

PVCCIN_CPU1_EN_R @S9S_MB_2U_LIB.S9S_MB_2U(SCH_1):PVCCIN_CPU1_EN_R
 C2860    1      A Q_CAP_0402-1000PF,50V,5%,X7R,TA    I67 @S9S_MB_2U_LIB.S9S_MB_2U(SCH_1):PAGE270
  R309    2      B Q_RES_0402LF-0,5%,1/16W,CHIP,CA    I59 @S9S_MB_2U_LIB.S9S_MB_2U(SCH_1):PAGE270
  PU29   17    EN0 RAA229126GNPHA0-RAA229126GNP#HA    I33 @S9S_MB_2U_LIB.S9S_MB_2U(SCH_1):PAGE270

PVCCIN_CPU1_IMON1 @S9S_MB_2U_LIB.S9S_MB_2U(SCH_1):PVCCIN_CPU1_IMON1
PU31_P1_1   38   IOUT ISL99390FRZTR5935-ISL99390FRZ-A    I40 @S9S_MB_2U_LIB.S9S_MB_2U(SCH_1):PAGE271
  PU29   27   CS11 RAA229126GNPHA0-RAA229126GNP#HA    I33 @S9S_MB_2U_LIB.S9S_MB_2U(SCH_1):PAGE270

PVCCIN_CPU1_IMON2 @S9S_MB_2U_LIB.S9S_MB_2U(SCH_1):PVCCIN_CPU1_IMON2
PU30_P1_2   38   IOUT ISL99390FRZTR5935-ISL99390FRZ-A     I7 @S9S_MB_2U_LIB.S9S_MB_2U(SCH_1):PAGE271
  PU29   28   CS10 RAA229126GNPHA0-RAA229126GNP#HA    I33 @S9S_MB_2U_LIB.S9S_MB_2U(SCH_1):PAGE270

PVCCIN_CPU1_IMON3 @S9S_MB_2U_LIB.S9S_MB_2U(SCH_1):PVCCIN_CPU1_IMON3
PU28_P1_3   38   IOUT ISL99390FRZTR5935-ISL99390FRZ-A    I66 @S9S_MB_2U_LIB.S9S_MB_2U(SCH_1):PAGE272
  PU29   29    CS9 RAA229126GNPHA0-RAA229126GNP#HA    I33 @S9S_MB_2U_LIB.S9S_MB_2U(SCH_1):PAGE270

PVCCIN_CPU1_IMON4 @S9S_MB_2U_LIB.S9S_MB_2U(SCH_1):PVCCIN_CPU1_IMON4
PU27_P1_4   38   IOUT ISL99390FRZTR5935-ISL99390FRZ-A    I10 @S9S_MB_2U_LIB.S9S_MB_2U(SCH_1):PAGE272
  PU29   30    CS8 RAA229126GNPHA0-RAA229126GNP#HA    I33 @S9S_MB_2U_LIB.S9S_MB_2U(SCH_1):PAGE270

PVCCIN_CPU1_IMON5 @S9S_MB_2U_LIB.S9S_MB_2U(SCH_1):PVCCIN_CPU1_IMON5
PU26_P1_5   38   IOUT ISL99390FRZTR5935-ISL99390FRZ-A    I23 @S9S_MB_2U_LIB.S9S_MB_2U(SCH_1):PAGE273
  PU29   31    CS7 RAA229126GNPHA0-RAA229126GNP#HA    I33 @S9S_MB_2U_LIB.S9S_MB_2U(SCH_1):PAGE270

PVCCIN_CPU1_IMON6 @S9S_MB_2U_LIB.S9S_MB_2U(SCH_1):PVCCIN_CPU1_IMON6
PU25_P1_6   38   IOUT ISL99390FRZTR5935-ISL99390FRZ-A    I16 @S9S_MB_2U_LIB.S9S_MB_2U(SCH_1):PAGE273
  PU29   32    CS6 RAA229126GNPHA0-RAA229126GNP#HA    I33 @S9S_MB_2U_LIB.S9S_MB_2U(SCH_1):PAGE270

PVCCIN_CPU1_IMON7 @S9S_MB_2U_LIB.S9S_MB_2U(SCH_1):PVCCIN_CPU1_IMON7
PU24_P1_7   38   IOUT ISL99390FRZTR5935-ISL99390FRZ-A    I20 @S9S_MB_2U_LIB.S9S_MB_2U(SCH_1):PAGE274
  PU29   33    CS5 RAA229126GNPHA0-RAA229126GNP#HA    I33 @S9S_MB_2U_LIB.S9S_MB_2U(SCH_1):PAGE270

PVCCIN_CPU1_IMON8 @S9S_MB_2U_LIB.S9S_MB_2U(SCH_1):PVCCIN_CPU1_IMON8
PU23_P1_8   38   IOUT ISL99390FRZTR5935-ISL99390FRZ-A    I11 @S9S_MB_2U_LIB.S9S_MB_2U(SCH_1):PAGE274
  PU29   34    CS4 RAA229126GNPHA0-RAA229126GNP#HA    I33 @S9S_MB_2U_LIB.S9S_MB_2U(SCH_1):PAGE270

PVCCIN_CPU1_LSET1 @S9S_MB_2U_LIB.S9S_MB_2U(SCH_1):PVCCIN_CPU1_LSET1
 PR326    1      A Q_RES_0402LF-8.87K,1%,1/16W,EMA    I29 @S9S_MB_2U_LIB.S9S_MB_2U(SCH_1):PAGE271
PU31_P1_1   37   LSET ISL99390FRZTR5935-ISL99390FRZ-A    I40 @S9S_MB_2U_LIB.S9S_MB_2U(SCH_1):PAGE271

PVCCIN_CPU1_LSET2 @S9S_MB_2U_LIB.S9S_MB_2U(SCH_1):PVCCIN_CPU1_LSET2
 PR325    1      A Q_RES_0402LF-8.87K,1%,1/16W,EMA     I3 @S9S_MB_2U_LIB.S9S_MB_2U(SCH_1):PAGE271
PU30_P1_2   37   LSET ISL99390FRZTR5935-ISL99390FRZ-A     I7 @S9S_MB_2U_LIB.S9S_MB_2U(SCH_1):PAGE271

PVCCIN_CPU1_LSET3 @S9S_MB_2U_LIB.S9S_MB_2U(SCH_1):PVCCIN_CPU1_LSET3
 PR298    1      A Q_RES_0402LF-8.87K,1%,1/16W,EMA    I15 @S9S_MB_2U_LIB.S9S_MB_2U(SCH_1):PAGE272
PU28_P1_3   37   LSET ISL99390FRZTR5935-ISL99390FRZ-A    I66 @S9S_MB_2U_LIB.S9S_MB_2U(SCH_1):PAGE272

PVCCIN_CPU1_LSET4 @S9S_MB_2U_LIB.S9S_MB_2U(SCH_1):PVCCIN_CPU1_LSET4
 PR297    1      A Q_RES_0402LF-8.87K,1%,1/16W,EMA     I3 @S9S_MB_2U_LIB.S9S_MB_2U(SCH_1):PAGE272
PU27_P1_4   37   LSET ISL99390FRZTR5935-ISL99390FRZ-A    I10 @S9S_MB_2U_LIB.S9S_MB_2U(SCH_1):PAGE272

PVCCIN_CPU1_LSET5 @S9S_MB_2U_LIB.S9S_MB_2U(SCH_1):PVCCIN_CPU1_LSET5
PU26_P1_5   37   LSET ISL99390FRZTR5935-ISL99390FRZ-A    I23 @S9S_MB_2U_LIB.S9S_MB_2U(SCH_1):PAGE273
 PR292    1      A Q_RES_0402LF-8.87K,1%,1/16W,EMA     I7 @S9S_MB_2U_LIB.S9S_MB_2U(SCH_1):PAGE273

PVCCIN_CPU1_LSET6 @S9S_MB_2U_LIB.S9S_MB_2U(SCH_1):PVCCIN_CPU1_LSET6
 PR291    1      A Q_RES_0402LF-8.87K,1%,1/16W,EMA     I2 @S9S_MB_2U_LIB.S9S_MB_2U(SCH_1):PAGE273
PU25_P1_6   37   LSET ISL99390FRZTR5935-ISL99390FRZ-A    I16 @S9S_MB_2U_LIB.S9S_MB_2U(SCH_1):PAGE273

PVCCIN_CPU1_LSET7 @S9S_MB_2U_LIB.S9S_MB_2U(SCH_1):PVCCIN_CPU1_LSET7
 PR286    1      A Q_RES_0402LF-8.87K,1%,1/16W,EMA    I15 @S9S_MB_2U_LIB.S9S_MB_2U(SCH_1):PAGE274
PU24_P1_7   37   LSET ISL99390FRZTR5935-ISL99390FRZ-A    I20 @S9S_MB_2U_LIB.S9S_MB_2U(SCH_1):PAGE274

PVCCIN_CPU1_LSET8 @S9S_MB_2U_LIB.S9S_MB_2U(SCH_1):PVCCIN_CPU1_LSET8
 PR285    1      A Q_RES_0402LF-8.87K,1%,1/16W,EMA     I3 @S9S_MB_2U_LIB.S9S_MB_2U(SCH_1):PAGE274
PU23_P1_8   37   LSET ISL99390FRZTR5935-ISL99390FRZ-A    I11 @S9S_MB_2U_LIB.S9S_MB_2U(SCH_1):PAGE274

PVCCIN_CPU1_PIN_ALERT @S9S_MB_2U_LIB.S9S_MB_2U(SCH_1):PVCCIN_CPU1_PIN_ALERT
 R2525    2      B Q_RES_0402LF-1K,1%,1/16W,CHIP,A    I18 @S9S_MB_2U_LIB.S9S_MB_2U(SCH_1):PAGE270
  PU29   19 NPINALERT||NPSYS_CRIT RAA229126GNPHA0-RAA229126GNP#HA    I33 @S9S_MB_2U_LIB.S9S_MB_2U(SCH_1):PAGE270

PVCCIN_CPU1_PVCC @S9S_MB_2U_LIB.S9S_MB_2U(SCH_1):PVCCIN_CPU1_PVCC
 PR299    1      A Q_RES_0402LF-2.2,1%,1/16W,CHIPA    I12 @S9S_MB_2U_LIB.S9S_MB_2U(SCH_1):PAGE272
PC503_P1_6    1      A Q_CAP_C0402-2.2UF,10V,10%,X6S,A    I21 @S9S_MB_2U_LIB.S9S_MB_2U(SCH_1):PAGE273
PU26_P1_5    4   PVCC ISL99390FRZTR5935-ISL99390FRZ-A    I23 @S9S_MB_2U_LIB.S9S_MB_2U(SCH_1):PAGE273
 PR294    1      A Q_RES_0402LF-2.2,1%,1/16W,CHIPA    I39 @S9S_MB_2U_LIB.S9S_MB_2U(SCH_1):PAGE273
PC504_P1_5    1      A Q_CAP_C0402-2.2UF,10V,10%,X6S,A    I41 @S9S_MB_2U_LIB.S9S_MB_2U(SCH_1):PAGE273
PC481_P1_8    1      A Q_CAP_C0402-2.2UF,10V,10%,X6S,A    I18 @S9S_MB_2U_LIB.S9S_MB_2U(SCH_1):PAGE274
PU27_P1_4    4   PVCC ISL99390FRZTR5935-ISL99390FRZ-A    I10 @S9S_MB_2U_LIB.S9S_MB_2U(SCH_1):PAGE272
PC525_P1_4    1      A Q_CAP_C0402-2.2UF,10V,10%,X6S,A    I19 @S9S_MB_2U_LIB.S9S_MB_2U(SCH_1):PAGE272
 PR300    1      A Q_RES_0402LF-2.2,1%,1/16W,CHIPA    I25 @S9S_MB_2U_LIB.S9S_MB_2U(SCH_1):PAGE272
PC526_P1_3    1      A Q_CAP_C0402-2.2UF,10V,10%,X6S,A    I29 @S9S_MB_2U_LIB.S9S_MB_2U(SCH_1):PAGE272
PU28_P1_3    4   PVCC ISL99390FRZTR5935-ISL99390FRZ-A    I66 @S9S_MB_2U_LIB.S9S_MB_2U(SCH_1):PAGE272
PU25_P1_6    4   PVCC ISL99390FRZTR5935-ISL99390FRZ-A    I16 @S9S_MB_2U_LIB.S9S_MB_2U(SCH_1):PAGE273
 PR293    1      A Q_RES_0402LF-2.2,1%,1/16W,CHIPA    I19 @S9S_MB_2U_LIB.S9S_MB_2U(SCH_1):PAGE273
PU23_P1_8    4   PVCC ISL99390FRZTR5935-ISL99390FRZ-A    I11 @S9S_MB_2U_LIB.S9S_MB_2U(SCH_1):PAGE274
 PR287    1      A Q_RES_0402LF-2.2,1%,1/16W,CHIPA    I12 @S9S_MB_2U_LIB.S9S_MB_2U(SCH_1):PAGE274
PU24_P1_7    4   PVCC ISL99390FRZTR5935-ISL99390FRZ-A    I20 @S9S_MB_2U_LIB.S9S_MB_2U(SCH_1):PAGE274
 PR288    1      A Q_RES_0402LF-2.2,1%,1/16W,CHIPA    I68 @S9S_MB_2U_LIB.S9S_MB_2U(SCH_1):PAGE274
PC482_P1_7    1      A Q_CAP_C0402-2.2UF,10V,10%,X6S,A    I69 @S9S_MB_2U_LIB.S9S_MB_2U(SCH_1):PAGE274
PC558_P1_2    1      A Q_CAP_C0402-2.2UF,10V,10%,X6S,A    I15 @S9S_MB_2U_LIB.S9S_MB_2U(SCH_1):PAGE271
 PR328    1      A Q_RES_0402LF-2.2,1%,1/16W,CHIPA    I37 @S9S_MB_2U_LIB.S9S_MB_2U(SCH_1):PAGE271
PC559_P1_1    1      A Q_CAP_C0402-2.2UF,10V,10%,X6S,A    I39 @S9S_MB_2U_LIB.S9S_MB_2U(SCH_1):PAGE271
PU31_P1_1    4   PVCC ISL99390FRZTR5935-ISL99390FRZ-A    I40 @S9S_MB_2U_LIB.S9S_MB_2U(SCH_1):PAGE271
PU30_P1_2    4   PVCC ISL99390FRZTR5935-ISL99390FRZ-A     I7 @S9S_MB_2U_LIB.S9S_MB_2U(SCH_1):PAGE271
 PR327    1      A Q_RES_0402LF-2.2,1%,1/16W,CHIPA    I13 @S9S_MB_2U_LIB.S9S_MB_2U(SCH_1):PAGE271
 PR639    2      B Q_RES_0402LF-0,5%,1/16W,CHIP,CA    I26 @S9S_MB_2U_LIB.S9S_MB_2U(SCH_1):PAGE271
 PR640    2      B Q_RES_0402LF-0,5%,1/16W,EMPTY,A    I41 @S9S_MB_2U_LIB.S9S_MB_2U(SCH_1):PAGE271

PVCCIN_CPU1_PWM1 @S9S_MB_2U_LIB.S9S_MB_2U(SCH_1):PVCCIN_CPU1_PWM1
PU31_P1_1   34    PWM ISL99390FRZTR5935-ISL99390FRZ-A    I40 @S9S_MB_2U_LIB.S9S_MB_2U(SCH_1):PAGE271
  PU29   12  PWM11 RAA229126GNPHA0-RAA229126GNP#HA    I33 @S9S_MB_2U_LIB.S9S_MB_2U(SCH_1):PAGE270

PVCCIN_CPU1_PWM2 @S9S_MB_2U_LIB.S9S_MB_2U(SCH_1):PVCCIN_CPU1_PWM2
PU30_P1_2   34    PWM ISL99390FRZTR5935-ISL99390FRZ-A     I7 @S9S_MB_2U_LIB.S9S_MB_2U(SCH_1):PAGE271
  PU29   11  PWM10 RAA229126GNPHA0-RAA229126GNP#HA    I33 @S9S_MB_2U_LIB.S9S_MB_2U(SCH_1):PAGE270

PVCCIN_CPU1_PWM3 @S9S_MB_2U_LIB.S9S_MB_2U(SCH_1):PVCCIN_CPU1_PWM3
PU28_P1_3   34    PWM ISL99390FRZTR5935-ISL99390FRZ-A    I66 @S9S_MB_2U_LIB.S9S_MB_2U(SCH_1):PAGE272
  PU29   10   PWM9 RAA229126GNPHA0-RAA229126GNP#HA    I33 @S9S_MB_2U_LIB.S9S_MB_2U(SCH_1):PAGE270

PVCCIN_CPU1_PWM4 @S9S_MB_2U_LIB.S9S_MB_2U(SCH_1):PVCCIN_CPU1_PWM4
PU27_P1_4   34    PWM ISL99390FRZTR5935-ISL99390FRZ-A    I10 @S9S_MB_2U_LIB.S9S_MB_2U(SCH_1):PAGE272
  PU29    9   PWM8 RAA229126GNPHA0-RAA229126GNP#HA    I33 @S9S_MB_2U_LIB.S9S_MB_2U(SCH_1):PAGE270

PVCCIN_CPU1_PWM5 @S9S_MB_2U_LIB.S9S_MB_2U(SCH_1):PVCCIN_CPU1_PWM5
PU26_P1_5   34    PWM ISL99390FRZTR5935-ISL99390FRZ-A    I23 @S9S_MB_2U_LIB.S9S_MB_2U(SCH_1):PAGE273
  PU29    8   PWM7 RAA229126GNPHA0-RAA229126GNP#HA    I33 @S9S_MB_2U_LIB.S9S_MB_2U(SCH_1):PAGE270

PVCCIN_CPU1_PWM6 @S9S_MB_2U_LIB.S9S_MB_2U(SCH_1):PVCCIN_CPU1_PWM6
PU25_P1_6   34    PWM ISL99390FRZTR5935-ISL99390FRZ-A    I16 @S9S_MB_2U_LIB.S9S_MB_2U(SCH_1):PAGE273
  PU29    7   PWM6 RAA229126GNPHA0-RAA229126GNP#HA    I33 @S9S_MB_2U_LIB.S9S_MB_2U(SCH_1):PAGE270

PVCCIN_CPU1_PWM7 @S9S_MB_2U_LIB.S9S_MB_2U(SCH_1):PVCCIN_CPU1_PWM7
PU24_P1_7   34    PWM ISL99390FRZTR5935-ISL99390FRZ-A    I20 @S9S_MB_2U_LIB.S9S_MB_2U(SCH_1):PAGE274
  PU29    6   PWM5 RAA229126GNPHA0-RAA229126GNP#HA    I33 @S9S_MB_2U_LIB.S9S_MB_2U(SCH_1):PAGE270

PVCCIN_CPU1_PWM8 @S9S_MB_2U_LIB.S9S_MB_2U(SCH_1):PVCCIN_CPU1_PWM8
PU23_P1_8   34    PWM ISL99390FRZTR5935-ISL99390FRZ-A    I11 @S9S_MB_2U_LIB.S9S_MB_2U(SCH_1):PAGE274
  PU29    5   PWM4 RAA229126GNPHA0-RAA229126GNP#HA    I33 @S9S_MB_2U_LIB.S9S_MB_2U(SCH_1):PAGE270

PVCCIN_CPU1_VCC @S9S_MB_2U_LIB.S9S_MB_2U(SCH_1):PVCCIN_CPU1_VCC
 PC552    1      A Q_CAP_C0402-100NF,50V,10%,EMPTA   I120 @S9S_MB_2U_LIB.S9S_MB_2U(SCH_1):PAGE270
 PC555    1      A Q_CAP_C0402-1UF,16V,10%,X6S,CHA   I122 @S9S_MB_2U_LIB.S9S_MB_2U(SCH_1):PAGE270
 PR323    1      A Q_RES_0402LF-1,1%,1/16W,CHIP,CA   I126 @S9S_MB_2U_LIB.S9S_MB_2U(SCH_1):PAGE270
  PU29   47    VCC RAA229126GNPHA0-RAA229126GNP#HA    I33 @S9S_MB_2U_LIB.S9S_MB_2U(SCH_1):PAGE270
PC2366    1      A Q_CAP_0402-0.1UF,25V,10%,EMPTYA   I128 @S9S_MB_2U_LIB.S9S_MB_2U(SCH_1):PAGE270

PVCCIN_CPU1_VDD1 @S9S_MB_2U_LIB.S9S_MB_2U(SCH_1):PVCCIN_CPU1_VDD1
 PR328    2      B Q_RES_0402LF-2.2,1%,1/16W,CHIPA    I37 @S9S_MB_2U_LIB.S9S_MB_2U(SCH_1):PAGE271
PU31_P1_1   35     EN ISL99390FRZTR5935-ISL99390FRZ-A    I40 @S9S_MB_2U_LIB.S9S_MB_2U(SCH_1):PAGE271
PU31_P1_1    3    VCC ISL99390FRZTR5935-ISL99390FRZ-A    I40 @S9S_MB_2U_LIB.S9S_MB_2U(SCH_1):PAGE271
 PC557    1      A Q_CAP_C0402-2.2UF,10V,10%,X6S,A    I36 @S9S_MB_2U_LIB.S9S_MB_2U(SCH_1):PAGE271

PVCCIN_CPU1_VDD2 @S9S_MB_2U_LIB.S9S_MB_2U(SCH_1):PVCCIN_CPU1_VDD2
 PC556    1      A Q_CAP_C0402-2.2UF,10V,10%,X6S,A    I11 @S9S_MB_2U_LIB.S9S_MB_2U(SCH_1):PAGE271
PU30_P1_2   35     EN ISL99390FRZTR5935-ISL99390FRZ-A     I7 @S9S_MB_2U_LIB.S9S_MB_2U(SCH_1):PAGE271
PU30_P1_2    3    VCC ISL99390FRZTR5935-ISL99390FRZ-A     I7 @S9S_MB_2U_LIB.S9S_MB_2U(SCH_1):PAGE271
 PR327    2      B Q_RES_0402LF-2.2,1%,1/16W,CHIPA    I13 @S9S_MB_2U_LIB.S9S_MB_2U(SCH_1):PAGE271

PVCCIN_CPU1_VDD3 @S9S_MB_2U_LIB.S9S_MB_2U(SCH_1):PVCCIN_CPU1_VDD3
 PC524    1      A Q_CAP_C0402-2.2UF,10V,10%,X6S,A    I24 @S9S_MB_2U_LIB.S9S_MB_2U(SCH_1):PAGE272
 PR300    2      B Q_RES_0402LF-2.2,1%,1/16W,CHIPA    I25 @S9S_MB_2U_LIB.S9S_MB_2U(SCH_1):PAGE272
PU28_P1_3   35     EN ISL99390FRZTR5935-ISL99390FRZ-A    I66 @S9S_MB_2U_LIB.S9S_MB_2U(SCH_1):PAGE272
PU28_P1_3    3    VCC ISL99390FRZTR5935-ISL99390FRZ-A    I66 @S9S_MB_2U_LIB.S9S_MB_2U(SCH_1):PAGE272

PVCCIN_CPU1_VDD4 @S9S_MB_2U_LIB.S9S_MB_2U(SCH_1):PVCCIN_CPU1_VDD4
 PC523    1      A Q_CAP_C0402-2.2UF,10V,10%,X6S,A    I11 @S9S_MB_2U_LIB.S9S_MB_2U(SCH_1):PAGE272
 PR299    2      B Q_RES_0402LF-2.2,1%,1/16W,CHIPA    I12 @S9S_MB_2U_LIB.S9S_MB_2U(SCH_1):PAGE272
PU27_P1_4   35     EN ISL99390FRZTR5935-ISL99390FRZ-A    I10 @S9S_MB_2U_LIB.S9S_MB_2U(SCH_1):PAGE272
PU27_P1_4    3    VCC ISL99390FRZTR5935-ISL99390FRZ-A    I10 @S9S_MB_2U_LIB.S9S_MB_2U(SCH_1):PAGE272

PVCCIN_CPU1_VDD5 @S9S_MB_2U_LIB.S9S_MB_2U(SCH_1):PVCCIN_CPU1_VDD5
PU26_P1_5   35     EN ISL99390FRZTR5935-ISL99390FRZ-A    I23 @S9S_MB_2U_LIB.S9S_MB_2U(SCH_1):PAGE273
PU26_P1_5    3    VCC ISL99390FRZTR5935-ISL99390FRZ-A    I23 @S9S_MB_2U_LIB.S9S_MB_2U(SCH_1):PAGE273
 PC502    1      A Q_CAP_C0402-2.2UF,10V,10%,X6S,A    I37 @S9S_MB_2U_LIB.S9S_MB_2U(SCH_1):PAGE273
 PR294    2      B Q_RES_0402LF-2.2,1%,1/16W,CHIPA    I39 @S9S_MB_2U_LIB.S9S_MB_2U(SCH_1):PAGE273

PVCCIN_CPU1_VDD6 @S9S_MB_2U_LIB.S9S_MB_2U(SCH_1):PVCCIN_CPU1_VDD6
PU25_P1_6   35     EN ISL99390FRZTR5935-ISL99390FRZ-A    I16 @S9S_MB_2U_LIB.S9S_MB_2U(SCH_1):PAGE273
PU25_P1_6    3    VCC ISL99390FRZTR5935-ISL99390FRZ-A    I16 @S9S_MB_2U_LIB.S9S_MB_2U(SCH_1):PAGE273
 PC501    1      A Q_CAP_C0402-2.2UF,10V,10%,X6S,A    I17 @S9S_MB_2U_LIB.S9S_MB_2U(SCH_1):PAGE273
 PR293    2      B Q_RES_0402LF-2.2,1%,1/16W,CHIPA    I19 @S9S_MB_2U_LIB.S9S_MB_2U(SCH_1):PAGE273

PVCCIN_CPU1_VDD7 @S9S_MB_2U_LIB.S9S_MB_2U(SCH_1):PVCCIN_CPU1_VDD7
 PC480    1      A Q_CAP_C0402-2.2UF,10V,10%,X6S,A    I34 @S9S_MB_2U_LIB.S9S_MB_2U(SCH_1):PAGE274
PU24_P1_7   35     EN ISL99390FRZTR5935-ISL99390FRZ-A    I20 @S9S_MB_2U_LIB.S9S_MB_2U(SCH_1):PAGE274
PU24_P1_7    3    VCC ISL99390FRZTR5935-ISL99390FRZ-A    I20 @S9S_MB_2U_LIB.S9S_MB_2U(SCH_1):PAGE274
 PR288    2      B Q_RES_0402LF-2.2,1%,1/16W,CHIPA    I68 @S9S_MB_2U_LIB.S9S_MB_2U(SCH_1):PAGE274

PVCCIN_CPU1_VDD8 @S9S_MB_2U_LIB.S9S_MB_2U(SCH_1):PVCCIN_CPU1_VDD8
 PC479    1      A Q_CAP_C0402-2.2UF,10V,10%,X6S,A     I9 @S9S_MB_2U_LIB.S9S_MB_2U(SCH_1):PAGE274
PU23_P1_8   35     EN ISL99390FRZTR5935-ISL99390FRZ-A    I11 @S9S_MB_2U_LIB.S9S_MB_2U(SCH_1):PAGE274
PU23_P1_8    3    VCC ISL99390FRZTR5935-ISL99390FRZ-A    I11 @S9S_MB_2U_LIB.S9S_MB_2U(SCH_1):PAGE274
 PR287    2      B Q_RES_0402LF-2.2,1%,1/16W,CHIPA    I12 @S9S_MB_2U_LIB.S9S_MB_2U(SCH_1):PAGE274

PVCCIN_CPU1_VIN_CSNIN @S9S_MB_2U_LIB.S9S_MB_2U(SCH_1):PVCCIN_CPU1_VIN_CSNIN
 PR313    1      A Q_RES_0402LF-1K,1%,1/16W,EMPTYA    I29 @S9S_MB_2U_LIB.S9S_MB_2U(SCH_1):PAGE270
 PC548    1      A Q_CAP_0402-0.1UF,25V,10%,X7R,CA    I31 @S9S_MB_2U_LIB.S9S_MB_2U(SCH_1):PAGE270
 PR303    2      B Q_RES_0402LF-0,5%,1/16W,CHIP,CA     I7 @S9S_MB_2U_LIB.S9S_MB_2U(SCH_1):PAGE270
  PU29   46 VINSEN||VSYS RAA229126GNPHA0-RAA229126GNP#HA    I33 @S9S_MB_2U_LIB.S9S_MB_2U(SCH_1):PAGE270

PVCCIN_CPU1_VOS1 @S9S_MB_2U_LIB.S9S_MB_2U(SCH_1):PVCCIN_CPU1_VOS1
PU31_P1_1    1    VOS ISL99390FRZTR5935-ISL99390FRZ-A    I40 @S9S_MB_2U_LIB.S9S_MB_2U(SCH_1):PAGE271
 PR330    1      A Q_RES_0402LF-0,5%,1/16W,CHIP,CA    I73 @S9S_MB_2U_LIB.S9S_MB_2U(SCH_1):PAGE271

PVCCIN_CPU1_VOS2 @S9S_MB_2U_LIB.S9S_MB_2U(SCH_1):PVCCIN_CPU1_VOS2
PU30_P1_2    1    VOS ISL99390FRZTR5935-ISL99390FRZ-A     I7 @S9S_MB_2U_LIB.S9S_MB_2U(SCH_1):PAGE271
 PR329    1      A Q_RES_0402LF-0,5%,1/16W,CHIP,CA    I51 @S9S_MB_2U_LIB.S9S_MB_2U(SCH_1):PAGE271

PVCCIN_CPU1_VOS3 @S9S_MB_2U_LIB.S9S_MB_2U(SCH_1):PVCCIN_CPU1_VOS3
 PR302    1      A Q_RES_0402LF-0,5%,1/16W,CHIP,CA    I45 @S9S_MB_2U_LIB.S9S_MB_2U(SCH_1):PAGE272
PU28_P1_3    1    VOS ISL99390FRZTR5935-ISL99390FRZ-A    I66 @S9S_MB_2U_LIB.S9S_MB_2U(SCH_1):PAGE272

PVCCIN_CPU1_VOS4 @S9S_MB_2U_LIB.S9S_MB_2U(SCH_1):PVCCIN_CPU1_VOS4
PU27_P1_4    1    VOS ISL99390FRZTR5935-ISL99390FRZ-A    I10 @S9S_MB_2U_LIB.S9S_MB_2U(SCH_1):PAGE272
 PR301    1      A Q_RES_0402LF-0,5%,1/16W,CHIP,CA    I38 @S9S_MB_2U_LIB.S9S_MB_2U(SCH_1):PAGE272

PVCCIN_CPU1_VOS5 @S9S_MB_2U_LIB.S9S_MB_2U(SCH_1):PVCCIN_CPU1_VOS5
PU26_P1_5    1    VOS ISL99390FRZTR5935-ISL99390FRZ-A    I23 @S9S_MB_2U_LIB.S9S_MB_2U(SCH_1):PAGE273
 PR296    1      A Q_RES_0402LF-0,5%,1/16W,CHIP,CA    I49 @S9S_MB_2U_LIB.S9S_MB_2U(SCH_1):PAGE273

PVCCIN_CPU1_VOS6 @S9S_MB_2U_LIB.S9S_MB_2U(SCH_1):PVCCIN_CPU1_VOS6
PU25_P1_6    1    VOS ISL99390FRZTR5935-ISL99390FRZ-A    I16 @S9S_MB_2U_LIB.S9S_MB_2U(SCH_1):PAGE273
 PR295    1      A Q_RES_0402LF-0,5%,1/16W,CHIP,CA    I27 @S9S_MB_2U_LIB.S9S_MB_2U(SCH_1):PAGE273

PVCCIN_CPU1_VOS7 @S9S_MB_2U_LIB.S9S_MB_2U(SCH_1):PVCCIN_CPU1_VOS7
PU24_P1_7    1    VOS ISL99390FRZTR5935-ISL99390FRZ-A    I20 @S9S_MB_2U_LIB.S9S_MB_2U(SCH_1):PAGE274
 PR290    1      A Q_RES_0402LF-0,5%,1/16W,CHIP,CA    I50 @S9S_MB_2U_LIB.S9S_MB_2U(SCH_1):PAGE274

PVCCIN_CPU1_VOS8 @S9S_MB_2U_LIB.S9S_MB_2U(SCH_1):PVCCIN_CPU1_VOS8
 PR289    1      A Q_RES_0402LF-0,5%,1/16W,CHIP,CA    I44 @S9S_MB_2U_LIB.S9S_MB_2U(SCH_1):PAGE274
PU23_P1_8    1    VOS ISL99390FRZTR5935-ISL99390FRZ-A    I11 @S9S_MB_2U_LIB.S9S_MB_2U(SCH_1):PAGE274

PVCCIN_CPU1_VREF @S9S_MB_2U_LIB.S9S_MB_2U(SCH_1):PVCCIN_CPU1_VREF
PC1359    2      B Q_CAP_0402-0.1UF,25V,10%,X7R,CA    I27 @S9S_MB_2U_LIB.S9S_MB_2U(SCH_1):PAGE272
PU26_P1_5   39  REFIN ISL99390FRZTR5935-ISL99390FRZ-A    I23 @S9S_MB_2U_LIB.S9S_MB_2U(SCH_1):PAGE273
PC1361    2      B Q_CAP_0402-0.1UF,25V,10%,X7R,CA    I36 @S9S_MB_2U_LIB.S9S_MB_2U(SCH_1):PAGE273
PC1363    2      B Q_CAP_0402-0.1UF,25V,10%,X7R,CA    I32 @S9S_MB_2U_LIB.S9S_MB_2U(SCH_1):PAGE274
PU76_P1_2   39  REFIN ISL99390FRZTR5935-ISL99390FRZ-A     I9 @S9S_MB_2U_LIB.S9S_MB_2U(SCH_1):PAGE275
 PR306    1      A Q_RES_0402LF-28K,1%,1/16W,EMPTA     I4 @S9S_MB_2U_LIB.S9S_MB_2U(SCH_1):PAGE270
PC1194    1      A Q_CAP_C0402-1UF,16V,10%,X6S,CHA   I121 @S9S_MB_2U_LIB.S9S_MB_2U(SCH_1):PAGE270
PC1338    2      B Q_CAP_0402-0.1UF,25V,10%,X7R,CA     I6 @S9S_MB_2U_LIB.S9S_MB_2U(SCH_1):PAGE271
PC1358    2      B Q_CAP_0402-0.1UF,25V,10%,X7R,CA     I6 @S9S_MB_2U_LIB.S9S_MB_2U(SCH_1):PAGE272
PU27_P1_4   39  REFIN ISL99390FRZTR5935-ISL99390FRZ-A    I10 @S9S_MB_2U_LIB.S9S_MB_2U(SCH_1):PAGE272
PU28_P1_3   39  REFIN ISL99390FRZTR5935-ISL99390FRZ-A    I66 @S9S_MB_2U_LIB.S9S_MB_2U(SCH_1):PAGE272
PC1360    2      B Q_CAP_0402-0.1UF,25V,10%,X7R,CA    I15 @S9S_MB_2U_LIB.S9S_MB_2U(SCH_1):PAGE273
PU25_P1_6   39  REFIN ISL99390FRZTR5935-ISL99390FRZ-A    I16 @S9S_MB_2U_LIB.S9S_MB_2U(SCH_1):PAGE273
PC1362    2      B Q_CAP_0402-0.1UF,25V,10%,X7R,CA     I7 @S9S_MB_2U_LIB.S9S_MB_2U(SCH_1):PAGE274
PU23_P1_8   39  REFIN ISL99390FRZTR5935-ISL99390FRZ-A    I11 @S9S_MB_2U_LIB.S9S_MB_2U(SCH_1):PAGE274
PU24_P1_7   39  REFIN ISL99390FRZTR5935-ISL99390FRZ-A    I20 @S9S_MB_2U_LIB.S9S_MB_2U(SCH_1):PAGE274
PC1367    2      B Q_CAP_0402-0.1UF,25V,10%,X7R,CA    I29 @S9S_MB_2U_LIB.S9S_MB_2U(SCH_1):PAGE275
PU78_P1_4   39  REFIN ISL99390FRZTR5935-ISL99390FRZ-A    I15 @S9S_MB_2U_LIB.S9S_MB_2U(SCH_1):PAGE276
PU31_P1_1   39  REFIN ISL99390FRZTR5935-ISL99390FRZ-A    I40 @S9S_MB_2U_LIB.S9S_MB_2U(SCH_1):PAGE271
PC1369    2      B Q_CAP_0402-0.1UF,25V,10%,X7R,CA    I23 @S9S_MB_2U_LIB.S9S_MB_2U(SCH_1):PAGE276
PU77_P1_3   39  REFIN ISL99390FRZTR5935-ISL99390FRZ-A    I24 @S9S_MB_2U_LIB.S9S_MB_2U(SCH_1):PAGE276
PC1368    2      B Q_CAP_0402-0.1UF,25V,10%,X7R,CA     I8 @S9S_MB_2U_LIB.S9S_MB_2U(SCH_1):PAGE275
PU75_P1_1   39  REFIN ISL99390FRZTR5935-ISL99390FRZ-A    I89 @S9S_MB_2U_LIB.S9S_MB_2U(SCH_1):PAGE275
PU30_P1_2   39  REFIN ISL99390FRZTR5935-ISL99390FRZ-A     I7 @S9S_MB_2U_LIB.S9S_MB_2U(SCH_1):PAGE271
PC1339    2      B Q_CAP_0402-0.1UF,25V,10%,X7R,CA    I34 @S9S_MB_2U_LIB.S9S_MB_2U(SCH_1):PAGE271
PC1370    2      B Q_CAP_0402-0.1UF,25V,10%,X7R,CA    I13 @S9S_MB_2U_LIB.S9S_MB_2U(SCH_1):PAGE276
  PU29   48   VCCS RAA229126GNPHA0-RAA229126GNP#HA    I33 @S9S_MB_2U_LIB.S9S_MB_2U(SCH_1):PAGE270
 PC553    1      A Q_CAP_C0402-10UF,6.3V,20%,X6S,B   I119 @S9S_MB_2U_LIB.S9S_MB_2U(SCH_1):PAGE270

PVCCIN_CPU1_VR_FAULT @S9S_MB_2U_LIB.S9S_MB_2U(SCH_1):PVCCIN_CPU1_VR_FAULT
 R2524    2      B Q_RES_0402LF-1K,1%,1/16W,CHIP,A    I17 @S9S_MB_2U_LIB.S9S_MB_2U(SCH_1):PAGE270
  PU29   41    CFP RAA229126GNPHA0-RAA229126GNP#HA    I33 @S9S_MB_2U_LIB.S9S_MB_2U(SCH_1):PAGE270

PVCCIO_PECI_BMC @S9S_MB_2U_LIB.S9S_MB_2U(SCH_1):PVCCIO_PECI_BMC
  R142    2      B Q_RES_0402LF-0,5%,1/16W,CHIP,CA    I84 @S9S_MB_2U_LIB.S9S_MB_2U(SCH_1):PAGE227
   J41  B28 GND_B28 SCONN168_ME1016810202011-SCONNA   I173 @S9S_MB_2U_LIB.S9S_MB_2U(SCH_1):PAGE227

PVNN_MAIN_CPU0 @S9S_MB_2U_LIB.S9S_MB_2U(SCH_1):PVNN_MAIN_CPU0
    U2 BA19 VCCVNN0 SOCKET4677_AZIF0045P001C01CS-SA     I8 @S9S_MB_2U_LIB.S9S_MB_2U(SCH_1):PAGE37
    U2 BE19 VCCVNN1 SOCKET4677_AZIF0045P001C01CS-SA     I8 @S9S_MB_2U_LIB.S9S_MB_2U(SCH_1):PAGE37
    U2 BJ19 VCCVNN2 SOCKET4677_AZIF0045P001C01CS-SA     I8 @S9S_MB_2U_LIB.S9S_MB_2U(SCH_1):PAGE37
    U2 BN19 VCCVNN3 SOCKET4677_AZIF0045P001C01CS-SA     I8 @S9S_MB_2U_LIB.S9S_MB_2U(SCH_1):PAGE37
  C590    1      A Q_CAP_C0402-22UF,4V,20%,X6S,CHA   I102 @S9S_MB_2U_LIB.S9S_MB_2U(SCH_1):PAGE74
 C1399    1      A Q_CAP_C0805-47UF,4V,20%,X6S,CHA    I13 @S9S_MB_2U_LIB.S9S_MB_2U(SCH_1):PAGE76
 C1364    1      A Q_CAP_C0402-22UF,4V,20%,X6S,CHA     I9 @S9S_MB_2U_LIB.S9S_MB_2U(SCH_1):PAGE80
  C395    1      A Q_CAP_C0805-47UF,4V,20%,X6S,CHA    I46 @S9S_MB_2U_LIB.S9S_MB_2U(SCH_1):PAGE75
 C1405    1      A Q_CAP_C0603-47UF,2.5V,20%,X6S,A    I47 @S9S_MB_2U_LIB.S9S_MB_2U(SCH_1):PAGE75
 C1406    1      A Q_CAP_C0603-47UF,2.5V,20%,X6S,A    I61 @S9S_MB_2U_LIB.S9S_MB_2U(SCH_1):PAGE75
 C1407    1      A Q_CAP_C0603-47UF,2.5V,20%,X6S,A    I62 @S9S_MB_2U_LIB.S9S_MB_2U(SCH_1):PAGE75
 C1400    1      A Q_CAP_C0805-47UF,4V,20%,X6S,CHA    I14 @S9S_MB_2U_LIB.S9S_MB_2U(SCH_1):PAGE76
 C1362    1      A Q_CAP_C0402-22UF,4V,20%,X6S,CHA    I16 @S9S_MB_2U_LIB.S9S_MB_2U(SCH_1):PAGE76
 C1363    1      A Q_CAP_C0402-22UF,4V,20%,X6S,CHA     I5 @S9S_MB_2U_LIB.S9S_MB_2U(SCH_1):PAGE80
  R324    1      A Q_RES_1206LF-0,,1/2W,CHIP,CS00A    I12 @S9S_MB_2U_LIB.S9S_MB_2U(SCH_1):PAGE80
PR4698    2      B Q_RES_0402LF-0,5%,1/16W,EMPTY,A    I40 @S9S_MB_2U_LIB.S9S_MB_2U(SCH_1):PAGE268
PC1278    1      A Q_CAP_C0805-22UF,4V,20%,X6S,CHA    I42 @S9S_MB_2U_LIB.S9S_MB_2U(SCH_1):PAGE268
PR4683    2      B Q_RES_0402LF-0,5%,1/16W,CHIP,CA    I41 @S9S_MB_2U_LIB.S9S_MB_2U(SCH_1):PAGE268
PC1279    1      A Q_CAP_C0805-22UF,4V,20%,X6S,CHA    I43 @S9S_MB_2U_LIB.S9S_MB_2U(SCH_1):PAGE268
 PL120    2      2 Q_INDUCTOR_SMLF-4.7UH,IND,CV-4B    I29 @S9S_MB_2U_LIB.S9S_MB_2U(SCH_1):PAGE268
PC1276    1      A Q_CAP_C0402-100NF,50V,10%,X7R,A    I37 @S9S_MB_2U_LIB.S9S_MB_2U(SCH_1):PAGE268
PC1277    1      A Q_CAP_C0805-22UF,4V,20%,X6S,CHA    I38 @S9S_MB_2U_LIB.S9S_MB_2U(SCH_1):PAGE268
PC1206    1      A Q_CAP_C0805-22UF,4V,20%,X6S,CHA    I47 @S9S_MB_2U_LIB.S9S_MB_2U(SCH_1):PAGE268

PVNN_MAIN_CPU0_CS @S9S_MB_2U_LIB.S9S_MB_2U(SCH_1):PVNN_MAIN_CPU0_CS
PR1303    1      A Q_RES_0402LF-22.6K,1%,1/16W,CHA    I21 @S9S_MB_2U_LIB.S9S_MB_2U(SCH_1):PAGE268
  PU81    4     CS RS53317LR-RS53317LR,SMLF,IC,ALA    I22 @S9S_MB_2U_LIB.S9S_MB_2U(SCH_1):PAGE268

PVNN_MAIN_CPU0_FB @S9S_MB_2U_LIB.S9S_MB_2U(SCH_1):PVNN_MAIN_CPU0_FB
 PR501    1      A Q_RES_0402LF-8.25K,0.1%,1/16W,A    I36 @S9S_MB_2U_LIB.S9S_MB_2U(SCH_1):PAGE268
 PC237    1      A Q_CAP_0402-680PF,50V,10%,X7R,TA    I35 @S9S_MB_2U_LIB.S9S_MB_2U(SCH_1):PAGE268
  PR50    1      A Q_RES_0402LF-12.4K,0.1%,1/16W,A    I28 @S9S_MB_2U_LIB.S9S_MB_2U(SCH_1):PAGE268
  PU81    6     FB RS53317LR-RS53317LR,SMLF,IC,ALA    I22 @S9S_MB_2U_LIB.S9S_MB_2U(SCH_1):PAGE268

PVNN_MAIN_CPU0_FB_RC @S9S_MB_2U_LIB.S9S_MB_2U(SCH_1):PVNN_MAIN_CPU0_FB_RC
 PR501    2      B Q_RES_0402LF-8.25K,0.1%,1/16W,A    I36 @S9S_MB_2U_LIB.S9S_MB_2U(SCH_1):PAGE268
PR4698    1      A Q_RES_0402LF-0,5%,1/16W,EMPTY,A    I40 @S9S_MB_2U_LIB.S9S_MB_2U(SCH_1):PAGE268
 PC237    2      B Q_CAP_0402-680PF,50V,10%,X7R,TA    I35 @S9S_MB_2U_LIB.S9S_MB_2U(SCH_1):PAGE268
PC1420    1      A Q_CAP_0402-0.01UF,25V,10%,X7R,A    I39 @S9S_MB_2U_LIB.S9S_MB_2U(SCH_1):PAGE268
PR4683    1      A Q_RES_0402LF-0,5%,1/16W,CHIP,CA    I41 @S9S_MB_2U_LIB.S9S_MB_2U(SCH_1):PAGE268

PVNN_MAIN_CPU0_MODE @S9S_MB_2U_LIB.S9S_MB_2U(SCH_1):PVNN_MAIN_CPU0_MODE
PR1301    1      A Q_RES_0402LF-60.4K,1%,1/16W,CHA     I9 @S9S_MB_2U_LIB.S9S_MB_2U(SCH_1):PAGE268
  PU81   12   MODE RS53317LR-RS53317LR,SMLF,IC,ALA    I22 @S9S_MB_2U_LIB.S9S_MB_2U(SCH_1):PAGE268

PVNN_MAIN_CPU0_REF @S9S_MB_2U_LIB.S9S_MB_2U(SCH_1):PVNN_MAIN_CPU0_REF
  PC27    1      A Q_CAP_0402-3300PF,50V,10%,X7R,A    I25 @S9S_MB_2U_LIB.S9S_MB_2U(SCH_1):PAGE268
  PU81    8    REF RS53317LR-RS53317LR,SMLF,IC,ALA    I22 @S9S_MB_2U_LIB.S9S_MB_2U(SCH_1):PAGE268

PVNN_MAIN_CPU0_VCC @S9S_MB_2U_LIB.S9S_MB_2U(SCH_1):PVNN_MAIN_CPU0_VCC
PR3339    2      B Q_RES_0402LF-0,5%,1/16W,CHIP,CA    I10 @S9S_MB_2U_LIB.S9S_MB_2U(SCH_1):PAGE268
PC2221    1      A Q_CAP_C0402-1UF,25V,10%,X6S,CHA     I7 @S9S_MB_2U_LIB.S9S_MB_2U(SCH_1):PAGE268
  PU81   13    VCC RS53317LR-RS53317LR,SMLF,IC,ALA    I22 @S9S_MB_2U_LIB.S9S_MB_2U(SCH_1):PAGE268

PVNN_MAIN_CPU1 @S9S_MB_2U_LIB.S9S_MB_2U(SCH_1):PVNN_MAIN_CPU1
    U1 BA19 VCCVNN0 SOCKET4677_AZIF0045P001C01CS-SA     I8 @S9S_MB_2U_LIB.S9S_MB_2U(SCH_1):PAGE68
    U1 BE19 VCCVNN1 SOCKET4677_AZIF0045P001C01CS-SA     I8 @S9S_MB_2U_LIB.S9S_MB_2U(SCH_1):PAGE68
    U1 BJ19 VCCVNN2 SOCKET4677_AZIF0045P001C01CS-SA     I8 @S9S_MB_2U_LIB.S9S_MB_2U(SCH_1):PAGE68
    U1 BN19 VCCVNN3 SOCKET4677_AZIF0045P001C01CS-SA     I8 @S9S_MB_2U_LIB.S9S_MB_2U(SCH_1):PAGE68
 C1391    1      A Q_CAP_C0603-47UF,2.5V,20%,X6S,A    I52 @S9S_MB_2U_LIB.S9S_MB_2U(SCH_1):PAGE78
 C1365    1      A Q_CAP_C0402-22UF,4V,20%,X6S,CHA    I20 @S9S_MB_2U_LIB.S9S_MB_2U(SCH_1):PAGE80
 C1366    1      A Q_CAP_C0402-22UF,4V,20%,X6S,CHA    I28 @S9S_MB_2U_LIB.S9S_MB_2U(SCH_1):PAGE80
  C310    1      A Q_CAP_C0402-22UF,4V,20%,X6S,CHA    I70 @S9S_MB_2U_LIB.S9S_MB_2U(SCH_1):PAGE77
 C1387    1      A Q_CAP_C0805-47UF,4V,20%,X6S,CHA    I49 @S9S_MB_2U_LIB.S9S_MB_2U(SCH_1):PAGE78
 C1389    1      A Q_CAP_C0603-47UF,2.5V,20%,X6S,A    I51 @S9S_MB_2U_LIB.S9S_MB_2U(SCH_1):PAGE78
 C1393    1      A Q_CAP_C0603-47UF,2.5V,20%,X6S,A    I57 @S9S_MB_2U_LIB.S9S_MB_2U(SCH_1):PAGE78
 C1403    1      A Q_CAP_C0805-47UF,4V,20%,X6S,CHA    I43 @S9S_MB_2U_LIB.S9S_MB_2U(SCH_1):PAGE79
 C1404    1      A Q_CAP_C0805-47UF,4V,20%,X6S,CHA    I44 @S9S_MB_2U_LIB.S9S_MB_2U(SCH_1):PAGE79
 C1353    1      A Q_CAP_C0402-22UF,4V,20%,X6S,CHA    I49 @S9S_MB_2U_LIB.S9S_MB_2U(SCH_1):PAGE79
  R330    1      A Q_RES_1206LF-0,,1/2W,CHIP,CS00A    I34 @S9S_MB_2U_LIB.S9S_MB_2U(SCH_1):PAGE80
 PL121    2      2 Q_INDUCTOR_SMLF-4.7UH,IND,CV-4B    I27 @S9S_MB_2U_LIB.S9S_MB_2U(SCH_1):PAGE286
PR4700    2      B Q_RES_0402LF-0,5%,1/16W,EMPTY,A    I42 @S9S_MB_2U_LIB.S9S_MB_2U(SCH_1):PAGE286
PC1287    1      A Q_CAP_C0805-22UF,4V,20%,X6S,CHA    I44 @S9S_MB_2U_LIB.S9S_MB_2U(SCH_1):PAGE286
PC1285    1      A Q_CAP_C0805-22UF,4V,20%,X6S,CHA    I36 @S9S_MB_2U_LIB.S9S_MB_2U(SCH_1):PAGE286
PC1286    1      A Q_CAP_C0805-22UF,4V,20%,X6S,CHA    I38 @S9S_MB_2U_LIB.S9S_MB_2U(SCH_1):PAGE286
PR4699    2      B Q_RES_0402LF-0,5%,1/16W,CHIP,CA    I43 @S9S_MB_2U_LIB.S9S_MB_2U(SCH_1):PAGE286
PC1284    1      A Q_CAP_C0402-100NF,50V,10%,X7R,A    I28 @S9S_MB_2U_LIB.S9S_MB_2U(SCH_1):PAGE286
PC1207    1      A Q_CAP_C0805-22UF,4V,20%,X6S,CHA    I45 @S9S_MB_2U_LIB.S9S_MB_2U(SCH_1):PAGE286

PVNN_MAIN_CPU1_CS @S9S_MB_2U_LIB.S9S_MB_2U(SCH_1):PVNN_MAIN_CPU1_CS
  PU82    4     CS RS53317LR-RS53317LR,SMLF,IC,ALA    I20 @S9S_MB_2U_LIB.S9S_MB_2U(SCH_1):PAGE286
PR2222    1      A Q_RES_0402LF-34.8K,1%,1/16W,CHA    I19 @S9S_MB_2U_LIB.S9S_MB_2U(SCH_1):PAGE286

PVNN_MAIN_CPU1_FB @S9S_MB_2U_LIB.S9S_MB_2U(SCH_1):PVNN_MAIN_CPU1_FB
  PR51    1      A Q_RES_0402LF-12.4K,0.1%,1/16W,A    I26 @S9S_MB_2U_LIB.S9S_MB_2U(SCH_1):PAGE286
  PU82    6     FB RS53317LR-RS53317LR,SMLF,IC,ALA    I20 @S9S_MB_2U_LIB.S9S_MB_2U(SCH_1):PAGE286
 PR502    1      A Q_RES_0402LF-8.25K,0.1%,1/16W,A    I34 @S9S_MB_2U_LIB.S9S_MB_2U(SCH_1):PAGE286
 PC238    1      A Q_CAP_0402-680PF,50V,10%,X7R,TA    I33 @S9S_MB_2U_LIB.S9S_MB_2U(SCH_1):PAGE286

PVNN_MAIN_CPU1_FB_RC @S9S_MB_2U_LIB.S9S_MB_2U(SCH_1):PVNN_MAIN_CPU1_FB_RC
PR4700    1      A Q_RES_0402LF-0,5%,1/16W,EMPTY,A    I42 @S9S_MB_2U_LIB.S9S_MB_2U(SCH_1):PAGE286
 PR502    2      B Q_RES_0402LF-8.25K,0.1%,1/16W,A    I34 @S9S_MB_2U_LIB.S9S_MB_2U(SCH_1):PAGE286
 PC238    2      B Q_CAP_0402-680PF,50V,10%,X7R,TA    I33 @S9S_MB_2U_LIB.S9S_MB_2U(SCH_1):PAGE286
PR4699    1      A Q_RES_0402LF-0,5%,1/16W,CHIP,CA    I43 @S9S_MB_2U_LIB.S9S_MB_2U(SCH_1):PAGE286
PC2277    1      A Q_CAP_0402-0.01UF,25V,10%,X7R,A    I40 @S9S_MB_2U_LIB.S9S_MB_2U(SCH_1):PAGE286

PVNN_MAIN_CPU1_MODE @S9S_MB_2U_LIB.S9S_MB_2U(SCH_1):PVNN_MAIN_CPU1_MODE
  PU82   12   MODE RS53317LR-RS53317LR,SMLF,IC,ALA    I20 @S9S_MB_2U_LIB.S9S_MB_2U(SCH_1):PAGE286
PR2220    1      A Q_RES_0402LF-60.4K,1%,1/16W,CHA    I12 @S9S_MB_2U_LIB.S9S_MB_2U(SCH_1):PAGE286

PVNN_MAIN_CPU1_REF @S9S_MB_2U_LIB.S9S_MB_2U(SCH_1):PVNN_MAIN_CPU1_REF
  PC28    1      A Q_CAP_0402-3300PF,50V,10%,X7R,A    I23 @S9S_MB_2U_LIB.S9S_MB_2U(SCH_1):PAGE286
  PU82    8    REF RS53317LR-RS53317LR,SMLF,IC,ALA    I20 @S9S_MB_2U_LIB.S9S_MB_2U(SCH_1):PAGE286

PVNN_MAIN_CPU1_VCC @S9S_MB_2U_LIB.S9S_MB_2U(SCH_1):PVNN_MAIN_CPU1_VCC
PR3338    2      B Q_RES_0402LF-0,5%,1/16W,CHIP,CA    I13 @S9S_MB_2U_LIB.S9S_MB_2U(SCH_1):PAGE286
  PU82   13    VCC RS53317LR-RS53317LR,SMLF,IC,ALA    I20 @S9S_MB_2U_LIB.S9S_MB_2U(SCH_1):PAGE286
PC2222    1      A Q_CAP_C0402-1UF,25V,10%,X6S,CHA    I10 @S9S_MB_2U_LIB.S9S_MB_2U(SCH_1):PAGE286

PVNN_TERM_CPU0 @S9S_MB_2U_LIB.S9S_MB_2U(SCH_1):PVNN_TERM_CPU0
  R328    2      B Q_RES_0402LF-100,1%,1/16W,CHIPA    I93 @S9S_MB_2U_LIB.S9S_MB_2U(SCH_1):PAGE14
  R548    2      B Q_RES_0402LF-49.9,1%,1/16W,CHIA    I94 @S9S_MB_2U_LIB.S9S_MB_2U(SCH_1):PAGE14
  R555    2      B Q_RES_0402LF-100,1%,1/16W,CHIPA    I98 @S9S_MB_2U_LIB.S9S_MB_2U(SCH_1):PAGE14
  R556    2      B Q_RES_0402LF-49.9,1%,1/16W,CHIA   I100 @S9S_MB_2U_LIB.S9S_MB_2U(SCH_1):PAGE14
   R18    1      A Q_RES_0402LF-499,1%,1/16W,CHIPA    I35 @S9S_MB_2U_LIB.S9S_MB_2U(SCH_1):PAGE16
   R19    1      A Q_RES_0402LF-499,1%,1/16W,CHIPA    I36 @S9S_MB_2U_LIB.S9S_MB_2U(SCH_1):PAGE16
 R1242    1      A Q_RES_0402LF-301,1%,1/16W,CHIPA    I13 @S9S_MB_2U_LIB.S9S_MB_2U(SCH_1):PAGE117
  R296    1      A Q_RES_0402LF-301,1%,1/16W,CHIPA    I65 @S9S_MB_2U_LIB.S9S_MB_2U(SCH_1):PAGE118
  R301    1      A Q_RES_0402LF-301,1%,1/16W,CHIPA    I73 @S9S_MB_2U_LIB.S9S_MB_2U(SCH_1):PAGE118
  R282    1      A Q_RES_0402LF-240,1%,1/16W,CHIPA    I53 @S9S_MB_2U_LIB.S9S_MB_2U(SCH_1):PAGE119
  R279    1      A Q_RES_0402LF-240,1%,1/16W,EMPTA    I54 @S9S_MB_2U_LIB.S9S_MB_2U(SCH_1):PAGE119
  R280    1      A Q_RES_0402LF-240,1%,1/16W,EMPTA    I57 @S9S_MB_2U_LIB.S9S_MB_2U(SCH_1):PAGE119
  R281    1      A Q_RES_0402LF-240,1%,1/16W,EMPTA    I58 @S9S_MB_2U_LIB.S9S_MB_2U(SCH_1):PAGE119
  R278    1      A Q_RES_0402LF-240,1%,1/16W,EMPTA    I61 @S9S_MB_2U_LIB.S9S_MB_2U(SCH_1):PAGE119
  R277    1      A Q_RES_0402LF-240,1%,1/16W,CHIPA    I62 @S9S_MB_2U_LIB.S9S_MB_2U(SCH_1):PAGE119
  R276    1      A Q_RES_0402LF-240,1%,1/16W,EMPTA    I66 @S9S_MB_2U_LIB.S9S_MB_2U(SCH_1):PAGE119
  R275    1      A Q_RES_0402LF-240,1%,1/16W,CHIPA    I68 @S9S_MB_2U_LIB.S9S_MB_2U(SCH_1):PAGE119
 R1009    1      A Q_RES_0402LF-1K,1%,1/16W,EMPTYA   I136 @S9S_MB_2U_LIB.S9S_MB_2U(SCH_1):PAGE119
 R1232    1      A Q_RES_0402LF-240,1%,1/16W,EMPTA   I156 @S9S_MB_2U_LIB.S9S_MB_2U(SCH_1):PAGE119
 R1233    1      A Q_RES_0402LF-240,1%,1/16W,EMPTA   I158 @S9S_MB_2U_LIB.S9S_MB_2U(SCH_1):PAGE119
  R292    1      A Q_RES_0402LF-240,1%,1/16W,EMPTA   I196 @S9S_MB_2U_LIB.S9S_MB_2U(SCH_1):PAGE119
  R249    1      A Q_RES_0402LF-240,1%,1/16W,EMPTA    I27 @S9S_MB_2U_LIB.S9S_MB_2U(SCH_1):PAGE120
  R251    1      A Q_RES_0402LF-240,1%,1/16W,EMPTA    I28 @S9S_MB_2U_LIB.S9S_MB_2U(SCH_1):PAGE120
  R250    1      A Q_RES_0402LF-240,1%,1/16W,EMPTA    I29 @S9S_MB_2U_LIB.S9S_MB_2U(SCH_1):PAGE120
  R252    1      A Q_RES_0402LF-240,1%,1/16W,CHIPA    I30 @S9S_MB_2U_LIB.S9S_MB_2U(SCH_1):PAGE120
  R253    1      A Q_RES_0402LF-240,1%,1/16W,CHIPA    I31 @S9S_MB_2U_LIB.S9S_MB_2U(SCH_1):PAGE120
  R254    1      A Q_RES_0402LF-240,1%,1/16W,CHIPA    I32 @S9S_MB_2U_LIB.S9S_MB_2U(SCH_1):PAGE120
  R185    2      B Q_RES_0402LF-100,1%,1/16W,CHIPA    I60 @S9S_MB_2U_LIB.S9S_MB_2U(SCH_1):PAGE124
  R183    2      B Q_RES_0402LF-100,1%,1/16W,CHIPA    I62 @S9S_MB_2U_LIB.S9S_MB_2U(SCH_1):PAGE124
   R96    1      A Q_RES_0402LF-240,1%,1/16W,EMPTA    I22 @S9S_MB_2U_LIB.S9S_MB_2U(SCH_1):PAGE126
   R95    1      A Q_RES_0402LF-240,1%,1/16W,EMPTA    I23 @S9S_MB_2U_LIB.S9S_MB_2U(SCH_1):PAGE126
   R94    1      A Q_RES_0402LF-240,1%,1/16W,EMPTA    I25 @S9S_MB_2U_LIB.S9S_MB_2U(SCH_1):PAGE126
   R97    1      A Q_RES_0402LF-240,1%,1/16W,EMPTA   I114 @S9S_MB_2U_LIB.S9S_MB_2U(SCH_1):PAGE126
  R779    1      A Q_RES_0402LF-150,1%,1/16W,CHIPA    I95 @S9S_MB_2U_LIB.S9S_MB_2U(SCH_1):PAGE133
  R757    1      A Q_RES_0402LF-120,1%,1/16W,CHIPA   I166 @S9S_MB_2U_LIB.S9S_MB_2U(SCH_1):PAGE134
  R758    1      A Q_RES_0402LF-150,1%,1/16W,CHIPA   I168 @S9S_MB_2U_LIB.S9S_MB_2U(SCH_1):PAGE134
  R759    1      A Q_RES_0402LF-150,1%,1/16W,CHIPA   I169 @S9S_MB_2U_LIB.S9S_MB_2U(SCH_1):PAGE134
  R760    1      A Q_RES_0402LF-499,1%,1/16W,CHIPA   I174 @S9S_MB_2U_LIB.S9S_MB_2U(SCH_1):PAGE134
  R761    1      A Q_RES_0402LF-499,1%,1/16W,CHIPA   I175 @S9S_MB_2U_LIB.S9S_MB_2U(SCH_1):PAGE134
  R741    1      A Q_RES_0402LF-150,1%,1/16W,CHIPA    I66 @S9S_MB_2U_LIB.S9S_MB_2U(SCH_1):PAGE135
  R744    1      A Q_RES_0402LF-75,1%,1/16W,CHIP,A    I77 @S9S_MB_2U_LIB.S9S_MB_2U(SCH_1):PAGE135
 R1486    1      A Q_RES_0402LF-200,1%,1/16W,EMPTA    I74 @S9S_MB_2U_LIB.S9S_MB_2U(SCH_1):PAGE174
 R1485    1      A Q_RES_0402LF-200,1%,1/16W,EMPTA    I75 @S9S_MB_2U_LIB.S9S_MB_2U(SCH_1):PAGE174
  R145    1      A Q_RES_0402LF-4.75K,1%,1/16W,EMA    I26 @S9S_MB_2U_LIB.S9S_MB_2U(SCH_1):PAGE185
  R146    1      A Q_RES_0402LF-4.75K,1%,1/16W,EMA    I30 @S9S_MB_2U_LIB.S9S_MB_2U(SCH_1):PAGE185
  R679    1      A Q_RES_0402LF-499,1%,1/16W,CHIPA    I29 @S9S_MB_2U_LIB.S9S_MB_2U(SCH_1):PAGE217
 R1006    1      A Q_RES_0402LF-4.7K,5%,1/16W,CHIA     I8 @S9S_MB_2U_LIB.S9S_MB_2U(SCH_1):PAGE223
  C559    1      A Q_CAP_0402-0.1UF,25V,10%,X7R,CA    I20 @S9S_MB_2U_LIB.S9S_MB_2U(SCH_1):PAGE223
  R911    1      A Q_RES_0402LF-240,1%,1/16W,CHIPA    I22 @S9S_MB_2U_LIB.S9S_MB_2U(SCH_1):PAGE223
  R910    1      A Q_RES_0402LF-240,1%,1/16W,CHIPA    I24 @S9S_MB_2U_LIB.S9S_MB_2U(SCH_1):PAGE223
   U28    1   VCCA PCA9617ADP-PCA9617ADP,SMLF,IC,A    I39 @S9S_MB_2U_LIB.S9S_MB_2U(SCH_1):PAGE223
  C567    1      A Q_CAP_0402-0.1UF,25V,10%,X7R,CA    I25 @S9S_MB_2U_LIB.S9S_MB_2U(SCH_1):PAGE224
   U30    1   VCCA PCA9517AD-PCA9517AD,SMLF,IC,ALA    I28 @S9S_MB_2U_LIB.S9S_MB_2U(SCH_1):PAGE224
  R971    1      A Q_RES_0402LF-240,1%,1/16W,CHIPA    I42 @S9S_MB_2U_LIB.S9S_MB_2U(SCH_1):PAGE224
  R969    1      A Q_RES_0402LF-240,1%,1/16W,CHIPA    I43 @S9S_MB_2U_LIB.S9S_MB_2U(SCH_1):PAGE224
 R2386    1      A Q_RES_0402LF-100,1%,1/16W,EMPTA    I37 @S9S_MB_2U_LIB.S9S_MB_2U(SCH_1):PAGE260
  R324    2      B Q_RES_1206LF-0,,1/2W,CHIP,CS00A    I12 @S9S_MB_2U_LIB.S9S_MB_2U(SCH_1):PAGE80
  R323    2      B Q_RES_1206LF-0,,1/2W,EMPTY,CS0A    I13 @S9S_MB_2U_LIB.S9S_MB_2U(SCH_1):PAGE80
 R2322    1      A Q_RES_0402LF-49.9,1%,1/16W,EMPA    I36 @S9S_MB_2U_LIB.S9S_MB_2U(SCH_1):PAGE260
 R1717    1      A Q_RES_0402LF-49.9,1%,1/16W,CHIA    I25 @S9S_MB_2U_LIB.S9S_MB_2U(SCH_1):PAGE264
 R4262    1      A Q_RES_0402LF-240,1%,1/16W,EMPTA   I215 @S9S_MB_2U_LIB.S9S_MB_2U(SCH_1):PAGE119
 R4260    1      A Q_RES_0402LF-240,1%,1/16W,EMPTA   I219 @S9S_MB_2U_LIB.S9S_MB_2U(SCH_1):PAGE119
  R288    1      A Q_RES_0402LF-240,1%,1/16W,EMPTA   I224 @S9S_MB_2U_LIB.S9S_MB_2U(SCH_1):PAGE119
 R4390    1      A Q_RES_0402LF-150,1%,1/16W,CHIPA   I169 @S9S_MB_2U_LIB.S9S_MB_2U(SCH_1):PAGE322
 R4388    1      A Q_RES_0402LF-150,1%,1/16W,CHIPA   I174 @S9S_MB_2U_LIB.S9S_MB_2U(SCH_1):PAGE322
 R4389    1      A Q_RES_0402LF-150,1%,1/16W,CHIPA   I177 @S9S_MB_2U_LIB.S9S_MB_2U(SCH_1):PAGE322
 R2382    2      B Q_RES_0402LF-49.9,1%,1/16W,EMPA   I123 @S9S_MB_2U_LIB.S9S_MB_2U(SCH_1):PAGE252
 C2443    1      A Q_CAP_C0402-10UF,6.3V,20%,X6S,B    I18 @S9S_MB_2U_LIB.S9S_MB_2U(SCH_1):PAGE264
 C2444    1      A Q_CAP_0402-0.1UF,25V,10%,X7R,CA    I19 @S9S_MB_2U_LIB.S9S_MB_2U(SCH_1):PAGE264
 R1735    1      A Q_RES_0402LF-100,1%,1/16W,CHIPA    I24 @S9S_MB_2U_LIB.S9S_MB_2U(SCH_1):PAGE264
 R2590    2      B Q_RES_0402LF-100,1%,1/16W,CHIPA   I124 @S9S_MB_2U_LIB.S9S_MB_2U(SCH_1):PAGE252
 R2381    2      B Q_RES_0402LF-49.9,1%,1/16W,CHIA   I125 @S9S_MB_2U_LIB.S9S_MB_2U(SCH_1):PAGE252
 C3270    1      A Q_CAP_C0603-10UF,4V,20%,EMPTY,A   I127 @S9S_MB_2U_LIB.S9S_MB_2U(SCH_1):PAGE252
 C3271    1      A Q_CAP_C0402-100NF,50V,10%,X7R,A   I128 @S9S_MB_2U_LIB.S9S_MB_2U(SCH_1):PAGE252
  R680    1      A Q_RES_0402LF-499,1%,1/16W,CHIPA    I30 @S9S_MB_2U_LIB.S9S_MB_2U(SCH_1):PAGE217
  R681    1      A Q_RES_0402LF-499,1%,1/16W,CHIPA    I32 @S9S_MB_2U_LIB.S9S_MB_2U(SCH_1):PAGE217
  R686    1      A Q_RES_0402LF-499,1%,1/16W,CHIPA    I33 @S9S_MB_2U_LIB.S9S_MB_2U(SCH_1):PAGE217
 R4395    1      A Q_RES_0402LF-100,1%,1/16W,CHIPA    I13 @S9S_MB_2U_LIB.S9S_MB_2U(SCH_1):PAGE121
  Q138    4     E2 BC847BPN-BC847BPN,SMLF,IC,BA00A    I17 @S9S_MB_2U_LIB.S9S_MB_2U(SCH_1):PAGE121
  R243    1      A Q_RES_0402LF-100,1%,1/16W,CHIPA    I23 @S9S_MB_2U_LIB.S9S_MB_2U(SCH_1):PAGE121
 R4401    1      A Q_RES_0402LF-100,1%,1/16W,CHIPA     I8 @S9S_MB_2U_LIB.S9S_MB_2U(SCH_1):PAGE122
  Q143    4     E2 BC847BPN-BC847BPN,SMLF,IC,BA00A    I12 @S9S_MB_2U_LIB.S9S_MB_2U(SCH_1):PAGE122
  R219    1      A Q_RES_0402LF-100,1%,1/16W,CHIPA    I37 @S9S_MB_2U_LIB.S9S_MB_2U(SCH_1):PAGE122
  Q141    4     E2 BC847BPN-BC847BPN,SMLF,IC,BA00A    I12 @S9S_MB_2U_LIB.S9S_MB_2U(SCH_1):PAGE123
  R200    1      A Q_RES_0402LF-100,1%,1/16W,CHIPA    I19 @S9S_MB_2U_LIB.S9S_MB_2U(SCH_1):PAGE123
  R197    1      A Q_RES_0402LF-301,1%,1/16W,CHIPA    I27 @S9S_MB_2U_LIB.S9S_MB_2U(SCH_1):PAGE123
 C1302    1      A Q_CAP_C0402-22UF,4V,20%,X6S,CHA    I82 @S9S_MB_2U_LIB.S9S_MB_2U(SCH_1):PAGE227
  R142    1      A Q_RES_0402LF-0,5%,1/16W,CHIP,CA    I84 @S9S_MB_2U_LIB.S9S_MB_2U(SCH_1):PAGE227

PVNN_TERM_CPU1 @S9S_MB_2U_LIB.S9S_MB_2U(SCH_1):PVNN_TERM_CPU1
  R559    2      B Q_RES_0402LF-100,1%,1/16W,CHIPA    I69 @S9S_MB_2U_LIB.S9S_MB_2U(SCH_1):PAGE45
  R560    2      B Q_RES_0402LF-49.9,1%,1/16W,CHIA    I70 @S9S_MB_2U_LIB.S9S_MB_2U(SCH_1):PAGE45
  R558    2      B Q_RES_0402LF-49.9,1%,1/16W,CHIA    I73 @S9S_MB_2U_LIB.S9S_MB_2U(SCH_1):PAGE45
  R557    2      B Q_RES_0402LF-100,1%,1/16W,CHIPA    I74 @S9S_MB_2U_LIB.S9S_MB_2U(SCH_1):PAGE45
   R49    1      A Q_RES_0402LF-499,1%,1/16W,CHIPA    I34 @S9S_MB_2U_LIB.S9S_MB_2U(SCH_1):PAGE47
   R50    1      A Q_RES_0402LF-499,1%,1/16W,CHIPA    I35 @S9S_MB_2U_LIB.S9S_MB_2U(SCH_1):PAGE47
 R1244    1      A Q_RES_0402LF-301,1%,1/16W,CHIPA    I16 @S9S_MB_2U_LIB.S9S_MB_2U(SCH_1):PAGE117
  R298    1      A Q_RES_0402LF-301,1%,1/16W,CHIPA    I67 @S9S_MB_2U_LIB.S9S_MB_2U(SCH_1):PAGE118
  R303    1      A Q_RES_0402LF-301,1%,1/16W,CHIPA    I76 @S9S_MB_2U_LIB.S9S_MB_2U(SCH_1):PAGE118
  R268    1      A Q_RES_0402LF-240,1%,1/16W,EMPTA    I94 @S9S_MB_2U_LIB.S9S_MB_2U(SCH_1):PAGE119
  R267    1      A Q_RES_0402LF-240,1%,1/16W,EMPTA    I95 @S9S_MB_2U_LIB.S9S_MB_2U(SCH_1):PAGE119
  R266    1      A Q_RES_0402LF-240,1%,1/16W,EMPTA    I96 @S9S_MB_2U_LIB.S9S_MB_2U(SCH_1):PAGE119
  R265    1      A Q_RES_0402LF-240,1%,1/16W,CHIPA    I97 @S9S_MB_2U_LIB.S9S_MB_2U(SCH_1):PAGE119
  R264    1      A Q_RES_0402LF-240,1%,1/16W,EMPTA    I98 @S9S_MB_2U_LIB.S9S_MB_2U(SCH_1):PAGE119
  R262    1      A Q_RES_0402LF-240,1%,1/16W,EMPTA   I100 @S9S_MB_2U_LIB.S9S_MB_2U(SCH_1):PAGE119
  R261    1      A Q_RES_0402LF-240,1%,1/16W,EMPTA   I101 @S9S_MB_2U_LIB.S9S_MB_2U(SCH_1):PAGE119
  R263    1      A Q_RES_0402LF-240,1%,1/16W,EMPTA   I125 @S9S_MB_2U_LIB.S9S_MB_2U(SCH_1):PAGE119
 R1008    1      A Q_RES_0402LF-1K,1%,1/16W,EMPTYA   I139 @S9S_MB_2U_LIB.S9S_MB_2U(SCH_1):PAGE119
 R1229    1      A Q_RES_0402LF-240,1%,1/16W,EMPTA   I169 @S9S_MB_2U_LIB.S9S_MB_2U(SCH_1):PAGE119
 R1230    1      A Q_RES_0402LF-240,1%,1/16W,EMPTA   I170 @S9S_MB_2U_LIB.S9S_MB_2U(SCH_1):PAGE119
  R255    1      A Q_RES_0402LF-240,1%,1/16W,EMPTA    I42 @S9S_MB_2U_LIB.S9S_MB_2U(SCH_1):PAGE120
  R257    1      A Q_RES_0402LF-240,1%,1/16W,EMPTA    I43 @S9S_MB_2U_LIB.S9S_MB_2U(SCH_1):PAGE120
  R258    1      A Q_RES_0402LF-240,1%,1/16W,CHIPA    I44 @S9S_MB_2U_LIB.S9S_MB_2U(SCH_1):PAGE120
  R259    1      A Q_RES_0402LF-240,1%,1/16W,CHIPA    I45 @S9S_MB_2U_LIB.S9S_MB_2U(SCH_1):PAGE120
  R260    1      A Q_RES_0402LF-240,1%,1/16W,CHIPA    I46 @S9S_MB_2U_LIB.S9S_MB_2U(SCH_1):PAGE120
  R256    1      A Q_RES_0402LF-240,1%,1/16W,EMPTA    I48 @S9S_MB_2U_LIB.S9S_MB_2U(SCH_1):PAGE120
  R157    2      B Q_RES_0402LF-100,1%,1/16W,CHIPA    I24 @S9S_MB_2U_LIB.S9S_MB_2U(SCH_1):PAGE125
  R155    2      B Q_RES_0402LF-100,1%,1/16W,CHIPA    I26 @S9S_MB_2U_LIB.S9S_MB_2U(SCH_1):PAGE125
   R90    1      A Q_RES_0402LF-240,1%,1/16W,EMPTA   I135 @S9S_MB_2U_LIB.S9S_MB_2U(SCH_1):PAGE126
   R91    1      A Q_RES_0402LF-240,1%,1/16W,EMPTA   I136 @S9S_MB_2U_LIB.S9S_MB_2U(SCH_1):PAGE126
   R92    1      A Q_RES_0402LF-240,1%,1/16W,EMPTA   I140 @S9S_MB_2U_LIB.S9S_MB_2U(SCH_1):PAGE126
   R93    1      A Q_RES_0402LF-240,1%,1/16W,EMPTA   I141 @S9S_MB_2U_LIB.S9S_MB_2U(SCH_1):PAGE126
  R743    1      A Q_RES_0402LF-150,1%,1/16W,CHIPA    I65 @S9S_MB_2U_LIB.S9S_MB_2U(SCH_1):PAGE135
  R742    1      A Q_RES_0402LF-75,1%,1/16W,CHIP,A    I78 @S9S_MB_2U_LIB.S9S_MB_2U(SCH_1):PAGE135
  R663    1      A Q_RES_0402LF-499,1%,1/16W,CHIPA    I18 @S9S_MB_2U_LIB.S9S_MB_2U(SCH_1):PAGE218
  R664    1      A Q_RES_0402LF-499,1%,1/16W,CHIPA    I28 @S9S_MB_2U_LIB.S9S_MB_2U(SCH_1):PAGE218
 R1007    1      A Q_RES_0402LF-4.7K,5%,1/16W,CHIA    I12 @S9S_MB_2U_LIB.S9S_MB_2U(SCH_1):PAGE223
  C560    1      A Q_CAP_0402-0.1UF,25V,10%,X7R,CA    I42 @S9S_MB_2U_LIB.S9S_MB_2U(SCH_1):PAGE223
   U29    1   VCCA PCA9617ADP-PCA9617ADP,SMLF,IC,A    I43 @S9S_MB_2U_LIB.S9S_MB_2U(SCH_1):PAGE223
  R964    1      A Q_RES_0402LF-240,1%,1/16W,CHIPA    I46 @S9S_MB_2U_LIB.S9S_MB_2U(SCH_1):PAGE223
  R963    1      A Q_RES_0402LF-240,1%,1/16W,CHIPA    I48 @S9S_MB_2U_LIB.S9S_MB_2U(SCH_1):PAGE223
  C568    1      A Q_CAP_0402-0.1UF,25V,10%,X7R,CA    I35 @S9S_MB_2U_LIB.S9S_MB_2U(SCH_1):PAGE224
   U31    1   VCCA PCA9517AD-PCA9517AD,SMLF,IC,ALA    I37 @S9S_MB_2U_LIB.S9S_MB_2U(SCH_1):PAGE224
  R972    1      A Q_RES_0402LF-240,1%,1/16W,CHIPA    I49 @S9S_MB_2U_LIB.S9S_MB_2U(SCH_1):PAGE224
  R970    1      A Q_RES_0402LF-240,1%,1/16W,CHIPA    I50 @S9S_MB_2U_LIB.S9S_MB_2U(SCH_1):PAGE224
  R330    2      B Q_RES_1206LF-0,,1/2W,CHIP,CS00A    I34 @S9S_MB_2U_LIB.S9S_MB_2U(SCH_1):PAGE80
  R329    2      B Q_RES_1206LF-0,,1/2W,EMPTY,CS0A    I35 @S9S_MB_2U_LIB.S9S_MB_2U(SCH_1):PAGE80
 R2345    1      A Q_RES_0402LF-49.9,1%,1/16W,EMPA    I15 @S9S_MB_2U_LIB.S9S_MB_2U(SCH_1):PAGE278
 R2593    1      A Q_RES_0402LF-100,1%,1/16W,CHIPA    I29 @S9S_MB_2U_LIB.S9S_MB_2U(SCH_1):PAGE282
 R1718    1      A Q_RES_0402LF-49.9,1%,1/16W,CHIA    I33 @S9S_MB_2U_LIB.S9S_MB_2U(SCH_1):PAGE282
 R2555    2      B Q_RES_0402LF-49.9,1%,1/16W,EMPA   I101 @S9S_MB_2U_LIB.S9S_MB_2U(SCH_1):PAGE270
 R2554    2      B Q_RES_0402LF-49.9,1%,1/16W,CHIA   I100 @S9S_MB_2U_LIB.S9S_MB_2U(SCH_1):PAGE270
 C2449    1      A Q_CAP_C0402-100NF,50V,10%,X7R,A   I104 @S9S_MB_2U_LIB.S9S_MB_2U(SCH_1):PAGE270
 R2354    1      A Q_RES_0402LF-100,1%,1/16W,EMPTA    I14 @S9S_MB_2U_LIB.S9S_MB_2U(SCH_1):PAGE278
 C1337    1      A Q_CAP_0402-0.1UF,25V,10%,X7R,CA    I28 @S9S_MB_2U_LIB.S9S_MB_2U(SCH_1):PAGE282
 C1336    1      A Q_CAP_C0402-10UF,6.3V,20%,X6S,B    I24 @S9S_MB_2U_LIB.S9S_MB_2U(SCH_1):PAGE282
 R2553    2      B Q_RES_0402LF-100,1%,1/16W,CHIPA    I99 @S9S_MB_2U_LIB.S9S_MB_2U(SCH_1):PAGE270
 C2448    1      A Q_CAP_C0603-10UF,4V,20%,EMPTY,A   I103 @S9S_MB_2U_LIB.S9S_MB_2U(SCH_1):PAGE270
 R4396    1      A Q_RES_0402LF-100,1%,1/16W,CHIPA     I4 @S9S_MB_2U_LIB.S9S_MB_2U(SCH_1):PAGE121
  Q139    4     E2 BC847BPN-BC847BPN,SMLF,IC,BA00A     I8 @S9S_MB_2U_LIB.S9S_MB_2U(SCH_1):PAGE121
  R244    1      A Q_RES_0402LF-100,1%,1/16W,CHIPA    I19 @S9S_MB_2U_LIB.S9S_MB_2U(SCH_1):PAGE121
 R4402    1      A Q_RES_0402LF-100,1%,1/16W,CHIPA     I5 @S9S_MB_2U_LIB.S9S_MB_2U(SCH_1):PAGE122
  Q142    4     E2 BC847BPN-BC847BPN,SMLF,IC,BA00A    I10 @S9S_MB_2U_LIB.S9S_MB_2U(SCH_1):PAGE122
  R220    1      A Q_RES_0402LF-100,1%,1/16W,CHIPA    I29 @S9S_MB_2U_LIB.S9S_MB_2U(SCH_1):PAGE122
  R202    1      A Q_RES_0402LF-100,1%,1/16W,CHIPA     I7 @S9S_MB_2U_LIB.S9S_MB_2U(SCH_1):PAGE123
  Q140    4     E2 BC847BPN-BC847BPN,SMLF,IC,BA00A    I11 @S9S_MB_2U_LIB.S9S_MB_2U(SCH_1):PAGE123
  R198    1      A Q_RES_0402LF-301,1%,1/16W,CHIPA    I23 @S9S_MB_2U_LIB.S9S_MB_2U(SCH_1):PAGE123
  R662    1      A Q_RES_0402LF-499,1%,1/16W,CHIPA    I17 @S9S_MB_2U_LIB.S9S_MB_2U(SCH_1):PAGE218
  R669    1      A Q_RES_0402LF-499,1%,1/16W,CHIPA    I29 @S9S_MB_2U_LIB.S9S_MB_2U(SCH_1):PAGE218

PVPP_HBM_CPU0 @S9S_MB_2U_LIB.S9S_MB_2U(SCH_1):PVPP_HBM_CPU0
    U2 CF67 VPP_HBM1 SOCKET4677_AZIF0045P001C01CS-SA     I8 @S9S_MB_2U_LIB.S9S_MB_2U(SCH_1):PAGE37
    U2 CE68 VPP_HBM2 SOCKET4677_AZIF0045P001C01CS-SA     I8 @S9S_MB_2U_LIB.S9S_MB_2U(SCH_1):PAGE37
    U2 CD67 VPP_HBM3 SOCKET4677_AZIF0045P001C01CS-SA     I8 @S9S_MB_2U_LIB.S9S_MB_2U(SCH_1):PAGE37
    U2 CC68 VPP_HBM4 SOCKET4677_AZIF0045P001C01CS-SA     I8 @S9S_MB_2U_LIB.S9S_MB_2U(SCH_1):PAGE37
    U2 CG68 VPP_HBM SOCKET4677_AZIF0045P001C01CS-SA     I8 @S9S_MB_2U_LIB.S9S_MB_2U(SCH_1):PAGE37
 C1396    1      A Q_CAP_C0805-47UF,4V,20%,X6S,CHA    I43 @S9S_MB_2U_LIB.S9S_MB_2U(SCH_1):PAGE75
 C1397    1      A Q_CAP_C0805-47UF,4V,20%,X6S,CHA    I44 @S9S_MB_2U_LIB.S9S_MB_2U(SCH_1):PAGE75
PC1254    1      A Q_CAP_0402-0.1UF,25V,10%,X7R,CA    I38 @S9S_MB_2U_LIB.S9S_MB_2U(SCH_1):PAGE267
PC1255    1      A Q_CAP_C0805-22UF,4V,20%,X6S,CHA    I42 @S9S_MB_2U_LIB.S9S_MB_2U(SCH_1):PAGE267
 C1398    1      A Q_CAP_C0805-47UF,4V,20%,X6S,CHA    I58 @S9S_MB_2U_LIB.S9S_MB_2U(SCH_1):PAGE75
 C1436    1      A Q_CAP_C0201-0.22UF,6.3V,10%,X6A    I59 @S9S_MB_2U_LIB.S9S_MB_2U(SCH_1):PAGE75
 PL118    2      2 Q_INDUCTOR_SMLF-0.68UH,IND,CV+A    I28 @S9S_MB_2U_LIB.S9S_MB_2U(SCH_1):PAGE267
PC1258    1      A Q_CAPP_THLF-560UF,6.3V,20%,OSCA    I49 @S9S_MB_2U_LIB.S9S_MB_2U(SCH_1):PAGE267
PC1256    1      A Q_CAP_C0805-22UF,4V,20%,X6S,CHA    I43 @S9S_MB_2U_LIB.S9S_MB_2U(SCH_1):PAGE267
  PJ64    2      2 Q_SHORT_SM-EMPTY,SHORT6    I41 @S9S_MB_2U_LIB.S9S_MB_2U(SCH_1):PAGE267
PC1257    1      A Q_CAP_C0805-22UF,4V,20%,X6S,CHA    I44 @S9S_MB_2U_LIB.S9S_MB_2U(SCH_1):PAGE267

PVPP_HBM_CPU0_CS @S9S_MB_2U_LIB.S9S_MB_2U(SCH_1):PVPP_HBM_CPU0_CS
PR1336    1      A Q_RES_0402LF-9.76K,1%,1/16W,CHA    I15 @S9S_MB_2U_LIB.S9S_MB_2U(SCH_1):PAGE267
  PU79    3     CS RS53318LR-RS53318LR,SMLF,IC,ALA    I19 @S9S_MB_2U_LIB.S9S_MB_2U(SCH_1):PAGE267

PVPP_HBM_CPU0_FB @S9S_MB_2U_LIB.S9S_MB_2U(SCH_1):PVPP_HBM_CPU0_FB
PR2336    1      A Q_RES_0402LF-26.1K,0.1%,1/16W,A    I34 @S9S_MB_2U_LIB.S9S_MB_2U(SCH_1):PAGE267
PR1310    1      A Q_RES_0402LF-11.3K,0.1%,1/16W,A    I26 @S9S_MB_2U_LIB.S9S_MB_2U(SCH_1):PAGE267
PR1337    1      A Q_RES_0402LF-38.3K,0.1%,1/16W,A    I36 @S9S_MB_2U_LIB.S9S_MB_2U(SCH_1):PAGE267
PC1253    1      A Q_CAP_C0402-680PF,50V,10%,X7R,A    I35 @S9S_MB_2U_LIB.S9S_MB_2U(SCH_1):PAGE267
  PU79    7     FB RS53318LR-RS53318LR,SMLF,IC,ALA    I19 @S9S_MB_2U_LIB.S9S_MB_2U(SCH_1):PAGE267

PVPP_HBM_CPU0_MODE @S9S_MB_2U_LIB.S9S_MB_2U(SCH_1):PVPP_HBM_CPU0_MODE
PR3335    1      A Q_RES_0402LF-30.1K,1%,1/16W,CHA    I18 @S9S_MB_2U_LIB.S9S_MB_2U(SCH_1):PAGE267
  PU79    4   MODE RS53318LR-RS53318LR,SMLF,IC,ALA    I19 @S9S_MB_2U_LIB.S9S_MB_2U(SCH_1):PAGE267

PVPP_HBM_CPU0_REF @S9S_MB_2U_LIB.S9S_MB_2U(SCH_1):PVPP_HBM_CPU0_REF
PC2001    1      A Q_CAP_0402-0.022UF,16V,10%,X7RA    I23 @S9S_MB_2U_LIB.S9S_MB_2U(SCH_1):PAGE267
  PU79    5    REF RS53318LR-RS53318LR,SMLF,IC,ALA    I19 @S9S_MB_2U_LIB.S9S_MB_2U(SCH_1):PAGE267
PC1251    1      A Q_CAP_0402-0.1UF,25V,10%,X7R,CA    I25 @S9S_MB_2U_LIB.S9S_MB_2U(SCH_1):PAGE267

PVPP_HBM_CPU0_VCC @S9S_MB_2U_LIB.S9S_MB_2U(SCH_1):PVPP_HBM_CPU0_VCC
PC2643    1      A Q_CAP_C0402-1UF,25V,10%,X6S,CHA     I4 @S9S_MB_2U_LIB.S9S_MB_2U(SCH_1):PAGE267
PR1335    2      B Q_RES_0402LF-0,5%,1/16W,CHIP,CA     I5 @S9S_MB_2U_LIB.S9S_MB_2U(SCH_1):PAGE267
  PU79   19    VCC RS53318LR-RS53318LR,SMLF,IC,ALA    I19 @S9S_MB_2U_LIB.S9S_MB_2U(SCH_1):PAGE267

PVPP_HBM_CPU1 @S9S_MB_2U_LIB.S9S_MB_2U(SCH_1):PVPP_HBM_CPU1
    U1 CF67 VPP_HBM1 SOCKET4677_AZIF0045P001C01CS-SA     I8 @S9S_MB_2U_LIB.S9S_MB_2U(SCH_1):PAGE68
    U1 CE68 VPP_HBM2 SOCKET4677_AZIF0045P001C01CS-SA     I8 @S9S_MB_2U_LIB.S9S_MB_2U(SCH_1):PAGE68
    U1 CD67 VPP_HBM3 SOCKET4677_AZIF0045P001C01CS-SA     I8 @S9S_MB_2U_LIB.S9S_MB_2U(SCH_1):PAGE68
    U1 CC68 VPP_HBM4 SOCKET4677_AZIF0045P001C01CS-SA     I8 @S9S_MB_2U_LIB.S9S_MB_2U(SCH_1):PAGE68
    U1 CG68 VPP_HBM SOCKET4677_AZIF0045P001C01CS-SA     I8 @S9S_MB_2U_LIB.S9S_MB_2U(SCH_1):PAGE68
 C1388    1      A Q_CAP_C0805-47UF,4V,20%,X6S,CHA    I46 @S9S_MB_2U_LIB.S9S_MB_2U(SCH_1):PAGE78
 C1390    1      A Q_CAP_C0805-47UF,4V,20%,X6S,CHA    I48 @S9S_MB_2U_LIB.S9S_MB_2U(SCH_1):PAGE78
 C1392    1      A Q_CAP_C0805-47UF,4V,20%,X6S,CHA    I53 @S9S_MB_2U_LIB.S9S_MB_2U(SCH_1):PAGE78
 C1437    1      A Q_CAP_C0201-0.22UF,6.3V,10%,X6A    I55 @S9S_MB_2U_LIB.S9S_MB_2U(SCH_1):PAGE78
 PL119    2      2 Q_INDUCTOR_SMLF-0.68UH,IND,CV+A    I33 @S9S_MB_2U_LIB.S9S_MB_2U(SCH_1):PAGE285
PC1269    1      A Q_CAP_C0805-22UF,4V,20%,X6S,CHA    I41 @S9S_MB_2U_LIB.S9S_MB_2U(SCH_1):PAGE285
  PJ66    2      2 Q_SHORT_SM-EMPTY,SHORT6    I46 @S9S_MB_2U_LIB.S9S_MB_2U(SCH_1):PAGE285
PC1267    1      A Q_CAP_0402-0.1UF,25V,10%,X7R,CA    I39 @S9S_MB_2U_LIB.S9S_MB_2U(SCH_1):PAGE285
PC1268    1      A Q_CAP_C0805-22UF,4V,20%,X6S,CHA    I40 @S9S_MB_2U_LIB.S9S_MB_2U(SCH_1):PAGE285
PC1270    1      A Q_CAP_C0805-22UF,4V,20%,X6S,CHA    I47 @S9S_MB_2U_LIB.S9S_MB_2U(SCH_1):PAGE285
PC1771    1      A Q_CAPP_THLF-560UF,6.3V,20%,OSCA    I49 @S9S_MB_2U_LIB.S9S_MB_2U(SCH_1):PAGE285

PVPP_HBM_CPU1_CS @S9S_MB_2U_LIB.S9S_MB_2U(SCH_1):PVPP_HBM_CPU1_CS
  PU80    3     CS RS53318LR-RS53318LR,SMLF,IC,ALA    I25 @S9S_MB_2U_LIB.S9S_MB_2U(SCH_1):PAGE285
PR1339    1      A Q_RES_0402LF-9.76K,1%,1/16W,CHA    I10 @S9S_MB_2U_LIB.S9S_MB_2U(SCH_1):PAGE285

PVPP_HBM_CPU1_FB @S9S_MB_2U_LIB.S9S_MB_2U(SCH_1):PVPP_HBM_CPU1_FB
PR2381    1      A Q_RES_0402LF-26.1K,0.1%,1/16W,A    I30 @S9S_MB_2U_LIB.S9S_MB_2U(SCH_1):PAGE285
PR1314    1      A Q_RES_0402LF-11.3K,0.1%,1/16W,A    I28 @S9S_MB_2U_LIB.S9S_MB_2U(SCH_1):PAGE285
PR1340    1      A Q_RES_0402LF-38.3K,0.1%,1/16W,A    I34 @S9S_MB_2U_LIB.S9S_MB_2U(SCH_1):PAGE285
  PU80    7     FB RS53318LR-RS53318LR,SMLF,IC,ALA    I25 @S9S_MB_2U_LIB.S9S_MB_2U(SCH_1):PAGE285
PC1266    1      A Q_CAP_0402-680PF,50V,10%,X7R,TA    I35 @S9S_MB_2U_LIB.S9S_MB_2U(SCH_1):PAGE285

PVPP_HBM_CPU1_MODE @S9S_MB_2U_LIB.S9S_MB_2U(SCH_1):PVPP_HBM_CPU1_MODE
PR3336    1      A Q_RES_0402LF-30.1K,1%,1/16W,CHA    I18 @S9S_MB_2U_LIB.S9S_MB_2U(SCH_1):PAGE285
  PU80    4   MODE RS53318LR-RS53318LR,SMLF,IC,ALA    I25 @S9S_MB_2U_LIB.S9S_MB_2U(SCH_1):PAGE285

PVPP_HBM_CPU1_REF @S9S_MB_2U_LIB.S9S_MB_2U(SCH_1):PVPP_HBM_CPU1_REF
  PU80    5    REF RS53318LR-RS53318LR,SMLF,IC,ALA    I25 @S9S_MB_2U_LIB.S9S_MB_2U(SCH_1):PAGE285
PC1264    1      A Q_CAP_0402-0.1UF,25V,10%,X7R,CA    I24 @S9S_MB_2U_LIB.S9S_MB_2U(SCH_1):PAGE285
PC2002    1      A Q_CAP_0402-0.022UF,16V,10%,X7RA    I23 @S9S_MB_2U_LIB.S9S_MB_2U(SCH_1):PAGE285

PVPP_HBM_CPU1_VCC @S9S_MB_2U_LIB.S9S_MB_2U(SCH_1):PVPP_HBM_CPU1_VCC
  PU80   19    VCC RS53318LR-RS53318LR,SMLF,IC,ALA    I25 @S9S_MB_2U_LIB.S9S_MB_2U(SCH_1):PAGE285
PR1338    2      B Q_RES_0402LF-0,5%,1/16W,CHIP,CA     I3 @S9S_MB_2U_LIB.S9S_MB_2U(SCH_1):PAGE285
 PC644    1      A Q_CAP_C0402-1UF,25V,10%,X6S,CHA     I1 @S9S_MB_2U_LIB.S9S_MB_2U(SCH_1):PAGE285

PWRGD_CHA_CPU0_DIMM1 @S9S_MB_2U_LIB.S9S_MB_2U(SCH_1):PWRGD_CHA_CPU0_DIMM1
    J1  147 PWR_GOOD||FAIL_N SCONN288_ADR50017P130CC-SCONN2A   I198 @S9S_MB_2U_LIB.S9S_MB_2U(SCH_1):PAGE82
 R2726    1      A Q_RES_0402LF-33.2,1%,1/16W,CHIA    I32 @S9S_MB_2U_LIB.S9S_MB_2U(SCH_1):PAGE114

PWRGD_CHA_CPU0_DIMM2 @S9S_MB_2U_LIB.S9S_MB_2U(SCH_1):PWRGD_CHA_CPU0_DIMM2
    J2  147 PWR_GOOD||FAIL_N SCONN288_ADR50017P087CC-SCONN2A   I177 @S9S_MB_2U_LIB.S9S_MB_2U(SCH_1):PAGE83
 R2727    1      A Q_RES_0402LF-33.2,1%,1/16W,CHIA    I31 @S9S_MB_2U_LIB.S9S_MB_2U(SCH_1):PAGE114

PWRGD_CHA_CPU1_DIMM1 @S9S_MB_2U_LIB.S9S_MB_2U(SCH_1):PWRGD_CHA_CPU1_DIMM1
   J17  147 PWR_GOOD||FAIL_N SCONN288_ADR50017P130CC-SCONN2A    I12 @S9S_MB_2U_LIB.S9S_MB_2U(SCH_1):PAGE98
  R893    1      A Q_RES_0402LF-33.2,1%,1/16W,CHIA    I79 @S9S_MB_2U_LIB.S9S_MB_2U(SCH_1):PAGE114

PWRGD_CHA_CPU1_DIMM2 @S9S_MB_2U_LIB.S9S_MB_2U(SCH_1):PWRGD_CHA_CPU1_DIMM2
   J18  147 PWR_GOOD||FAIL_N SCONN288_ADR50017P087CC-SCONN2A    I24 @S9S_MB_2U_LIB.S9S_MB_2U(SCH_1):PAGE99
  R894    1      A Q_RES_0402LF-33.2,1%,1/16W,CHIA    I78 @S9S_MB_2U_LIB.S9S_MB_2U(SCH_1):PAGE114

PWRGD_CHB_CPU0_DIMM1 @S9S_MB_2U_LIB.S9S_MB_2U(SCH_1):PWRGD_CHB_CPU0_DIMM1
    J3  147 PWR_GOOD||FAIL_N SCONN288_ADR50017P130CC-SCONN2A   I180 @S9S_MB_2U_LIB.S9S_MB_2U(SCH_1):PAGE84
 R2728    1      A Q_RES_0402LF-33.2,1%,1/16W,CHIA    I30 @S9S_MB_2U_LIB.S9S_MB_2U(SCH_1):PAGE114

PWRGD_CHB_CPU0_DIMM2 @S9S_MB_2U_LIB.S9S_MB_2U(SCH_1):PWRGD_CHB_CPU0_DIMM2
    J4  147 PWR_GOOD||FAIL_N SCONN288_ADR50017P087CC-SCONN2A    I23 @S9S_MB_2U_LIB.S9S_MB_2U(SCH_1):PAGE85
  R880    1      A Q_RES_0402LF-33.2,1%,1/16W,CHIA    I29 @S9S_MB_2U_LIB.S9S_MB_2U(SCH_1):PAGE114

PWRGD_CHB_CPU1_DIMM1 @S9S_MB_2U_LIB.S9S_MB_2U(SCH_1):PWRGD_CHB_CPU1_DIMM1
   J19  147 PWR_GOOD||FAIL_N SCONN288_ADR50017P130CC-SCONN2A    I25 @S9S_MB_2U_LIB.S9S_MB_2U(SCH_1):PAGE100
  R895    1      A Q_RES_0402LF-33.2,1%,1/16W,CHIA    I77 @S9S_MB_2U_LIB.S9S_MB_2U(SCH_1):PAGE114

PWRGD_CHB_CPU1_DIMM2 @S9S_MB_2U_LIB.S9S_MB_2U(SCH_1):PWRGD_CHB_CPU1_DIMM2
   J20  147 PWR_GOOD||FAIL_N SCONN288_ADR50017P087CC-SCONN2A    I47 @S9S_MB_2U_LIB.S9S_MB_2U(SCH_1):PAGE101
  R896    1      A Q_RES_0402LF-33.2,1%,1/16W,CHIA    I69 @S9S_MB_2U_LIB.S9S_MB_2U(SCH_1):PAGE114

PWRGD_CHC_CPU0_DIMM1 @S9S_MB_2U_LIB.S9S_MB_2U(SCH_1):PWRGD_CHC_CPU0_DIMM1
    J5  147 PWR_GOOD||FAIL_N SCONN288_ADR50017P130CC-SCONN2A    I24 @S9S_MB_2U_LIB.S9S_MB_2U(SCH_1):PAGE86
 R2729    1      A Q_RES_0402LF-33.2,1%,1/16W,CHIA    I28 @S9S_MB_2U_LIB.S9S_MB_2U(SCH_1):PAGE114

PWRGD_CHC_CPU0_DIMM2 @S9S_MB_2U_LIB.S9S_MB_2U(SCH_1):PWRGD_CHC_CPU0_DIMM2
    J6  147 PWR_GOOD||FAIL_N SCONN288_ADR50017P087CC-SCONN2A    I46 @S9S_MB_2U_LIB.S9S_MB_2U(SCH_1):PAGE87
 R2730    1      A Q_RES_0402LF-33.2,1%,1/16W,CHIA    I27 @S9S_MB_2U_LIB.S9S_MB_2U(SCH_1):PAGE114

PWRGD_CHC_CPU1_DIMM1 @S9S_MB_2U_LIB.S9S_MB_2U(SCH_1):PWRGD_CHC_CPU1_DIMM1
   J21  147 PWR_GOOD||FAIL_N SCONN288_ADR50017P130CC-SCONN2A    I13 @S9S_MB_2U_LIB.S9S_MB_2U(SCH_1):PAGE102
  R897    1      A Q_RES_0402LF-33.2,1%,1/16W,CHIA    I67 @S9S_MB_2U_LIB.S9S_MB_2U(SCH_1):PAGE114

PWRGD_CHC_CPU1_DIMM2 @S9S_MB_2U_LIB.S9S_MB_2U(SCH_1):PWRGD_CHC_CPU1_DIMM2
   J22  147 PWR_GOOD||FAIL_N SCONN288_ADR50017P087CC-SCONN2A    I51 @S9S_MB_2U_LIB.S9S_MB_2U(SCH_1):PAGE103
  R898    1      A Q_RES_0402LF-33.2,1%,1/16W,CHIA    I68 @S9S_MB_2U_LIB.S9S_MB_2U(SCH_1):PAGE114

PWRGD_CHD_CPU0_DIMM1 @S9S_MB_2U_LIB.S9S_MB_2U(SCH_1):PWRGD_CHD_CPU0_DIMM1
    J7  147 PWR_GOOD||FAIL_N SCONN288_ADR50017P130CC-SCONN2A    I12 @S9S_MB_2U_LIB.S9S_MB_2U(SCH_1):PAGE88
 R2731    1      A Q_RES_0402LF-33.2,1%,1/16W,CHIA    I25 @S9S_MB_2U_LIB.S9S_MB_2U(SCH_1):PAGE114

PWRGD_CHD_CPU0_DIMM2 @S9S_MB_2U_LIB.S9S_MB_2U(SCH_1):PWRGD_CHD_CPU0_DIMM2
    J8  147 PWR_GOOD||FAIL_N SCONN288_ADR50017P087CC-SCONN2A    I50 @S9S_MB_2U_LIB.S9S_MB_2U(SCH_1):PAGE89
  R884    1      A Q_RES_0402LF-33.2,1%,1/16W,CHIA    I26 @S9S_MB_2U_LIB.S9S_MB_2U(SCH_1):PAGE114

PWRGD_CHD_CPU1_DIMM1 @S9S_MB_2U_LIB.S9S_MB_2U(SCH_1):PWRGD_CHD_CPU1_DIMM1
   J23  147 PWR_GOOD||FAIL_N SCONN288_ADR50017P130CC-SCONN2A    I25 @S9S_MB_2U_LIB.S9S_MB_2U(SCH_1):PAGE104
  R899    1      A Q_RES_0402LF-33.2,1%,1/16W,CHIA    I65 @S9S_MB_2U_LIB.S9S_MB_2U(SCH_1):PAGE114

PWRGD_CHD_CPU1_DIMM2 @S9S_MB_2U_LIB.S9S_MB_2U(SCH_1):PWRGD_CHD_CPU1_DIMM2
   J24  147 PWR_GOOD||FAIL_N SCONN288_ADR50017P087CC-SCONN2A   I178 @S9S_MB_2U_LIB.S9S_MB_2U(SCH_1):PAGE105
  R900    1      A Q_RES_0402LF-33.2,1%,1/16W,CHIA    I66 @S9S_MB_2U_LIB.S9S_MB_2U(SCH_1):PAGE114

PWRGD_CHE_CPU0_DIMM1 @S9S_MB_2U_LIB.S9S_MB_2U(SCH_1):PWRGD_CHE_CPU0_DIMM1
    J9  147 PWR_GOOD||FAIL_N SCONN288_ADR50017P130CC-SCONN2A    I12 @S9S_MB_2U_LIB.S9S_MB_2U(SCH_1):PAGE90
  R885    1      A Q_RES_0402LF-33.2,1%,1/16W,CHIA    I24 @S9S_MB_2U_LIB.S9S_MB_2U(SCH_1):PAGE114

PWRGD_CHE_CPU0_DIMM2 @S9S_MB_2U_LIB.S9S_MB_2U(SCH_1):PWRGD_CHE_CPU0_DIMM2
   J10  147 PWR_GOOD||FAIL_N SCONN288_ADR50017P087CC-SCONN2A    I13 @S9S_MB_2U_LIB.S9S_MB_2U(SCH_1):PAGE91
  R886    1      A Q_RES_0402LF-33.2,1%,1/16W,CHIA    I23 @S9S_MB_2U_LIB.S9S_MB_2U(SCH_1):PAGE114

PWRGD_CHE_CPU1_DIMM1 @S9S_MB_2U_LIB.S9S_MB_2U(SCH_1):PWRGD_CHE_CPU1_DIMM1
   J25  147 PWR_GOOD||FAIL_N SCONN288_ADR50017P130CC-SCONN2A   I180 @S9S_MB_2U_LIB.S9S_MB_2U(SCH_1):PAGE106
  R901    1      A Q_RES_0402LF-33.2,1%,1/16W,CHIA    I64 @S9S_MB_2U_LIB.S9S_MB_2U(SCH_1):PAGE114

PWRGD_CHE_CPU1_DIMM2 @S9S_MB_2U_LIB.S9S_MB_2U(SCH_1):PWRGD_CHE_CPU1_DIMM2
   J26  147 PWR_GOOD||FAIL_N SCONN288_ADR50017P087CC-SCONN2A   I180 @S9S_MB_2U_LIB.S9S_MB_2U(SCH_1):PAGE107
  R902    1      A Q_RES_0402LF-33.2,1%,1/16W,CHIA    I63 @S9S_MB_2U_LIB.S9S_MB_2U(SCH_1):PAGE114

PWRGD_CHF_CPU0_DIMM1 @S9S_MB_2U_LIB.S9S_MB_2U(SCH_1):PWRGD_CHF_CPU0_DIMM1
   J11  147 PWR_GOOD||FAIL_N SCONN288_ADR50017P130CC-SCONN2A    I25 @S9S_MB_2U_LIB.S9S_MB_2U(SCH_1):PAGE92
 R2732    1      A Q_RES_0402LF-33.2,1%,1/16W,CHIA    I22 @S9S_MB_2U_LIB.S9S_MB_2U(SCH_1):PAGE114

PWRGD_CHF_CPU0_DIMM2 @S9S_MB_2U_LIB.S9S_MB_2U(SCH_1):PWRGD_CHF_CPU0_DIMM2
   J12  147 PWR_GOOD||FAIL_N SCONN288_ADR50017P087CC-SCONN2A    I24 @S9S_MB_2U_LIB.S9S_MB_2U(SCH_1):PAGE93
 R2733    1      A Q_RES_0402LF-33.2,1%,1/16W,CHIA    I21 @S9S_MB_2U_LIB.S9S_MB_2U(SCH_1):PAGE114

PWRGD_CHF_CPU1_DIMM1 @S9S_MB_2U_LIB.S9S_MB_2U(SCH_1):PWRGD_CHF_CPU1_DIMM1
   J27  147 PWR_GOOD||FAIL_N SCONN288_ADR50017P130CC-SCONN2A   I179 @S9S_MB_2U_LIB.S9S_MB_2U(SCH_1):PAGE108
  R903    1      A Q_RES_0402LF-33.2,1%,1/16W,CHIA    I62 @S9S_MB_2U_LIB.S9S_MB_2U(SCH_1):PAGE114

PWRGD_CHF_CPU1_DIMM2 @S9S_MB_2U_LIB.S9S_MB_2U(SCH_1):PWRGD_CHF_CPU1_DIMM2
   J28  147 PWR_GOOD||FAIL_N SCONN288_ADR50017P087CC-SCONN2A    I47 @S9S_MB_2U_LIB.S9S_MB_2U(SCH_1):PAGE109
 R2736    1      A Q_RES_0402LF-33.2,1%,1/16W,CHIA    I61 @S9S_MB_2U_LIB.S9S_MB_2U(SCH_1):PAGE114

PWRGD_CHG_CPU0_DIMM1 @S9S_MB_2U_LIB.S9S_MB_2U(SCH_1):PWRGD_CHG_CPU0_DIMM1
   J13  147 PWR_GOOD||FAIL_N SCONN288_ADR50017P130CC-SCONN2A    I11 @S9S_MB_2U_LIB.S9S_MB_2U(SCH_1):PAGE94
  R889    1      A Q_RES_0402LF-33.2,1%,1/16W,CHIA    I20 @S9S_MB_2U_LIB.S9S_MB_2U(SCH_1):PAGE114

PWRGD_CHG_CPU0_DIMM2 @S9S_MB_2U_LIB.S9S_MB_2U(SCH_1):PWRGD_CHG_CPU0_DIMM2
   J14  147 PWR_GOOD||FAIL_N SCONN288_ADR50017P087CC-SCONN2A    I47 @S9S_MB_2U_LIB.S9S_MB_2U(SCH_1):PAGE95
  R890    1      A Q_RES_0402LF-33.2,1%,1/16W,CHIA    I19 @S9S_MB_2U_LIB.S9S_MB_2U(SCH_1):PAGE114

PWRGD_CHG_CPU1_DIMM1 @S9S_MB_2U_LIB.S9S_MB_2U(SCH_1):PWRGD_CHG_CPU1_DIMM1
   J29  147 PWR_GOOD||FAIL_N SCONN288_ADR50017P130CC-SCONN2A   I179 @S9S_MB_2U_LIB.S9S_MB_2U(SCH_1):PAGE110
  R905    1      A Q_RES_0402LF-33.2,1%,1/16W,CHIA    I60 @S9S_MB_2U_LIB.S9S_MB_2U(SCH_1):PAGE114

PWRGD_CHG_CPU1_DIMM2 @S9S_MB_2U_LIB.S9S_MB_2U(SCH_1):PWRGD_CHG_CPU1_DIMM2
   J30  147 PWR_GOOD||FAIL_N SCONN288_ADR50017P087CC-SCONN2A   I179 @S9S_MB_2U_LIB.S9S_MB_2U(SCH_1):PAGE111
  R906    1      A Q_RES_0402LF-33.2,1%,1/16W,CHIA    I59 @S9S_MB_2U_LIB.S9S_MB_2U(SCH_1):PAGE114

PWRGD_CHH_CPU0_DIMM1 @S9S_MB_2U_LIB.S9S_MB_2U(SCH_1):PWRGD_CHH_CPU0_DIMM1
   J15  147 PWR_GOOD||FAIL_N SCONN288_ADR50017P130CC-SCONN2A    I48 @S9S_MB_2U_LIB.S9S_MB_2U(SCH_1):PAGE96
 R2734    1      A Q_RES_0402LF-33.2,1%,1/16W,CHIA    I18 @S9S_MB_2U_LIB.S9S_MB_2U(SCH_1):PAGE114

PWRGD_CHH_CPU0_DIMM2 @S9S_MB_2U_LIB.S9S_MB_2U(SCH_1):PWRGD_CHH_CPU0_DIMM2
   J16  147 PWR_GOOD||FAIL_N SCONN288_ADR50017P087CC-SCONN2A     I6 @S9S_MB_2U_LIB.S9S_MB_2U(SCH_1):PAGE97
 R2735    1      A Q_RES_0402LF-33.2,1%,1/16W,CHIA    I17 @S9S_MB_2U_LIB.S9S_MB_2U(SCH_1):PAGE114

PWRGD_CHH_CPU1_DIMM1 @S9S_MB_2U_LIB.S9S_MB_2U(SCH_1):PWRGD_CHH_CPU1_DIMM1
   J31  147 PWR_GOOD||FAIL_N SCONN288_ADR50017P130CC-SCONN2A   I180 @S9S_MB_2U_LIB.S9S_MB_2U(SCH_1):PAGE112
  R907    1      A Q_RES_0402LF-33.2,1%,1/16W,CHIA    I58 @S9S_MB_2U_LIB.S9S_MB_2U(SCH_1):PAGE114

PWRGD_CHH_CPU1_DIMM2 @S9S_MB_2U_LIB.S9S_MB_2U(SCH_1):PWRGD_CHH_CPU1_DIMM2
   J32  147 PWR_GOOD||FAIL_N SCONN288_ADR50017P087CC-SCONN2A   I179 @S9S_MB_2U_LIB.S9S_MB_2U(SCH_1):PAGE113
  R908    1      A Q_RES_0402LF-33.2,1%,1/16W,CHIA    I57 @S9S_MB_2U_LIB.S9S_MB_2U(SCH_1):PAGE114

PWRGD_CPU0_BUF_R @S9S_MB_2U_LIB.S9S_MB_2U(SCH_1):PWRGD_CPU0_BUF_R
  R168    2      B Q_RES_0402LF-0,5%,1/16W,CHIP,CA    I43 @S9S_MB_2U_LIB.S9S_MB_2U(SCH_1):PAGE124
  R183    1      A Q_RES_0402LF-100,1%,1/16W,CHIPA    I62 @S9S_MB_2U_LIB.S9S_MB_2U(SCH_1):PAGE124
  R184    1      A Q_RES_0402LF-100,1%,1/16W,CHIPA    I77 @S9S_MB_2U_LIB.S9S_MB_2U(SCH_1):PAGE124

PWRGD_CPU0_LVC1 @S9S_MB_2U_LIB.S9S_MB_2U(SCH_1):PWRGD_CPU0_LVC1
    U2 AV20 PWRGOOD SOCKET4677_AZIF0045P001C01CS-SA     I1 @S9S_MB_2U_LIB.S9S_MB_2U(SCH_1):PAGE14
  R184    2      B Q_RES_0402LF-100,1%,1/16W,CHIPA    I77 @S9S_MB_2U_LIB.S9S_MB_2U(SCH_1):PAGE124

PWRGD_CPU0_LVC1_R @S9S_MB_2U_LIB.S9S_MB_2U(SCH_1):PWRGD_CPU0_LVC1_R
  R168    1      A Q_RES_0402LF-0,5%,1/16W,CHIP,CA    I43 @S9S_MB_2U_LIB.S9S_MB_2U(SCH_1):PAGE124
  R992    1      A Q_RES_0402LF-2K,1%,1/16W,EMPTYA    I21 @S9S_MB_2U_LIB.S9S_MB_2U(SCH_1):PAGE208
  U249   W2  PL28B LCMXO3LF9400C5BG484C-LCMXO3LF-A    I33 @S9S_MB_2U_LIB.S9S_MB_2U(SCH_1):PAGE311

PWRGD_CPU1_BUF_R @S9S_MB_2U_LIB.S9S_MB_2U(SCH_1):PWRGD_CPU1_BUF_R
  R130    2      B Q_RES_0402LF-0,5%,1/16W,CHIP,CA     I5 @S9S_MB_2U_LIB.S9S_MB_2U(SCH_1):PAGE125
  R155    1      A Q_RES_0402LF-100,1%,1/16W,CHIPA    I26 @S9S_MB_2U_LIB.S9S_MB_2U(SCH_1):PAGE125
  R156    1      A Q_RES_0402LF-100,1%,1/16W,CHIPA    I64 @S9S_MB_2U_LIB.S9S_MB_2U(SCH_1):PAGE125

PWRGD_CPU1_LVC1 @S9S_MB_2U_LIB.S9S_MB_2U(SCH_1):PWRGD_CPU1_LVC1
    U1 AV20 PWRGOOD SOCKET4677_AZIF0045P001C01CS-SA    I29 @S9S_MB_2U_LIB.S9S_MB_2U(SCH_1):PAGE45
  R156    2      B Q_RES_0402LF-100,1%,1/16W,CHIPA    I64 @S9S_MB_2U_LIB.S9S_MB_2U(SCH_1):PAGE125

PWRGD_CPU1_LVC1_R @S9S_MB_2U_LIB.S9S_MB_2U(SCH_1):PWRGD_CPU1_LVC1_R
  R130    1      A Q_RES_0402LF-0,5%,1/16W,CHIP,CA     I5 @S9S_MB_2U_LIB.S9S_MB_2U(SCH_1):PAGE125
 R1398    1      A Q_RES_0402LF-2K,1%,1/16W,EMPTYA    I22 @S9S_MB_2U_LIB.S9S_MB_2U(SCH_1):PAGE208
  U249   W1  PL28A LCMXO3LF9400C5BG484C-LCMXO3LF-A    I33 @S9S_MB_2U_LIB.S9S_MB_2U(SCH_1):PAGE311

PWRGD_CPUPWRGD_GTL @S9S_MB_2U_LIB.S9S_MB_2U(SCH_1):PWRGD_CPUPWRGD_GTL
  R315    1      A Q_RES_0402LF-33.2,1%,1/16W,CHIA    I92 @S9S_MB_2U_LIB.S9S_MB_2U(SCH_1):PAGE118
    U4  G10 CPUPWRGD EMMITSBURG_REV0P9-GFNOCPU04302A    I36 @S9S_MB_2U_LIB.S9S_MB_2U(SCH_1):PAGE174

PWRGD_CPUPWRGD_LVC1 @S9S_MB_2U_LIB.S9S_MB_2U(SCH_1):PWRGD_CPUPWRGD_LVC1
 R1443    1      A Q_RES_0402LF-33.2,1%,1/16W,CHIA    I49 @S9S_MB_2U_LIB.S9S_MB_2U(SCH_1):PAGE211
  U301    6     B3 GTL2014PW-GTL2014PW,SMLF,IC,ALA    I91 @S9S_MB_2U_LIB.S9S_MB_2U(SCH_1):PAGE321

PWRGD_CPUPWRGD_LVC1_R @S9S_MB_2U_LIB.S9S_MB_2U(SCH_1):PWRGD_CPUPWRGD_LVC1_R
  R315    2      B Q_RES_0402LF-33.2,1%,1/16W,CHIA    I92 @S9S_MB_2U_LIB.S9S_MB_2U(SCH_1):PAGE118
 R1443    2      B Q_RES_0402LF-33.2,1%,1/16W,CHIA    I49 @S9S_MB_2U_LIB.S9S_MB_2U(SCH_1):PAGE211

PWRGD_CPUPWRGD_LVC2_R @S9S_MB_2U_LIB.S9S_MB_2U(SCH_1):PWRGD_CPUPWRGD_LVC2_R
 R4021    1      A Q_RES_0402LF-33.2,1%,1/16W,CHIA    I78 @S9S_MB_2U_LIB.S9S_MB_2U(SCH_1):PAGE321
  U301    9     A3 GTL2014PW-GTL2014PW,SMLF,IC,ALA    I91 @S9S_MB_2U_LIB.S9S_MB_2U(SCH_1):PAGE321

PWRGD_CPUPWRGD_LVC2_R1 @S9S_MB_2U_LIB.S9S_MB_2U(SCH_1):PWRGD_CPUPWRGD_LVC2_R1
   Q88    2     G1 MOSFET_NCH_DUAL-PJT138K,SMLF,IA     I8 @S9S_MB_2U_LIB.S9S_MB_2U(SCH_1):PAGE241
  U249   P5  PL21C LCMXO3LF9400C5BG484C-LCMXO3LF-A    I33 @S9S_MB_2U_LIB.S9S_MB_2U(SCH_1):PAGE311
 R4021    2      B Q_RES_0402LF-33.2,1%,1/16W,CHIA    I78 @S9S_MB_2U_LIB.S9S_MB_2U(SCH_1):PAGE321

PWRGD_DRAMPWRGD_CPU0_AB_LVC1_R @S9S_MB_2U_LIB.S9S_MB_2U(SCH_1):PWRGD_DRAMPWRGD_CPU0_AB_LVC1_R
    U2  A43 DDR01_DRAM_PWR_OK SOCKET4677_AZIF0045P001C01CS-SA     I1 @S9S_MB_2U_LIB.S9S_MB_2U(SCH_1):PAGE14
 R4295    2      B Q_RES_0402LF-100,1%,1/16W,CHIPA    I87 @S9S_MB_2U_LIB.S9S_MB_2U(SCH_1):PAGE124

PWRGD_DRAMPWRGD_CPU0_AB_LVC1_R2 @S9S_MB_2U_LIB.S9S_MB_2U(SCH_1):PWRGD_DRAMPWRGD_CPU0_AB_LVC1_R2
  R160    2      B Q_RES_0402LF-0,5%,1/16W,CHIP,CA    I17 @S9S_MB_2U_LIB.S9S_MB_2U(SCH_1):PAGE124
  R175    1      A Q_RES_0402LF-100,1%,1/16W,CHIPA    I76 @S9S_MB_2U_LIB.S9S_MB_2U(SCH_1):PAGE124
 R4295    1      A Q_RES_0402LF-100,1%,1/16W,CHIPA    I87 @S9S_MB_2U_LIB.S9S_MB_2U(SCH_1):PAGE124

PWRGD_DRAMPWRGD_CPU0_AB_R_LVC1 @S9S_MB_2U_LIB.S9S_MB_2U(SCH_1):PWRGD_DRAMPWRGD_CPU0_AB_R_LVC1
  R160    1      A Q_RES_0402LF-0,5%,1/16W,CHIP,CA    I17 @S9S_MB_2U_LIB.S9S_MB_2U(SCH_1):PAGE124
 R1302    1      A Q_RES_0402LF-2K,1%,1/16W,EMPTYA    I12 @S9S_MB_2U_LIB.S9S_MB_2U(SCH_1):PAGE208
  U249   G2 PL7A||PCLKT5_0 LCMXO3LF9400C5BG484C-LCMXO3LF-A    I33 @S9S_MB_2U_LIB.S9S_MB_2U(SCH_1):PAGE311

PWRGD_DRAMPWRGD_CPU0_CD_LVC1_R @S9S_MB_2U_LIB.S9S_MB_2U(SCH_1):PWRGD_DRAMPWRGD_CPU0_CD_LVC1_R
    U2  F47 DDR23_DRAM_PWR_OK SOCKET4677_AZIF0045P001C01CS-SA     I1 @S9S_MB_2U_LIB.S9S_MB_2U(SCH_1):PAGE14
 R4296    2      B Q_RES_0402LF-100,1%,1/16W,CHIPA    I85 @S9S_MB_2U_LIB.S9S_MB_2U(SCH_1):PAGE124

PWRGD_DRAMPWRGD_CPU0_CD_LVC1_R2 @S9S_MB_2U_LIB.S9S_MB_2U(SCH_1):PWRGD_DRAMPWRGD_CPU0_CD_LVC1_R2
  R162    2      B Q_RES_0402LF-0,5%,1/16W,CHIP,CA    I19 @S9S_MB_2U_LIB.S9S_MB_2U(SCH_1):PAGE124
  R177    1      A Q_RES_0402LF-100,1%,1/16W,CHIPA    I72 @S9S_MB_2U_LIB.S9S_MB_2U(SCH_1):PAGE124
 R4296    1      A Q_RES_0402LF-100,1%,1/16W,CHIPA    I85 @S9S_MB_2U_LIB.S9S_MB_2U(SCH_1):PAGE124

PWRGD_DRAMPWRGD_CPU0_CD_R_LVC1 @S9S_MB_2U_LIB.S9S_MB_2U(SCH_1):PWRGD_DRAMPWRGD_CPU0_CD_R_LVC1
  R162    1      A Q_RES_0402LF-0,5%,1/16W,CHIP,CA    I19 @S9S_MB_2U_LIB.S9S_MB_2U(SCH_1):PAGE124
 R1326    1      A Q_RES_0402LF-2K,1%,1/16W,EMPTYA    I11 @S9S_MB_2U_LIB.S9S_MB_2U(SCH_1):PAGE208
  U249   G1 PL7B||PCLKC5_0 LCMXO3LF9400C5BG484C-LCMXO3LF-A    I33 @S9S_MB_2U_LIB.S9S_MB_2U(SCH_1):PAGE311

PWRGD_DRAMPWRGD_CPU0_EF_LVC1_R @S9S_MB_2U_LIB.S9S_MB_2U(SCH_1):PWRGD_DRAMPWRGD_CPU0_EF_LVC1_R
    U2 CY44 DDR45_DRAM_PWR_OK SOCKET4677_AZIF0045P001C01CS-SA     I1 @S9S_MB_2U_LIB.S9S_MB_2U(SCH_1):PAGE14
 R4297    2      B Q_RES_0402LF-100,1%,1/16W,CHIPA    I82 @S9S_MB_2U_LIB.S9S_MB_2U(SCH_1):PAGE124

PWRGD_DRAMPWRGD_CPU0_EF_LVC1_R2 @S9S_MB_2U_LIB.S9S_MB_2U(SCH_1):PWRGD_DRAMPWRGD_CPU0_EF_LVC1_R2
  R164    2      B Q_RES_0402LF-0,5%,1/16W,CHIP,CA    I26 @S9S_MB_2U_LIB.S9S_MB_2U(SCH_1):PAGE124
  R179    1      A Q_RES_0402LF-100,1%,1/16W,CHIPA    I70 @S9S_MB_2U_LIB.S9S_MB_2U(SCH_1):PAGE124
 R4297    1      A Q_RES_0402LF-100,1%,1/16W,CHIPA    I82 @S9S_MB_2U_LIB.S9S_MB_2U(SCH_1):PAGE124

PWRGD_DRAMPWRGD_CPU0_EF_R_LVC1 @S9S_MB_2U_LIB.S9S_MB_2U(SCH_1):PWRGD_DRAMPWRGD_CPU0_EF_R_LVC1
  R164    1      A Q_RES_0402LF-0,5%,1/16W,CHIP,CA    I26 @S9S_MB_2U_LIB.S9S_MB_2U(SCH_1):PAGE124
 R1327    1      A Q_RES_0402LF-2K,1%,1/16W,EMPTYA    I14 @S9S_MB_2U_LIB.S9S_MB_2U(SCH_1):PAGE208
  U249   H4   PL7C LCMXO3LF9400C5BG484C-LCMXO3LF-A    I33 @S9S_MB_2U_LIB.S9S_MB_2U(SCH_1):PAGE311

PWRGD_DRAMPWRGD_CPU0_GH_LVC1_R @S9S_MB_2U_LIB.S9S_MB_2U(SCH_1):PWRGD_DRAMPWRGD_CPU0_GH_LVC1_R
    U2 CW45 DDR67_DRAM_PWR_OK SOCKET4677_AZIF0045P001C01CS-SA     I1 @S9S_MB_2U_LIB.S9S_MB_2U(SCH_1):PAGE14
 R4298    2      B Q_RES_0402LF-100,1%,1/16W,CHIPA    I79 @S9S_MB_2U_LIB.S9S_MB_2U(SCH_1):PAGE124

PWRGD_DRAMPWRGD_CPU0_GH_LVC1_R2 @S9S_MB_2U_LIB.S9S_MB_2U(SCH_1):PWRGD_DRAMPWRGD_CPU0_GH_LVC1_R2
  R166    2      B Q_RES_0402LF-0,5%,1/16W,CHIP,CA    I33 @S9S_MB_2U_LIB.S9S_MB_2U(SCH_1):PAGE124
  R181    1      A Q_RES_0402LF-100,1%,1/16W,CHIPA    I68 @S9S_MB_2U_LIB.S9S_MB_2U(SCH_1):PAGE124
 R4298    1      A Q_RES_0402LF-100,1%,1/16W,CHIPA    I79 @S9S_MB_2U_LIB.S9S_MB_2U(SCH_1):PAGE124

PWRGD_DRAMPWRGD_CPU0_GH_R_LVC1 @S9S_MB_2U_LIB.S9S_MB_2U(SCH_1):PWRGD_DRAMPWRGD_CPU0_GH_R_LVC1
  R166    1      A Q_RES_0402LF-0,5%,1/16W,CHIP,CA    I33 @S9S_MB_2U_LIB.S9S_MB_2U(SCH_1):PAGE124
 R1328    1      A Q_RES_0402LF-2K,1%,1/16W,EMPTYA    I13 @S9S_MB_2U_LIB.S9S_MB_2U(SCH_1):PAGE208
  U249   H3   PL7D LCMXO3LF9400C5BG484C-LCMXO3LF-A    I33 @S9S_MB_2U_LIB.S9S_MB_2U(SCH_1):PAGE311

PWRGD_DRAMPWRGD_CPU1_AB_LVC1_R @S9S_MB_2U_LIB.S9S_MB_2U(SCH_1):PWRGD_DRAMPWRGD_CPU1_AB_LVC1_R
    U1  A43 DDR01_DRAM_PWR_OK SOCKET4677_AZIF0045P001C01CS-SA    I29 @S9S_MB_2U_LIB.S9S_MB_2U(SCH_1):PAGE45
 R4299    2      B Q_RES_0402LF-100,1%,1/16W,CHIPA    I72 @S9S_MB_2U_LIB.S9S_MB_2U(SCH_1):PAGE125

PWRGD_DRAMPWRGD_CPU1_AB_LVC1_R2 @S9S_MB_2U_LIB.S9S_MB_2U(SCH_1):PWRGD_DRAMPWRGD_CPU1_AB_LVC1_R2
  R122    2      B Q_RES_0402LF-0,5%,1/16W,CHIP,CA    I17 @S9S_MB_2U_LIB.S9S_MB_2U(SCH_1):PAGE125
  R135    1      A Q_RES_0402LF-100,1%,1/16W,CHIPA    I62 @S9S_MB_2U_LIB.S9S_MB_2U(SCH_1):PAGE125
 R4299    1      A Q_RES_0402LF-100,1%,1/16W,CHIPA    I72 @S9S_MB_2U_LIB.S9S_MB_2U(SCH_1):PAGE125

PWRGD_DRAMPWRGD_CPU1_AB_R_LVC1 @S9S_MB_2U_LIB.S9S_MB_2U(SCH_1):PWRGD_DRAMPWRGD_CPU1_AB_R_LVC1
  R122    1      A Q_RES_0402LF-0,5%,1/16W,CHIP,CA    I17 @S9S_MB_2U_LIB.S9S_MB_2U(SCH_1):PAGE125
 R1329    1      A Q_RES_0402LF-2K,1%,1/16W,EMPTYA    I15 @S9S_MB_2U_LIB.S9S_MB_2U(SCH_1):PAGE208
  U249   H2  PL10A LCMXO3LF9400C5BG484C-LCMXO3LF-A    I33 @S9S_MB_2U_LIB.S9S_MB_2U(SCH_1):PAGE311

PWRGD_DRAMPWRGD_CPU1_CD_LVC1_R @S9S_MB_2U_LIB.S9S_MB_2U(SCH_1):PWRGD_DRAMPWRGD_CPU1_CD_LVC1_R
    U1  F47 DDR23_DRAM_PWR_OK SOCKET4677_AZIF0045P001C01CS-SA    I29 @S9S_MB_2U_LIB.S9S_MB_2U(SCH_1):PAGE45
 R4300    2      B Q_RES_0402LF-100,1%,1/16W,CHIPA    I70 @S9S_MB_2U_LIB.S9S_MB_2U(SCH_1):PAGE125

PWRGD_DRAMPWRGD_CPU1_CD_LVC1_R2 @S9S_MB_2U_LIB.S9S_MB_2U(SCH_1):PWRGD_DRAMPWRGD_CPU1_CD_LVC1_R2
  R124    2      B Q_RES_0402LF-0,5%,1/16W,CHIP,CA    I15 @S9S_MB_2U_LIB.S9S_MB_2U(SCH_1):PAGE125
  R137    1      A Q_RES_0402LF-100,1%,1/16W,CHIPA    I60 @S9S_MB_2U_LIB.S9S_MB_2U(SCH_1):PAGE125
 R4300    1      A Q_RES_0402LF-100,1%,1/16W,CHIPA    I70 @S9S_MB_2U_LIB.S9S_MB_2U(SCH_1):PAGE125

PWRGD_DRAMPWRGD_CPU1_CD_R_LVC1 @S9S_MB_2U_LIB.S9S_MB_2U(SCH_1):PWRGD_DRAMPWRGD_CPU1_CD_R_LVC1
  R124    1      A Q_RES_0402LF-0,5%,1/16W,CHIP,CA    I15 @S9S_MB_2U_LIB.S9S_MB_2U(SCH_1):PAGE125
 R1330    1      A Q_RES_0402LF-2K,1%,1/16W,EMPTYA    I16 @S9S_MB_2U_LIB.S9S_MB_2U(SCH_1):PAGE208
  U249   H1  PL10B LCMXO3LF9400C5BG484C-LCMXO3LF-A    I33 @S9S_MB_2U_LIB.S9S_MB_2U(SCH_1):PAGE311

PWRGD_DRAMPWRGD_CPU1_EF_LVC1_R @S9S_MB_2U_LIB.S9S_MB_2U(SCH_1):PWRGD_DRAMPWRGD_CPU1_EF_LVC1_R
    U1 CY44 DDR45_DRAM_PWR_OK SOCKET4677_AZIF0045P001C01CS-SA    I29 @S9S_MB_2U_LIB.S9S_MB_2U(SCH_1):PAGE45
 R4301    2      B Q_RES_0402LF-100,1%,1/16W,CHIPA    I68 @S9S_MB_2U_LIB.S9S_MB_2U(SCH_1):PAGE125

PWRGD_DRAMPWRGD_CPU1_EF_LVC1_R2 @S9S_MB_2U_LIB.S9S_MB_2U(SCH_1):PWRGD_DRAMPWRGD_CPU1_EF_LVC1_R2
  R126    2      B Q_RES_0402LF-0,5%,1/16W,CHIP,CA    I13 @S9S_MB_2U_LIB.S9S_MB_2U(SCH_1):PAGE125
  R151    1      A Q_RES_0402LF-100,1%,1/16W,CHIPA    I58 @S9S_MB_2U_LIB.S9S_MB_2U(SCH_1):PAGE125
 R4301    1      A Q_RES_0402LF-100,1%,1/16W,CHIPA    I68 @S9S_MB_2U_LIB.S9S_MB_2U(SCH_1):PAGE125

PWRGD_DRAMPWRGD_CPU1_EF_R_LVC1 @S9S_MB_2U_LIB.S9S_MB_2U(SCH_1):PWRGD_DRAMPWRGD_CPU1_EF_R_LVC1
  R126    1      A Q_RES_0402LF-0,5%,1/16W,CHIP,CA    I13 @S9S_MB_2U_LIB.S9S_MB_2U(SCH_1):PAGE125
 R1388    1      A Q_RES_0402LF-2K,1%,1/16W,EMPTYA    I17 @S9S_MB_2U_LIB.S9S_MB_2U(SCH_1):PAGE208
  U249   J7  PL10C LCMXO3LF9400C5BG484C-LCMXO3LF-A    I33 @S9S_MB_2U_LIB.S9S_MB_2U(SCH_1):PAGE311

PWRGD_DRAMPWRGD_CPU1_GH_LVC1_R @S9S_MB_2U_LIB.S9S_MB_2U(SCH_1):PWRGD_DRAMPWRGD_CPU1_GH_LVC1_R
    U1 CW45 DDR67_DRAM_PWR_OK SOCKET4677_AZIF0045P001C01CS-SA    I29 @S9S_MB_2U_LIB.S9S_MB_2U(SCH_1):PAGE45
 R4302    2      B Q_RES_0402LF-100,1%,1/16W,CHIPA    I66 @S9S_MB_2U_LIB.S9S_MB_2U(SCH_1):PAGE125

PWRGD_DRAMPWRGD_CPU1_GH_LVC1_R2 @S9S_MB_2U_LIB.S9S_MB_2U(SCH_1):PWRGD_DRAMPWRGD_CPU1_GH_LVC1_R2
  R128    2      B Q_RES_0402LF-0,5%,1/16W,CHIP,CA     I7 @S9S_MB_2U_LIB.S9S_MB_2U(SCH_1):PAGE125
  R153    1      A Q_RES_0402LF-100,1%,1/16W,CHIPA    I56 @S9S_MB_2U_LIB.S9S_MB_2U(SCH_1):PAGE125
 R4302    1      A Q_RES_0402LF-100,1%,1/16W,CHIPA    I66 @S9S_MB_2U_LIB.S9S_MB_2U(SCH_1):PAGE125

PWRGD_DRAMPWRGD_CPU1_GH_R_LVC1 @S9S_MB_2U_LIB.S9S_MB_2U(SCH_1):PWRGD_DRAMPWRGD_CPU1_GH_R_LVC1
  R128    1      A Q_RES_0402LF-0,5%,1/16W,CHIP,CA     I7 @S9S_MB_2U_LIB.S9S_MB_2U(SCH_1):PAGE125
 R4533    1      A Q_RES_0402LF-2K,1%,1/16W,EMPTYA    I19 @S9S_MB_2U_LIB.S9S_MB_2U(SCH_1):PAGE208
  U249   J6  PL10D LCMXO3LF9400C5BG484C-LCMXO3LF-A    I33 @S9S_MB_2U_LIB.S9S_MB_2U(SCH_1):PAGE311

PWRGD_DSW_PWROK @S9S_MB_2U_LIB.S9S_MB_2U(SCH_1):PWRGD_DSW_PWROK
    U4  BE8 DSW_PWROK EMMITSBURG_REV0P9-GFNOCPU04302A    I36 @S9S_MB_2U_LIB.S9S_MB_2U(SCH_1):PAGE174
 R1694    2      B Q_RES_0402LF-10K,1%,1/16W,CHIPA    I33 @S9S_MB_2U_LIB.S9S_MB_2U(SCH_1):PAGE232
 C1319    1      A Q_CAP_C0402-1UF,25V,10%,X6S,CHA    I35 @S9S_MB_2U_LIB.S9S_MB_2U(SCH_1):PAGE232
 R2412    1      A Q_RES_0402LF-0,5%,1/16W,CHIP,CA    I83 @S9S_MB_2U_LIB.S9S_MB_2U(SCH_1):PAGE313
 R2330    2      B Q_RES_0402LF-0,5%,1/16W,EMPTY,A    I33 @S9S_MB_2U_LIB.S9S_MB_2U(SCH_1):PAGE326
 R4789    2      B Q_RES_0402LF-10K,1%,1/16W,EMPTA    I49 @S9S_MB_2U_LIB.S9S_MB_2U(SCH_1):PAGE329
 R4788    2      B Q_RES_0402LF-33.2,1%,1/16W,EMPA    I50 @S9S_MB_2U_LIB.S9S_MB_2U(SCH_1):PAGE329
 R4808    1      A Q_RES_0402LF-100K,1%,1/16W,EMPA    I31 @S9S_MB_2U_LIB.S9S_MB_2U(SCH_1):PAGE232
 R1693    2      B Q_RES_0402LF-33.2,1%,1/16W,CHIA    I32 @S9S_MB_2U_LIB.S9S_MB_2U(SCH_1):PAGE232
 R1695    1      A Q_RES_0402LF-0,5%,1/16W,EMPTY,A    I36 @S9S_MB_2U_LIB.S9S_MB_2U(SCH_1):PAGE232

PWRGD_DSW_PWROK_R1 @S9S_MB_2U_LIB.S9S_MB_2U(SCH_1):PWRGD_DSW_PWROK_R1
 R1691    2      B Q_RES_0402LF-10K,1%,1/16W,EMPTA     I4 @S9S_MB_2U_LIB.S9S_MB_2U(SCH_1):PAGE232
 R1692    1      A Q_RES_0402LF-100K,1%,1/16W,CHIA     I3 @S9S_MB_2U_LIB.S9S_MB_2U(SCH_1):PAGE232
 C1318    1      A Q_CAP_C0402-1UF,25V,10%,EMPTY,A     I7 @S9S_MB_2U_LIB.S9S_MB_2U(SCH_1):PAGE232
   U95    2      A 74LVC1G07SE7-74LVC1G07SE-7,SMLA    I11 @S9S_MB_2U_LIB.S9S_MB_2U(SCH_1):PAGE232
 R4807    1      A Q_RES_0402LF-0,5%,1/16W,EMPTY,A    I13 @S9S_MB_2U_LIB.S9S_MB_2U(SCH_1):PAGE232
  U117    4 SENSE_OUT TPS3895ADRYR-TPS3895ADRYR,SMLFA    I26 @S9S_MB_2U_LIB.S9S_MB_2U(SCH_1):PAGE232
   U94    4  ENOUT ADM1086AKSZREEL7-ADM1086AKSZ-RA    I27 @S9S_MB_2U_LIB.S9S_MB_2U(SCH_1):PAGE232

PWRGD_DSW_PWROK_R2 @S9S_MB_2U_LIB.S9S_MB_2U(SCH_1):PWRGD_DSW_PWROK_R2
   U95    4      Y 74LVC1G07SE7-74LVC1G07SE-7,SMLA    I11 @S9S_MB_2U_LIB.S9S_MB_2U(SCH_1):PAGE232
 R4807    2      B Q_RES_0402LF-0,5%,1/16W,EMPTY,A    I13 @S9S_MB_2U_LIB.S9S_MB_2U(SCH_1):PAGE232
 R1693    1      A Q_RES_0402LF-33.2,1%,1/16W,CHIA    I32 @S9S_MB_2U_LIB.S9S_MB_2U(SCH_1):PAGE232

PWRGD_DSW_PWROK_R3 @S9S_MB_2U_LIB.S9S_MB_2U(SCH_1):PWRGD_DSW_PWROK_R3
  U249  T22  PR21A LCMXO3LF9400C5BG484C-LCMXO3LF-A     I1 @S9S_MB_2U_LIB.S9S_MB_2U(SCH_1):PAGE313
 R2412    2      B Q_RES_0402LF-0,5%,1/16W,CHIP,CA    I83 @S9S_MB_2U_LIB.S9S_MB_2U(SCH_1):PAGE313

PWRGD_DSW_PWROK_R4 @S9S_MB_2U_LIB.S9S_MB_2U(SCH_1):PWRGD_DSW_PWROK_R4
  U205    1   OUTA TPS3700DDCR-TPS3700DDCR,SMLF,EA     I5 @S9S_MB_2U_LIB.S9S_MB_2U(SCH_1):PAGE326
 R2330    1      A Q_RES_0402LF-0,5%,1/16W,EMPTY,A    I33 @S9S_MB_2U_LIB.S9S_MB_2U(SCH_1):PAGE326

PWRGD_DSW_PWROK_R5 @S9S_MB_2U_LIB.S9S_MB_2U(SCH_1):PWRGD_DSW_PWROK_R5
  U342    4 OUTPUT AP331AWG7-AP331AWG-7,SMLF,EMPTA    I45 @S9S_MB_2U_LIB.S9S_MB_2U(SCH_1):PAGE329
 R4787    2      B Q_RES_0402LF-1M,1%,1/16W,EMPTYA    I46 @S9S_MB_2U_LIB.S9S_MB_2U(SCH_1):PAGE329
 R4788    1      A Q_RES_0402LF-33.2,1%,1/16W,EMPA    I50 @S9S_MB_2U_LIB.S9S_MB_2U(SCH_1):PAGE329

PWRGD_DSW_PWROK_TRIGGER @S9S_MB_2U_LIB.S9S_MB_2U(SCH_1):PWRGD_DSW_PWROK_TRIGGER
  U342    3    IN+ AP331AWG7-AP331AWG-7,SMLF,EMPTA    I45 @S9S_MB_2U_LIB.S9S_MB_2U(SCH_1):PAGE329
 R4787    1      A Q_RES_0402LF-1M,1%,1/16W,EMPTYA    I46 @S9S_MB_2U_LIB.S9S_MB_2U(SCH_1):PAGE329
 C2386    1      A Q_CAP_C0402-100NF,50V,10%,EMPTA    I55 @S9S_MB_2U_LIB.S9S_MB_2U(SCH_1):PAGE329
 R4790    2      B Q_RES_0402LF-4.75K,1%,1/16W,EMA    I67 @S9S_MB_2U_LIB.S9S_MB_2U(SCH_1):PAGE329
 R4791    1      A Q_RES_0402LF-2K,1%,1/16W,EMPTYA    I68 @S9S_MB_2U_LIB.S9S_MB_2U(SCH_1):PAGE329

PWRGD_FAIL_CPU0_AB @S9S_MB_2U_LIB.S9S_MB_2U(SCH_1):PWRGD_FAIL_CPU0_AB
 R2490    1      A Q_RES_0402LF-1K,1%,1/16W,CHIP,A    I46 @S9S_MB_2U_LIB.S9S_MB_2U(SCH_1):PAGE115
  R880    2      B Q_RES_0402LF-33.2,1%,1/16W,CHIA    I29 @S9S_MB_2U_LIB.S9S_MB_2U(SCH_1):PAGE114
 R2728    2      B Q_RES_0402LF-33.2,1%,1/16W,CHIA    I30 @S9S_MB_2U_LIB.S9S_MB_2U(SCH_1):PAGE114
 R2727    2      B Q_RES_0402LF-33.2,1%,1/16W,CHIA    I31 @S9S_MB_2U_LIB.S9S_MB_2U(SCH_1):PAGE114
 R2726    2      B Q_RES_0402LF-33.2,1%,1/16W,CHIA    I32 @S9S_MB_2U_LIB.S9S_MB_2U(SCH_1):PAGE114

PWRGD_FAIL_CPU0_AB_R @S9S_MB_2U_LIB.S9S_MB_2U(SCH_1):PWRGD_FAIL_CPU0_AB_R
  U249  W22  PR25B LCMXO3LF9400C5BG484C-LCMXO3LF-A     I1 @S9S_MB_2U_LIB.S9S_MB_2U(SCH_1):PAGE313
 R2498    2      B Q_RES_0402LF-33.2,1%,1/16W,CHIA    I72 @S9S_MB_2U_LIB.S9S_MB_2U(SCH_1):PAGE115

PWRGD_FAIL_CPU0_AB_R1 @S9S_MB_2U_LIB.S9S_MB_2U(SCH_1):PWRGD_FAIL_CPU0_AB_R1
 R2490    2      B Q_RES_0402LF-1K,1%,1/16W,CHIP,A    I46 @S9S_MB_2U_LIB.S9S_MB_2U(SCH_1):PAGE115
  R940    2      B Q_RES_0402LF-10K,1%,1/16W,CHIPA    I48 @S9S_MB_2U_LIB.S9S_MB_2U(SCH_1):PAGE115
   D42    1      A SCHOTTKY_12-B0530WS7F,SMLF,IC,A    I59 @S9S_MB_2U_LIB.S9S_MB_2U(SCH_1):PAGE115
 R2498    1      A Q_RES_0402LF-33.2,1%,1/16W,CHIA    I72 @S9S_MB_2U_LIB.S9S_MB_2U(SCH_1):PAGE115

PWRGD_FAIL_CPU0_CD @S9S_MB_2U_LIB.S9S_MB_2U(SCH_1):PWRGD_FAIL_CPU0_CD
 R2491    1      A Q_RES_0402LF-1K,1%,1/16W,CHIP,A    I42 @S9S_MB_2U_LIB.S9S_MB_2U(SCH_1):PAGE115
  R884    2      B Q_RES_0402LF-33.2,1%,1/16W,CHIA    I26 @S9S_MB_2U_LIB.S9S_MB_2U(SCH_1):PAGE114
 R2729    2      B Q_RES_0402LF-33.2,1%,1/16W,CHIA    I28 @S9S_MB_2U_LIB.S9S_MB_2U(SCH_1):PAGE114
 R2731    2      B Q_RES_0402LF-33.2,1%,1/16W,CHIA    I25 @S9S_MB_2U_LIB.S9S_MB_2U(SCH_1):PAGE114
 R2730    2      B Q_RES_0402LF-33.2,1%,1/16W,CHIA    I27 @S9S_MB_2U_LIB.S9S_MB_2U(SCH_1):PAGE114

PWRGD_FAIL_CPU0_CD_R @S9S_MB_2U_LIB.S9S_MB_2U(SCH_1):PWRGD_FAIL_CPU0_CD_R
  U249  R20  PR25C LCMXO3LF9400C5BG484C-LCMXO3LF-A     I1 @S9S_MB_2U_LIB.S9S_MB_2U(SCH_1):PAGE313
 R2499    2      B Q_RES_0402LF-33.2,1%,1/16W,CHIA    I71 @S9S_MB_2U_LIB.S9S_MB_2U(SCH_1):PAGE115

PWRGD_FAIL_CPU0_CD_R1 @S9S_MB_2U_LIB.S9S_MB_2U(SCH_1):PWRGD_FAIL_CPU0_CD_R1
 R2491    2      B Q_RES_0402LF-1K,1%,1/16W,CHIP,A    I42 @S9S_MB_2U_LIB.S9S_MB_2U(SCH_1):PAGE115
  R941    2      B Q_RES_0402LF-10K,1%,1/16W,CHIPA    I45 @S9S_MB_2U_LIB.S9S_MB_2U(SCH_1):PAGE115
   D43    1      A SCHOTTKY_12-B0530WS7F,SMLF,IC,A    I54 @S9S_MB_2U_LIB.S9S_MB_2U(SCH_1):PAGE115
 R2499    1      A Q_RES_0402LF-33.2,1%,1/16W,CHIA    I71 @S9S_MB_2U_LIB.S9S_MB_2U(SCH_1):PAGE115

PWRGD_FAIL_CPU0_EF @S9S_MB_2U_LIB.S9S_MB_2U(SCH_1):PWRGD_FAIL_CPU0_EF
 R2733    2      B Q_RES_0402LF-33.2,1%,1/16W,CHIA    I21 @S9S_MB_2U_LIB.S9S_MB_2U(SCH_1):PAGE114
  R886    2      B Q_RES_0402LF-33.2,1%,1/16W,CHIA    I23 @S9S_MB_2U_LIB.S9S_MB_2U(SCH_1):PAGE114
  R885    2      B Q_RES_0402LF-33.2,1%,1/16W,CHIA    I24 @S9S_MB_2U_LIB.S9S_MB_2U(SCH_1):PAGE114
 R2492    1      A Q_RES_0402LF-1K,1%,1/16W,CHIP,A    I41 @S9S_MB_2U_LIB.S9S_MB_2U(SCH_1):PAGE115
 R2732    2      B Q_RES_0402LF-33.2,1%,1/16W,CHIA    I22 @S9S_MB_2U_LIB.S9S_MB_2U(SCH_1):PAGE114

PWRGD_FAIL_CPU0_EF_R @S9S_MB_2U_LIB.S9S_MB_2U(SCH_1):PWRGD_FAIL_CPU0_EF_R
  U249  R19  PR25D LCMXO3LF9400C5BG484C-LCMXO3LF-A     I1 @S9S_MB_2U_LIB.S9S_MB_2U(SCH_1):PAGE313
 R2500    2      B Q_RES_0402LF-33.2,1%,1/16W,CHIA    I70 @S9S_MB_2U_LIB.S9S_MB_2U(SCH_1):PAGE115

PWRGD_FAIL_CPU0_EF_R1 @S9S_MB_2U_LIB.S9S_MB_2U(SCH_1):PWRGD_FAIL_CPU0_EF_R1
  R942    2      B Q_RES_0402LF-10K,1%,1/16W,CHIPA    I40 @S9S_MB_2U_LIB.S9S_MB_2U(SCH_1):PAGE115
 R2492    2      B Q_RES_0402LF-1K,1%,1/16W,CHIP,A    I41 @S9S_MB_2U_LIB.S9S_MB_2U(SCH_1):PAGE115
   D44    1      A SCHOTTKY_12-B0530WS7F,SMLF,IC,A    I52 @S9S_MB_2U_LIB.S9S_MB_2U(SCH_1):PAGE115
 R2500    1      A Q_RES_0402LF-33.2,1%,1/16W,CHIA    I70 @S9S_MB_2U_LIB.S9S_MB_2U(SCH_1):PAGE115

PWRGD_FAIL_CPU0_GH @S9S_MB_2U_LIB.S9S_MB_2U(SCH_1):PWRGD_FAIL_CPU0_GH
 R2493    1      A Q_RES_0402LF-1K,1%,1/16W,CHIP,A    I38 @S9S_MB_2U_LIB.S9S_MB_2U(SCH_1):PAGE115
 R2735    2      B Q_RES_0402LF-33.2,1%,1/16W,CHIA    I17 @S9S_MB_2U_LIB.S9S_MB_2U(SCH_1):PAGE114
 R2734    2      B Q_RES_0402LF-33.2,1%,1/16W,CHIA    I18 @S9S_MB_2U_LIB.S9S_MB_2U(SCH_1):PAGE114
  R890    2      B Q_RES_0402LF-33.2,1%,1/16W,CHIA    I19 @S9S_MB_2U_LIB.S9S_MB_2U(SCH_1):PAGE114
  R889    2      B Q_RES_0402LF-33.2,1%,1/16W,CHIA    I20 @S9S_MB_2U_LIB.S9S_MB_2U(SCH_1):PAGE114

PWRGD_FAIL_CPU0_GH_R @S9S_MB_2U_LIB.S9S_MB_2U(SCH_1):PWRGD_FAIL_CPU0_GH_R
  U249  R18  PR26A LCMXO3LF9400C5BG484C-LCMXO3LF-A     I1 @S9S_MB_2U_LIB.S9S_MB_2U(SCH_1):PAGE313
 R2501    2      B Q_RES_0402LF-33.2,1%,1/16W,CHIA    I69 @S9S_MB_2U_LIB.S9S_MB_2U(SCH_1):PAGE115

PWRGD_FAIL_CPU0_GH_R1 @S9S_MB_2U_LIB.S9S_MB_2U(SCH_1):PWRGD_FAIL_CPU0_GH_R1
 R2493    2      B Q_RES_0402LF-1K,1%,1/16W,CHIP,A    I38 @S9S_MB_2U_LIB.S9S_MB_2U(SCH_1):PAGE115
  R943    2      B Q_RES_0402LF-10K,1%,1/16W,CHIPA    I37 @S9S_MB_2U_LIB.S9S_MB_2U(SCH_1):PAGE115
   D45    1      A SCHOTTKY_12-B0530WS7F,SMLF,IC,A    I50 @S9S_MB_2U_LIB.S9S_MB_2U(SCH_1):PAGE115
 R2501    1      A Q_RES_0402LF-33.2,1%,1/16W,CHIA    I69 @S9S_MB_2U_LIB.S9S_MB_2U(SCH_1):PAGE115

PWRGD_FAIL_CPU1_AB @S9S_MB_2U_LIB.S9S_MB_2U(SCH_1):PWRGD_FAIL_CPU1_AB
  R896    2      B Q_RES_0402LF-33.2,1%,1/16W,CHIA    I69 @S9S_MB_2U_LIB.S9S_MB_2U(SCH_1):PAGE114
 R2494    1      A Q_RES_0402LF-1K,1%,1/16W,CHIP,A    I18 @S9S_MB_2U_LIB.S9S_MB_2U(SCH_1):PAGE115
  R895    2      B Q_RES_0402LF-33.2,1%,1/16W,CHIA    I77 @S9S_MB_2U_LIB.S9S_MB_2U(SCH_1):PAGE114
  R894    2      B Q_RES_0402LF-33.2,1%,1/16W,CHIA    I78 @S9S_MB_2U_LIB.S9S_MB_2U(SCH_1):PAGE114
  R893    2      B Q_RES_0402LF-33.2,1%,1/16W,CHIA    I79 @S9S_MB_2U_LIB.S9S_MB_2U(SCH_1):PAGE114

PWRGD_FAIL_CPU1_AB_R @S9S_MB_2U_LIB.S9S_MB_2U(SCH_1):PWRGD_FAIL_CPU1_AB_R
  U249  R17  PR26B LCMXO3LF9400C5BG484C-LCMXO3LF-A     I1 @S9S_MB_2U_LIB.S9S_MB_2U(SCH_1):PAGE313
 R2502    2      B Q_RES_0402LF-33.2,1%,1/16W,CHIA    I68 @S9S_MB_2U_LIB.S9S_MB_2U(SCH_1):PAGE115

PWRGD_FAIL_CPU1_AB_R1 @S9S_MB_2U_LIB.S9S_MB_2U(SCH_1):PWRGD_FAIL_CPU1_AB_R1
  R944    2      B Q_RES_0402LF-10K,1%,1/16W,CHIPA    I19 @S9S_MB_2U_LIB.S9S_MB_2U(SCH_1):PAGE115
 R2494    2      B Q_RES_0402LF-1K,1%,1/16W,CHIP,A    I18 @S9S_MB_2U_LIB.S9S_MB_2U(SCH_1):PAGE115
   D46    1      A SCHOTTKY_12-B0530WS7F,SMLF,IC,A    I29 @S9S_MB_2U_LIB.S9S_MB_2U(SCH_1):PAGE115
 R2502    1      A Q_RES_0402LF-33.2,1%,1/16W,CHIA    I68 @S9S_MB_2U_LIB.S9S_MB_2U(SCH_1):PAGE115

PWRGD_FAIL_CPU1_CD @S9S_MB_2U_LIB.S9S_MB_2U(SCH_1):PWRGD_FAIL_CPU1_CD
 R2495    1      A Q_RES_0402LF-1K,1%,1/16W,CHIP,A    I17 @S9S_MB_2U_LIB.S9S_MB_2U(SCH_1):PAGE115
  R900    2      B Q_RES_0402LF-33.2,1%,1/16W,CHIA    I66 @S9S_MB_2U_LIB.S9S_MB_2U(SCH_1):PAGE114
  R897    2      B Q_RES_0402LF-33.2,1%,1/16W,CHIA    I67 @S9S_MB_2U_LIB.S9S_MB_2U(SCH_1):PAGE114
  R899    2      B Q_RES_0402LF-33.2,1%,1/16W,CHIA    I65 @S9S_MB_2U_LIB.S9S_MB_2U(SCH_1):PAGE114
  R898    2      B Q_RES_0402LF-33.2,1%,1/16W,CHIA    I68 @S9S_MB_2U_LIB.S9S_MB_2U(SCH_1):PAGE114

PWRGD_FAIL_CPU1_CD_R @S9S_MB_2U_LIB.S9S_MB_2U(SCH_1):PWRGD_FAIL_CPU1_CD_R
  U249  R16  PR26C LCMXO3LF9400C5BG484C-LCMXO3LF-A     I1 @S9S_MB_2U_LIB.S9S_MB_2U(SCH_1):PAGE313
 R2503    2      B Q_RES_0402LF-33.2,1%,1/16W,CHIA    I67 @S9S_MB_2U_LIB.S9S_MB_2U(SCH_1):PAGE115

PWRGD_FAIL_CPU1_CD_R1 @S9S_MB_2U_LIB.S9S_MB_2U(SCH_1):PWRGD_FAIL_CPU1_CD_R1
  R945    2      B Q_RES_0402LF-10K,1%,1/16W,CHIPA    I16 @S9S_MB_2U_LIB.S9S_MB_2U(SCH_1):PAGE115
 R2495    2      B Q_RES_0402LF-1K,1%,1/16W,CHIP,A    I17 @S9S_MB_2U_LIB.S9S_MB_2U(SCH_1):PAGE115
   D47    1      A SCHOTTKY_12-B0530WS7F,SMLF,IC,A    I27 @S9S_MB_2U_LIB.S9S_MB_2U(SCH_1):PAGE115
 R2503    1      A Q_RES_0402LF-33.2,1%,1/16W,CHIA    I67 @S9S_MB_2U_LIB.S9S_MB_2U(SCH_1):PAGE115

PWRGD_FAIL_CPU1_EF @S9S_MB_2U_LIB.S9S_MB_2U(SCH_1):PWRGD_FAIL_CPU1_EF
 R2736    2      B Q_RES_0402LF-33.2,1%,1/16W,CHIA    I61 @S9S_MB_2U_LIB.S9S_MB_2U(SCH_1):PAGE114
  R902    2      B Q_RES_0402LF-33.2,1%,1/16W,CHIA    I63 @S9S_MB_2U_LIB.S9S_MB_2U(SCH_1):PAGE114
 R2496    1      A Q_RES_0402LF-1K,1%,1/16W,CHIP,A    I12 @S9S_MB_2U_LIB.S9S_MB_2U(SCH_1):PAGE115
  R903    2      B Q_RES_0402LF-33.2,1%,1/16W,CHIA    I62 @S9S_MB_2U_LIB.S9S_MB_2U(SCH_1):PAGE114
  R901    2      B Q_RES_0402LF-33.2,1%,1/16W,CHIA    I64 @S9S_MB_2U_LIB.S9S_MB_2U(SCH_1):PAGE114

PWRGD_FAIL_CPU1_EF_R @S9S_MB_2U_LIB.S9S_MB_2U(SCH_1):PWRGD_FAIL_CPU1_EF_R
  U249  T20  PR26D LCMXO3LF9400C5BG484C-LCMXO3LF-A     I1 @S9S_MB_2U_LIB.S9S_MB_2U(SCH_1):PAGE313
 R2504    2      B Q_RES_0402LF-33.2,1%,1/16W,CHIA    I66 @S9S_MB_2U_LIB.S9S_MB_2U(SCH_1):PAGE115

PWRGD_FAIL_CPU1_EF_R1 @S9S_MB_2U_LIB.S9S_MB_2U(SCH_1):PWRGD_FAIL_CPU1_EF_R1
 R2496    2      B Q_RES_0402LF-1K,1%,1/16W,CHIP,A    I12 @S9S_MB_2U_LIB.S9S_MB_2U(SCH_1):PAGE115
  R946    2      B Q_RES_0402LF-10K,1%,1/16W,CHIPA    I14 @S9S_MB_2U_LIB.S9S_MB_2U(SCH_1):PAGE115
   D48    1      A SCHOTTKY_12-B0530WS7F,SMLF,IC,A    I25 @S9S_MB_2U_LIB.S9S_MB_2U(SCH_1):PAGE115
 R2504    1      A Q_RES_0402LF-33.2,1%,1/16W,CHIA    I66 @S9S_MB_2U_LIB.S9S_MB_2U(SCH_1):PAGE115

PWRGD_FAIL_CPU1_GH @S9S_MB_2U_LIB.S9S_MB_2U(SCH_1):PWRGD_FAIL_CPU1_GH
  R906    2      B Q_RES_0402LF-33.2,1%,1/16W,CHIA    I59 @S9S_MB_2U_LIB.S9S_MB_2U(SCH_1):PAGE114
 R2497    1      A Q_RES_0402LF-1K,1%,1/16W,CHIP,A     I9 @S9S_MB_2U_LIB.S9S_MB_2U(SCH_1):PAGE115
  R908    2      B Q_RES_0402LF-33.2,1%,1/16W,CHIA    I57 @S9S_MB_2U_LIB.S9S_MB_2U(SCH_1):PAGE114
  R907    2      B Q_RES_0402LF-33.2,1%,1/16W,CHIA    I58 @S9S_MB_2U_LIB.S9S_MB_2U(SCH_1):PAGE114
  R905    2      B Q_RES_0402LF-33.2,1%,1/16W,CHIA    I60 @S9S_MB_2U_LIB.S9S_MB_2U(SCH_1):PAGE114

PWRGD_FAIL_CPU1_GH_R @S9S_MB_2U_LIB.S9S_MB_2U(SCH_1):PWRGD_FAIL_CPU1_GH_R
  U249  T19  PR27A LCMXO3LF9400C5BG484C-LCMXO3LF-A     I1 @S9S_MB_2U_LIB.S9S_MB_2U(SCH_1):PAGE313
 R2505    2      B Q_RES_0402LF-33.2,1%,1/16W,CHIA    I65 @S9S_MB_2U_LIB.S9S_MB_2U(SCH_1):PAGE115

PWRGD_FAIL_CPU1_GH_R1 @S9S_MB_2U_LIB.S9S_MB_2U(SCH_1):PWRGD_FAIL_CPU1_GH_R1
 R2497    2      B Q_RES_0402LF-1K,1%,1/16W,CHIP,A     I9 @S9S_MB_2U_LIB.S9S_MB_2U(SCH_1):PAGE115
  R947    2      B Q_RES_0402LF-10K,1%,1/16W,CHIPA    I11 @S9S_MB_2U_LIB.S9S_MB_2U(SCH_1):PAGE115
   D49    1      A SCHOTTKY_12-B0530WS7F,SMLF,IC,A    I22 @S9S_MB_2U_LIB.S9S_MB_2U(SCH_1):PAGE115
 R2505    1      A Q_RES_0402LF-33.2,1%,1/16W,CHIA    I65 @S9S_MB_2U_LIB.S9S_MB_2U(SCH_1):PAGE115

PWRGD_P1V05_PCH_AUX @S9S_MB_2U_LIB.S9S_MB_2U(SCH_1):PWRGD_P1V05_PCH_AUX
   Q76    5     G2 MOSFET_NCH_DUAL-PJT138K,SMLF,IA     I8 @S9S_MB_2U_LIB.S9S_MB_2U(SCH_1):PAGE242
  U249  J16  PR11A LCMXO3LF9400C5BG484C-LCMXO3LF-A     I1 @S9S_MB_2U_LIB.S9S_MB_2U(SCH_1):PAGE313
 R1650    2      B Q_RES_0402LF-0,5%,1/16W,CHIP,CA    I51 @S9S_MB_2U_LIB.S9S_MB_2U(SCH_1):PAGE248

PWRGD_P1V05_PCH_AUX_R @S9S_MB_2U_LIB.S9S_MB_2U(SCH_1):PWRGD_P1V05_PCH_AUX_R
 R1650    1      A Q_RES_0402LF-0,5%,1/16W,CHIP,CA    I51 @S9S_MB_2U_LIB.S9S_MB_2U(SCH_1):PAGE248
 R2357    2      B Q_RES_0402LF-10K,1%,1/16W,CHIPA    I32 @S9S_MB_2U_LIB.S9S_MB_2U(SCH_1):PAGE248
  PU73    9  PGOOD RS53319LR-RS53319LR,SMLF,IC,ALA    I11 @S9S_MB_2U_LIB.S9S_MB_2U(SCH_1):PAGE248
 R4780    1      A Q_RES_0402LF-0,5%,1/16W,CHIP,CA    I52 @S9S_MB_2U_LIB.S9S_MB_2U(SCH_1):PAGE248

PWRGD_P1V8_PCH_AUX @S9S_MB_2U_LIB.S9S_MB_2U(SCH_1):PWRGD_P1V8_PCH_AUX
 R2476    2      B Q_RES_0402LF-200K,1%,1/16W,EMPA    I70 @S9S_MB_2U_LIB.S9S_MB_2U(SCH_1):PAGE183
 R1444    1      A Q_RES_0402LF-33.2,1%,1/16W,CHIA    I54 @S9S_MB_2U_LIB.S9S_MB_2U(SCH_1):PAGE211
   Q76    2     G1 MOSFET_NCH_DUAL-PJT138K,SMLF,IA    I17 @S9S_MB_2U_LIB.S9S_MB_2U(SCH_1):PAGE242
 C2287    1      A Q_CAP_C0402-0.01UF,50V,10%,X7RA    I36 @S9S_MB_2U_LIB.S9S_MB_2U(SCH_1):PAGE249
 R2360    2      B Q_RES_0402LF-0,5%,1/16W,CHIP,CA    I34 @S9S_MB_2U_LIB.S9S_MB_2U(SCH_1):PAGE249

PWRGD_P1V8_PCH_AUX_PLD @S9S_MB_2U_LIB.S9S_MB_2U(SCH_1):PWRGD_P1V8_PCH_AUX_PLD
 R1444    2      B Q_RES_0402LF-33.2,1%,1/16W,CHIA    I54 @S9S_MB_2U_LIB.S9S_MB_2U(SCH_1):PAGE211
  U249  J17  PR11B LCMXO3LF9400C5BG484C-LCMXO3LF-A     I1 @S9S_MB_2U_LIB.S9S_MB_2U(SCH_1):PAGE313

PWRGD_P1V8_PCH_AUX_R @S9S_MB_2U_LIB.S9S_MB_2U(SCH_1):PWRGD_P1V8_PCH_AUX_R
  PU74   13     PG NB682GDZ-NB682GD-Z,SMLF,IC,AL0A    I26 @S9S_MB_2U_LIB.S9S_MB_2U(SCH_1):PAGE249
 R2359    2      B Q_RES_0402LF-10K,1%,1/16W,CHIPA    I31 @S9S_MB_2U_LIB.S9S_MB_2U(SCH_1):PAGE249
 R2360    1      A Q_RES_0402LF-0,5%,1/16W,CHIP,CA    I34 @S9S_MB_2U_LIB.S9S_MB_2U(SCH_1):PAGE249

PWRGD_P3V3 @S9S_MB_2U_LIB.S9S_MB_2U(SCH_1):PWRGD_P3V3
  U249  E12  PT27B LCMXO3LF9400C5BG484C-LCMXO3LF-A   I188 @S9S_MB_2U_LIB.S9S_MB_2U(SCH_1):PAGE314
 R4677    2      B Q_RES_0402LF-33.2,1%,1/16W,CHIA    I91 @S9S_MB_2U_LIB.S9S_MB_2U(SCH_1):PAGE246

PWRGD_P3V3_AUX @S9S_MB_2U_LIB.S9S_MB_2U(SCH_1):PWRGD_P3V3_AUX
 R1919    1      A Q_RES_0402LF-33.2,1%,1/16W,CHIA   I127 @S9S_MB_2U_LIB.S9S_MB_2U(SCH_1):PAGE211
 R4267    1      A Q_RES_0402LF-33.2,1%,1/16W,CHIA   I129 @S9S_MB_2U_LIB.S9S_MB_2U(SCH_1):PAGE211
   PU9    2  PGOOD IR3889MTRPBF-IR3889MTRPBF,SMLFA    I95 @S9S_MB_2U_LIB.S9S_MB_2U(SCH_1):PAGE245
  PR73    2      B Q_RES_0402LF-10K,1%,1/16W,CHIPA   I139 @S9S_MB_2U_LIB.S9S_MB_2U(SCH_1):PAGE245
 PU181    8     EN RS53318LR-RS53318LR,SMLF,IC,ALA    I20 @S9S_MB_2U_LIB.S9S_MB_2U(SCH_1):PAGE244
   Q53    G      G MOSFET_NCH_GDS_ESD_PROTECTED-2A    I39 @S9S_MB_2U_LIB.S9S_MB_2U(SCH_1):PAGE232

PWRGD_P3V3_AUX_PDB @S9S_MB_2U_LIB.S9S_MB_2U(SCH_1):PWRGD_P3V3_AUX_PDB
 R4268    1      A Q_RES_0402LF-0,5%,1/16W,CHIP,CA    I41 @S9S_MB_2U_LIB.S9S_MB_2U(SCH_1):PAGE230
 R4267    2      B Q_RES_0402LF-33.2,1%,1/16W,CHIA   I129 @S9S_MB_2U_LIB.S9S_MB_2U(SCH_1):PAGE211

PWRGD_P3V3_AUX_PDB_BUF @S9S_MB_2U_LIB.S9S_MB_2U(SCH_1):PWRGD_P3V3_AUX_PDB_BUF
 R4266    2      B Q_RES_0402LF-33.2,1%,1/16W,CHIA    I48 @S9S_MB_2U_LIB.S9S_MB_2U(SCH_1):PAGE230
   J45   B2     B2 CONN60_101062636003K02LF-CONN6A    I12 @S9S_MB_2U_LIB.S9S_MB_2U(SCH_1):PAGE233

PWRGD_P3V3_AUX_PDB_BUF_R @S9S_MB_2U_LIB.S9S_MB_2U(SCH_1):PWRGD_P3V3_AUX_PDB_BUF_R
  U308    6     1Y 74LVC2G07DW7-74LVC2G07DW-7,SMLA    I37 @S9S_MB_2U_LIB.S9S_MB_2U(SCH_1):PAGE230
 R4265    1      A Q_RES_0402LF-4.7K,5%,1/16W,EMPA    I43 @S9S_MB_2U_LIB.S9S_MB_2U(SCH_1):PAGE230
 R4264    2      B Q_RES_0402LF-4.7K,5%,1/16W,CHIA    I47 @S9S_MB_2U_LIB.S9S_MB_2U(SCH_1):PAGE230
 R4266    1      A Q_RES_0402LF-33.2,1%,1/16W,CHIA    I48 @S9S_MB_2U_LIB.S9S_MB_2U(SCH_1):PAGE230

PWRGD_P3V3_AUX_PDB_R @S9S_MB_2U_LIB.S9S_MB_2U(SCH_1):PWRGD_P3V3_AUX_PDB_R
  U308    1     1A 74LVC2G07DW7-74LVC2G07DW-7,SMLA    I37 @S9S_MB_2U_LIB.S9S_MB_2U(SCH_1):PAGE230
 R4268    2      B Q_RES_0402LF-0,5%,1/16W,CHIP,CA    I41 @S9S_MB_2U_LIB.S9S_MB_2U(SCH_1):PAGE230

PWRGD_P3V3_AUX_PLD @S9S_MB_2U_LIB.S9S_MB_2U(SCH_1):PWRGD_P3V3_AUX_PLD
 R1919    2      B Q_RES_0402LF-33.2,1%,1/16W,CHIA   I127 @S9S_MB_2U_LIB.S9S_MB_2U(SCH_1):PAGE211
  U249  G12  PT28A LCMXO3LF9400C5BG484C-LCMXO3LF-A   I188 @S9S_MB_2U_LIB.S9S_MB_2U(SCH_1):PAGE314

PWRGD_P3V3_AUX_R2 @S9S_MB_2U_LIB.S9S_MB_2U(SCH_1):PWRGD_P3V3_AUX_R2
   Q52    G      G MOSFET_NCH_GDS_ESD_PROTECTED-2A    I14 @S9S_MB_2U_LIB.S9S_MB_2U(SCH_1):PAGE232
   Q53    D      D MOSFET_NCH_GDS_ESD_PROTECTED-2A    I39 @S9S_MB_2U_LIB.S9S_MB_2U(SCH_1):PAGE232
 R2486    2      B Q_RES_0402LF-10K,1%,1/16W,CHIPA    I40 @S9S_MB_2U_LIB.S9S_MB_2U(SCH_1):PAGE232

PWRGD_P3V3_R1 @S9S_MB_2U_LIB.S9S_MB_2U(SCH_1):PWRGD_P3V3_R1
 R1706    2      B Q_RES_0402LF-10K,1%,1/16W,EMPTA    I89 @S9S_MB_2U_LIB.S9S_MB_2U(SCH_1):PAGE246
 R4677    1      A Q_RES_0402LF-33.2,1%,1/16W,CHIA    I91 @S9S_MB_2U_LIB.S9S_MB_2U(SCH_1):PAGE246
  U330    2 RESET_L APX80929SAG7-APX809-29SAG-7,SMA   I105 @S9S_MB_2U_LIB.S9S_MB_2U(SCH_1):PAGE246
 R4681    1      A Q_RES_0402LF-100K,1%,1/16W,CHIA   I109 @S9S_MB_2U_LIB.S9S_MB_2U(SCH_1):PAGE246

PWRGD_P5V @S9S_MB_2U_LIB.S9S_MB_2U(SCH_1):PWRGD_P5V
   U99    1 RESET# RT9818C44GV-RT9818C-44GV,SMLF,A     I4 @S9S_MB_2U_LIB.S9S_MB_2U(SCH_1):PAGE246
 R4679    2      B Q_RES_0402LF-10K,1%,1/16W,CHIPA    I96 @S9S_MB_2U_LIB.S9S_MB_2U(SCH_1):PAGE246
  Q236    2     G1 MOSFET_NCH_DUAL-PJT138K,SMLF,IA    I99 @S9S_MB_2U_LIB.S9S_MB_2U(SCH_1):PAGE246
 R4682    1      A Q_RES_0402LF-100K,1%,1/16W,CHIA   I112 @S9S_MB_2U_LIB.S9S_MB_2U(SCH_1):PAGE246

PWRGD_P5V_AUX @S9S_MB_2U_LIB.S9S_MB_2U(SCH_1):PWRGD_P5V_AUX
 R2316    2      B Q_RES_0402LF-0,5%,1/16W,CHIP,CA    I28 @S9S_MB_2U_LIB.S9S_MB_2U(SCH_1):PAGE244
 R2343    2      B Q_RES_0402LF-10K,1%,1/16W,EMPTA    I41 @S9S_MB_2U_LIB.S9S_MB_2U(SCH_1):PAGE314
   Q50    2     G1 MOSFET_NCH_DUAL-PJT138K,SMLF,IA    I43 @S9S_MB_2U_LIB.S9S_MB_2U(SCH_1):PAGE314

PWRGD_P5V_AUX_R @S9S_MB_2U_LIB.S9S_MB_2U(SCH_1):PWRGD_P5V_AUX_R
 R2356    2      B Q_RES_0402LF-10K,1%,1/16W,CHIPA    I27 @S9S_MB_2U_LIB.S9S_MB_2U(SCH_1):PAGE244
 R2316    1      A Q_RES_0402LF-0,5%,1/16W,CHIP,CA    I28 @S9S_MB_2U_LIB.S9S_MB_2U(SCH_1):PAGE244
 PU181    9  PGOOD RS53318LR-RS53318LR,SMLF,IC,ALA    I20 @S9S_MB_2U_LIB.S9S_MB_2U(SCH_1):PAGE244

PWRGD_P5V_AUX_R1 @S9S_MB_2U_LIB.S9S_MB_2U(SCH_1):PWRGD_P5V_AUX_R1
   Q50    5     G2 MOSFET_NCH_DUAL-PJT138K,SMLF,IA    I49 @S9S_MB_2U_LIB.S9S_MB_2U(SCH_1):PAGE314
   Q50    6     D1 MOSFET_NCH_DUAL-PJT138K,SMLF,IA    I43 @S9S_MB_2U_LIB.S9S_MB_2U(SCH_1):PAGE314
 R2344    2      B Q_RES_0402LF-4.7K,5%,1/16W,CHIA    I45 @S9S_MB_2U_LIB.S9S_MB_2U(SCH_1):PAGE314

PWRGD_P5V_AUX_R2 @S9S_MB_2U_LIB.S9S_MB_2U(SCH_1):PWRGD_P5V_AUX_R2
   Q50    3     D2 MOSFET_NCH_DUAL-PJT138K,SMLF,IA    I49 @S9S_MB_2U_LIB.S9S_MB_2U(SCH_1):PAGE314
 R2346    2      B Q_RES_0402LF-4.7K,5%,1/16W,CHIA    I51 @S9S_MB_2U_LIB.S9S_MB_2U(SCH_1):PAGE314
  U249  D12  PT27A LCMXO3LF9400C5BG484C-LCMXO3LF-A   I188 @S9S_MB_2U_LIB.S9S_MB_2U(SCH_1):PAGE314

PWRGD_P5V_ISO @S9S_MB_2U_LIB.S9S_MB_2U(SCH_1):PWRGD_P5V_ISO
  Q236    3     D2 MOSFET_NCH_DUAL-PJT138K,SMLF,IA    I98 @S9S_MB_2U_LIB.S9S_MB_2U(SCH_1):PAGE246
 R4678    2      B Q_RES_0402LF-1K,1%,1/16W,CHIP,A   I104 @S9S_MB_2U_LIB.S9S_MB_2U(SCH_1):PAGE246

PWRGD_P5V_ISO_R @S9S_MB_2U_LIB.S9S_MB_2U(SCH_1):PWRGD_P5V_ISO_R
 R1655    2      B Q_RES_0402LF-10K,1%,1/16W,CHIPA     I6 @S9S_MB_2U_LIB.S9S_MB_2U(SCH_1):PAGE246
   Q56    4      4 MOSFET_NCH_1D3S-PSMNR58-30YLH,A    I51 @S9S_MB_2U_LIB.S9S_MB_2U(SCH_1):PAGE246
 C2359    1      A Q_CAP_C0402-0.22UF,25V,10%,X7RA    I94 @S9S_MB_2U_LIB.S9S_MB_2U(SCH_1):PAGE246
 R4678    1      A Q_RES_0402LF-1K,1%,1/16W,CHIP,A   I104 @S9S_MB_2U_LIB.S9S_MB_2U(SCH_1):PAGE246

PWRGD_P5V_N @S9S_MB_2U_LIB.S9S_MB_2U(SCH_1):PWRGD_P5V_N
  Q236    5     G2 MOSFET_NCH_DUAL-PJT138K,SMLF,IA    I98 @S9S_MB_2U_LIB.S9S_MB_2U(SCH_1):PAGE246
  Q236    6     D1 MOSFET_NCH_DUAL-PJT138K,SMLF,IA    I99 @S9S_MB_2U_LIB.S9S_MB_2U(SCH_1):PAGE246
 R4680    2      B Q_RES_0402LF-100K,1%,1/16W,CHIA   I102 @S9S_MB_2U_LIB.S9S_MB_2U(SCH_1):PAGE246

PWRGD_PCH_PWROK @S9S_MB_2U_LIB.S9S_MB_2U(SCH_1):PWRGD_PCH_PWROK
    U4  BE4 PCH_PWROK EMMITSBURG_REV0P9-GFNOCPU04302A    I36 @S9S_MB_2U_LIB.S9S_MB_2U(SCH_1):PAGE174
 R1403    1      A Q_RES_0402LF-2K,1%,1/16W,CHIP,A    I24 @S9S_MB_2U_LIB.S9S_MB_2U(SCH_1):PAGE208
 R1442    2      B Q_RES_0402LF-33.2,1%,1/16W,CHIA    I48 @S9S_MB_2U_LIB.S9S_MB_2U(SCH_1):PAGE211

PWRGD_PCH_PWROK_R @S9S_MB_2U_LIB.S9S_MB_2U(SCH_1):PWRGD_PCH_PWROK_R
 R1442    1      A Q_RES_0402LF-33.2,1%,1/16W,CHIA    I48 @S9S_MB_2U_LIB.S9S_MB_2U(SCH_1):PAGE211
   Q87    2     G1 MOSFET_NCH_DUAL-PJT138K,SMLF,IA    I17 @S9S_MB_2U_LIB.S9S_MB_2U(SCH_1):PAGE241
  U249  J19  PR11D LCMXO3LF9400C5BG484C-LCMXO3LF-A     I1 @S9S_MB_2U_LIB.S9S_MB_2U(SCH_1):PAGE313
 C1211    1      A Q_CAP_0402-100PF,50V,5%,NPO,CHA     I4 @S9S_MB_2U_LIB.S9S_MB_2U(SCH_1):PAGE209

PWRGD_PLT_AUX_CPU0_LVT3 @S9S_MB_2U_LIB.S9S_MB_2U(SCH_1):PWRGD_PLT_AUX_CPU0_LVT3
    U2 CV20 PLT_AUX_PWRGOOD SOCKET4677_AZIF0045P001C01CS-SA     I1 @S9S_MB_2U_LIB.S9S_MB_2U(SCH_1):PAGE15
   R67    2      B Q_RES_0402LF-33.2,1%,1/16W,CHIA    I12 @S9S_MB_2U_LIB.S9S_MB_2U(SCH_1):PAGE43
   R69    1      A Q_RES_0402LF-10K,1%,1/16W,CHIPA    I16 @S9S_MB_2U_LIB.S9S_MB_2U(SCH_1):PAGE43

PWRGD_PLT_AUX_CPU0_LVT3_R @S9S_MB_2U_LIB.S9S_MB_2U(SCH_1):PWRGD_PLT_AUX_CPU0_LVT3_R
   R67    1      A Q_RES_0402LF-33.2,1%,1/16W,CHIA    I12 @S9S_MB_2U_LIB.S9S_MB_2U(SCH_1):PAGE43
  U249  AA5  PB10A LCMXO3LF9400C5BG484C-LCMXO3LF-A     I1 @S9S_MB_2U_LIB.S9S_MB_2U(SCH_1):PAGE312

PWRGD_PLT_AUX_CPU1_LVT3 @S9S_MB_2U_LIB.S9S_MB_2U(SCH_1):PWRGD_PLT_AUX_CPU1_LVT3
   R68    2      B Q_RES_0402LF-33.2,1%,1/16W,CHIA    I13 @S9S_MB_2U_LIB.S9S_MB_2U(SCH_1):PAGE43
   R70    1      A Q_RES_0402LF-10K,1%,1/16W,CHIPA    I17 @S9S_MB_2U_LIB.S9S_MB_2U(SCH_1):PAGE43
    U1 CV20 PLT_AUX_PWRGOOD SOCKET4677_AZIF0045P001C01CS-SA     I5 @S9S_MB_2U_LIB.S9S_MB_2U(SCH_1):PAGE46

PWRGD_PLT_AUX_CPU1_LVT3_R @S9S_MB_2U_LIB.S9S_MB_2U(SCH_1):PWRGD_PLT_AUX_CPU1_LVT3_R
   R68    1      A Q_RES_0402LF-33.2,1%,1/16W,CHIA    I13 @S9S_MB_2U_LIB.S9S_MB_2U(SCH_1):PAGE43
  U249  AB5  PB10B LCMXO3LF9400C5BG484C-LCMXO3LF-A     I1 @S9S_MB_2U_LIB.S9S_MB_2U(SCH_1):PAGE312

PWRGD_PS_PWROK @S9S_MB_2U_LIB.S9S_MB_2U(SCH_1):PWRGD_PS_PWROK
 R3054    2      B Q_RES_0402LF-33.2,1%,1/16W,CHIA    I23 @S9S_MB_2U_LIB.S9S_MB_2U(SCH_1):PAGE215
 R3048    2      B Q_RES_0402LF-0,5%,1/16W,CHIP,CA    I86 @S9S_MB_2U_LIB.S9S_MB_2U(SCH_1):PAGE313
 R1816    1      A Q_RES_0402LF-0,5%,1/16W,CHIP,CA    I27 @S9S_MB_2U_LIB.S9S_MB_2U(SCH_1):PAGE227

PWRGD_PS_PWROK_ME_CONN @S9S_MB_2U_LIB.S9S_MB_2U(SCH_1):PWRGD_PS_PWROK_ME_CONN
 R3054    1      A Q_RES_0402LF-33.2,1%,1/16W,CHIA    I23 @S9S_MB_2U_LIB.S9S_MB_2U(SCH_1):PAGE215
  J100   18     18 SCONN20_513860200CV01-SCONN20_A    I32 @S9S_MB_2U_LIB.S9S_MB_2U(SCH_1):PAGE215

PWRGD_PS_PWROK_PLD @S9S_MB_2U_LIB.S9S_MB_2U(SCH_1):PWRGD_PS_PWROK_PLD
   Q78    5     G2 MOSFET_NCH_DUAL-PJT138K,SMLF,IA    I26 @S9S_MB_2U_LIB.S9S_MB_2U(SCH_1):PAGE242
 R3047    2      B Q_RES_0402LF-0,5%,1/16W,CHIP,CA    I85 @S9S_MB_2U_LIB.S9S_MB_2U(SCH_1):PAGE313
  Q144    2     G1 MOSFET_NCH_DUAL-PJT138K,SMLF,IA    I27 @S9S_MB_2U_LIB.S9S_MB_2U(SCH_1):PAGE213

PWRGD_PS_PWROK_PLD_ISO @S9S_MB_2U_LIB.S9S_MB_2U(SCH_1):PWRGD_PS_PWROK_PLD_ISO
  Q144    3     D2 MOSFET_NCH_DUAL-PJT138K,SMLF,IA    I21 @S9S_MB_2U_LIB.S9S_MB_2U(SCH_1):PAGE213
 R4605    2      B Q_RES_0402LF-4.7K,5%,1/16W,CHIA    I22 @S9S_MB_2U_LIB.S9S_MB_2U(SCH_1):PAGE213
 R1446    1      A Q_RES_0402LF-33.2,1%,1/16W,CHIA    I29 @S9S_MB_2U_LIB.S9S_MB_2U(SCH_1):PAGE213

PWRGD_PS_PWROK_PLD_ISO_R @S9S_MB_2U_LIB.S9S_MB_2U(SCH_1):PWRGD_PS_PWROK_PLD_ISO_R
  U249  H16  PR10D LCMXO3LF9400C5BG484C-LCMXO3LF-A     I1 @S9S_MB_2U_LIB.S9S_MB_2U(SCH_1):PAGE313
 R1446    2      B Q_RES_0402LF-33.2,1%,1/16W,CHIA    I29 @S9S_MB_2U_LIB.S9S_MB_2U(SCH_1):PAGE213

PWRGD_PS_PWROK_PLD_N @S9S_MB_2U_LIB.S9S_MB_2U(SCH_1):PWRGD_PS_PWROK_PLD_N
 R4604    2      B Q_RES_0402LF-4.7K,5%,1/16W,CHIA    I18 @S9S_MB_2U_LIB.S9S_MB_2U(SCH_1):PAGE213
  Q144    5     G2 MOSFET_NCH_DUAL-PJT138K,SMLF,IA    I21 @S9S_MB_2U_LIB.S9S_MB_2U(SCH_1):PAGE213
  Q144    6     D1 MOSFET_NCH_DUAL-PJT138K,SMLF,IA    I27 @S9S_MB_2U_LIB.S9S_MB_2U(SCH_1):PAGE213

PWRGD_PS_PWROK_R @S9S_MB_2U_LIB.S9S_MB_2U(SCH_1):PWRGD_PS_PWROK_R
 R1816    2      B Q_RES_0402LF-0,5%,1/16W,CHIP,CA    I27 @S9S_MB_2U_LIB.S9S_MB_2U(SCH_1):PAGE227
   J41  A44  PERN8 SCONN168_ME1016810202011-SCONNA   I173 @S9S_MB_2U_LIB.S9S_MB_2U(SCH_1):PAGE227

PWRGD_PVCCD_HV_CPU0 @S9S_MB_2U_LIB.S9S_MB_2U(SCH_1):PWRGD_PVCCD_HV_CPU0
   Q79    2     G1 MOSFET_NCH_DUAL-PJT138K,SMLF,IA     I8 @S9S_MB_2U_LIB.S9S_MB_2U(SCH_1):PAGE305
  R362    1      A Q_RES_0402LF-0,5%,1/16W,CHIP,CA    I44 @S9S_MB_2U_LIB.S9S_MB_2U(SCH_1):PAGE264
  U249  F12  PT28B LCMXO3LF9400C5BG484C-LCMXO3LF-A   I188 @S9S_MB_2U_LIB.S9S_MB_2U(SCH_1):PAGE314

PWRGD_PVCCD_HV_CPU0_R @S9S_MB_2U_LIB.S9S_MB_2U(SCH_1):PWRGD_PVCCD_HV_CPU0_R
  R361    2      B Q_RES_0402LF-1K,1%,1/16W,CHIP,A    I46 @S9S_MB_2U_LIB.S9S_MB_2U(SCH_1):PAGE264
  C626    1      A Q_CAP_0402-1000PF,50V,5%,EMPTYA    I47 @S9S_MB_2U_LIB.S9S_MB_2U(SCH_1):PAGE264
  PU35   12    PG0 ISL69260IRAZT-ISL69260IRAZ-T,SA    I53 @S9S_MB_2U_LIB.S9S_MB_2U(SCH_1):PAGE264
  R362    2      B Q_RES_0402LF-0,5%,1/16W,CHIP,CA    I44 @S9S_MB_2U_LIB.S9S_MB_2U(SCH_1):PAGE264

PWRGD_PVCCD_HV_CPU1 @S9S_MB_2U_LIB.S9S_MB_2U(SCH_1):PWRGD_PVCCD_HV_CPU1
   Q84    2     G1 MOSFET_NCH_DUAL-PJT138K,SMLF,IA    I18 @S9S_MB_2U_LIB.S9S_MB_2U(SCH_1):PAGE306
  U249  H18  PR10B LCMXO3LF9400C5BG484C-LCMXO3LF-A     I1 @S9S_MB_2U_LIB.S9S_MB_2U(SCH_1):PAGE313
 R2576    1      A Q_RES_0402LF-0,5%,1/16W,CHIP,CA    I44 @S9S_MB_2U_LIB.S9S_MB_2U(SCH_1):PAGE282

PWRGD_PVCCD_HV_CPU1_R @S9S_MB_2U_LIB.S9S_MB_2U(SCH_1):PWRGD_PVCCD_HV_CPU1_R
 R2575    2      B Q_RES_0402LF-1K,1%,1/16W,CHIP,A    I46 @S9S_MB_2U_LIB.S9S_MB_2U(SCH_1):PAGE282
  PU18   12    PG0 ISL69260IRAZT-ISL69260IRAZ-T,SA    I53 @S9S_MB_2U_LIB.S9S_MB_2U(SCH_1):PAGE282
 C2454    1      A Q_CAP_0402-1000PF,50V,5%,EMPTYA    I45 @S9S_MB_2U_LIB.S9S_MB_2U(SCH_1):PAGE282
 R2576    2      B Q_RES_0402LF-0,5%,1/16W,CHIP,CA    I44 @S9S_MB_2U_LIB.S9S_MB_2U(SCH_1):PAGE282

PWRGD_PVCCFA_EHV_CPU0 @S9S_MB_2U_LIB.S9S_MB_2U(SCH_1):PWRGD_PVCCFA_EHV_CPU0
   Q80    2     G1 MOSFET_NCH_DUAL-PJT138K,SMLF,IA     I4 @S9S_MB_2U_LIB.S9S_MB_2U(SCH_1):PAGE305
  U249  H22   PR7A LCMXO3LF9400C5BG484C-LCMXO3LF-A     I1 @S9S_MB_2U_LIB.S9S_MB_2U(SCH_1):PAGE313
 R2397    1      A Q_RES_0402LF-0,5%,1/16W,CHIP,CA    I11 @S9S_MB_2U_LIB.S9S_MB_2U(SCH_1):PAGE260

PWRGD_PVCCFA_EHV_CPU0_R @S9S_MB_2U_LIB.S9S_MB_2U(SCH_1):PWRGD_PVCCFA_EHV_CPU0_R
   PU5   16    PG1 ISL69260IRAZT-ISL69260IRAZ-T,SA    I65 @S9S_MB_2U_LIB.S9S_MB_2U(SCH_1):PAGE260
 R2397    2      B Q_RES_0402LF-0,5%,1/16W,CHIP,CA    I11 @S9S_MB_2U_LIB.S9S_MB_2U(SCH_1):PAGE260
 R2396    2      B Q_RES_0402LF-1K,1%,1/16W,CHIP,A    I13 @S9S_MB_2U_LIB.S9S_MB_2U(SCH_1):PAGE260
 C3276    1      A Q_CAP_0402-1000PF,50V,5%,EMPTYA    I22 @S9S_MB_2U_LIB.S9S_MB_2U(SCH_1):PAGE260

PWRGD_PVCCFA_EHV_CPU1 @S9S_MB_2U_LIB.S9S_MB_2U(SCH_1):PWRGD_PVCCFA_EHV_CPU1
   Q85    2     G1 MOSFET_NCH_DUAL-PJT138K,SMLF,IA     I6 @S9S_MB_2U_LIB.S9S_MB_2U(SCH_1):PAGE306
  U249  H21   PR7B LCMXO3LF9400C5BG484C-LCMXO3LF-A     I1 @S9S_MB_2U_LIB.S9S_MB_2U(SCH_1):PAGE313
 R2572    1      A Q_RES_0402LF-0,5%,1/16W,CHIP,CA    I29 @S9S_MB_2U_LIB.S9S_MB_2U(SCH_1):PAGE278

PWRGD_PVCCFA_EHV_CPU1_R @S9S_MB_2U_LIB.S9S_MB_2U(SCH_1):PWRGD_PVCCFA_EHV_CPU1_R
 C2453    1      A Q_CAP_0402-1000PF,50V,5%,EMPTYA    I32 @S9S_MB_2U_LIB.S9S_MB_2U(SCH_1):PAGE278
 R2572    2      B Q_RES_0402LF-0,5%,1/16W,CHIP,CA    I29 @S9S_MB_2U_LIB.S9S_MB_2U(SCH_1):PAGE278
 R2571    2      B Q_RES_0402LF-1K,1%,1/16W,CHIP,A    I30 @S9S_MB_2U_LIB.S9S_MB_2U(SCH_1):PAGE278
  PU22   16    PG1 ISL69260IRAZT-ISL69260IRAZ-T,SA    I38 @S9S_MB_2U_LIB.S9S_MB_2U(SCH_1):PAGE278

PWRGD_PVCCFA_EHV_FIVRA_CPU0 @S9S_MB_2U_LIB.S9S_MB_2U(SCH_1):PWRGD_PVCCFA_EHV_FIVRA_CPU0
   Q80    5     G2 MOSFET_NCH_DUAL-PJT138K,SMLF,IA     I2 @S9S_MB_2U_LIB.S9S_MB_2U(SCH_1):PAGE305
 R2379    1      A Q_RES_0402LF-0,5%,1/16W,CHIP,CA    I55 @S9S_MB_2U_LIB.S9S_MB_2U(SCH_1):PAGE252
  U249  E13  PT28C LCMXO3LF9400C5BG484C-LCMXO3LF-A   I188 @S9S_MB_2U_LIB.S9S_MB_2U(SCH_1):PAGE314

PWRGD_PVCCFA_EHV_FIVRA_CPU0_R @S9S_MB_2U_LIB.S9S_MB_2U(SCH_1):PWRGD_PVCCFA_EHV_FIVRA_CPU0_R
  PU14   20    PG1 RAA229126GNPHA0-RAA229126GNP#HA    I63 @S9S_MB_2U_LIB.S9S_MB_2U(SCH_1):PAGE252
 R2377    2      B Q_RES_0402LF-1K,1%,1/16W,CHIP,A    I54 @S9S_MB_2U_LIB.S9S_MB_2U(SCH_1):PAGE252
 R2379    2      B Q_RES_0402LF-0,5%,1/16W,CHIP,CA    I55 @S9S_MB_2U_LIB.S9S_MB_2U(SCH_1):PAGE252
 C3269    1      A Q_CAP_0402-1000PF,50V,5%,EMPTYA    I57 @S9S_MB_2U_LIB.S9S_MB_2U(SCH_1):PAGE252

PWRGD_PVCCFA_EHV_FIVRA_CPU1 @S9S_MB_2U_LIB.S9S_MB_2U(SCH_1):PWRGD_PVCCFA_EHV_FIVRA_CPU1
   Q85    5     G2 MOSFET_NCH_DUAL-PJT138K,SMLF,IA     I3 @S9S_MB_2U_LIB.S9S_MB_2U(SCH_1):PAGE306
  U249  H19  PR10A LCMXO3LF9400C5BG484C-LCMXO3LF-A     I1 @S9S_MB_2U_LIB.S9S_MB_2U(SCH_1):PAGE313
 R2552    1      A Q_RES_0402LF-0,5%,1/16W,CHIP,CA    I16 @S9S_MB_2U_LIB.S9S_MB_2U(SCH_1):PAGE270

PWRGD_PVCCFA_EHV_FIVRA_CPU1_R @S9S_MB_2U_LIB.S9S_MB_2U(SCH_1):PWRGD_PVCCFA_EHV_FIVRA_CPU1_R
 C2447    1      A Q_CAP_0402-1000PF,50V,5%,EMPTYA    I35 @S9S_MB_2U_LIB.S9S_MB_2U(SCH_1):PAGE270
 R2552    2      B Q_RES_0402LF-0,5%,1/16W,CHIP,CA    I16 @S9S_MB_2U_LIB.S9S_MB_2U(SCH_1):PAGE270
 R2551    2      B Q_RES_0402LF-1K,1%,1/16W,CHIP,A    I15 @S9S_MB_2U_LIB.S9S_MB_2U(SCH_1):PAGE270
  PU29   20    PG1 RAA229126GNPHA0-RAA229126GNP#HA    I33 @S9S_MB_2U_LIB.S9S_MB_2U(SCH_1):PAGE270

PWRGD_PVCCINFAON_CPU0 @S9S_MB_2U_LIB.S9S_MB_2U(SCH_1):PWRGD_PVCCINFAON_CPU0
   Q81    2     G1 MOSFET_NCH_DUAL-PJT138K,SMLF,IA    I41 @S9S_MB_2U_LIB.S9S_MB_2U(SCH_1):PAGE305
  U249  G17   PR7C LCMXO3LF9400C5BG484C-LCMXO3LF-A     I1 @S9S_MB_2U_LIB.S9S_MB_2U(SCH_1):PAGE313
 R2595    1      A Q_RES_0402LF-0,5%,1/16W,CHIP,CA    I58 @S9S_MB_2U_LIB.S9S_MB_2U(SCH_1):PAGE260

PWRGD_PVCCINFAON_CPU0_R @S9S_MB_2U_LIB.S9S_MB_2U(SCH_1):PWRGD_PVCCINFAON_CPU0_R
 R2383    2      B Q_RES_0402LF-1K,1%,1/16W,CHIP,A    I59 @S9S_MB_2U_LIB.S9S_MB_2U(SCH_1):PAGE260
 C3273    1      A Q_CAP_0402-1000PF,50V,5%,EMPTYA    I61 @S9S_MB_2U_LIB.S9S_MB_2U(SCH_1):PAGE260
   PU5   12    PG0 ISL69260IRAZT-ISL69260IRAZ-T,SA    I65 @S9S_MB_2U_LIB.S9S_MB_2U(SCH_1):PAGE260
 R2595    2      B Q_RES_0402LF-0,5%,1/16W,CHIP,CA    I58 @S9S_MB_2U_LIB.S9S_MB_2U(SCH_1):PAGE260

PWRGD_PVCCINFAON_CPU1 @S9S_MB_2U_LIB.S9S_MB_2U(SCH_1):PWRGD_PVCCINFAON_CPU1
   Q86    2     G1 MOSFET_NCH_DUAL-PJT138K,SMLF,IA    I35 @S9S_MB_2U_LIB.S9S_MB_2U(SCH_1):PAGE306
  U249  H20   PR7D LCMXO3LF9400C5BG484C-LCMXO3LF-A     I1 @S9S_MB_2U_LIB.S9S_MB_2U(SCH_1):PAGE313
 R4781    1      A Q_RES_0402LF-0,5%,1/16W,CHIP,CA   I103 @S9S_MB_2U_LIB.S9S_MB_2U(SCH_1):PAGE278

PWRGD_PVCCINFAON_CPU1_R @S9S_MB_2U_LIB.S9S_MB_2U(SCH_1):PWRGD_PVCCINFAON_CPU1_R
 R4781    2      B Q_RES_0402LF-0,5%,1/16W,CHIP,CA   I103 @S9S_MB_2U_LIB.S9S_MB_2U(SCH_1):PAGE278
  PU22   12    PG0 ISL69260IRAZT-ISL69260IRAZ-T,SA    I38 @S9S_MB_2U_LIB.S9S_MB_2U(SCH_1):PAGE278
 R2556    2      B Q_RES_0402LF-1K,1%,1/16W,CHIP,A   I105 @S9S_MB_2U_LIB.S9S_MB_2U(SCH_1):PAGE278
 C2450    1      A Q_CAP_0402-1000PF,50V,5%,EMPTYA   I106 @S9S_MB_2U_LIB.S9S_MB_2U(SCH_1):PAGE278

PWRGD_PVCCIN_CPU0 @S9S_MB_2U_LIB.S9S_MB_2U(SCH_1):PWRGD_PVCCIN_CPU0
   Q83    2     G1 MOSFET_NCH_DUAL-PJT138K,SMLF,IA    I32 @S9S_MB_2U_LIB.S9S_MB_2U(SCH_1):PAGE305
 R2366    1      A Q_RES_0402LF-0,5%,1/16W,CHIP,CA    I49 @S9S_MB_2U_LIB.S9S_MB_2U(SCH_1):PAGE252
  U249  F13  PT28D LCMXO3LF9400C5BG484C-LCMXO3LF-A   I188 @S9S_MB_2U_LIB.S9S_MB_2U(SCH_1):PAGE314

PWRGD_PVCCIN_CPU0_R @S9S_MB_2U_LIB.S9S_MB_2U(SCH_1):PWRGD_PVCCIN_CPU0_R
 R2365    2      B Q_RES_0402LF-1K,1%,1/16W,CHIP,A    I50 @S9S_MB_2U_LIB.S9S_MB_2U(SCH_1):PAGE252
 R2366    2      B Q_RES_0402LF-0,5%,1/16W,CHIP,CA    I49 @S9S_MB_2U_LIB.S9S_MB_2U(SCH_1):PAGE252
  PU14   16    PG0 RAA229126GNPHA0-RAA229126GNP#HA    I63 @S9S_MB_2U_LIB.S9S_MB_2U(SCH_1):PAGE252
 C3266    1      A Q_CAP_0402-1000PF,50V,5%,EMPTYA    I84 @S9S_MB_2U_LIB.S9S_MB_2U(SCH_1):PAGE252

PWRGD_PVCCIN_CPU1 @S9S_MB_2U_LIB.S9S_MB_2U(SCH_1):PWRGD_PVCCIN_CPU1
   Q83    5     G2 MOSFET_NCH_DUAL-PJT138K,SMLF,IA    I43 @S9S_MB_2U_LIB.S9S_MB_2U(SCH_1):PAGE306
  U249  G18   PR6D LCMXO3LF9400C5BG484C-LCMXO3LF-A     I1 @S9S_MB_2U_LIB.S9S_MB_2U(SCH_1):PAGE313
  R308    1      A Q_RES_0402LF-0,5%,1/16W,CHIP,CA    I60 @S9S_MB_2U_LIB.S9S_MB_2U(SCH_1):PAGE270

PWRGD_PVCCIN_CPU1_R @S9S_MB_2U_LIB.S9S_MB_2U(SCH_1):PWRGD_PVCCIN_CPU1_R
  R308    2      B Q_RES_0402LF-0,5%,1/16W,CHIP,CA    I60 @S9S_MB_2U_LIB.S9S_MB_2U(SCH_1):PAGE270
  R307    2      B Q_RES_0402LF-1K,1%,1/16W,CHIP,A    I61 @S9S_MB_2U_LIB.S9S_MB_2U(SCH_1):PAGE270
 C2859    1      A Q_CAP_0402-1000PF,50V,5%,EMPTYA    I68 @S9S_MB_2U_LIB.S9S_MB_2U(SCH_1):PAGE270
  PU29   16    PG0 RAA229126GNPHA0-RAA229126GNP#HA    I33 @S9S_MB_2U_LIB.S9S_MB_2U(SCH_1):PAGE270

PWRGD_PVNN_MAIN_CPU0 @S9S_MB_2U_LIB.S9S_MB_2U(SCH_1):PWRGD_PVNN_MAIN_CPU0
   U17    1    1OE 74CBTLV3126PW-74CBTLV3126PW,SMA    I80 @S9S_MB_2U_LIB.S9S_MB_2U(SCH_1):PAGE134
   U17    4    2OE 74CBTLV3126PW-74CBTLV3126PW,SMA    I80 @S9S_MB_2U_LIB.S9S_MB_2U(SCH_1):PAGE134
   U17   10    3OE 74CBTLV3126PW-74CBTLV3126PW,SMA    I80 @S9S_MB_2U_LIB.S9S_MB_2U(SCH_1):PAGE134
   U17   13    4OE 74CBTLV3126PW-74CBTLV3126PW,SMA    I80 @S9S_MB_2U_LIB.S9S_MB_2U(SCH_1):PAGE134
   U18    1    1OE 74CBTLV3126PW-74CBTLV3126PW,SMA   I129 @S9S_MB_2U_LIB.S9S_MB_2U(SCH_1):PAGE134
   U18    4    2OE 74CBTLV3126PW-74CBTLV3126PW,SMA   I129 @S9S_MB_2U_LIB.S9S_MB_2U(SCH_1):PAGE134
   U18   10    3OE 74CBTLV3126PW-74CBTLV3126PW,SMA   I129 @S9S_MB_2U_LIB.S9S_MB_2U(SCH_1):PAGE134
   U18   13    4OE 74CBTLV3126PW-74CBTLV3126PW,SMA   I129 @S9S_MB_2U_LIB.S9S_MB_2U(SCH_1):PAGE134
   Q81    5     G2 MOSFET_NCH_DUAL-PJT138K,SMLF,IA    I40 @S9S_MB_2U_LIB.S9S_MB_2U(SCH_1):PAGE305
 C1296    1      A Q_CAP_0402-1000PF,50V,5%,X7R,TA    I31 @S9S_MB_2U_LIB.S9S_MB_2U(SCH_1):PAGE268
 R1652    2      B Q_RES_0402LF-0,5%,1/16W,CHIP,CA    I33 @S9S_MB_2U_LIB.S9S_MB_2U(SCH_1):PAGE268
  U249  A13  PT29A LCMXO3LF9400C5BG484C-LCMXO3LF-A   I188 @S9S_MB_2U_LIB.S9S_MB_2U(SCH_1):PAGE314

PWRGD_PVNN_MAIN_CPU0_R @S9S_MB_2U_LIB.S9S_MB_2U(SCH_1):PWRGD_PVNN_MAIN_CPU0_R
 R1652    1      A Q_RES_0402LF-0,5%,1/16W,CHIP,CA    I33 @S9S_MB_2U_LIB.S9S_MB_2U(SCH_1):PAGE268
 R2409    2      B Q_RES_0402LF-10K,1%,1/16W,CHIPA    I32 @S9S_MB_2U_LIB.S9S_MB_2U(SCH_1):PAGE268
  PU81    9  PGOOD RS53317LR-RS53317LR,SMLF,IC,ALA    I22 @S9S_MB_2U_LIB.S9S_MB_2U(SCH_1):PAGE268

PWRGD_PVNN_MAIN_CPU1 @S9S_MB_2U_LIB.S9S_MB_2U(SCH_1):PWRGD_PVNN_MAIN_CPU1
   Q86    5     G2 MOSFET_NCH_DUAL-PJT138K,SMLF,IA    I27 @S9S_MB_2U_LIB.S9S_MB_2U(SCH_1):PAGE306
 R2387    2      B Q_RES_0402LF-0,5%,1/16W,CHIP,CA    I29 @S9S_MB_2U_LIB.S9S_MB_2U(SCH_1):PAGE286
  U249  C13  PT29C LCMXO3LF9400C5BG484C-LCMXO3LF-A   I188 @S9S_MB_2U_LIB.S9S_MB_2U(SCH_1):PAGE314
 C1297    1      A Q_CAP_0402-1000PF,50V,5%,X7R,TA    I37 @S9S_MB_2U_LIB.S9S_MB_2U(SCH_1):PAGE286

PWRGD_PVNN_MAIN_CPU1_R @S9S_MB_2U_LIB.S9S_MB_2U(SCH_1):PWRGD_PVNN_MAIN_CPU1_R
 R2387    1      A Q_RES_0402LF-0,5%,1/16W,CHIP,CA    I29 @S9S_MB_2U_LIB.S9S_MB_2U(SCH_1):PAGE286
 R2584    2      B Q_RES_0402LF-10K,1%,1/16W,CHIPA    I31 @S9S_MB_2U_LIB.S9S_MB_2U(SCH_1):PAGE286
  PU82    9  PGOOD RS53317LR-RS53317LR,SMLF,IC,ALA    I20 @S9S_MB_2U_LIB.S9S_MB_2U(SCH_1):PAGE286

PWRGD_PVNN_PCH_AUX @S9S_MB_2U_LIB.S9S_MB_2U(SCH_1):PWRGD_PVNN_PCH_AUX
  U249  B13  PT29B LCMXO3LF9400C5BG484C-LCMXO3LF-A   I188 @S9S_MB_2U_LIB.S9S_MB_2U(SCH_1):PAGE314
 R4780    2      B Q_RES_0402LF-0,5%,1/16W,CHIP,CA    I52 @S9S_MB_2U_LIB.S9S_MB_2U(SCH_1):PAGE248

PWRGD_PVPP_HBM_CPU0 @S9S_MB_2U_LIB.S9S_MB_2U(SCH_1):PWRGD_PVPP_HBM_CPU0
   Q79    5     G2 MOSFET_NCH_DUAL-PJT138K,SMLF,IA     I7 @S9S_MB_2U_LIB.S9S_MB_2U(SCH_1):PAGE305
  U249  D13  PT29D LCMXO3LF9400C5BG484C-LCMXO3LF-A   I188 @S9S_MB_2U_LIB.S9S_MB_2U(SCH_1):PAGE314
 R2408    2      B Q_RES_0402LF-0,5%,1/16W,CHIP,CA    I29 @S9S_MB_2U_LIB.S9S_MB_2U(SCH_1):PAGE267

PWRGD_PVPP_HBM_CPU0_R @S9S_MB_2U_LIB.S9S_MB_2U(SCH_1):PWRGD_PVPP_HBM_CPU0_R
 C1301    1      A Q_CAP_0402-1000PF,50V,5%,X7R,TA    I30 @S9S_MB_2U_LIB.S9S_MB_2U(SCH_1):PAGE267
 R2407    2      B Q_RES_0402LF-10K,1%,1/16W,CHIPA    I45 @S9S_MB_2U_LIB.S9S_MB_2U(SCH_1):PAGE267
  PU79    9  PGOOD RS53318LR-RS53318LR,SMLF,IC,ALA    I19 @S9S_MB_2U_LIB.S9S_MB_2U(SCH_1):PAGE267
 R2408    1      A Q_RES_0402LF-0,5%,1/16W,CHIP,CA    I29 @S9S_MB_2U_LIB.S9S_MB_2U(SCH_1):PAGE267

PWRGD_PVPP_HBM_CPU1 @S9S_MB_2U_LIB.S9S_MB_2U(SCH_1):PWRGD_PVPP_HBM_CPU1
   Q84    5     G2 MOSFET_NCH_DUAL-PJT138K,SMLF,IA     I8 @S9S_MB_2U_LIB.S9S_MB_2U(SCH_1):PAGE306
 R2380    2      B Q_RES_0402LF-0,5%,1/16W,CHIP,CA    I37 @S9S_MB_2U_LIB.S9S_MB_2U(SCH_1):PAGE285
  U249  A14  PT30A LCMXO3LF9400C5BG484C-LCMXO3LF-A   I188 @S9S_MB_2U_LIB.S9S_MB_2U(SCH_1):PAGE314

PWRGD_PVPP_HBM_CPU1_R @S9S_MB_2U_LIB.S9S_MB_2U(SCH_1):PWRGD_PVPP_HBM_CPU1_R
 C2460    1      A Q_CAP_0402-1000PF,50V,5%,X7R,TA    I36 @S9S_MB_2U_LIB.S9S_MB_2U(SCH_1):PAGE285
 R2583    2      B Q_RES_0402LF-10K,1%,1/16W,CHIPA    I27 @S9S_MB_2U_LIB.S9S_MB_2U(SCH_1):PAGE285
  PU80    9  PGOOD RS53318LR-RS53318LR,SMLF,IC,ALA    I25 @S9S_MB_2U_LIB.S9S_MB_2U(SCH_1):PAGE285
 R2380    1      A Q_RES_0402LF-0,5%,1/16W,CHIP,CA    I37 @S9S_MB_2U_LIB.S9S_MB_2U(SCH_1):PAGE285

PWRGD_SYS_PWROK @S9S_MB_2U_LIB.S9S_MB_2U(SCH_1):PWRGD_SYS_PWROK
    U4 AL10 SYS_PWROK EMMITSBURG_REV0P9-GFNOCPU04302A    I36 @S9S_MB_2U_LIB.S9S_MB_2U(SCH_1):PAGE174
 R1402    1      A Q_RES_0402LF-2K,1%,1/16W,CHIP,A    I23 @S9S_MB_2U_LIB.S9S_MB_2U(SCH_1):PAGE208
 R1423    2      B Q_RES_0402LF-33.2,1%,1/16W,CHIA    I44 @S9S_MB_2U_LIB.S9S_MB_2U(SCH_1):PAGE211
   J41  A48  PERP9 SCONN168_ME1016810202011-SCONNA   I173 @S9S_MB_2U_LIB.S9S_MB_2U(SCH_1):PAGE227

PWRGD_SYS_PWROK_R @S9S_MB_2U_LIB.S9S_MB_2U(SCH_1):PWRGD_SYS_PWROK_R
 R1423    1      A Q_RES_0402LF-33.2,1%,1/16W,CHIA    I44 @S9S_MB_2U_LIB.S9S_MB_2U(SCH_1):PAGE211
   Q87    5     G2 MOSFET_NCH_DUAL-PJT138K,SMLF,IA    I16 @S9S_MB_2U_LIB.S9S_MB_2U(SCH_1):PAGE241
  U249  J18  PR11C LCMXO3LF9400C5BG484C-LCMXO3LF-A     I1 @S9S_MB_2U_LIB.S9S_MB_2U(SCH_1):PAGE313
 C1209    1      A Q_CAP_0402-100PF,50V,5%,NPO,CHA     I3 @S9S_MB_2U_LIB.S9S_MB_2U(SCH_1):PAGE209

RMII_BMC_OCP_RX_ER @S9S_MB_2U_LIB.S9S_MB_2U(SCH_1):RMII_BMC_OCP_RX_ER
 R1356    1      A Q_RES_0402LF-1K,1%,1/16W,CHIP,A    I53 @S9S_MB_2U_LIB.S9S_MB_2U(SCH_1):PAGE151
   J41  B23  PETN2 SCONN168_ME1016810202011-SCONNA   I173 @S9S_MB_2U_LIB.S9S_MB_2U(SCH_1):PAGE227

RMII_BMC_OCP_TXD_0 @S9S_MB_2U_LIB.S9S_MB_2U(SCH_1):RMII_BMC_OCP_TXD_0
 R3214    2      B Q_RES_0402LF-0,5%,1/16W,EMPTY,A    I60 @S9S_MB_2U_LIB.S9S_MB_2U(SCH_1):PAGE307
 R1354    1      A Q_RES_0402LF-100K,1%,1/16W,CHIA    I55 @S9S_MB_2U_LIB.S9S_MB_2U(SCH_1):PAGE151
 R1295    2      B Q_RES_0402LF-0,5%,1/16W,CHIP,CA    I65 @S9S_MB_2U_LIB.S9S_MB_2U(SCH_1):PAGE151
   J41  B21  PETP1 SCONN168_ME1016810202011-SCONNA   I173 @S9S_MB_2U_LIB.S9S_MB_2U(SCH_1):PAGE227

RMII_BMC_OCP_TXD_1 @S9S_MB_2U_LIB.S9S_MB_2U(SCH_1):RMII_BMC_OCP_TXD_1
 R3215    2      B Q_RES_0402LF-0,5%,1/16W,EMPTY,A    I56 @S9S_MB_2U_LIB.S9S_MB_2U(SCH_1):PAGE307
 R1355    1      A Q_RES_0402LF-100K,1%,1/16W,CHIA    I54 @S9S_MB_2U_LIB.S9S_MB_2U(SCH_1):PAGE151
 R1296    2      B Q_RES_0402LF-0,5%,1/16W,CHIP,CA    I61 @S9S_MB_2U_LIB.S9S_MB_2U(SCH_1):PAGE151
   J41  B22 GND_B22 SCONN168_ME1016810202011-SCONNA   I173 @S9S_MB_2U_LIB.S9S_MB_2U(SCH_1):PAGE227

RMII_BMC_OCP_TX_EN @S9S_MB_2U_LIB.S9S_MB_2U(SCH_1):RMII_BMC_OCP_TX_EN
 R1353    1      A Q_RES_0402LF-100K,1%,1/16W,CHIA    I56 @S9S_MB_2U_LIB.S9S_MB_2U(SCH_1):PAGE151
 R3213    2      B Q_RES_0402LF-0,5%,1/16W,EMPTY,A    I61 @S9S_MB_2U_LIB.S9S_MB_2U(SCH_1):PAGE307
 R1294    2      B Q_RES_0402LF-0,5%,1/16W,CHIP,CA    I66 @S9S_MB_2U_LIB.S9S_MB_2U(SCH_1):PAGE151
   J41  B20  PETN1 SCONN168_ME1016810202011-SCONNA   I173 @S9S_MB_2U_LIB.S9S_MB_2U(SCH_1):PAGE227

RMII_OCP_BMC_CRSDV @S9S_MB_2U_LIB.S9S_MB_2U(SCH_1):RMII_OCP_BMC_CRSDV
 R3210    2      B Q_RES_0402LF-22,1%,1/16W,EMPTYA    I65 @S9S_MB_2U_LIB.S9S_MB_2U(SCH_1):PAGE307
 R1291    2      B Q_RES_0402LF-22,1%,1/16W,CHIP,A    I69 @S9S_MB_2U_LIB.S9S_MB_2U(SCH_1):PAGE151
 R1350    1      A Q_RES_0402LF-100K,1%,1/16W,CHIA    I73 @S9S_MB_2U_LIB.S9S_MB_2U(SCH_1):PAGE151
   J41  B19 GND_B19 SCONN168_ME1016810202011-SCONNA   I173 @S9S_MB_2U_LIB.S9S_MB_2U(SCH_1):PAGE227

RMII_OCP_BMC_RXD_0 @S9S_MB_2U_LIB.S9S_MB_2U(SCH_1):RMII_OCP_BMC_RXD_0
 R3211    2      B Q_RES_0402LF-22,1%,1/16W,EMPTYA    I63 @S9S_MB_2U_LIB.S9S_MB_2U(SCH_1):PAGE307
 R1292    2      B Q_RES_0402LF-22,1%,1/16W,CHIP,A    I68 @S9S_MB_2U_LIB.S9S_MB_2U(SCH_1):PAGE151
 R1351    1      A Q_RES_0402LF-100K,1%,1/16W,CHIA    I72 @S9S_MB_2U_LIB.S9S_MB_2U(SCH_1):PAGE151
   J41  B24  PETP2 SCONN168_ME1016810202011-SCONNA   I173 @S9S_MB_2U_LIB.S9S_MB_2U(SCH_1):PAGE227

RMII_OCP_BMC_RXD_1 @S9S_MB_2U_LIB.S9S_MB_2U(SCH_1):RMII_OCP_BMC_RXD_1
 R3212    2      B Q_RES_0402LF-22,1%,1/16W,EMPTYA    I62 @S9S_MB_2U_LIB.S9S_MB_2U(SCH_1):PAGE307
 R1293    2      B Q_RES_0402LF-22,1%,1/16W,CHIP,A    I67 @S9S_MB_2U_LIB.S9S_MB_2U(SCH_1):PAGE151
 R1352    1      A Q_RES_0402LF-100K,1%,1/16W,CHIA    I71 @S9S_MB_2U_LIB.S9S_MB_2U(SCH_1):PAGE151
   J41  B25 GND_B25 SCONN168_ME1016810202011-SCONNA   I173 @S9S_MB_2U_LIB.S9S_MB_2U(SCH_1):PAGE227

ROT_P1_RST_IND_N @S9S_MB_2U_LIB.S9S_MB_2U(SCH_1):ROT_P1_RST_IND_N
 R1798    2      B Q_RES_0402LF-0,5%,1/16W,CHIP,CA    I20 @S9S_MB_2U_LIB.S9S_MB_2U(SCH_1):PAGE227
   J41  A53 PERN11 SCONN168_ME1016810202011-SCONNA   I173 @S9S_MB_2U_LIB.S9S_MB_2U(SCH_1):PAGE227

ROT_P1_RST_IND_N_R @S9S_MB_2U_LIB.S9S_MB_2U(SCH_1):ROT_P1_RST_IND_N_R
  U249  V15  PB38C LCMXO3LF9400C5BG484C-LCMXO3LF-A     I1 @S9S_MB_2U_LIB.S9S_MB_2U(SCH_1):PAGE312
 R2244    1      A Q_RES_0402LF-10K,1%,1/16W,CHIPA    I39 @S9S_MB_2U_LIB.S9S_MB_2U(SCH_1):PAGE209
 R1798    1      A Q_RES_0402LF-0,5%,1/16W,CHIP,CA    I20 @S9S_MB_2U_LIB.S9S_MB_2U(SCH_1):PAGE227

RST_BMC_FROM_SWB @S9S_MB_2U_LIB.S9S_MB_2U(SCH_1):RST_BMC_FROM_SWB
 R2834    2      B Q_RES_0402LF-4.7K,5%,1/16W,CHIA    I18 @S9S_MB_2U_LIB.S9S_MB_2U(SCH_1):PAGE145
   Q69    5     G2 MOSFET_NCH_DUAL-PJT138K,SMLF,IA    I88 @S9S_MB_2U_LIB.S9S_MB_2U(SCH_1):PAGE145
   Q69    6     D1 MOSFET_NCH_DUAL-PJT138K,SMLF,IA   I117 @S9S_MB_2U_LIB.S9S_MB_2U(SCH_1):PAGE145

RST_BMC_FROM_SWB_ISO_N @S9S_MB_2U_LIB.S9S_MB_2U(SCH_1):RST_BMC_FROM_SWB_ISO_N
   Q69    3     D2 MOSFET_NCH_DUAL-PJT138K,SMLF,IA    I88 @S9S_MB_2U_LIB.S9S_MB_2U(SCH_1):PAGE145
 R2919    2      B Q_RES_0402LF-4.7K,5%,1/16W,CHIA    I91 @S9S_MB_2U_LIB.S9S_MB_2U(SCH_1):PAGE145
 C1772    1      A Q_CAP_0402-1000PF,50V,5%,EMPTYA   I116 @S9S_MB_2U_LIB.S9S_MB_2U(SCH_1):PAGE145
 R2847    1      A Q_RES_0402LF-33.2,1%,1/16W,CHIA   I107 @S9S_MB_2U_LIB.S9S_MB_2U(SCH_1):PAGE314

RST_BMC_FROM_SWB_ISO_R_N @S9S_MB_2U_LIB.S9S_MB_2U(SCH_1):RST_BMC_FROM_SWB_ISO_R_N
 R2847    2      B Q_RES_0402LF-33.2,1%,1/16W,CHIA   I107 @S9S_MB_2U_LIB.S9S_MB_2U(SCH_1):PAGE314
  U249   F8  PT11C LCMXO3LF9400C5BG484C-LCMXO3LF-A   I188 @S9S_MB_2U_LIB.S9S_MB_2U(SCH_1):PAGE314

RST_BMC_FROM_SWB_N @S9S_MB_2U_LIB.S9S_MB_2U(SCH_1):RST_BMC_FROM_SWB_N
  J105   N8     N8 CONN112_10137002101LF-CONN112_A    I68 @S9S_MB_2U_LIB.S9S_MB_2U(SCH_1):PAGE142
 R2829    1      A Q_RES_0402LF-100K,1%,1/16W,EMPA    I58 @S9S_MB_2U_LIB.S9S_MB_2U(SCH_1):PAGE145
 R2828    2      B Q_RES_0402LF-100K,1%,1/16W,CHIA    I66 @S9S_MB_2U_LIB.S9S_MB_2U(SCH_1):PAGE145
   Q69    2     G1 MOSFET_NCH_DUAL-PJT138K,SMLF,IA   I117 @S9S_MB_2U_LIB.S9S_MB_2U(SCH_1):PAGE145

RST_CPU0_BUF_R_N @S9S_MB_2U_LIB.S9S_MB_2U(SCH_1):RST_CPU0_BUF_R_N
  R171    2      B Q_RES_0402LF-0,5%,1/16W,CHIP,CA    I52 @S9S_MB_2U_LIB.S9S_MB_2U(SCH_1):PAGE124
  R185    1      A Q_RES_0402LF-100,1%,1/16W,CHIPA    I60 @S9S_MB_2U_LIB.S9S_MB_2U(SCH_1):PAGE124
  R186    1      A Q_RES_0402LF-100,1%,1/16W,CHIPA    I78 @S9S_MB_2U_LIB.S9S_MB_2U(SCH_1):PAGE124

RST_CPU0_DRAM_AB_N @S9S_MB_2U_LIB.S9S_MB_2U(SCH_1):RST_CPU0_DRAM_AB_N
    U2 AU50 DDR01_RESET_N SOCKET4677_AZIF0045P001C01CS-SA    I57 @S9S_MB_2U_LIB.S9S_MB_2U(SCH_1):PAGE13
  R851    1      A Q_RES_0402LF-0,5%,1/16W,CHIP,CA    I12 @S9S_MB_2U_LIB.S9S_MB_2U(SCH_1):PAGE128
  R932    1      A Q_RES_0402LF-10K,1%,1/16W,CHIPA    I80 @S9S_MB_2U_LIB.S9S_MB_2U(SCH_1):PAGE128

RST_CPU0_DRAM_AB_PLD_LVT3_N @S9S_MB_2U_LIB.S9S_MB_2U(SCH_1):RST_CPU0_DRAM_AB_PLD_LVT3_N
  U249   D3   PL2A LCMXO3LF9400C5BG484C-LCMXO3LF-A    I33 @S9S_MB_2U_LIB.S9S_MB_2U(SCH_1):PAGE311
 R4042    2      B Q_RES_0402LF-33.2,1%,1/16W,CHIA    I39 @S9S_MB_2U_LIB.S9S_MB_2U(SCH_1):PAGE322

RST_CPU0_DRAM_AB_PLD_LVT3_R_N @S9S_MB_2U_LIB.S9S_MB_2U(SCH_1):RST_CPU0_DRAM_AB_PLD_LVT3_R_N
  U304    9     A3 GTL2014PW-GTL2014PW,SMLF,IC,ALA    I27 @S9S_MB_2U_LIB.S9S_MB_2U(SCH_1):PAGE322
 R4042    1      A Q_RES_0402LF-33.2,1%,1/16W,CHIA    I39 @S9S_MB_2U_LIB.S9S_MB_2U(SCH_1):PAGE322

RST_CPU0_DRAM_AB_PLD_N @S9S_MB_2U_LIB.S9S_MB_2U(SCH_1):RST_CPU0_DRAM_AB_PLD_N
  R851    2      B Q_RES_0402LF-0,5%,1/16W,CHIP,CA    I12 @S9S_MB_2U_LIB.S9S_MB_2U(SCH_1):PAGE128
  U304    6     B3 GTL2014PW-GTL2014PW,SMLF,IC,ALA    I27 @S9S_MB_2U_LIB.S9S_MB_2U(SCH_1):PAGE322

RST_CPU0_DRAM_CD_N @S9S_MB_2U_LIB.S9S_MB_2U(SCH_1):RST_CPU0_DRAM_CD_N
    U2 AV51 DDR23_RESET_N SOCKET4677_AZIF0045P001C01CS-SA    I57 @S9S_MB_2U_LIB.S9S_MB_2U(SCH_1):PAGE13
  R852    1      A Q_RES_0402LF-0,5%,1/16W,CHIP,CA    I11 @S9S_MB_2U_LIB.S9S_MB_2U(SCH_1):PAGE128
  R934    1      A Q_RES_0402LF-10K,1%,1/16W,CHIPA    I79 @S9S_MB_2U_LIB.S9S_MB_2U(SCH_1):PAGE128

RST_CPU0_DRAM_CD_PLD_LVT3_N @S9S_MB_2U_LIB.S9S_MB_2U(SCH_1):RST_CPU0_DRAM_CD_PLD_LVT3_N
  U249   D4   PL2B LCMXO3LF9400C5BG484C-LCMXO3LF-A    I33 @S9S_MB_2U_LIB.S9S_MB_2U(SCH_1):PAGE311
 R4043    2      B Q_RES_0402LF-33.2,1%,1/16W,CHIA    I38 @S9S_MB_2U_LIB.S9S_MB_2U(SCH_1):PAGE322

RST_CPU0_DRAM_CD_PLD_LVT3_R_N @S9S_MB_2U_LIB.S9S_MB_2U(SCH_1):RST_CPU0_DRAM_CD_PLD_LVT3_R_N
  U304   10     A2 GTL2014PW-GTL2014PW,SMLF,IC,ALA    I27 @S9S_MB_2U_LIB.S9S_MB_2U(SCH_1):PAGE322
 R4043    1      A Q_RES_0402LF-33.2,1%,1/16W,CHIA    I38 @S9S_MB_2U_LIB.S9S_MB_2U(SCH_1):PAGE322

RST_CPU0_DRAM_CD_PLD_N @S9S_MB_2U_LIB.S9S_MB_2U(SCH_1):RST_CPU0_DRAM_CD_PLD_N
  R852    2      B Q_RES_0402LF-0,5%,1/16W,CHIP,CA    I11 @S9S_MB_2U_LIB.S9S_MB_2U(SCH_1):PAGE128
  U304    5     B2 GTL2014PW-GTL2014PW,SMLF,IC,ALA    I27 @S9S_MB_2U_LIB.S9S_MB_2U(SCH_1):PAGE322

RST_CPU0_DRAM_EF_N @S9S_MB_2U_LIB.S9S_MB_2U(SCH_1):RST_CPU0_DRAM_EF_N
    U2 CY42 DDR45_RESET_N SOCKET4677_AZIF0045P001C01CS-SA    I57 @S9S_MB_2U_LIB.S9S_MB_2U(SCH_1):PAGE13
  R853    1      A Q_RES_0402LF-0,5%,1/16W,CHIP,CA    I10 @S9S_MB_2U_LIB.S9S_MB_2U(SCH_1):PAGE128
  R936    1      A Q_RES_0402LF-10K,1%,1/16W,CHIPA    I78 @S9S_MB_2U_LIB.S9S_MB_2U(SCH_1):PAGE128

RST_CPU0_DRAM_EF_PLD_LVT3_N @S9S_MB_2U_LIB.S9S_MB_2U(SCH_1):RST_CPU0_DRAM_EF_PLD_LVT3_N
  U249   F6   PL2C LCMXO3LF9400C5BG484C-LCMXO3LF-A    I33 @S9S_MB_2U_LIB.S9S_MB_2U(SCH_1):PAGE311
 R4044    2      B Q_RES_0402LF-33.2,1%,1/16W,CHIA    I37 @S9S_MB_2U_LIB.S9S_MB_2U(SCH_1):PAGE322

RST_CPU0_DRAM_EF_PLD_LVT3_R_N @S9S_MB_2U_LIB.S9S_MB_2U(SCH_1):RST_CPU0_DRAM_EF_PLD_LVT3_R_N
  U304   12     A1 GTL2014PW-GTL2014PW,SMLF,IC,ALA    I27 @S9S_MB_2U_LIB.S9S_MB_2U(SCH_1):PAGE322
 R4044    1      A Q_RES_0402LF-33.2,1%,1/16W,CHIA    I37 @S9S_MB_2U_LIB.S9S_MB_2U(SCH_1):PAGE322

RST_CPU0_DRAM_EF_PLD_N @S9S_MB_2U_LIB.S9S_MB_2U(SCH_1):RST_CPU0_DRAM_EF_PLD_N
  R853    2      B Q_RES_0402LF-0,5%,1/16W,CHIP,CA    I10 @S9S_MB_2U_LIB.S9S_MB_2U(SCH_1):PAGE128
  U304    3     B1 GTL2014PW-GTL2014PW,SMLF,IC,ALA    I27 @S9S_MB_2U_LIB.S9S_MB_2U(SCH_1):PAGE322

RST_CPU0_DRAM_GH_N @S9S_MB_2U_LIB.S9S_MB_2U(SCH_1):RST_CPU0_DRAM_GH_N
    U2 CY55 DDR67_RESET_N SOCKET4677_AZIF0045P001C01CS-SA    I57 @S9S_MB_2U_LIB.S9S_MB_2U(SCH_1):PAGE13
  R854    1      A Q_RES_0402LF-0,5%,1/16W,CHIP,CA     I9 @S9S_MB_2U_LIB.S9S_MB_2U(SCH_1):PAGE128
  R938    1      A Q_RES_0402LF-10K,1%,1/16W,CHIPA    I77 @S9S_MB_2U_LIB.S9S_MB_2U(SCH_1):PAGE128

RST_CPU0_DRAM_GH_PLD_LVT3_N @S9S_MB_2U_LIB.S9S_MB_2U(SCH_1):RST_CPU0_DRAM_GH_PLD_LVT3_N
  U249   G7   PL2D LCMXO3LF9400C5BG484C-LCMXO3LF-A    I33 @S9S_MB_2U_LIB.S9S_MB_2U(SCH_1):PAGE311
 R4045    2      B Q_RES_0402LF-33.2,1%,1/16W,CHIA    I36 @S9S_MB_2U_LIB.S9S_MB_2U(SCH_1):PAGE322

RST_CPU0_DRAM_GH_PLD_LVT3_R_N @S9S_MB_2U_LIB.S9S_MB_2U(SCH_1):RST_CPU0_DRAM_GH_PLD_LVT3_R_N
  U304   13     A0 GTL2014PW-GTL2014PW,SMLF,IC,ALA    I27 @S9S_MB_2U_LIB.S9S_MB_2U(SCH_1):PAGE322
 R4045    1      A Q_RES_0402LF-33.2,1%,1/16W,CHIA    I36 @S9S_MB_2U_LIB.S9S_MB_2U(SCH_1):PAGE322

RST_CPU0_DRAM_GH_PLD_N @S9S_MB_2U_LIB.S9S_MB_2U(SCH_1):RST_CPU0_DRAM_GH_PLD_N
  R854    2      B Q_RES_0402LF-0,5%,1/16W,CHIP,CA     I9 @S9S_MB_2U_LIB.S9S_MB_2U(SCH_1):PAGE128
  U304    2     B0 GTL2014PW-GTL2014PW,SMLF,IC,ALA    I27 @S9S_MB_2U_LIB.S9S_MB_2U(SCH_1):PAGE322

RST_CPU0_LVC1_N @S9S_MB_2U_LIB.S9S_MB_2U(SCH_1):RST_CPU0_LVC1_N
    U2 BH61 RESET_N SOCKET4677_AZIF0045P001C01CS-SA     I1 @S9S_MB_2U_LIB.S9S_MB_2U(SCH_1):PAGE14
  R186    2      B Q_RES_0402LF-100,1%,1/16W,CHIPA    I78 @S9S_MB_2U_LIB.S9S_MB_2U(SCH_1):PAGE124

RST_CPU0_LVC1_R_N @S9S_MB_2U_LIB.S9S_MB_2U(SCH_1):RST_CPU0_LVC1_R_N
  R171    1      A Q_RES_0402LF-0,5%,1/16W,CHIP,CA    I52 @S9S_MB_2U_LIB.S9S_MB_2U(SCH_1):PAGE124
 R1415    1      A Q_RES_0402LF-2K,1%,1/16W,EMPTYA     I4 @S9S_MB_2U_LIB.S9S_MB_2U(SCH_1):PAGE208
  U249   U5  PL28D LCMXO3LF9400C5BG484C-LCMXO3LF-A    I33 @S9S_MB_2U_LIB.S9S_MB_2U(SCH_1):PAGE311

RST_CPU1_BUF_R_N @S9S_MB_2U_LIB.S9S_MB_2U(SCH_1):RST_CPU1_BUF_R_N
  R132    2      B Q_RES_0402LF-0,5%,1/16W,CHIP,CA     I3 @S9S_MB_2U_LIB.S9S_MB_2U(SCH_1):PAGE125
  R157    1      A Q_RES_0402LF-100,1%,1/16W,CHIPA    I24 @S9S_MB_2U_LIB.S9S_MB_2U(SCH_1):PAGE125
  R158    1      A Q_RES_0402LF-100,1%,1/16W,CHIPA    I65 @S9S_MB_2U_LIB.S9S_MB_2U(SCH_1):PAGE125

RST_CPU1_DRAM_AB_N @S9S_MB_2U_LIB.S9S_MB_2U(SCH_1):RST_CPU1_DRAM_AB_N
    U1 AU50 DDR01_RESET_N SOCKET4677_AZIF0045P001C01CS-SA    I51 @S9S_MB_2U_LIB.S9S_MB_2U(SCH_1):PAGE44
  R859    1      A Q_RES_0402LF-0,5%,1/16W,CHIP,CA    I50 @S9S_MB_2U_LIB.S9S_MB_2U(SCH_1):PAGE128
  R933    1      A Q_RES_0402LF-10K,1%,1/16W,CHIPA    I82 @S9S_MB_2U_LIB.S9S_MB_2U(SCH_1):PAGE128

RST_CPU1_DRAM_AB_PLD_LVT3_N @S9S_MB_2U_LIB.S9S_MB_2U(SCH_1):RST_CPU1_DRAM_AB_PLD_LVT3_N
  U249   E4 PL3A||L_GPLLT_FB LCMXO3LF9400C5BG484C-LCMXO3LF-A    I33 @S9S_MB_2U_LIB.S9S_MB_2U(SCH_1):PAGE311
 R4046    2      B Q_RES_0402LF-33.2,1%,1/16W,CHIA    I52 @S9S_MB_2U_LIB.S9S_MB_2U(SCH_1):PAGE322

RST_CPU1_DRAM_AB_PLD_LVT3_R_N @S9S_MB_2U_LIB.S9S_MB_2U(SCH_1):RST_CPU1_DRAM_AB_PLD_LVT3_R_N
  U305    9     A3 GTL2014PW-GTL2014PW,SMLF,IC,ALA    I44 @S9S_MB_2U_LIB.S9S_MB_2U(SCH_1):PAGE322
 R4046    1      A Q_RES_0402LF-33.2,1%,1/16W,CHIA    I52 @S9S_MB_2U_LIB.S9S_MB_2U(SCH_1):PAGE322

RST_CPU1_DRAM_AB_PLD_N @S9S_MB_2U_LIB.S9S_MB_2U(SCH_1):RST_CPU1_DRAM_AB_PLD_N
  R859    2      B Q_RES_0402LF-0,5%,1/16W,CHIP,CA    I50 @S9S_MB_2U_LIB.S9S_MB_2U(SCH_1):PAGE128
  U305    6     B3 GTL2014PW-GTL2014PW,SMLF,IC,ALA    I44 @S9S_MB_2U_LIB.S9S_MB_2U(SCH_1):PAGE322

RST_CPU1_DRAM_CD_N @S9S_MB_2U_LIB.S9S_MB_2U(SCH_1):RST_CPU1_DRAM_CD_N
    U1 AV51 DDR23_RESET_N SOCKET4677_AZIF0045P001C01CS-SA    I51 @S9S_MB_2U_LIB.S9S_MB_2U(SCH_1):PAGE44
  R860    1      A Q_RES_0402LF-0,5%,1/16W,CHIP,CA    I51 @S9S_MB_2U_LIB.S9S_MB_2U(SCH_1):PAGE128
  R935    1      A Q_RES_0402LF-10K,1%,1/16W,CHIPA    I86 @S9S_MB_2U_LIB.S9S_MB_2U(SCH_1):PAGE128

RST_CPU1_DRAM_CD_PLD_LVT3_N @S9S_MB_2U_LIB.S9S_MB_2U(SCH_1):RST_CPU1_DRAM_CD_PLD_LVT3_N
  U249   F5 PL3B||L_GPLLC_FB LCMXO3LF9400C5BG484C-LCMXO3LF-A    I33 @S9S_MB_2U_LIB.S9S_MB_2U(SCH_1):PAGE311
 R4047    2      B Q_RES_0402LF-33.2,1%,1/16W,CHIA    I53 @S9S_MB_2U_LIB.S9S_MB_2U(SCH_1):PAGE322

RST_CPU1_DRAM_CD_PLD_LVT3_R_N @S9S_MB_2U_LIB.S9S_MB_2U(SCH_1):RST_CPU1_DRAM_CD_PLD_LVT3_R_N
  U305   10     A2 GTL2014PW-GTL2014PW,SMLF,IC,ALA    I44 @S9S_MB_2U_LIB.S9S_MB_2U(SCH_1):PAGE322
 R4047    1      A Q_RES_0402LF-33.2,1%,1/16W,CHIA    I53 @S9S_MB_2U_LIB.S9S_MB_2U(SCH_1):PAGE322

RST_CPU1_DRAM_CD_PLD_N @S9S_MB_2U_LIB.S9S_MB_2U(SCH_1):RST_CPU1_DRAM_CD_PLD_N
  R860    2      B Q_RES_0402LF-0,5%,1/16W,CHIP,CA    I51 @S9S_MB_2U_LIB.S9S_MB_2U(SCH_1):PAGE128
  U305    5     B2 GTL2014PW-GTL2014PW,SMLF,IC,ALA    I44 @S9S_MB_2U_LIB.S9S_MB_2U(SCH_1):PAGE322

RST_CPU1_DRAM_EF_N @S9S_MB_2U_LIB.S9S_MB_2U(SCH_1):RST_CPU1_DRAM_EF_N
    U1 CY42 DDR45_RESET_N SOCKET4677_AZIF0045P001C01CS-SA    I51 @S9S_MB_2U_LIB.S9S_MB_2U(SCH_1):PAGE44
  R861    1      A Q_RES_0402LF-0,5%,1/16W,CHIP,CA    I48 @S9S_MB_2U_LIB.S9S_MB_2U(SCH_1):PAGE128
  R937    1      A Q_RES_0402LF-10K,1%,1/16W,CHIPA    I85 @S9S_MB_2U_LIB.S9S_MB_2U(SCH_1):PAGE128

RST_CPU1_DRAM_EF_PLD_LVT3_N @S9S_MB_2U_LIB.S9S_MB_2U(SCH_1):RST_CPU1_DRAM_EF_PLD_LVT3_N
  U249   G6   PL3C LCMXO3LF9400C5BG484C-LCMXO3LF-A    I33 @S9S_MB_2U_LIB.S9S_MB_2U(SCH_1):PAGE311
 R4048    2      B Q_RES_0402LF-33.2,1%,1/16W,CHIA    I55 @S9S_MB_2U_LIB.S9S_MB_2U(SCH_1):PAGE322

RST_CPU1_DRAM_EF_PLD_LVT3_R_N @S9S_MB_2U_LIB.S9S_MB_2U(SCH_1):RST_CPU1_DRAM_EF_PLD_LVT3_R_N
  U305   12     A1 GTL2014PW-GTL2014PW,SMLF,IC,ALA    I44 @S9S_MB_2U_LIB.S9S_MB_2U(SCH_1):PAGE322
 R4048    1      A Q_RES_0402LF-33.2,1%,1/16W,CHIA    I55 @S9S_MB_2U_LIB.S9S_MB_2U(SCH_1):PAGE322

RST_CPU1_DRAM_EF_PLD_N @S9S_MB_2U_LIB.S9S_MB_2U(SCH_1):RST_CPU1_DRAM_EF_PLD_N
  R861    2      B Q_RES_0402LF-0,5%,1/16W,CHIP,CA    I48 @S9S_MB_2U_LIB.S9S_MB_2U(SCH_1):PAGE128
  U305    3     B1 GTL2014PW-GTL2014PW,SMLF,IC,ALA    I44 @S9S_MB_2U_LIB.S9S_MB_2U(SCH_1):PAGE322

RST_CPU1_DRAM_GH_N @S9S_MB_2U_LIB.S9S_MB_2U(SCH_1):RST_CPU1_DRAM_GH_N
    U1 CY55 DDR67_RESET_N SOCKET4677_AZIF0045P001C01CS-SA    I51 @S9S_MB_2U_LIB.S9S_MB_2U(SCH_1):PAGE44
 R2969    1      A Q_RES_0402LF-0,5%,1/16W,CHIP,CA    I49 @S9S_MB_2U_LIB.S9S_MB_2U(SCH_1):PAGE128
  R939    1      A Q_RES_0402LF-10K,1%,1/16W,CHIPA    I83 @S9S_MB_2U_LIB.S9S_MB_2U(SCH_1):PAGE128

RST_CPU1_DRAM_GH_PLD_LVT3_N @S9S_MB_2U_LIB.S9S_MB_2U(SCH_1):RST_CPU1_DRAM_GH_PLD_LVT3_N
  U249   H7   PL3D LCMXO3LF9400C5BG484C-LCMXO3LF-A    I33 @S9S_MB_2U_LIB.S9S_MB_2U(SCH_1):PAGE311
 R4049    2      B Q_RES_0402LF-33.2,1%,1/16W,CHIA    I54 @S9S_MB_2U_LIB.S9S_MB_2U(SCH_1):PAGE322

RST_CPU1_DRAM_GH_PLD_LVT3_R_N @S9S_MB_2U_LIB.S9S_MB_2U(SCH_1):RST_CPU1_DRAM_GH_PLD_LVT3_R_N
  U305   13     A0 GTL2014PW-GTL2014PW,SMLF,IC,ALA    I44 @S9S_MB_2U_LIB.S9S_MB_2U(SCH_1):PAGE322
 R4049    1      A Q_RES_0402LF-33.2,1%,1/16W,CHIA    I54 @S9S_MB_2U_LIB.S9S_MB_2U(SCH_1):PAGE322

RST_CPU1_DRAM_GH_PLD_N @S9S_MB_2U_LIB.S9S_MB_2U(SCH_1):RST_CPU1_DRAM_GH_PLD_N
 R2969    2      B Q_RES_0402LF-0,5%,1/16W,CHIP,CA    I49 @S9S_MB_2U_LIB.S9S_MB_2U(SCH_1):PAGE128
  U305    2     B0 GTL2014PW-GTL2014PW,SMLF,IC,ALA    I44 @S9S_MB_2U_LIB.S9S_MB_2U(SCH_1):PAGE322

RST_CPU1_LVC1_N @S9S_MB_2U_LIB.S9S_MB_2U(SCH_1):RST_CPU1_LVC1_N
    U1 BH61 RESET_N SOCKET4677_AZIF0045P001C01CS-SA    I29 @S9S_MB_2U_LIB.S9S_MB_2U(SCH_1):PAGE45
  R158    2      B Q_RES_0402LF-100,1%,1/16W,CHIPA    I65 @S9S_MB_2U_LIB.S9S_MB_2U(SCH_1):PAGE125

RST_CPU1_LVC1_R_N @S9S_MB_2U_LIB.S9S_MB_2U(SCH_1):RST_CPU1_LVC1_R_N
  R132    1      A Q_RES_0402LF-0,5%,1/16W,CHIP,CA     I3 @S9S_MB_2U_LIB.S9S_MB_2U(SCH_1):PAGE125
 R1416    1      A Q_RES_0402LF-2K,1%,1/16W,EMPTYA     I5 @S9S_MB_2U_LIB.S9S_MB_2U(SCH_1):PAGE208
  U249   V4  PL28C LCMXO3LF9400C5BG484C-LCMXO3LF-A    I33 @S9S_MB_2U_LIB.S9S_MB_2U(SCH_1):PAGE311

RST_ESPI_RESET_N @S9S_MB_2U_LIB.S9S_MB_2U(SCH_1):RST_ESPI_RESET_N
    U4 BF17 GPPC_A_8_ESPI_RESET_N EMMITSBURG_REV0P9-GFNOCPU04302A    I93 @S9S_MB_2U_LIB.S9S_MB_2U(SCH_1):PAGE175
 R2363    1      A Q_RES_0402LF-10,1%,1/16W,CHIP,A   I101 @S9S_MB_2U_LIB.S9S_MB_2U(SCH_1):PAGE190

RST_ESPI_RESET_N_R @S9S_MB_2U_LIB.S9S_MB_2U(SCH_1):RST_ESPI_RESET_N_R
   U61    1     B1 NC7SB3157_SMLF-NC7SB3157P6X,NCA    I39 @S9S_MB_2U_LIB.S9S_MB_2U(SCH_1):PAGE190
 R2363    2      B Q_RES_0402LF-10,1%,1/16W,CHIP,A   I101 @S9S_MB_2U_LIB.S9S_MB_2U(SCH_1):PAGE190

RST_HP_OCP_SFF_R_N @S9S_MB_2U_LIB.S9S_MB_2U(SCH_1):RST_HP_OCP_SFF_R_N
  U224    4      Y 74LVC1G126SE7-74LVC1G126SE-7,SA     I7 @S9S_MB_2U_LIB.S9S_MB_2U(SCH_1):PAGE151
 R3232    1      A Q_RES_0402LF-100K,1%,1/16W,CHIA    I13 @S9S_MB_2U_LIB.S9S_MB_2U(SCH_1):PAGE151
 R3233    1      A Q_RES_0402LF-0,5%,1/16W,CHIP,CA    I17 @S9S_MB_2U_LIB.S9S_MB_2U(SCH_1):PAGE151

RST_HP_OCP_V3_1_N @S9S_MB_2U_LIB.S9S_MB_2U(SCH_1):RST_HP_OCP_V3_1_N
   U75    2      A 74LVC1G17GW-74LVC1G17GW,SMLF,IA     I1 @S9S_MB_2U_LIB.S9S_MB_2U(SCH_1):PAGE152
  U210    4      Y 74LVC1G08W57-74LVC1G08W5-7,SMLA   I189 @S9S_MB_2U_LIB.S9S_MB_2U(SCH_1):PAGE154

RST_HP_OCP_V3_2_N @S9S_MB_2U_LIB.S9S_MB_2U(SCH_1):RST_HP_OCP_V3_2_N
   U53    4      Y 74LVC1G08W57-74LVC1G08W5-7,SMLA    I56 @S9S_MB_2U_LIB.S9S_MB_2U(SCH_1):PAGE132
  U207    2      A 74LVC1G17GW-74LVC1G17GW,SMLF,IA    I35 @S9S_MB_2U_LIB.S9S_MB_2U(SCH_1):PAGE156

RST_HP_OCP_V3_2_R_N @S9S_MB_2U_LIB.S9S_MB_2U(SCH_1):RST_HP_OCP_V3_2_R_N
 R3236    1      A Q_RES_0402LF-0,5%,1/16W,CHIP,CA    I70 @S9S_MB_2U_LIB.S9S_MB_2U(SCH_1):PAGE156
 R3235    1      A Q_RES_0402LF-100K,1%,1/16W,CHIA    I72 @S9S_MB_2U_LIB.S9S_MB_2U(SCH_1):PAGE156
  U225    4      Y 74LVC1G126SE7-74LVC1G126SE-7,SA    I74 @S9S_MB_2U_LIB.S9S_MB_2U(SCH_1):PAGE156

RST_MB_STBY_N @S9S_MB_2U_LIB.S9S_MB_2U(SCH_1):RST_MB_STBY_N
 R1206    2      B Q_RES_0402LF-33.2,1%,1/16W,CHIA    I10 @S9S_MB_2U_LIB.S9S_MB_2U(SCH_1):PAGE212
   J41  A46 GND_A46 SCONN168_ME1016810202011-SCONNA   I173 @S9S_MB_2U_LIB.S9S_MB_2U(SCH_1):PAGE227

RST_MB_STBY_R_N @S9S_MB_2U_LIB.S9S_MB_2U(SCH_1):RST_MB_STBY_R_N
 R1206    1      A Q_RES_0402LF-33.2,1%,1/16W,CHIA    I10 @S9S_MB_2U_LIB.S9S_MB_2U(SCH_1):PAGE212
  U249  AA6  PB11A LCMXO3LF9400C5BG484C-LCMXO3LF-A     I1 @S9S_MB_2U_LIB.S9S_MB_2U(SCH_1):PAGE312
 R1823    2      B Q_RES_0402LF-1K,1%,1/16W,CHIP,A     I4 @S9S_MB_2U_LIB.S9S_MB_2U(SCH_1):PAGE311

RST_M_AB_CPU0_FPGA_N @S9S_MB_2U_LIB.S9S_MB_2U(SCH_1):RST_M_AB_CPU0_FPGA_N
    J1  207 RESET_N SCONN288_ADR50017P130CC-SCONN2A   I198 @S9S_MB_2U_LIB.S9S_MB_2U(SCH_1):PAGE82
    J2  207 RESET_N SCONN288_ADR50017P087CC-SCONN2A   I177 @S9S_MB_2U_LIB.S9S_MB_2U(SCH_1):PAGE83
    J4  207 RESET_N SCONN288_ADR50017P087CC-SCONN2A    I23 @S9S_MB_2U_LIB.S9S_MB_2U(SCH_1):PAGE85
  R836    2      B Q_RES_0402LF-0,5%,1/16W,CHIP,CA    I26 @S9S_MB_2U_LIB.S9S_MB_2U(SCH_1):PAGE129
  R840    2      B Q_RES_0402LF-1K,1%,1/16W,CHIP,A   I119 @S9S_MB_2U_LIB.S9S_MB_2U(SCH_1):PAGE129
    J3  207 RESET_N SCONN288_ADR50017P130CC-SCONN2A   I180 @S9S_MB_2U_LIB.S9S_MB_2U(SCH_1):PAGE84

RST_M_AB_CPU1_FPGA_N @S9S_MB_2U_LIB.S9S_MB_2U(SCH_1):RST_M_AB_CPU1_FPGA_N
   J17  207 RESET_N SCONN288_ADR50017P130CC-SCONN2A    I12 @S9S_MB_2U_LIB.S9S_MB_2U(SCH_1):PAGE98
   J18  207 RESET_N SCONN288_ADR50017P087CC-SCONN2A    I24 @S9S_MB_2U_LIB.S9S_MB_2U(SCH_1):PAGE99
   J19  207 RESET_N SCONN288_ADR50017P130CC-SCONN2A    I25 @S9S_MB_2U_LIB.S9S_MB_2U(SCH_1):PAGE100
   J20  207 RESET_N SCONN288_ADR50017P087CC-SCONN2A    I47 @S9S_MB_2U_LIB.S9S_MB_2U(SCH_1):PAGE101
  R816    2      B Q_RES_0402LF-0,5%,1/16W,CHIP,CA    I37 @S9S_MB_2U_LIB.S9S_MB_2U(SCH_1):PAGE130
  R820    2      B Q_RES_0402LF-1K,1%,1/16W,CHIP,A    I82 @S9S_MB_2U_LIB.S9S_MB_2U(SCH_1):PAGE130

RST_M_CD_CPU0_FPGA_N @S9S_MB_2U_LIB.S9S_MB_2U(SCH_1):RST_M_CD_CPU0_FPGA_N
    J5  207 RESET_N SCONN288_ADR50017P130CC-SCONN2A    I24 @S9S_MB_2U_LIB.S9S_MB_2U(SCH_1):PAGE86
    J6  207 RESET_N SCONN288_ADR50017P087CC-SCONN2A    I46 @S9S_MB_2U_LIB.S9S_MB_2U(SCH_1):PAGE87
    J7  207 RESET_N SCONN288_ADR50017P130CC-SCONN2A    I12 @S9S_MB_2U_LIB.S9S_MB_2U(SCH_1):PAGE88
    J8  207 RESET_N SCONN288_ADR50017P087CC-SCONN2A    I50 @S9S_MB_2U_LIB.S9S_MB_2U(SCH_1):PAGE89
  R837    2      B Q_RES_0402LF-0,5%,1/16W,CHIP,CA    I59 @S9S_MB_2U_LIB.S9S_MB_2U(SCH_1):PAGE129
  R841    2      B Q_RES_0402LF-1K,1%,1/16W,CHIP,A   I121 @S9S_MB_2U_LIB.S9S_MB_2U(SCH_1):PAGE129

RST_M_CD_CPU1_FPGA_N @S9S_MB_2U_LIB.S9S_MB_2U(SCH_1):RST_M_CD_CPU1_FPGA_N
   J21  207 RESET_N SCONN288_ADR50017P130CC-SCONN2A    I13 @S9S_MB_2U_LIB.S9S_MB_2U(SCH_1):PAGE102
   J22  207 RESET_N SCONN288_ADR50017P087CC-SCONN2A    I51 @S9S_MB_2U_LIB.S9S_MB_2U(SCH_1):PAGE103
   J23  207 RESET_N SCONN288_ADR50017P130CC-SCONN2A    I25 @S9S_MB_2U_LIB.S9S_MB_2U(SCH_1):PAGE104
   J24  207 RESET_N SCONN288_ADR50017P087CC-SCONN2A   I178 @S9S_MB_2U_LIB.S9S_MB_2U(SCH_1):PAGE105
  R817    2      B Q_RES_0402LF-0,5%,1/16W,CHIP,CA    I26 @S9S_MB_2U_LIB.S9S_MB_2U(SCH_1):PAGE130
  R821    2      B Q_RES_0402LF-1K,1%,1/16W,CHIP,A    I84 @S9S_MB_2U_LIB.S9S_MB_2U(SCH_1):PAGE130

RST_M_EF_CPU0_FPGA_N @S9S_MB_2U_LIB.S9S_MB_2U(SCH_1):RST_M_EF_CPU0_FPGA_N
    J9  207 RESET_N SCONN288_ADR50017P130CC-SCONN2A    I12 @S9S_MB_2U_LIB.S9S_MB_2U(SCH_1):PAGE90
   J10  207 RESET_N SCONN288_ADR50017P087CC-SCONN2A    I13 @S9S_MB_2U_LIB.S9S_MB_2U(SCH_1):PAGE91
   J11  207 RESET_N SCONN288_ADR50017P130CC-SCONN2A    I25 @S9S_MB_2U_LIB.S9S_MB_2U(SCH_1):PAGE92
   J12  207 RESET_N SCONN288_ADR50017P087CC-SCONN2A    I24 @S9S_MB_2U_LIB.S9S_MB_2U(SCH_1):PAGE93
  R838    2      B Q_RES_0402LF-0,5%,1/16W,CHIP,CA    I76 @S9S_MB_2U_LIB.S9S_MB_2U(SCH_1):PAGE129
  R842    2      B Q_RES_0402LF-1K,1%,1/16W,CHIP,A   I123 @S9S_MB_2U_LIB.S9S_MB_2U(SCH_1):PAGE129

RST_M_EF_CPU1_FPGA_N @S9S_MB_2U_LIB.S9S_MB_2U(SCH_1):RST_M_EF_CPU1_FPGA_N
   J25  207 RESET_N SCONN288_ADR50017P130CC-SCONN2A   I180 @S9S_MB_2U_LIB.S9S_MB_2U(SCH_1):PAGE106
   J26  207 RESET_N SCONN288_ADR50017P087CC-SCONN2A   I180 @S9S_MB_2U_LIB.S9S_MB_2U(SCH_1):PAGE107
   J27  207 RESET_N SCONN288_ADR50017P130CC-SCONN2A   I179 @S9S_MB_2U_LIB.S9S_MB_2U(SCH_1):PAGE108
   J28  207 RESET_N SCONN288_ADR50017P087CC-SCONN2A    I47 @S9S_MB_2U_LIB.S9S_MB_2U(SCH_1):PAGE109
  R818    2      B Q_RES_0402LF-0,5%,1/16W,CHIP,CA    I22 @S9S_MB_2U_LIB.S9S_MB_2U(SCH_1):PAGE130
  R822    2      B Q_RES_0402LF-1K,1%,1/16W,CHIP,A    I88 @S9S_MB_2U_LIB.S9S_MB_2U(SCH_1):PAGE130

RST_M_GH_CPU0_FPGA_N @S9S_MB_2U_LIB.S9S_MB_2U(SCH_1):RST_M_GH_CPU0_FPGA_N
   J13  207 RESET_N SCONN288_ADR50017P130CC-SCONN2A    I11 @S9S_MB_2U_LIB.S9S_MB_2U(SCH_1):PAGE94
   J14  207 RESET_N SCONN288_ADR50017P087CC-SCONN2A    I47 @S9S_MB_2U_LIB.S9S_MB_2U(SCH_1):PAGE95
   J15  207 RESET_N SCONN288_ADR50017P130CC-SCONN2A    I48 @S9S_MB_2U_LIB.S9S_MB_2U(SCH_1):PAGE96
   J16  207 RESET_N SCONN288_ADR50017P087CC-SCONN2A     I6 @S9S_MB_2U_LIB.S9S_MB_2U(SCH_1):PAGE97
  R835    2      B Q_RES_0402LF-0,5%,1/16W,CHIP,CA    I86 @S9S_MB_2U_LIB.S9S_MB_2U(SCH_1):PAGE129
  R839    2      B Q_RES_0402LF-1K,1%,1/16W,CHIP,A   I125 @S9S_MB_2U_LIB.S9S_MB_2U(SCH_1):PAGE129

RST_M_GH_CPU1_FPGA_N @S9S_MB_2U_LIB.S9S_MB_2U(SCH_1):RST_M_GH_CPU1_FPGA_N
   J29  207 RESET_N SCONN288_ADR50017P130CC-SCONN2A   I179 @S9S_MB_2U_LIB.S9S_MB_2U(SCH_1):PAGE110
   J30  207 RESET_N SCONN288_ADR50017P087CC-SCONN2A   I179 @S9S_MB_2U_LIB.S9S_MB_2U(SCH_1):PAGE111
   J31  207 RESET_N SCONN288_ADR50017P130CC-SCONN2A   I180 @S9S_MB_2U_LIB.S9S_MB_2U(SCH_1):PAGE112
   J32  207 RESET_N SCONN288_ADR50017P087CC-SCONN2A   I179 @S9S_MB_2U_LIB.S9S_MB_2U(SCH_1):PAGE113
  R815    2      B Q_RES_0402LF-0,5%,1/16W,CHIP,CA    I11 @S9S_MB_2U_LIB.S9S_MB_2U(SCH_1):PAGE130
  R819    2      B Q_RES_0402LF-1K,1%,1/16W,CHIP,A    I90 @S9S_MB_2U_LIB.S9S_MB_2U(SCH_1):PAGE130

RST_OCP_V3_1_BUF_N @S9S_MB_2U_LIB.S9S_MB_2U(SCH_1):RST_OCP_V3_1_BUF_N
   U75    4      Y 74LVC1G17GW-74LVC1G17GW,SMLF,IA     I1 @S9S_MB_2U_LIB.S9S_MB_2U(SCH_1):PAGE152
  R419    1      A Q_RES_0402LF-33.2,1%,1/16W,CHIA     I6 @S9S_MB_2U_LIB.S9S_MB_2U(SCH_1):PAGE152
  R435    1      A Q_RES_0402LF-33.2,1%,1/16W,CHIA     I8 @S9S_MB_2U_LIB.S9S_MB_2U(SCH_1):PAGE152
 R1504    1      A Q_RES_0402LF-33.2,1%,1/16W,CHIA    I10 @S9S_MB_2U_LIB.S9S_MB_2U(SCH_1):PAGE152
 R1505    1      A Q_RES_0402LF-33.2,1%,1/16W,CHIA    I13 @S9S_MB_2U_LIB.S9S_MB_2U(SCH_1):PAGE152

RST_OCP_V3_1_N @S9S_MB_2U_LIB.S9S_MB_2U(SCH_1):RST_OCP_V3_1_N
 R1514    2      B Q_RES_0402LF-33.2,1%,1/16W,CHIA   I105 @S9S_MB_2U_LIB.S9S_MB_2U(SCH_1):PAGE212
  U210    2      B 74LVC1G08W57-74LVC1G08W5-7,SMLA   I189 @S9S_MB_2U_LIB.S9S_MB_2U(SCH_1):PAGE154

RST_OCP_V3_2_BUF_N @S9S_MB_2U_LIB.S9S_MB_2U(SCH_1):RST_OCP_V3_2_BUF_N
  U207    4      Y 74LVC1G17GW-74LVC1G17GW,SMLF,IA    I35 @S9S_MB_2U_LIB.S9S_MB_2U(SCH_1):PAGE156
 R3189    1      A Q_RES_0402LF-33.2,1%,1/16W,CHIA    I38 @S9S_MB_2U_LIB.S9S_MB_2U(SCH_1):PAGE156
 R3188    1      A Q_RES_0402LF-33.2,1%,1/16W,CHIA    I39 @S9S_MB_2U_LIB.S9S_MB_2U(SCH_1):PAGE156
 R3187    1      A Q_RES_0402LF-33.2,1%,1/16W,CHIA    I40 @S9S_MB_2U_LIB.S9S_MB_2U(SCH_1):PAGE156
 R3186    1      A Q_RES_0402LF-33.2,1%,1/16W,CHIA    I41 @S9S_MB_2U_LIB.S9S_MB_2U(SCH_1):PAGE156

RST_OCP_V3_2_N @S9S_MB_2U_LIB.S9S_MB_2U(SCH_1):RST_OCP_V3_2_N
 R1520    2      B Q_RES_0402LF-33.2,1%,1/16W,CHIA   I113 @S9S_MB_2U_LIB.S9S_MB_2U(SCH_1):PAGE212
   U53    2      B 74LVC1G08W57-74LVC1G08W5-7,SMLA    I56 @S9S_MB_2U_LIB.S9S_MB_2U(SCH_1):PAGE132

RST_PCH_RSTBTN_R_N @S9S_MB_2U_LIB.S9S_MB_2U(SCH_1):RST_PCH_RSTBTN_R_N
    U4 AJ10 SYS_RESET_N EMMITSBURG_REV0P9-GFNOCPU04302A    I36 @S9S_MB_2U_LIB.S9S_MB_2U(SCH_1):PAGE174
  R696    2      B Q_RES_0402LF-4.75K,1%,1/16W,CHA    I63 @S9S_MB_2U_LIB.S9S_MB_2U(SCH_1):PAGE174
  R697    2      B Q_RES_0402LF-33.2,1%,1/16W,CHIA    I66 @S9S_MB_2U_LIB.S9S_MB_2U(SCH_1):PAGE174

RST_PCIE_CPU0_DEV_PERST_N @S9S_MB_2U_LIB.S9S_MB_2U(SCH_1):RST_PCIE_CPU0_DEV_PERST_N
 R1417    1      A Q_RES_0402LF-2K,1%,1/16W,CHIP,A     I7 @S9S_MB_2U_LIB.S9S_MB_2U(SCH_1):PAGE208
 R1514    1      A Q_RES_0402LF-33.2,1%,1/16W,CHIA   I105 @S9S_MB_2U_LIB.S9S_MB_2U(SCH_1):PAGE212
  U249  M20  PR17C LCMXO3LF9400C5BG484C-LCMXO3LF-A     I1 @S9S_MB_2U_LIB.S9S_MB_2U(SCH_1):PAGE313

RST_PCIE_CPU1_DEV_PERST_N @S9S_MB_2U_LIB.S9S_MB_2U(SCH_1):RST_PCIE_CPU1_DEV_PERST_N
 R1418    1      A Q_RES_0402LF-2K,1%,1/16W,CHIP,A     I6 @S9S_MB_2U_LIB.S9S_MB_2U(SCH_1):PAGE208
 R1520    1      A Q_RES_0402LF-33.2,1%,1/16W,CHIA   I113 @S9S_MB_2U_LIB.S9S_MB_2U(SCH_1):PAGE212
  U249  M19  PR17D LCMXO3LF9400C5BG484C-LCMXO3LF-A     I1 @S9S_MB_2U_LIB.S9S_MB_2U(SCH_1):PAGE313

RST_PCIE_PCH_DEV_0_N @S9S_MB_2U_LIB.S9S_MB_2U(SCH_1):RST_PCIE_PCH_DEV_0_N
   J59   50 PERST# SCONN75K_APCI0155P004A-SCONN75A   I178 @S9S_MB_2U_LIB.S9S_MB_2U(SCH_1):PAGE182
 R2113    2      B Q_RES_0402LF-33.2,1%,1/16W,CHIA   I344 @S9S_MB_2U_LIB.S9S_MB_2U(SCH_1):PAGE182

RST_PCIE_PCH_DEV_BUF_M2_0_PERST @S9S_MB_2U_LIB.S9S_MB_2U(SCH_1):RST_PCIE_PCH_DEV_BUF_M2_0_PERST_N
  U259    4     2Y SN74LVC2G07DCKR_SMLF-SN74LVC2GA   I327 @S9S_MB_2U_LIB.S9S_MB_2U(SCH_1):PAGE182
 R2121    2      B Q_RES_0402LF-4.7K,5%,1/16W,CHIA   I337 @S9S_MB_2U_LIB.S9S_MB_2U(SCH_1):PAGE182
 R2113    1      A Q_RES_0402LF-33.2,1%,1/16W,CHIA   I344 @S9S_MB_2U_LIB.S9S_MB_2U(SCH_1):PAGE182

RST_PCIE_PCH_DEV_PERST_E1S_R_N @S9S_MB_2U_LIB.S9S_MB_2U(SCH_1):RST_PCIE_PCH_DEV_PERST_E1S_R_N
 R3779    1      A Q_RES_0402LF-0,5%,1/16W,CHIP,CA   I309 @S9S_MB_2U_LIB.S9S_MB_2U(SCH_1):PAGE297
 R4174    2      B Q_RES_0402LF-33.2,1%,1/16W,CHIA   I134 @S9S_MB_2U_LIB.S9S_MB_2U(SCH_1):PAGE312

RST_PCIE_PCH_DEV_PERST_M2_R_N @S9S_MB_2U_LIB.S9S_MB_2U(SCH_1):RST_PCIE_PCH_DEV_PERST_M2_R_N
  U259    3     2A SN74LVC2G07DCKR_SMLF-SN74LVC2GA   I327 @S9S_MB_2U_LIB.S9S_MB_2U(SCH_1):PAGE182
 R4175    2      B Q_RES_0402LF-33.2,1%,1/16W,CHIA   I135 @S9S_MB_2U_LIB.S9S_MB_2U(SCH_1):PAGE312

RST_PCIE_PCH_DEV_PERST_N @S9S_MB_2U_LIB.S9S_MB_2U(SCH_1):RST_PCIE_PCH_DEV_PERST_N
 R1419    1      A Q_RES_0402LF-2K,1%,1/16W,CHIP,A     I8 @S9S_MB_2U_LIB.S9S_MB_2U(SCH_1):PAGE208
  U249  U14  PB32C LCMXO3LF9400C5BG484C-LCMXO3LF-A     I1 @S9S_MB_2U_LIB.S9S_MB_2U(SCH_1):PAGE312
 R4174    1      A Q_RES_0402LF-33.2,1%,1/16W,CHIA   I134 @S9S_MB_2U_LIB.S9S_MB_2U(SCH_1):PAGE312
 R4175    1      A Q_RES_0402LF-33.2,1%,1/16W,CHIA   I135 @S9S_MB_2U_LIB.S9S_MB_2U(SCH_1):PAGE312

RST_PCIE_PCH_E1S_PERST_N @S9S_MB_2U_LIB.S9S_MB_2U(SCH_1):RST_PCIE_PCH_E1S_PERST_N
 R3779    2      B Q_RES_0402LF-0,5%,1/16W,CHIP,CA   I309 @S9S_MB_2U_LIB.S9S_MB_2U(SCH_1):PAGE297
   J90  B10 PERST0# SCONN56_123276793-SCONN56_1-23A   I318 @S9S_MB_2U_LIB.S9S_MB_2U(SCH_1):PAGE297

RST_PERST0_OCP_SFF_N @S9S_MB_2U_LIB.S9S_MB_2U(SCH_1):RST_PERST0_OCP_SFF_N
  R419    2      B Q_RES_0402LF-33.2,1%,1/16W,CHIA     I6 @S9S_MB_2U_LIB.S9S_MB_2U(SCH_1):PAGE152
   J37  B10 PERST0# SCONN168_ME1016810202011-SCONNA   I199 @S9S_MB_2U_LIB.S9S_MB_2U(SCH_1):PAGE150

RST_PERST0_OCP_V3_2_N @S9S_MB_2U_LIB.S9S_MB_2U(SCH_1):RST_PERST0_OCP_V3_2_N
 R3186    2      B Q_RES_0402LF-33.2,1%,1/16W,CHIA    I41 @S9S_MB_2U_LIB.S9S_MB_2U(SCH_1):PAGE156
   J35  B10 PERST0# SCONN168_ME1016810202011-SCONNA   I303 @S9S_MB_2U_LIB.S9S_MB_2U(SCH_1):PAGE146

RST_PERST1_OCP_SFF_N @S9S_MB_2U_LIB.S9S_MB_2U(SCH_1):RST_PERST1_OCP_SFF_N
  R435    2      B Q_RES_0402LF-33.2,1%,1/16W,CHIA     I8 @S9S_MB_2U_LIB.S9S_MB_2U(SCH_1):PAGE152
   J37  A11 PERST1# SCONN168_ME1016810202011-SCONNA   I199 @S9S_MB_2U_LIB.S9S_MB_2U(SCH_1):PAGE150

RST_PERST1_OCP_V3_2_N @S9S_MB_2U_LIB.S9S_MB_2U(SCH_1):RST_PERST1_OCP_V3_2_N
 R3187    2      B Q_RES_0402LF-33.2,1%,1/16W,CHIA    I40 @S9S_MB_2U_LIB.S9S_MB_2U(SCH_1):PAGE156
   J35  A11 PERST1# SCONN168_ME1016810202011-SCONNA   I303 @S9S_MB_2U_LIB.S9S_MB_2U(SCH_1):PAGE146

RST_PERST2_OCP_SFF_N @S9S_MB_2U_LIB.S9S_MB_2U(SCH_1):RST_PERST2_OCP_SFF_N
 R1504    2      B Q_RES_0402LF-33.2,1%,1/16W,CHIA    I10 @S9S_MB_2U_LIB.S9S_MB_2U(SCH_1):PAGE152
   J37  OA1 PERST2# SCONN168_ME1016810202011-SCONNA   I199 @S9S_MB_2U_LIB.S9S_MB_2U(SCH_1):PAGE150

RST_PERST2_OCP_V3_2_N @S9S_MB_2U_LIB.S9S_MB_2U(SCH_1):RST_PERST2_OCP_V3_2_N
 R3188    2      B Q_RES_0402LF-33.2,1%,1/16W,CHIA    I39 @S9S_MB_2U_LIB.S9S_MB_2U(SCH_1):PAGE156
   J35  OA1 PERST2# SCONN168_ME1016810202011-SCONNA   I303 @S9S_MB_2U_LIB.S9S_MB_2U(SCH_1):PAGE146

RST_PERST3_OCP_SFF_N @S9S_MB_2U_LIB.S9S_MB_2U(SCH_1):RST_PERST3_OCP_SFF_N
 R1505    2      B Q_RES_0402LF-33.2,1%,1/16W,CHIA    I13 @S9S_MB_2U_LIB.S9S_MB_2U(SCH_1):PAGE152
   J37  OA2 PERST3# SCONN168_ME1016810202011-SCONNA   I199 @S9S_MB_2U_LIB.S9S_MB_2U(SCH_1):PAGE150

RST_PERST3_OCP_V3_2_N @S9S_MB_2U_LIB.S9S_MB_2U(SCH_1):RST_PERST3_OCP_V3_2_N
 R3189    2      B Q_RES_0402LF-33.2,1%,1/16W,CHIA    I38 @S9S_MB_2U_LIB.S9S_MB_2U(SCH_1):PAGE156
   J35  OA2 PERST3# SCONN168_ME1016810202011-SCONNA   I303 @S9S_MB_2U_LIB.S9S_MB_2U(SCH_1):PAGE146

RST_PERST_0_SWB_BUF_N @S9S_MB_2U_LIB.S9S_MB_2U(SCH_1):RST_PERST_0_SWB_BUF_N
  J112   T8     T8 CONN160_10131762101LF-CONN160_A    I75 @S9S_MB_2U_LIB.S9S_MB_2U(SCH_1):PAGE149
 R3469    2      B Q_RES_0402LF-49.9,1%,1/16W,CHIA   I199 @S9S_MB_2U_LIB.S9S_MB_2U(SCH_1):PAGE160

RST_PERST_0_SWB_BUF_R_N @S9S_MB_2U_LIB.S9S_MB_2U(SCH_1):RST_PERST_0_SWB_BUF_R_N
  U252    6     B0 74LVC2G17GW-74LVC2G17GW,SMLF,IA   I153 @S9S_MB_2U_LIB.S9S_MB_2U(SCH_1):PAGE160
 R3467    1      A Q_RES_0402LF-10K,1%,1/16W,CHIPA   I181 @S9S_MB_2U_LIB.S9S_MB_2U(SCH_1):PAGE160
 R3469    1      A Q_RES_0402LF-49.9,1%,1/16W,CHIA   I199 @S9S_MB_2U_LIB.S9S_MB_2U(SCH_1):PAGE160

RST_PERST_1_SWB_BUF_N @S9S_MB_2U_LIB.S9S_MB_2U(SCH_1):RST_PERST_1_SWB_BUF_N
  J112   A5     A5 CONN160_10131762101LF-CONN160_A    I75 @S9S_MB_2U_LIB.S9S_MB_2U(SCH_1):PAGE149
 R3391    2      B Q_RES_0402LF-49.9,1%,1/16W,CHIA   I200 @S9S_MB_2U_LIB.S9S_MB_2U(SCH_1):PAGE160

RST_PERST_1_SWB_BUF_R_N @S9S_MB_2U_LIB.S9S_MB_2U(SCH_1):RST_PERST_1_SWB_BUF_R_N
 R3455    1      A Q_RES_0402LF-10K,1%,1/16W,CHIPA   I139 @S9S_MB_2U_LIB.S9S_MB_2U(SCH_1):PAGE160
  U252    4     B1 74LVC2G17GW-74LVC2G17GW,SMLF,IA   I153 @S9S_MB_2U_LIB.S9S_MB_2U(SCH_1):PAGE160
 R3391    1      A Q_RES_0402LF-49.9,1%,1/16W,CHIA   I200 @S9S_MB_2U_LIB.S9S_MB_2U(SCH_1):PAGE160

RST_PERST_2_SWB_BUF_N @S9S_MB_2U_LIB.S9S_MB_2U(SCH_1):RST_PERST_2_SWB_BUF_N
  J112   A1     A1 CONN160_10131762101LF-CONN160_A    I76 @S9S_MB_2U_LIB.S9S_MB_2U(SCH_1):PAGE149
 R3468    2      B Q_RES_0402LF-49.9,1%,1/16W,CHIA   I197 @S9S_MB_2U_LIB.S9S_MB_2U(SCH_1):PAGE160

RST_PERST_2_SWB_BUF_R_N @S9S_MB_2U_LIB.S9S_MB_2U(SCH_1):RST_PERST_2_SWB_BUF_R_N
  U256    6     B0 74LVC2G17GW-74LVC2G17GW,SMLF,IA   I173 @S9S_MB_2U_LIB.S9S_MB_2U(SCH_1):PAGE160
 R3466    1      A Q_RES_0402LF-10K,1%,1/16W,CHIPA   I184 @S9S_MB_2U_LIB.S9S_MB_2U(SCH_1):PAGE160
 R3468    1      A Q_RES_0402LF-49.9,1%,1/16W,CHIA   I197 @S9S_MB_2U_LIB.S9S_MB_2U(SCH_1):PAGE160

RST_PERST_SWB_N @S9S_MB_2U_LIB.S9S_MB_2U(SCH_1):RST_PERST_SWB_N
 R2738    1      A Q_RES_0402LF-33.2,1%,1/16W,CHIA   I127 @S9S_MB_2U_LIB.S9S_MB_2U(SCH_1):PAGE212
  U249  W19  PR30C LCMXO3LF9400C5BG484C-LCMXO3LF-A     I1 @S9S_MB_2U_LIB.S9S_MB_2U(SCH_1):PAGE313
 R4622    1      A Q_RES_0402LF-2K,1%,1/16W,CHIP,A    I66 @S9S_MB_2U_LIB.S9S_MB_2U(SCH_1):PAGE208

RST_PERST_SWB_R_N @S9S_MB_2U_LIB.S9S_MB_2U(SCH_1):RST_PERST_SWB_R_N
 R2738    2      B Q_RES_0402LF-33.2,1%,1/16W,CHIA   I127 @S9S_MB_2U_LIB.S9S_MB_2U(SCH_1):PAGE212
  U252    1     A0 74LVC2G17GW-74LVC2G17GW,SMLF,IA   I153 @S9S_MB_2U_LIB.S9S_MB_2U(SCH_1):PAGE160
  U252    3     A1 74LVC2G17GW-74LVC2G17GW,SMLF,IA   I153 @S9S_MB_2U_LIB.S9S_MB_2U(SCH_1):PAGE160
  U256    1     A0 74LVC2G17GW-74LVC2G17GW,SMLF,IA   I173 @S9S_MB_2U_LIB.S9S_MB_2U(SCH_1):PAGE160

RST_PFR_OVR_RTC @S9S_MB_2U_LIB.S9S_MB_2U(SCH_1):RST_PFR_OVR_RTC
 R1839    1      A Q_RES_0402LF-0,5%,1/16W,EMPTY,A    I85 @S9S_MB_2U_LIB.S9S_MB_2U(SCH_1):PAGE177
 R1843    2      B Q_RES_0402LF-33.2,1%,1/16W,CHIA   I122 @S9S_MB_2U_LIB.S9S_MB_2U(SCH_1):PAGE211
   Q34    G      G MOSFET_NCH_GDS_ESD_PROTECTED-2A   I123 @S9S_MB_2U_LIB.S9S_MB_2U(SCH_1):PAGE177
 R4712    1      A Q_RES_0402LF-100K,1%,1/16W,CHIA   I125 @S9S_MB_2U_LIB.S9S_MB_2U(SCH_1):PAGE177

RST_PFR_OVR_RTC_R @S9S_MB_2U_LIB.S9S_MB_2U(SCH_1):RST_PFR_OVR_RTC_R
 R1843    1      A Q_RES_0402LF-33.2,1%,1/16W,CHIA   I122 @S9S_MB_2U_LIB.S9S_MB_2U(SCH_1):PAGE211
  U249   W6  PB11C LCMXO3LF9400C5BG484C-LCMXO3LF-A     I1 @S9S_MB_2U_LIB.S9S_MB_2U(SCH_1):PAGE312

RST_PFR_OVR_SRTC @S9S_MB_2U_LIB.S9S_MB_2U(SCH_1):RST_PFR_OVR_SRTC
 R1840    1      A Q_RES_0402LF-0,5%,1/16W,EMPTY,A    I89 @S9S_MB_2U_LIB.S9S_MB_2U(SCH_1):PAGE177
 R1844    2      B Q_RES_0402LF-33.2,1%,1/16W,CHIA   I123 @S9S_MB_2U_LIB.S9S_MB_2U(SCH_1):PAGE211
   Q35    G      G MOSFET_NCH_GDS_ESD_PROTECTED-2A   I124 @S9S_MB_2U_LIB.S9S_MB_2U(SCH_1):PAGE177
 R4713    1      A Q_RES_0402LF-100K,1%,1/16W,CHIA   I127 @S9S_MB_2U_LIB.S9S_MB_2U(SCH_1):PAGE177

RST_PFR_OVR_SRTC_R @S9S_MB_2U_LIB.S9S_MB_2U(SCH_1):RST_PFR_OVR_SRTC_R
 R1844    1      A Q_RES_0402LF-33.2,1%,1/16W,CHIA   I123 @S9S_MB_2U_LIB.S9S_MB_2U(SCH_1):PAGE211
  U249   V7  PB11D LCMXO3LF9400C5BG484C-LCMXO3LF-A     I1 @S9S_MB_2U_LIB.S9S_MB_2U(SCH_1):PAGE312

RST_PLD_CPU0_DRAM_AB_N @S9S_MB_2U_LIB.S9S_MB_2U(SCH_1):RST_PLD_CPU0_DRAM_AB_N
  R836    1      A Q_RES_0402LF-0,5%,1/16W,CHIP,CA    I26 @S9S_MB_2U_LIB.S9S_MB_2U(SCH_1):PAGE129
  C622    1      A Q_CAP_C0402-1UF,25V,10%,EMPTY,A    I91 @S9S_MB_2U_LIB.S9S_MB_2U(SCH_1):PAGE129
  R706    1      A Q_RES_0402LF-10K,1%,1/16W,EMPTA   I103 @S9S_MB_2U_LIB.S9S_MB_2U(SCH_1):PAGE129
   Q98    2     G1 MOSFET_NCH_DUAL-NX6008NBKS,SMLA    I68 @S9S_MB_2U_LIB.S9S_MB_2U(SCH_1):PAGE304
  U249   C1 PL4A||L_GPLLT_IN LCMXO3LF9400C5BG484C-LCMXO3LF-A    I33 @S9S_MB_2U_LIB.S9S_MB_2U(SCH_1):PAGE311

RST_PLD_CPU0_DRAM_CD_N @S9S_MB_2U_LIB.S9S_MB_2U(SCH_1):RST_PLD_CPU0_DRAM_CD_N
  R837    1      A Q_RES_0402LF-0,5%,1/16W,CHIP,CA    I59 @S9S_MB_2U_LIB.S9S_MB_2U(SCH_1):PAGE129
  C623    1      A Q_CAP_C0402-1UF,25V,10%,EMPTY,A    I94 @S9S_MB_2U_LIB.S9S_MB_2U(SCH_1):PAGE129
  R707    1      A Q_RES_0402LF-10K,1%,1/16W,EMPTA   I106 @S9S_MB_2U_LIB.S9S_MB_2U(SCH_1):PAGE129
   Q98    5     G2 MOSFET_NCH_DUAL-NX6008NBKS,SMLA    I69 @S9S_MB_2U_LIB.S9S_MB_2U(SCH_1):PAGE304
  U249   D2 PL4B||L_GPLLC_IN LCMXO3LF9400C5BG484C-LCMXO3LF-A    I33 @S9S_MB_2U_LIB.S9S_MB_2U(SCH_1):PAGE311

RST_PLD_CPU0_DRAM_EF_N @S9S_MB_2U_LIB.S9S_MB_2U(SCH_1):RST_PLD_CPU0_DRAM_EF_N
  R838    1      A Q_RES_0402LF-0,5%,1/16W,CHIP,CA    I76 @S9S_MB_2U_LIB.S9S_MB_2U(SCH_1):PAGE129
  C624    1      A Q_CAP_C0402-1UF,25V,10%,EMPTY,A    I99 @S9S_MB_2U_LIB.S9S_MB_2U(SCH_1):PAGE129
  R708    1      A Q_RES_0402LF-10K,1%,1/16W,EMPTA   I109 @S9S_MB_2U_LIB.S9S_MB_2U(SCH_1):PAGE129
   Q97    2     G1 MOSFET_NCH_DUAL-NX6008NBKS,SMLA    I71 @S9S_MB_2U_LIB.S9S_MB_2U(SCH_1):PAGE304
  U249   G5   PL4C LCMXO3LF9400C5BG484C-LCMXO3LF-A    I33 @S9S_MB_2U_LIB.S9S_MB_2U(SCH_1):PAGE311

RST_PLD_CPU0_DRAM_GH_N @S9S_MB_2U_LIB.S9S_MB_2U(SCH_1):RST_PLD_CPU0_DRAM_GH_N
  R835    1      A Q_RES_0402LF-0,5%,1/16W,CHIP,CA    I86 @S9S_MB_2U_LIB.S9S_MB_2U(SCH_1):PAGE129
  C621    1      A Q_CAP_C0402-1UF,25V,10%,EMPTY,A   I102 @S9S_MB_2U_LIB.S9S_MB_2U(SCH_1):PAGE129
  R705    1      A Q_RES_0402LF-10K,1%,1/16W,EMPTA   I112 @S9S_MB_2U_LIB.S9S_MB_2U(SCH_1):PAGE129
   Q97    5     G2 MOSFET_NCH_DUAL-NX6008NBKS,SMLA    I70 @S9S_MB_2U_LIB.S9S_MB_2U(SCH_1):PAGE304
  U249   H6   PL4D LCMXO3LF9400C5BG484C-LCMXO3LF-A    I33 @S9S_MB_2U_LIB.S9S_MB_2U(SCH_1):PAGE311

RST_PLD_CPU1_DRAM_AB_N @S9S_MB_2U_LIB.S9S_MB_2U(SCH_1):RST_PLD_CPU1_DRAM_AB_N
  R816    1      A Q_RES_0402LF-0,5%,1/16W,CHIP,CA    I37 @S9S_MB_2U_LIB.S9S_MB_2U(SCH_1):PAGE130
  C614    1      A Q_CAP_C0402-1UF,25V,10%,EMPTY,A    I65 @S9S_MB_2U_LIB.S9S_MB_2U(SCH_1):PAGE130
  R703    1      A Q_RES_0402LF-10K,1%,1/16W,EMPTA    I79 @S9S_MB_2U_LIB.S9S_MB_2U(SCH_1):PAGE130
  U249   D1   PL5A LCMXO3LF9400C5BG484C-LCMXO3LF-A    I33 @S9S_MB_2U_LIB.S9S_MB_2U(SCH_1):PAGE311
  Q105    2     G1 MOSFET_NCH_DUAL-NX6008NBKS,SMLA    I76 @S9S_MB_2U_LIB.S9S_MB_2U(SCH_1):PAGE304

RST_PLD_CPU1_DRAM_CD_N @S9S_MB_2U_LIB.S9S_MB_2U(SCH_1):RST_PLD_CPU1_DRAM_CD_N
  R817    1      A Q_RES_0402LF-0,5%,1/16W,CHIP,CA    I26 @S9S_MB_2U_LIB.S9S_MB_2U(SCH_1):PAGE130
  C615    1      A Q_CAP_C0402-1UF,25V,10%,EMPTY,A    I62 @S9S_MB_2U_LIB.S9S_MB_2U(SCH_1):PAGE130
  R701    1      A Q_RES_0402LF-10K,1%,1/16W,EMPTA    I63 @S9S_MB_2U_LIB.S9S_MB_2U(SCH_1):PAGE130
   Q99    2     G1 MOSFET_NCH_DUAL-NX6008NBKS,SMLA    I72 @S9S_MB_2U_LIB.S9S_MB_2U(SCH_1):PAGE304
  U249   E2   PL5B LCMXO3LF9400C5BG484C-LCMXO3LF-A    I33 @S9S_MB_2U_LIB.S9S_MB_2U(SCH_1):PAGE311

RST_PLD_CPU1_DRAM_EF_N @S9S_MB_2U_LIB.S9S_MB_2U(SCH_1):RST_PLD_CPU1_DRAM_EF_N
  R818    1      A Q_RES_0402LF-0,5%,1/16W,CHIP,CA    I22 @S9S_MB_2U_LIB.S9S_MB_2U(SCH_1):PAGE130
  C616    1      A Q_CAP_C0402-1UF,25V,10%,EMPTY,A    I59 @S9S_MB_2U_LIB.S9S_MB_2U(SCH_1):PAGE130
  R704    1      A Q_RES_0402LF-10K,1%,1/16W,EMPTA    I75 @S9S_MB_2U_LIB.S9S_MB_2U(SCH_1):PAGE130
  Q100    2     G1 MOSFET_NCH_DUAL-NX6008NBKS,SMLA    I74 @S9S_MB_2U_LIB.S9S_MB_2U(SCH_1):PAGE304
  U249   E3   PL5C LCMXO3LF9400C5BG484C-LCMXO3LF-A    I33 @S9S_MB_2U_LIB.S9S_MB_2U(SCH_1):PAGE311

RST_PLD_CPU1_DRAM_GH_N @S9S_MB_2U_LIB.S9S_MB_2U(SCH_1):RST_PLD_CPU1_DRAM_GH_N
  R815    1      A Q_RES_0402LF-0,5%,1/16W,CHIP,CA    I11 @S9S_MB_2U_LIB.S9S_MB_2U(SCH_1):PAGE130
  C613    1      A Q_CAP_C0402-1UF,25V,10%,EMPTY,A    I68 @S9S_MB_2U_LIB.S9S_MB_2U(SCH_1):PAGE130
  R702    1      A Q_RES_0402LF-10K,1%,1/16W,EMPTA    I76 @S9S_MB_2U_LIB.S9S_MB_2U(SCH_1):PAGE130
  Q100    5     G2 MOSFET_NCH_DUAL-NX6008NBKS,SMLA    I75 @S9S_MB_2U_LIB.S9S_MB_2U(SCH_1):PAGE304
  U249   F4   PL5D LCMXO3LF9400C5BG484C-LCMXO3LF-A    I33 @S9S_MB_2U_LIB.S9S_MB_2U(SCH_1):PAGE311

RST_PLTRST_B_MUX_N @S9S_MB_2U_LIB.S9S_MB_2U(SCH_1):RST_PLTRST_B_MUX_N
   U61    3     B0 NC7SB3157_SMLF-NC7SB3157P6X,NCA    I39 @S9S_MB_2U_LIB.S9S_MB_2U(SCH_1):PAGE190
 R1470    2      B Q_RES_0402LF-33.2,1%,1/16W,CHIA    I56 @S9S_MB_2U_LIB.S9S_MB_2U(SCH_1):PAGE212

RST_PLTRST_B_N @S9S_MB_2U_LIB.S9S_MB_2U(SCH_1):RST_PLTRST_B_N
 R1469    2      B Q_RES_0402LF-33.2,1%,1/16W,CHIA    I55 @S9S_MB_2U_LIB.S9S_MB_2U(SCH_1):PAGE212
   J41  A51 PERP10 SCONN168_ME1016810202011-SCONNA   I173 @S9S_MB_2U_LIB.S9S_MB_2U(SCH_1):PAGE227

RST_PLTRST_N @S9S_MB_2U_LIB.S9S_MB_2U(SCH_1):RST_PLTRST_N
    U4  AB4 GPP_D_11_PLTRST_N EMMITSBURG_REV0P9-GFNOCPU04302A    I93 @S9S_MB_2U_LIB.S9S_MB_2U(SCH_1):PAGE175
 R1205    1      A Q_RES_0402LF-33.2,1%,1/16W,CHIA     I7 @S9S_MB_2U_LIB.S9S_MB_2U(SCH_1):PAGE212
 R1541    2      B Q_RES_0402LF-100K,1%,1/16W,CHIA    I92 @S9S_MB_2U_LIB.S9S_MB_2U(SCH_1):PAGE212
   Q88    5     G2 MOSFET_NCH_DUAL-PJT138K,SMLF,IA    I42 @S9S_MB_2U_LIB.S9S_MB_2U(SCH_1):PAGE241

RST_PLTRST_PLD_B_N @S9S_MB_2U_LIB.S9S_MB_2U(SCH_1):RST_PLTRST_PLD_B_N
 R1420    1      A Q_RES_0402LF-2K,1%,1/16W,CHIP,A     I9 @S9S_MB_2U_LIB.S9S_MB_2U(SCH_1):PAGE208
 R1469    1      A Q_RES_0402LF-33.2,1%,1/16W,CHIA    I55 @S9S_MB_2U_LIB.S9S_MB_2U(SCH_1):PAGE212
 R1470    1      A Q_RES_0402LF-33.2,1%,1/16W,CHIA    I56 @S9S_MB_2U_LIB.S9S_MB_2U(SCH_1):PAGE212
  U249 AB14  PB33A LCMXO3LF9400C5BG484C-LCMXO3LF-A     I1 @S9S_MB_2U_LIB.S9S_MB_2U(SCH_1):PAGE312

RST_PLTRST_PLD_N @S9S_MB_2U_LIB.S9S_MB_2U(SCH_1):RST_PLTRST_PLD_N
 R1205    2      B Q_RES_0402LF-33.2,1%,1/16W,CHIA     I7 @S9S_MB_2U_LIB.S9S_MB_2U(SCH_1):PAGE212
  U249  Y17  PB40C LCMXO3LF9400C5BG484C-LCMXO3LF-A     I1 @S9S_MB_2U_LIB.S9S_MB_2U(SCH_1):PAGE312

RST_RSMRST_NM_HDR_N @S9S_MB_2U_LIB.S9S_MB_2U(SCH_1):RST_RSMRST_NM_HDR_N
 R3050    2      B Q_RES_0402LF-33.2,1%,1/16W,CHIA   I129 @S9S_MB_2U_LIB.S9S_MB_2U(SCH_1):PAGE212
  J100    9      9 SCONN20_513860200CV01-SCONN20_A    I32 @S9S_MB_2U_LIB.S9S_MB_2U(SCH_1):PAGE215

RST_RSMRST_PCH_N @S9S_MB_2U_LIB.S9S_MB_2U(SCH_1):RST_RSMRST_PCH_N
  R772    2      B Q_RES_0402LF-1K,1%,1/16W,CHIP,A   I118 @S9S_MB_2U_LIB.S9S_MB_2U(SCH_1):PAGE133
    U4  BD9 RSMRST_N EMMITSBURG_REV0P9-GFNOCPU04302A    I36 @S9S_MB_2U_LIB.S9S_MB_2U(SCH_1):PAGE174
 R1207    2      B Q_RES_0402LF-33.2,1%,1/16W,CHIA    I15 @S9S_MB_2U_LIB.S9S_MB_2U(SCH_1):PAGE212
 R1695    2      B Q_RES_0402LF-0,5%,1/16W,EMPTY,A    I36 @S9S_MB_2U_LIB.S9S_MB_2U(SCH_1):PAGE232

RST_RSMRST_PLD_R_N @S9S_MB_2U_LIB.S9S_MB_2U(SCH_1):RST_RSMRST_PLD_R_N
 R1421    1      A Q_RES_0402LF-2K,1%,1/16W,CHIP,A    I10 @S9S_MB_2U_LIB.S9S_MB_2U(SCH_1):PAGE208
 R1207    1      A Q_RES_0402LF-33.2,1%,1/16W,CHIA    I15 @S9S_MB_2U_LIB.S9S_MB_2U(SCH_1):PAGE212
 R3050    1      A Q_RES_0402LF-33.2,1%,1/16W,CHIA   I129 @S9S_MB_2U_LIB.S9S_MB_2U(SCH_1):PAGE212
   Q77    2     G1 MOSFET_NCH_DUAL-PJT138K,SMLF,IA     I6 @S9S_MB_2U_LIB.S9S_MB_2U(SCH_1):PAGE242
  U249  V16  PB40D LCMXO3LF9400C5BG484C-LCMXO3LF-A     I1 @S9S_MB_2U_LIB.S9S_MB_2U(SCH_1):PAGE312

RST_RTCRST_N @S9S_MB_2U_LIB.S9S_MB_2U(SCH_1):RST_RTCRST_N
    U4  BD7 RCTRST_N EMMITSBURG_REV0P9-GFNOCPU04302A    I27 @S9S_MB_2U_LIB.S9S_MB_2U(SCH_1):PAGE177
 R1839    2      B Q_RES_0402LF-0,5%,1/16W,EMPTY,A    I85 @S9S_MB_2U_LIB.S9S_MB_2U(SCH_1):PAGE177
   SW5    3      3 SW_PUSHBUTTON4P_24-SW4S_DTSM-6A   I122 @S9S_MB_2U_LIB.S9S_MB_2U(SCH_1):PAGE189
   SW5    4      4 SW_PUSHBUTTON4P_24-SW4S_DTSM-6A   I122 @S9S_MB_2U_LIB.S9S_MB_2U(SCH_1):PAGE189
 R1340    2      B Q_RES_0402LF-20K,1%,1/16W,CHIPA   I127 @S9S_MB_2U_LIB.S9S_MB_2U(SCH_1):PAGE189
 C1177    1      A Q_CAP_C0402-1UF,25V,10%,X6S,CHA   I128 @S9S_MB_2U_LIB.S9S_MB_2U(SCH_1):PAGE189
   Q34    D      D MOSFET_NCH_GDS_ESD_PROTECTED-2A   I123 @S9S_MB_2U_LIB.S9S_MB_2U(SCH_1):PAGE177

RST_SGPIO_RESET_N @S9S_MB_2U_LIB.S9S_MB_2U(SCH_1):RST_SGPIO_RESET_N
 R1811    1      A Q_RES_0402LF-33.2,1%,1/16W,CHIA   I110 @S9S_MB_2U_LIB.S9S_MB_2U(SCH_1):PAGE211
   J41  B39  PETN7 SCONN168_ME1016810202011-SCONNA   I173 @S9S_MB_2U_LIB.S9S_MB_2U(SCH_1):PAGE227

RST_SGPIO_RESET_N_R @S9S_MB_2U_LIB.S9S_MB_2U(SCH_1):RST_SGPIO_RESET_N_R
 R1811    2      B Q_RES_0402LF-33.2,1%,1/16W,CHIA   I110 @S9S_MB_2U_LIB.S9S_MB_2U(SCH_1):PAGE211
  U249  T13  PB32A LCMXO3LF9400C5BG484C-LCMXO3LF-A     I1 @S9S_MB_2U_LIB.S9S_MB_2U(SCH_1):PAGE312

RST_SMB_BUF_E1S_0_N @S9S_MB_2U_LIB.S9S_MB_2U(SCH_1):RST_SMB_BUF_E1S_0_N
 R3772    1      A Q_RES_0402LF-0,5%,1/16W,CHIP,CA   I301 @S9S_MB_2U_LIB.S9S_MB_2U(SCH_1):PAGE297
  U134    6     1Y 74LVC2G07DW7-74LVC2G07DW-7,SMLA   I305 @S9S_MB_2U_LIB.S9S_MB_2U(SCH_1):PAGE297

RST_SMB_E1S_0_N @S9S_MB_2U_LIB.S9S_MB_2U(SCH_1):RST_SMB_E1S_0_N
 R3773    2      B Q_RES_0402LF-4.7K,5%,1/16W,EMPA   I299 @S9S_MB_2U_LIB.S9S_MB_2U(SCH_1):PAGE297
 R3772    2      B Q_RES_0402LF-0,5%,1/16W,CHIP,CA   I301 @S9S_MB_2U_LIB.S9S_MB_2U(SCH_1):PAGE297
 R1673    2      B Q_RES_0402LF-10K,1%,1/16W,CHIPA   I312 @S9S_MB_2U_LIB.S9S_MB_2U(SCH_1):PAGE297
   J90   A9 SMBRST# SCONN56_123276793-SCONN56_1-23A   I318 @S9S_MB_2U_LIB.S9S_MB_2U(SCH_1):PAGE297

RST_SMB_E1S_N @S9S_MB_2U_LIB.S9S_MB_2U(SCH_1):RST_SMB_E1S_N
  U134    1     1A 74LVC2G07DW7-74LVC2G07DW-7,SMLA   I305 @S9S_MB_2U_LIB.S9S_MB_2U(SCH_1):PAGE297
  U134    3     2A 74LVC2G07DW7-74LVC2G07DW-7,SMLA   I305 @S9S_MB_2U_LIB.S9S_MB_2U(SCH_1):PAGE297
 R3775    2      B Q_RES_0402LF-0,5%,1/16W,CHIP,CA   I307 @S9S_MB_2U_LIB.S9S_MB_2U(SCH_1):PAGE297

RST_SMB_OCP_SFF_N @S9S_MB_2U_LIB.S9S_MB_2U(SCH_1):RST_SMB_OCP_SFF_N
   J37   A9 SMRST# SCONN168_ME1016810202011-SCONNA   I199 @S9S_MB_2U_LIB.S9S_MB_2U(SCH_1):PAGE150
 R3233    2      B Q_RES_0402LF-0,5%,1/16W,CHIP,CA    I17 @S9S_MB_2U_LIB.S9S_MB_2U(SCH_1):PAGE151

RST_SMB_OCP_V3_2_N @S9S_MB_2U_LIB.S9S_MB_2U(SCH_1):RST_SMB_OCP_V3_2_N
 R3236    2      B Q_RES_0402LF-0,5%,1/16W,CHIP,CA    I70 @S9S_MB_2U_LIB.S9S_MB_2U(SCH_1):PAGE156
   J35   A9 SMRST# SCONN168_ME1016810202011-SCONNA   I303 @S9S_MB_2U_LIB.S9S_MB_2U(SCH_1):PAGE146

RST_SMB_S3M_N @S9S_MB_2U_LIB.S9S_MB_2U(SCH_1):RST_SMB_S3M_N
 R2313    2      B Q_RES_0402LF-0,5%,1/16W,CHIP,CA    I97 @S9S_MB_2U_LIB.S9S_MB_2U(SCH_1):PAGE224
  U143    3 RESET# PCA9545APW-PCA9545APW,SMLF,IC,A   I106 @S9S_MB_2U_LIB.S9S_MB_2U(SCH_1):PAGE224

RST_SMB_SWITCH_N @S9S_MB_2U_LIB.S9S_MB_2U(SCH_1):RST_SMB_SWITCH_N
 R2313    1      A Q_RES_0402LF-0,5%,1/16W,CHIP,CA    I97 @S9S_MB_2U_LIB.S9S_MB_2U(SCH_1):PAGE224
 R2921    2      B Q_RES_0402LF-10K,1%,1/16W,EMPTA    I93 @S9S_MB_2U_LIB.S9S_MB_2U(SCH_1):PAGE214
 R2922    1      A Q_RES_0402LF-0,5%,1/16W,CHIP,CA    I95 @S9S_MB_2U_LIB.S9S_MB_2U(SCH_1):PAGE214
  U249  AB6  PB11B LCMXO3LF9400C5BG484C-LCMXO3LF-A     I1 @S9S_MB_2U_LIB.S9S_MB_2U(SCH_1):PAGE312
 R3775    1      A Q_RES_0402LF-0,5%,1/16W,CHIP,CA   I307 @S9S_MB_2U_LIB.S9S_MB_2U(SCH_1):PAGE297
  U225    2      A 74LVC1G126SE7-74LVC1G126SE-7,SA    I74 @S9S_MB_2U_LIB.S9S_MB_2U(SCH_1):PAGE156
 R3710    1      A Q_RES_0402LF-0,5%,1/16W,CHIP,CA   I145 @S9S_MB_2U_LIB.S9S_MB_2U(SCH_1):PAGE221
 R3705    2      B Q_RES_0402LF-10K,1%,1/16W,EMPTA   I147 @S9S_MB_2U_LIB.S9S_MB_2U(SCH_1):PAGE221
  U224    2      A 74LVC1G126SE7-74LVC1G126SE-7,SA     I7 @S9S_MB_2U_LIB.S9S_MB_2U(SCH_1):PAGE151
 R2905    1      A Q_RES_0402LF-0,5%,1/16W,CHIP,CA    I34 @S9S_MB_2U_LIB.S9S_MB_2U(SCH_1):PAGE233
 R1822    2      B Q_RES_0402LF-10K,1%,1/16W,CHIPA    I18 @S9S_MB_2U_LIB.S9S_MB_2U(SCH_1):PAGE219
 R2268    1      A Q_RES_0402LF-0,5%,1/16W,CHIP,CA    I41 @S9S_MB_2U_LIB.S9S_MB_2U(SCH_1):PAGE219

RST_SMB_SWITCH_R_N @S9S_MB_2U_LIB.S9S_MB_2U(SCH_1):RST_SMB_SWITCH_R_N
   J45   B1     B1 CONN60_101062636003K02LF-CONN6A    I12 @S9S_MB_2U_LIB.S9S_MB_2U(SCH_1):PAGE233
 R2905    2      B Q_RES_0402LF-0,5%,1/16W,CHIP,CA    I34 @S9S_MB_2U_LIB.S9S_MB_2U(SCH_1):PAGE233
 C2293    1      A Q_CAP_0402-0.1UF,25V,10%,EMPTYA    I57 @S9S_MB_2U_LIB.S9S_MB_2U(SCH_1):PAGE233

RST_SRST_PLD_BMC_N @S9S_MB_2U_LIB.S9S_MB_2U(SCH_1):RST_SRST_PLD_BMC_N
 R4697    2      B Q_RES_0402LF-0,5%,1/16W,CHIP,CA    I14 @S9S_MB_2U_LIB.S9S_MB_2U(SCH_1):PAGE314
   J41 OB11 REFCLKN2 SCONN168_ME1016810202011-SCONNA   I173 @S9S_MB_2U_LIB.S9S_MB_2U(SCH_1):PAGE227

RST_SRST_PLD_BMC_R_N @S9S_MB_2U_LIB.S9S_MB_2U(SCH_1):RST_SRST_PLD_BMC_R_N
 R4697    1      A Q_RES_0402LF-0,5%,1/16W,CHIP,CA    I14 @S9S_MB_2U_LIB.S9S_MB_2U(SCH_1):PAGE314
  U249  F15  PT42C LCMXO3LF9400C5BG484C-LCMXO3LF-A   I188 @S9S_MB_2U_LIB.S9S_MB_2U(SCH_1):PAGE314

RST_SRTCRST_N @S9S_MB_2U_LIB.S9S_MB_2U(SCH_1):RST_SRTCRST_N
    U4  BF9 SRTCRST_N EMMITSBURG_REV0P9-GFNOCPU04302A    I27 @S9S_MB_2U_LIB.S9S_MB_2U(SCH_1):PAGE177
  C610    1      A Q_CAP_C0402-1UF,25V,10%,X6S,CHA    I68 @S9S_MB_2U_LIB.S9S_MB_2U(SCH_1):PAGE177
 R1202    2      B Q_RES_0402LF-20K,1%,1/16W,CHIPA    I70 @S9S_MB_2U_LIB.S9S_MB_2U(SCH_1):PAGE177
 R1840    2      B Q_RES_0402LF-0,5%,1/16W,EMPTY,A    I89 @S9S_MB_2U_LIB.S9S_MB_2U(SCH_1):PAGE177
   Q35    D      D MOSFET_NCH_GDS_ESD_PROTECTED-2A   I124 @S9S_MB_2U_LIB.S9S_MB_2U(SCH_1):PAGE177

RST_SWB_BIC_BUF_N @S9S_MB_2U_LIB.S9S_MB_2U(SCH_1):RST_SWB_BIC_BUF_N
  J105   N6     N6 CONN112_10137002101LF-CONN112_A    I68 @S9S_MB_2U_LIB.S9S_MB_2U(SCH_1):PAGE142
 R2924    2      B Q_RES_0402LF-49.9,1%,1/16W,CHIA   I207 @S9S_MB_2U_LIB.S9S_MB_2U(SCH_1):PAGE140

RST_SWB_BIC_BUF_R_N @S9S_MB_2U_LIB.S9S_MB_2U(SCH_1):RST_SWB_BIC_BUF_R_N
  U195    4     B1 74LVC2G17GW-74LVC2G17GW,SMLF,IA    I65 @S9S_MB_2U_LIB.S9S_MB_2U(SCH_1):PAGE140
 R2911    2      B Q_RES_0402LF-4.7K,5%,1/16W,EMPA   I153 @S9S_MB_2U_LIB.S9S_MB_2U(SCH_1):PAGE140
 R2927    1      A Q_RES_0402LF-100K,1%,1/16W,CHIA   I203 @S9S_MB_2U_LIB.S9S_MB_2U(SCH_1):PAGE140
 R2924    1      A Q_RES_0402LF-49.9,1%,1/16W,CHIA   I207 @S9S_MB_2U_LIB.S9S_MB_2U(SCH_1):PAGE140

RST_SWB_BIC_N @S9S_MB_2U_LIB.S9S_MB_2U(SCH_1):RST_SWB_BIC_N
 R2848    1      A Q_RES_0402LF-0,5%,1/16W,CHIP,CA    I34 @S9S_MB_2U_LIB.S9S_MB_2U(SCH_1):PAGE214
  U181    5  IO0_1 PCA9539RPW-PCA9539RPW,SMLF,IC,A    I66 @S9S_MB_2U_LIB.S9S_MB_2U(SCH_1):PAGE214

RST_SWB_BIC_R_N @S9S_MB_2U_LIB.S9S_MB_2U(SCH_1):RST_SWB_BIC_R_N
 R2848    2      B Q_RES_0402LF-0,5%,1/16W,CHIP,CA    I34 @S9S_MB_2U_LIB.S9S_MB_2U(SCH_1):PAGE214
  U195    3     A1 74LVC2G17GW-74LVC2G17GW,SMLF,IA    I65 @S9S_MB_2U_LIB.S9S_MB_2U(SCH_1):PAGE140
 R2916    1      A Q_RES_0402LF-4.7K,5%,1/16W,EMPA    I93 @S9S_MB_2U_LIB.S9S_MB_2U(SCH_1):PAGE140
 R2909    2      B Q_RES_0402LF-4.7K,5%,1/16W,CHIA   I198 @S9S_MB_2U_LIB.S9S_MB_2U(SCH_1):PAGE140

RST_USB_HUB_2_R_N @S9S_MB_2U_LIB.S9S_MB_2U(SCH_1):RST_USB_HUB_2_R_N
 R4451    2      B Q_RES_0402LF-33.2,1%,1/16W,EMPA    I13 @S9S_MB_2U_LIB.S9S_MB_2U(SCH_1):PAGE194
 C2317    1      A Q_CAP_C0402-1UF,25V,10%,EMPTY,A    I15 @S9S_MB_2U_LIB.S9S_MB_2U(SCH_1):PAGE194
 R4453    2      B Q_RES_0402LF-47K,0.1%,1/16W,EMA    I26 @S9S_MB_2U_LIB.S9S_MB_2U(SCH_1):PAGE194
 R4452    2      B Q_RES_0402LF-10K,1%,1/16W,EMPTA    I27 @S9S_MB_2U_LIB.S9S_MB_2U(SCH_1):PAGE194
  U313   17 RESET# GL852GOHY60-GL852G-OHY60,SMLF,B    I40 @S9S_MB_2U_LIB.S9S_MB_2U(SCH_1):PAGE194

RST_USB_HUB_N @S9S_MB_2U_LIB.S9S_MB_2U(SCH_1):RST_USB_HUB_N
  U181    4  IO0_0 PCA9539RPW-PCA9539RPW,SMLF,IC,A    I66 @S9S_MB_2U_LIB.S9S_MB_2U(SCH_1):PAGE214
 R3654    1      A Q_RES_0402LF-33.2,1%,1/16W,CHIA   I155 @S9S_MB_2U_LIB.S9S_MB_2U(SCH_1):PAGE155
 R4451    1      A Q_RES_0402LF-33.2,1%,1/16W,EMPA    I13 @S9S_MB_2U_LIB.S9S_MB_2U(SCH_1):PAGE194

RST_USB_HUB_R_N @S9S_MB_2U_LIB.S9S_MB_2U(SCH_1):RST_USB_HUB_R_N
  U268   17 RESET# GL852GOHY60-GL852G-OHY60,SMLF,A   I100 @S9S_MB_2U_LIB.S9S_MB_2U(SCH_1):PAGE155
 R3654    2      B Q_RES_0402LF-33.2,1%,1/16W,CHIA   I155 @S9S_MB_2U_LIB.S9S_MB_2U(SCH_1):PAGE155
 C2041    1      A Q_CAP_C0402-1UF,25V,10%,X6S,CHA   I158 @S9S_MB_2U_LIB.S9S_MB_2U(SCH_1):PAGE155
 R3660    2      B Q_RES_0402LF-10K,1%,1/16W,CHIPA   I159 @S9S_MB_2U_LIB.S9S_MB_2U(SCH_1):PAGE155
 R3661    2      B Q_RES_0402LF-47K,0.1%,1/16W,EMA   I201 @S9S_MB_2U_LIB.S9S_MB_2U(SCH_1):PAGE155

RTC_EXT_CAP @S9S_MB_2U_LIB.S9S_MB_2U(SCH_1):RTC_EXT_CAP
    U4  BF5 RTC_EXTCAP EMMITSBURG_REV0P9-GFNOCPU04302A    I78 @S9S_MB_2U_LIB.S9S_MB_2U(SCH_1):PAGE171
  C609    1      A Q_CAP_0402-0.1UF,25V,10%,X7R,CA    I89 @S9S_MB_2U_LIB.S9S_MB_2U(SCH_1):PAGE171

SGPIO_BMC_CLK @S9S_MB_2U_LIB.S9S_MB_2U(SCH_1):SGPIO_BMC_CLK
 R1756    2      B Q_RES_0402LF-33.2,1%,1/16W,CHIA    I98 @S9S_MB_2U_LIB.S9S_MB_2U(SCH_1):PAGE211
  U249  D14  PT30D LCMXO3LF9400C5BG484C-LCMXO3LF-A   I188 @S9S_MB_2U_LIB.S9S_MB_2U(SCH_1):PAGE314

SGPIO_BMC_DIN_R @S9S_MB_2U_LIB.S9S_MB_2U(SCH_1):SGPIO_BMC_DIN_R
 R1757    2      B Q_RES_0402LF-33.2,1%,1/16W,CHIA    I99 @S9S_MB_2U_LIB.S9S_MB_2U(SCH_1):PAGE211
  U249  G14  PT31A LCMXO3LF9400C5BG484C-LCMXO3LF-A   I188 @S9S_MB_2U_LIB.S9S_MB_2U(SCH_1):PAGE314

SGPIO_BMC_DOUT @S9S_MB_2U_LIB.S9S_MB_2U(SCH_1):SGPIO_BMC_DOUT
 R1755    2      B Q_RES_0402LF-33.2,1%,1/16W,CHIA    I96 @S9S_MB_2U_LIB.S9S_MB_2U(SCH_1):PAGE211
  U249  C14  PT30C LCMXO3LF9400C5BG484C-LCMXO3LF-A   I188 @S9S_MB_2U_LIB.S9S_MB_2U(SCH_1):PAGE314

SGPIO_BMC_LD_N @S9S_MB_2U_LIB.S9S_MB_2U(SCH_1):SGPIO_BMC_LD_N
 R1758    2      B Q_RES_0402LF-33.2,1%,1/16W,CHIA    I91 @S9S_MB_2U_LIB.S9S_MB_2U(SCH_1):PAGE211
  U249  F14  PT31B LCMXO3LF9400C5BG484C-LCMXO3LF-A   I188 @S9S_MB_2U_LIB.S9S_MB_2U(SCH_1):PAGE314

SGPIO_CLK_0 @S9S_MB_2U_LIB.S9S_MB_2U(SCH_1):SGPIO_CLK_0
 R1752    1      A Q_RES_0402LF-33.2,1%,1/16W,CHIA    I82 @S9S_MB_2U_LIB.S9S_MB_2U(SCH_1):PAGE211
   J41  B30  PETN4 SCONN168_ME1016810202011-SCONNA   I173 @S9S_MB_2U_LIB.S9S_MB_2U(SCH_1):PAGE227

SGPIO_CLK_1 @S9S_MB_2U_LIB.S9S_MB_2U(SCH_1):SGPIO_CLK_1
 R1756    1      A Q_RES_0402LF-33.2,1%,1/16W,CHIA    I98 @S9S_MB_2U_LIB.S9S_MB_2U(SCH_1):PAGE211
   J41  B35 GND_B35 SCONN168_ME1016810202011-SCONNA   I173 @S9S_MB_2U_LIB.S9S_MB_2U(SCH_1):PAGE227

SGPIO_DEBUG_PLD_CLK @S9S_MB_2U_LIB.S9S_MB_2U(SCH_1):SGPIO_DEBUG_PLD_CLK
 R1752    2      B Q_RES_0402LF-33.2,1%,1/16W,CHIA    I82 @S9S_MB_2U_LIB.S9S_MB_2U(SCH_1):PAGE211
  U249  B15  PT38B LCMXO3LF9400C5BG484C-LCMXO3LF-A   I188 @S9S_MB_2U_LIB.S9S_MB_2U(SCH_1):PAGE314

SGPIO_DEBUG_PLD_DIN @S9S_MB_2U_LIB.S9S_MB_2U(SCH_1):SGPIO_DEBUG_PLD_DIN
 R1753    2      B Q_RES_0402LF-33.2,1%,1/16W,CHIA    I84 @S9S_MB_2U_LIB.S9S_MB_2U(SCH_1):PAGE211
  U249  C15  PT38C LCMXO3LF9400C5BG484C-LCMXO3LF-A   I188 @S9S_MB_2U_LIB.S9S_MB_2U(SCH_1):PAGE314

SGPIO_DEBUG_PLD_DOUT @S9S_MB_2U_LIB.S9S_MB_2U(SCH_1):SGPIO_DEBUG_PLD_DOUT
 R1751    2      B Q_RES_0402LF-33.2,1%,1/16W,CHIA    I81 @S9S_MB_2U_LIB.S9S_MB_2U(SCH_1):PAGE211
  U249  A15  PT38A LCMXO3LF9400C5BG484C-LCMXO3LF-A   I188 @S9S_MB_2U_LIB.S9S_MB_2U(SCH_1):PAGE314

SGPIO_DEBUG_PLD_LD_N @S9S_MB_2U_LIB.S9S_MB_2U(SCH_1):SGPIO_DEBUG_PLD_LD_N
 R1754    2      B Q_RES_0402LF-33.2,1%,1/16W,CHIA    I88 @S9S_MB_2U_LIB.S9S_MB_2U(SCH_1):PAGE211
  U249  D15  PT38D LCMXO3LF9400C5BG484C-LCMXO3LF-A   I188 @S9S_MB_2U_LIB.S9S_MB_2U(SCH_1):PAGE314

SGPIO_DI_0 @S9S_MB_2U_LIB.S9S_MB_2U(SCH_1):SGPIO_DI_0
 R1753    1      A Q_RES_0402LF-33.2,1%,1/16W,CHIA    I84 @S9S_MB_2U_LIB.S9S_MB_2U(SCH_1):PAGE211
   J41  B31  PETP4 SCONN168_ME1016810202011-SCONNA   I173 @S9S_MB_2U_LIB.S9S_MB_2U(SCH_1):PAGE227

SGPIO_DI_1 @S9S_MB_2U_LIB.S9S_MB_2U(SCH_1):SGPIO_DI_1
 R1757    1      A Q_RES_0402LF-33.2,1%,1/16W,CHIA    I99 @S9S_MB_2U_LIB.S9S_MB_2U(SCH_1):PAGE211
   J41  B36  PETN6 SCONN168_ME1016810202011-SCONNA   I173 @S9S_MB_2U_LIB.S9S_MB_2U(SCH_1):PAGE227

SGPIO_DO_0 @S9S_MB_2U_LIB.S9S_MB_2U(SCH_1):SGPIO_DO_0
 R1751    1      A Q_RES_0402LF-33.2,1%,1/16W,CHIA    I81 @S9S_MB_2U_LIB.S9S_MB_2U(SCH_1):PAGE211
   J41  B29 GND_B29 SCONN168_ME1016810202011-SCONNA   I173 @S9S_MB_2U_LIB.S9S_MB_2U(SCH_1):PAGE227

SGPIO_DO_1 @S9S_MB_2U_LIB.S9S_MB_2U(SCH_1):SGPIO_DO_1
 R1755    1      A Q_RES_0402LF-33.2,1%,1/16W,CHIA    I96 @S9S_MB_2U_LIB.S9S_MB_2U(SCH_1):PAGE211
   J41  B34  PETP5 SCONN168_ME1016810202011-SCONNA   I173 @S9S_MB_2U_LIB.S9S_MB_2U(SCH_1):PAGE227

SGPIO_LD_0 @S9S_MB_2U_LIB.S9S_MB_2U(SCH_1):SGPIO_LD_0
 R1754    1      A Q_RES_0402LF-33.2,1%,1/16W,CHIA    I88 @S9S_MB_2U_LIB.S9S_MB_2U(SCH_1):PAGE211
   J41  B32 GND_B32 SCONN168_ME1016810202011-SCONNA   I173 @S9S_MB_2U_LIB.S9S_MB_2U(SCH_1):PAGE227

SGPIO_LD_1 @S9S_MB_2U_LIB.S9S_MB_2U(SCH_1):SGPIO_LD_1
 R1758    1      A Q_RES_0402LF-33.2,1%,1/16W,CHIA    I91 @S9S_MB_2U_LIB.S9S_MB_2U(SCH_1):PAGE211
   J41  B37  PETP6 SCONN168_ME1016810202011-SCONNA   I173 @S9S_MB_2U_LIB.S9S_MB_2U(SCH_1):PAGE227

SGPIO_OCP_SFF_CLK @S9S_MB_2U_LIB.S9S_MB_2U(SCH_1):SGPIO_OCP_SFF_CLK
   J37  OB6    CLK SCONN168_ME1016810202011-SCONNA   I199 @S9S_MB_2U_LIB.S9S_MB_2U(SCH_1):PAGE150
  R423    1      A Q_RES_0402LF-1K,1%,1/16W,CHIP,A   I212 @S9S_MB_2U_LIB.S9S_MB_2U(SCH_1):PAGE150
  U249  B17  PT39B LCMXO3LF9400C5BG484C-LCMXO3LF-A   I188 @S9S_MB_2U_LIB.S9S_MB_2U(SCH_1):PAGE314

SGPIO_OCP_SFF_DATAIN @S9S_MB_2U_LIB.S9S_MB_2U(SCH_1):SGPIO_OCP_SFF_DATAIN
   J37  OB4 DATA_IN SCONN168_ME1016810202011-SCONNA   I199 @S9S_MB_2U_LIB.S9S_MB_2U(SCH_1):PAGE150
  R421    1      A Q_RES_0402LF-10K,1%,1/16W,CHIPA   I217 @S9S_MB_2U_LIB.S9S_MB_2U(SCH_1):PAGE150
  U249  C17  PT39C LCMXO3LF9400C5BG484C-LCMXO3LF-A   I188 @S9S_MB_2U_LIB.S9S_MB_2U(SCH_1):PAGE314

SGPIO_OCP_SFF_DATAOUT @S9S_MB_2U_LIB.S9S_MB_2U(SCH_1):SGPIO_OCP_SFF_DATAOUT
   J37  OB5 DATA_OUT SCONN168_ME1016810202011-SCONNA   I199 @S9S_MB_2U_LIB.S9S_MB_2U(SCH_1):PAGE150
  R422    1      A Q_RES_0402LF-10K,1%,1/16W,CHIPA   I215 @S9S_MB_2U_LIB.S9S_MB_2U(SCH_1):PAGE150
  U249  A16  PT39A LCMXO3LF9400C5BG484C-LCMXO3LF-A   I188 @S9S_MB_2U_LIB.S9S_MB_2U(SCH_1):PAGE314

SGPIO_OCP_SFF_LD_N @S9S_MB_2U_LIB.S9S_MB_2U(SCH_1):SGPIO_OCP_SFF_LD_N
   J37  OB3    LD# SCONN168_ME1016810202011-SCONNA   I199 @S9S_MB_2U_LIB.S9S_MB_2U(SCH_1):PAGE150
  R420    1      A Q_RES_0402LF-1K,1%,1/16W,CHIP,A   I218 @S9S_MB_2U_LIB.S9S_MB_2U(SCH_1):PAGE150
  U249  D16  PT39D LCMXO3LF9400C5BG484C-LCMXO3LF-A   I188 @S9S_MB_2U_LIB.S9S_MB_2U(SCH_1):PAGE314

SGPIO_OCP_V3_2_CLK @S9S_MB_2U_LIB.S9S_MB_2U(SCH_1):SGPIO_OCP_V3_2_CLK
   J35  OB6    CLK SCONN168_ME1016810202011-SCONNA   I303 @S9S_MB_2U_LIB.S9S_MB_2U(SCH_1):PAGE146
 R3176    1      A Q_RES_0402LF-1K,1%,1/16W,CHIP,A   I336 @S9S_MB_2U_LIB.S9S_MB_2U(SCH_1):PAGE146
  U249  B18  PT40B LCMXO3LF9400C5BG484C-LCMXO3LF-A   I188 @S9S_MB_2U_LIB.S9S_MB_2U(SCH_1):PAGE314

SGPIO_OCP_V3_2_DATAIN @S9S_MB_2U_LIB.S9S_MB_2U(SCH_1):SGPIO_OCP_V3_2_DATAIN
   J35  OB4 DATA_IN SCONN168_ME1016810202011-SCONNA   I303 @S9S_MB_2U_LIB.S9S_MB_2U(SCH_1):PAGE146
 R3174    1      A Q_RES_0402LF-10K,1%,1/16W,CHIPA   I333 @S9S_MB_2U_LIB.S9S_MB_2U(SCH_1):PAGE146
  U249  E16  PT40C LCMXO3LF9400C5BG484C-LCMXO3LF-A   I188 @S9S_MB_2U_LIB.S9S_MB_2U(SCH_1):PAGE314

SGPIO_OCP_V3_2_DATAOUT @S9S_MB_2U_LIB.S9S_MB_2U(SCH_1):SGPIO_OCP_V3_2_DATAOUT
   J35  OB5 DATA_OUT SCONN168_ME1016810202011-SCONNA   I303 @S9S_MB_2U_LIB.S9S_MB_2U(SCH_1):PAGE146
 R3175    1      A Q_RES_0402LF-10K,1%,1/16W,CHIPA   I334 @S9S_MB_2U_LIB.S9S_MB_2U(SCH_1):PAGE146
  U249  A17  PT40A LCMXO3LF9400C5BG484C-LCMXO3LF-A   I188 @S9S_MB_2U_LIB.S9S_MB_2U(SCH_1):PAGE314

SGPIO_OCP_V3_2_LD_N @S9S_MB_2U_LIB.S9S_MB_2U(SCH_1):SGPIO_OCP_V3_2_LD_N
 R3173    1      A Q_RES_0402LF-1K,1%,1/16W,CHIP,A   I165 @S9S_MB_2U_LIB.S9S_MB_2U(SCH_1):PAGE146
   J35  OB3    LD# SCONN168_ME1016810202011-SCONNA   I303 @S9S_MB_2U_LIB.S9S_MB_2U(SCH_1):PAGE146
  U249  D17  PT40D LCMXO3LF9400C5BG484C-LCMXO3LF-A   I188 @S9S_MB_2U_LIB.S9S_MB_2U(SCH_1):PAGE314

SH_P1V05_PCH_AUX_N @S9S_MB_2U_LIB.S9S_MB_2U(SCH_1):SH_P1V05_PCH_AUX_N
 PR187    2      B Q_RES_0402LF-10K,0.1%,1/16W,CHA    I34 @S9S_MB_2U_LIB.S9S_MB_2U(SCH_1):PAGE248
PC2279    2      B Q_CAP_0402-0.01UF,25V,10%,X7R,A    I37 @S9S_MB_2U_LIB.S9S_MB_2U(SCH_1):PAGE248
  PJ63    1      1 Q_SHORT_SM-EMPTY,SHORT6    I42 @S9S_MB_2U_LIB.S9S_MB_2U(SCH_1):PAGE248
  PU73    6    RTN RS53319LR-RS53319LR,SMLF,IC,ALA    I11 @S9S_MB_2U_LIB.S9S_MB_2U(SCH_1):PAGE248
PC1221    2      B Q_CAP_0402-0.1UF,25V,10%,X7R,CA    I16 @S9S_MB_2U_LIB.S9S_MB_2U(SCH_1):PAGE248

SH_P1V05_PCH_AUX_P @S9S_MB_2U_LIB.S9S_MB_2U(SCH_1):SH_P1V05_PCH_AUX_P
PC1223    2      B Q_CAP_0402-680PF,50V,10%,X7R,TA    I35 @S9S_MB_2U_LIB.S9S_MB_2U(SCH_1):PAGE248
PR1328    2      B Q_RES_0402LF-7.32K,0.1%,1/16W,A    I36 @S9S_MB_2U_LIB.S9S_MB_2U(SCH_1):PAGE248
PC2279    1      A Q_CAP_0402-0.01UF,25V,10%,X7R,A    I37 @S9S_MB_2U_LIB.S9S_MB_2U(SCH_1):PAGE248
  PJ62    1      1 Q_SHORT_SM-EMPTY,SHORT6    I43 @S9S_MB_2U_LIB.S9S_MB_2U(SCH_1):PAGE248

SH_PVCCD_HV_CPU0 @S9S_MB_2U_LIB.S9S_MB_2U(SCH_1):SH_PVCCD_HV_CPU0
  PJ54    2      2 Q_SHORT_SM-EMPTY,SHORT6    I32 @S9S_MB_2U_LIB.S9S_MB_2U(SCH_1):PAGE264
 PR371    1      A Q_RES_0402LF-0,5%,1/16W,CHIP,CA    I36 @S9S_MB_2U_LIB.S9S_MB_2U(SCH_1):PAGE264

SH_PVCCD_HV_CPU0_R @S9S_MB_2U_LIB.S9S_MB_2U(SCH_1):SH_PVCCD_HV_CPU0_R
  PU35   21  VSEN0 ISL69260IRAZT-ISL69260IRAZ-T,SA    I53 @S9S_MB_2U_LIB.S9S_MB_2U(SCH_1):PAGE264
 PR371    2      B Q_RES_0402LF-0,5%,1/16W,CHIP,CA    I36 @S9S_MB_2U_LIB.S9S_MB_2U(SCH_1):PAGE264
 PC627    1      A Q_CAP_0402-3300PF,50V,10%,X7R,A    I37 @S9S_MB_2U_LIB.S9S_MB_2U(SCH_1):PAGE264

SH_PVCCD_HV_CPU1 @S9S_MB_2U_LIB.S9S_MB_2U(SCH_1):SH_PVCCD_HV_CPU1
 PR216    1      A Q_RES_0402LF-0,5%,1/16W,CHIP,CA    I21 @S9S_MB_2U_LIB.S9S_MB_2U(SCH_1):PAGE282
  PJ48    2      2 Q_SHORT_SM-EMPTY,SHORT6    I16 @S9S_MB_2U_LIB.S9S_MB_2U(SCH_1):PAGE282

SH_PVCCD_HV_CPU1_R @S9S_MB_2U_LIB.S9S_MB_2U(SCH_1):SH_PVCCD_HV_CPU1_R
  PU18   21  VSEN0 ISL69260IRAZT-ISL69260IRAZ-T,SA    I53 @S9S_MB_2U_LIB.S9S_MB_2U(SCH_1):PAGE282
 PR216    2      B Q_RES_0402LF-0,5%,1/16W,CHIP,CA    I21 @S9S_MB_2U_LIB.S9S_MB_2U(SCH_1):PAGE282
 PC389    1      A Q_CAP_0402-3300PF,50V,10%,X7R,A    I22 @S9S_MB_2U_LIB.S9S_MB_2U(SCH_1):PAGE282

SH_PVCCFA_EHV_CPU0 @S9S_MB_2U_LIB.S9S_MB_2U(SCH_1):SH_PVCCFA_EHV_CPU0
  PJ46    2      2 Q_SHORT_SM-EMPTY,SHORT6    I39 @S9S_MB_2U_LIB.S9S_MB_2U(SCH_1):PAGE260
 PR121    1      A Q_RES_0402LF-0,5%,1/16W,CHIP,CA    I47 @S9S_MB_2U_LIB.S9S_MB_2U(SCH_1):PAGE260

SH_PVCCFA_EHV_CPU0_R @S9S_MB_2U_LIB.S9S_MB_2U(SCH_1):SH_PVCCFA_EHV_CPU0_R
   PU5   32  VSEN1 ISL69260IRAZT-ISL69260IRAZ-T,SA    I65 @S9S_MB_2U_LIB.S9S_MB_2U(SCH_1):PAGE260
 PC216    1      A Q_CAP_0402-3300PF,50V,10%,X7R,A    I48 @S9S_MB_2U_LIB.S9S_MB_2U(SCH_1):PAGE260
 PR121    2      B Q_RES_0402LF-0,5%,1/16W,CHIP,CA    I47 @S9S_MB_2U_LIB.S9S_MB_2U(SCH_1):PAGE260

SH_PVCCFA_EHV_CPU1 @S9S_MB_2U_LIB.S9S_MB_2U(SCH_1):SH_PVCCFA_EHV_CPU1
 PR274    1      A Q_RES_0402LF-0,5%,1/16W,CHIP,CA    I52 @S9S_MB_2U_LIB.S9S_MB_2U(SCH_1):PAGE278
  PJ51    2      2 Q_SHORT_SM-EMPTY,SHORT6    I44 @S9S_MB_2U_LIB.S9S_MB_2U(SCH_1):PAGE278

SH_PVCCFA_EHV_CPU1_R @S9S_MB_2U_LIB.S9S_MB_2U(SCH_1):SH_PVCCFA_EHV_CPU1_R
 PC469    1      A Q_CAP_0402-3300PF,50V,10%,X7R,A    I51 @S9S_MB_2U_LIB.S9S_MB_2U(SCH_1):PAGE278
 PR274    2      B Q_RES_0402LF-0,5%,1/16W,CHIP,CA    I52 @S9S_MB_2U_LIB.S9S_MB_2U(SCH_1):PAGE278
  PU22   32  VSEN1 ISL69260IRAZT-ISL69260IRAZ-T,SA    I38 @S9S_MB_2U_LIB.S9S_MB_2U(SCH_1):PAGE278

SH_PVCCFA_EHV_FIVRA_CPU0 @S9S_MB_2U_LIB.S9S_MB_2U(SCH_1):SH_PVCCFA_EHV_FIVRA_CPU0
  PJ53    2      2 Q_SHORT_SM-EMPTY,SHORT6    I24 @S9S_MB_2U_LIB.S9S_MB_2U(SCH_1):PAGE252
 PR345    1      A Q_RES_0402LF-0,5%,1/16W,CHIP,CA    I68 @S9S_MB_2U_LIB.S9S_MB_2U(SCH_1):PAGE252

SH_PVCCFA_EHV_FIVRA_CPU0_R @S9S_MB_2U_LIB.S9S_MB_2U(SCH_1):SH_PVCCFA_EHV_FIVRA_CPU0_R
  PU14   40  VSEN1 RAA229126GNPHA0-RAA229126GNP#HA    I63 @S9S_MB_2U_LIB.S9S_MB_2U(SCH_1):PAGE252
 PC594    1      A Q_CAP_0402-3300PF,50V,10%,X7R,A    I67 @S9S_MB_2U_LIB.S9S_MB_2U(SCH_1):PAGE252
 PR345    2      B Q_RES_0402LF-0,5%,1/16W,CHIP,CA    I68 @S9S_MB_2U_LIB.S9S_MB_2U(SCH_1):PAGE252

SH_PVCCFA_EHV_FIVRA_CPU1 @S9S_MB_2U_LIB.S9S_MB_2U(SCH_1):SH_PVCCFA_EHV_FIVRA_CPU1
  PJ49    2      2 Q_SHORT_SM-EMPTY,SHORT6    I22 @S9S_MB_2U_LIB.S9S_MB_2U(SCH_1):PAGE270
 PR242    1      A Q_RES_0402LF-0,5%,1/16W,CHIP,CA    I37 @S9S_MB_2U_LIB.S9S_MB_2U(SCH_1):PAGE270

SH_PVCCFA_EHV_FIVRA_CPU1_R @S9S_MB_2U_LIB.S9S_MB_2U(SCH_1):SH_PVCCFA_EHV_FIVRA_CPU1_R
 PC422    1      A Q_CAP_0402-3300PF,50V,10%,X7R,A    I38 @S9S_MB_2U_LIB.S9S_MB_2U(SCH_1):PAGE270
  PU29   40  VSEN1 RAA229126GNPHA0-RAA229126GNP#HA    I33 @S9S_MB_2U_LIB.S9S_MB_2U(SCH_1):PAGE270
 PR242    2      B Q_RES_0402LF-0,5%,1/16W,CHIP,CA    I37 @S9S_MB_2U_LIB.S9S_MB_2U(SCH_1):PAGE270

SH_PVCCINFAON_CPU0 @S9S_MB_2U_LIB.S9S_MB_2U(SCH_1):SH_PVCCINFAON_CPU0
  PJ45    2      2 Q_SHORT_SM-EMPTY,SHORT6    I43 @S9S_MB_2U_LIB.S9S_MB_2U(SCH_1):PAGE260
 PR120    1      A Q_RES_0402LF-0,5%,1/16W,CHIP,CA    I49 @S9S_MB_2U_LIB.S9S_MB_2U(SCH_1):PAGE260

SH_PVCCINFAON_CPU0_R @S9S_MB_2U_LIB.S9S_MB_2U(SCH_1):SH_PVCCINFAON_CPU0_R
   PU5   21  VSEN0 ISL69260IRAZT-ISL69260IRAZ-T,SA    I65 @S9S_MB_2U_LIB.S9S_MB_2U(SCH_1):PAGE260
 PC215    1      A Q_CAP_0402-3300PF,50V,10%,X7R,A    I50 @S9S_MB_2U_LIB.S9S_MB_2U(SCH_1):PAGE260
 PR120    2      B Q_RES_0402LF-0,5%,1/16W,CHIP,CA    I49 @S9S_MB_2U_LIB.S9S_MB_2U(SCH_1):PAGE260

SH_PVCCINFAON_CPU1 @S9S_MB_2U_LIB.S9S_MB_2U(SCH_1):SH_PVCCINFAON_CPU1
  PJ50    2      2 Q_SHORT_SM-EMPTY,SHORT6    I54 @S9S_MB_2U_LIB.S9S_MB_2U(SCH_1):PAGE278
 PR273    1      A Q_RES_0402LF-0,5%,1/16W,CHIP,CA    I62 @S9S_MB_2U_LIB.S9S_MB_2U(SCH_1):PAGE278

SH_PVCCINFAON_CPU1_R @S9S_MB_2U_LIB.S9S_MB_2U(SCH_1):SH_PVCCINFAON_CPU1_R
 PC468    1      A Q_CAP_0402-3300PF,50V,10%,X7R,A    I53 @S9S_MB_2U_LIB.S9S_MB_2U(SCH_1):PAGE278
 PR273    2      B Q_RES_0402LF-0,5%,1/16W,CHIP,CA    I62 @S9S_MB_2U_LIB.S9S_MB_2U(SCH_1):PAGE278
  PU22   21  VSEN0 ISL69260IRAZT-ISL69260IRAZ-T,SA    I38 @S9S_MB_2U_LIB.S9S_MB_2U(SCH_1):PAGE278

SH_PVCCIN_CPU0 @S9S_MB_2U_LIB.S9S_MB_2U(SCH_1):SH_PVCCIN_CPU0
  PJ47    2      2 Q_SHORT_SM-EMPTY,SHORT6    I37 @S9S_MB_2U_LIB.S9S_MB_2U(SCH_1):PAGE252
 PR170    1      A Q_RES_0402LF-0,5%,1/16W,CHIP,CA    I77 @S9S_MB_2U_LIB.S9S_MB_2U(SCH_1):PAGE252

SH_PVCCIN_CPU0_R @S9S_MB_2U_LIB.S9S_MB_2U(SCH_1):SH_PVCCIN_CPU0_R
  PU14   25  VSEN0 RAA229126GNPHA0-RAA229126GNP#HA    I63 @S9S_MB_2U_LIB.S9S_MB_2U(SCH_1):PAGE252
 PC331    1      A Q_CAP_0402-3300PF,50V,10%,X7R,A    I79 @S9S_MB_2U_LIB.S9S_MB_2U(SCH_1):PAGE252
 PR170    2      B Q_RES_0402LF-0,5%,1/16W,CHIP,CA    I77 @S9S_MB_2U_LIB.S9S_MB_2U(SCH_1):PAGE252

SH_PVCCIN_CPU1 @S9S_MB_2U_LIB.S9S_MB_2U(SCH_1):SH_PVCCIN_CPU1
 PR317    1      A Q_RES_0402LF-0,5%,1/16W,CHIP,CA    I63 @S9S_MB_2U_LIB.S9S_MB_2U(SCH_1):PAGE270
  PJ52    2      2 Q_SHORT_SM-EMPTY,SHORT6    I46 @S9S_MB_2U_LIB.S9S_MB_2U(SCH_1):PAGE270

SH_PVCCIN_CPU1_R @S9S_MB_2U_LIB.S9S_MB_2U(SCH_1):SH_PVCCIN_CPU1_R
 PR317    2      B Q_RES_0402LF-0,5%,1/16W,CHIP,CA    I63 @S9S_MB_2U_LIB.S9S_MB_2U(SCH_1):PAGE270
 PC549    1      A Q_CAP_0402-3300PF,50V,10%,X7R,A    I64 @S9S_MB_2U_LIB.S9S_MB_2U(SCH_1):PAGE270
  PU29   25  VSEN0 RAA229126GNPHA0-RAA229126GNP#HA    I33 @S9S_MB_2U_LIB.S9S_MB_2U(SCH_1):PAGE270

SH_PVPP_HBM_CPU0_N @S9S_MB_2U_LIB.S9S_MB_2U(SCH_1):SH_PVPP_HBM_CPU0_N
PR1310    2      B Q_RES_0402LF-11.3K,0.1%,1/16W,A    I26 @S9S_MB_2U_LIB.S9S_MB_2U(SCH_1):PAGE267
  PJ65    1      1 Q_SHORT_SM-EMPTY,SHORT6    I33 @S9S_MB_2U_LIB.S9S_MB_2U(SCH_1):PAGE267
 PU173    S SOURCE MOSFET_N_SMLF-BSS138K,BSS138K,B    I31 @S9S_MB_2U_LIB.S9S_MB_2U(SCH_1):PAGE267
  PU79    6    RTN RS53318LR-RS53318LR,SMLF,IC,ALA    I19 @S9S_MB_2U_LIB.S9S_MB_2U(SCH_1):PAGE267
PC1251    2      B Q_CAP_0402-0.1UF,25V,10%,X7R,CA    I25 @S9S_MB_2U_LIB.S9S_MB_2U(SCH_1):PAGE267
PC1421    2      B Q_CAP_0402-0.01UF,25V,10%,X7R,A    I40 @S9S_MB_2U_LIB.S9S_MB_2U(SCH_1):PAGE267

SH_PVPP_HBM_CPU0_P @S9S_MB_2U_LIB.S9S_MB_2U(SCH_1):SH_PVPP_HBM_CPU0_P
PR1337    2      B Q_RES_0402LF-38.3K,0.1%,1/16W,A    I36 @S9S_MB_2U_LIB.S9S_MB_2U(SCH_1):PAGE267
PC1253    2      B Q_CAP_C0402-680PF,50V,10%,X7R,A    I35 @S9S_MB_2U_LIB.S9S_MB_2U(SCH_1):PAGE267
PC1421    1      A Q_CAP_0402-0.01UF,25V,10%,X7R,A    I40 @S9S_MB_2U_LIB.S9S_MB_2U(SCH_1):PAGE267
  PJ64    1      1 Q_SHORT_SM-EMPTY,SHORT6    I41 @S9S_MB_2U_LIB.S9S_MB_2U(SCH_1):PAGE267

SH_PVPP_HBM_CPU1_N @S9S_MB_2U_LIB.S9S_MB_2U(SCH_1):SH_PVPP_HBM_CPU1_N
PC2282    2      B Q_CAP_0402-0.01UF,25V,10%,X7R,A    I32 @S9S_MB_2U_LIB.S9S_MB_2U(SCH_1):PAGE285
PR1314    2      B Q_RES_0402LF-11.3K,0.1%,1/16W,A    I28 @S9S_MB_2U_LIB.S9S_MB_2U(SCH_1):PAGE285
  PJ67    1      1 Q_SHORT_SM-EMPTY,SHORT6    I44 @S9S_MB_2U_LIB.S9S_MB_2U(SCH_1):PAGE285
  PU80    6    RTN RS53318LR-RS53318LR,SMLF,IC,ALA    I25 @S9S_MB_2U_LIB.S9S_MB_2U(SCH_1):PAGE285
PC1264    2      B Q_CAP_0402-0.1UF,25V,10%,X7R,CA    I24 @S9S_MB_2U_LIB.S9S_MB_2U(SCH_1):PAGE285
 PU174    S SOURCE MOSFET_N_SMLF-BSS138K,BSS138K,B    I29 @S9S_MB_2U_LIB.S9S_MB_2U(SCH_1):PAGE285

SH_PVPP_HBM_CPU1_P @S9S_MB_2U_LIB.S9S_MB_2U(SCH_1):SH_PVPP_HBM_CPU1_P
PC2282    1      A Q_CAP_0402-0.01UF,25V,10%,X7R,A    I32 @S9S_MB_2U_LIB.S9S_MB_2U(SCH_1):PAGE285
PR1340    2      B Q_RES_0402LF-38.3K,0.1%,1/16W,A    I34 @S9S_MB_2U_LIB.S9S_MB_2U(SCH_1):PAGE285
  PJ66    1      1 Q_SHORT_SM-EMPTY,SHORT6    I46 @S9S_MB_2U_LIB.S9S_MB_2U(SCH_1):PAGE285
PC1266    2      B Q_CAP_0402-680PF,50V,10%,X7R,TA    I35 @S9S_MB_2U_LIB.S9S_MB_2U(SCH_1):PAGE285

SMB_1_BMC_GPU_BUF_R_SCL @S9S_MB_2U_LIB.S9S_MB_2U(SCH_1):SMB_1_BMC_GPU_BUF_R_SCL
 R2893    2      B Q_RES_0402LF-0,5%,1/16W,EMPTY,A    I38 @S9S_MB_2U_LIB.S9S_MB_2U(SCH_1):PAGE222
  U194    2 SCL_OUT LTC4307CMS8-LTC4307CMS8,SMLF,IA    I63 @S9S_MB_2U_LIB.S9S_MB_2U(SCH_1):PAGE222
 R2897    1      A Q_RES_0402LF-33.2,1%,1/16W,CHIA    I78 @S9S_MB_2U_LIB.S9S_MB_2U(SCH_1):PAGE222
 R3523    2      B Q_RES_0402LF-54.9K,1%,1/16W,CHA    I80 @S9S_MB_2U_LIB.S9S_MB_2U(SCH_1):PAGE222

SMB_1_BMC_GPU_BUF_R_SDA @S9S_MB_2U_LIB.S9S_MB_2U(SCH_1):SMB_1_BMC_GPU_BUF_R_SDA
 R2894    2      B Q_RES_0402LF-0,5%,1/16W,EMPTY,A    I33 @S9S_MB_2U_LIB.S9S_MB_2U(SCH_1):PAGE222
  U194    7 SDA_OUT LTC4307CMS8-LTC4307CMS8,SMLF,IA    I63 @S9S_MB_2U_LIB.S9S_MB_2U(SCH_1):PAGE222
 R2898    1      A Q_RES_0402LF-33.2,1%,1/16W,CHIA    I79 @S9S_MB_2U_LIB.S9S_MB_2U(SCH_1):PAGE222
 R3524    2      B Q_RES_0402LF-54.9K,1%,1/16W,CHA    I81 @S9S_MB_2U_LIB.S9S_MB_2U(SCH_1):PAGE222

SMB_1_BMC_GPU_BUF_SCL @S9S_MB_2U_LIB.S9S_MB_2U(SCH_1):SMB_1_BMC_GPU_BUF_SCL
  J112   Q4     Q4 CONN160_10131762101LF-CONN160_A    I76 @S9S_MB_2U_LIB.S9S_MB_2U(SCH_1):PAGE149
 R2897    2      B Q_RES_0402LF-33.2,1%,1/16W,CHIA    I78 @S9S_MB_2U_LIB.S9S_MB_2U(SCH_1):PAGE222

SMB_1_BMC_GPU_BUF_SDA @S9S_MB_2U_LIB.S9S_MB_2U(SCH_1):SMB_1_BMC_GPU_BUF_SDA
  J112   R4     R4 CONN160_10131762101LF-CONN160_A    I76 @S9S_MB_2U_LIB.S9S_MB_2U(SCH_1):PAGE149
 R2898    2      B Q_RES_0402LF-33.2,1%,1/16W,CHIA    I79 @S9S_MB_2U_LIB.S9S_MB_2U(SCH_1):PAGE222

SMB_1_BMC_GPU_R_SCL @S9S_MB_2U_LIB.S9S_MB_2U(SCH_1):SMB_1_BMC_GPU_R_SCL
 R2893    1      A Q_RES_0402LF-0,5%,1/16W,EMPTY,A    I38 @S9S_MB_2U_LIB.S9S_MB_2U(SCH_1):PAGE222
 R3109    2      B Q_RES_0402LF-0,5%,1/16W,CHIP,CA    I51 @S9S_MB_2U_LIB.S9S_MB_2U(SCH_1):PAGE222
  U194    3 SCL_IN LTC4307CMS8-LTC4307CMS8,SMLF,IA    I63 @S9S_MB_2U_LIB.S9S_MB_2U(SCH_1):PAGE222

SMB_1_BMC_GPU_R_SDA @S9S_MB_2U_LIB.S9S_MB_2U(SCH_1):SMB_1_BMC_GPU_R_SDA
 R2894    1      A Q_RES_0402LF-0,5%,1/16W,EMPTY,A    I33 @S9S_MB_2U_LIB.S9S_MB_2U(SCH_1):PAGE222
 R3110    2      B Q_RES_0402LF-0,5%,1/16W,CHIP,CA    I52 @S9S_MB_2U_LIB.S9S_MB_2U(SCH_1):PAGE222
  U194    6 SDA_IN LTC4307CMS8-LTC4307CMS8,SMLF,IA    I63 @S9S_MB_2U_LIB.S9S_MB_2U(SCH_1):PAGE222

SMB_1_BMC_GPU_SCL @S9S_MB_2U_LIB.S9S_MB_2U(SCH_1):SMB_1_BMC_GPU_SCL
 R3226    1      A Q_RES_0402LF-2.2K,5%,1/16W,EMPA   I251 @S9S_MB_2U_LIB.S9S_MB_2U(SCH_1):PAGE228
 R3109    1      A Q_RES_0402LF-0,5%,1/16W,CHIP,CA    I51 @S9S_MB_2U_LIB.S9S_MB_2U(SCH_1):PAGE222
 R2415    1      A Q_RES_0402LF-0,5%,1/16W,CHIP,CA    I25 @S9S_MB_2U_LIB.S9S_MB_2U(SCH_1):PAGE227

SMB_1_BMC_GPU_SDA @S9S_MB_2U_LIB.S9S_MB_2U(SCH_1):SMB_1_BMC_GPU_SDA
 R3227    1      A Q_RES_0402LF-2.2K,5%,1/16W,EMPA   I250 @S9S_MB_2U_LIB.S9S_MB_2U(SCH_1):PAGE228
 R3110    1      A Q_RES_0402LF-0,5%,1/16W,CHIP,CA    I52 @S9S_MB_2U_LIB.S9S_MB_2U(SCH_1):PAGE222
 R2416    1      A Q_RES_0402LF-0,5%,1/16W,CHIP,CA    I24 @S9S_MB_2U_LIB.S9S_MB_2U(SCH_1):PAGE227

SMB_1_PLD_3V3AUX_SCL @S9S_MB_2U_LIB.S9S_MB_2U(SCH_1):SMB_1_PLD_3V3AUX_SCL
 R4149    1      A Q_RES_0402LF-33.2,1%,1/16W,CHIA   I272 @S9S_MB_2U_LIB.S9S_MB_2U(SCH_1):PAGE228
 R4151    1      A Q_RES_0402LF-33.2,1%,1/16W,CHIA   I274 @S9S_MB_2U_LIB.S9S_MB_2U(SCH_1):PAGE228
 R4508    1      A Q_RES_0402LF-33.2,1%,1/16W,CHIA    I87 @S9S_MB_2U_LIB.S9S_MB_2U(SCH_1):PAGE227

SMB_1_PLD_3V3AUX_SCL_R1 @S9S_MB_2U_LIB.S9S_MB_2U(SCH_1):SMB_1_PLD_3V3AUX_SCL_R1
 R4149    2      B Q_RES_0402LF-33.2,1%,1/16W,CHIA   I272 @S9S_MB_2U_LIB.S9S_MB_2U(SCH_1):PAGE228
 R1467    2      B Q_RES_0402LF-4.7K,1%,1/16W,EMPA   I178 @S9S_MB_2U_LIB.S9S_MB_2U(SCH_1):PAGE314
  U249  B12 PT27C||SCL||PCLKT0_0 LCMXO3LF9400C5BG484C-LCMXO3LF-A   I188 @S9S_MB_2U_LIB.S9S_MB_2U(SCH_1):PAGE314

SMB_1_PLD_3V3AUX_SCL_R3 @S9S_MB_2U_LIB.S9S_MB_2U(SCH_1):SMB_1_PLD_3V3AUX_SCL_R3
 R4508    2      B Q_RES_0402LF-33.2,1%,1/16W,CHIA    I87 @S9S_MB_2U_LIB.S9S_MB_2U(SCH_1):PAGE227
   J41  A27  PERP3 SCONN168_ME1016810202011-SCONNA   I173 @S9S_MB_2U_LIB.S9S_MB_2U(SCH_1):PAGE227

SMB_1_PLD_3V3AUX_SDA @S9S_MB_2U_LIB.S9S_MB_2U(SCH_1):SMB_1_PLD_3V3AUX_SDA
 R4150    1      A Q_RES_0402LF-33.2,1%,1/16W,CHIA   I271 @S9S_MB_2U_LIB.S9S_MB_2U(SCH_1):PAGE228
 R4152    1      A Q_RES_0402LF-33.2,1%,1/16W,CHIA   I273 @S9S_MB_2U_LIB.S9S_MB_2U(SCH_1):PAGE228
 R4509    1      A Q_RES_0402LF-33.2,1%,1/16W,CHIA    I88 @S9S_MB_2U_LIB.S9S_MB_2U(SCH_1):PAGE227

SMB_1_PLD_3V3AUX_SDA_R1 @S9S_MB_2U_LIB.S9S_MB_2U(SCH_1):SMB_1_PLD_3V3AUX_SDA_R1
 R4150    2      B Q_RES_0402LF-33.2,1%,1/16W,CHIA   I271 @S9S_MB_2U_LIB.S9S_MB_2U(SCH_1):PAGE228
 R1551    2      B Q_RES_0402LF-4.7K,1%,1/16W,EMPA   I179 @S9S_MB_2U_LIB.S9S_MB_2U(SCH_1):PAGE314
  U249  A12 PT27D||SDA||PCLKC0_0 LCMXO3LF9400C5BG484C-LCMXO3LF-A   I188 @S9S_MB_2U_LIB.S9S_MB_2U(SCH_1):PAGE314

SMB_1_PLD_3V3AUX_SDA_R3 @S9S_MB_2U_LIB.S9S_MB_2U(SCH_1):SMB_1_PLD_3V3AUX_SDA_R3
 R4509    2      B Q_RES_0402LF-33.2,1%,1/16W,CHIA    I88 @S9S_MB_2U_LIB.S9S_MB_2U(SCH_1):PAGE227
   J41  A28 GND_A28 SCONN168_ME1016810202011-SCONNA   I173 @S9S_MB_2U_LIB.S9S_MB_2U(SCH_1):PAGE227

SMB_2_BMC_GPU_BUF_R_SCL @S9S_MB_2U_LIB.S9S_MB_2U(SCH_1):SMB_2_BMC_GPU_BUF_R_SCL
  U200    2 SCL_OUT LTC4307CMS8-LTC4307CMS8,SMLF,IA    I11 @S9S_MB_2U_LIB.S9S_MB_2U(SCH_1):PAGE222
 R2986    2      B Q_RES_0402LF-0,5%,1/16W,EMPTY,A    I13 @S9S_MB_2U_LIB.S9S_MB_2U(SCH_1):PAGE222
 R3521    2      B Q_RES_0402LF-54.9K,1%,1/16W,CHA    I23 @S9S_MB_2U_LIB.S9S_MB_2U(SCH_1):PAGE222
 R2990    1      A Q_RES_0402LF-33.2,1%,1/16W,CHIA    I26 @S9S_MB_2U_LIB.S9S_MB_2U(SCH_1):PAGE222

SMB_2_BMC_GPU_BUF_R_SDA @S9S_MB_2U_LIB.S9S_MB_2U(SCH_1):SMB_2_BMC_GPU_BUF_R_SDA
 R2987    2      B Q_RES_0402LF-0,5%,1/16W,EMPTY,A    I12 @S9S_MB_2U_LIB.S9S_MB_2U(SCH_1):PAGE222
  U200    7 SDA_OUT LTC4307CMS8-LTC4307CMS8,SMLF,IA    I11 @S9S_MB_2U_LIB.S9S_MB_2U(SCH_1):PAGE222
 R3522    2      B Q_RES_0402LF-54.9K,1%,1/16W,CHA    I25 @S9S_MB_2U_LIB.S9S_MB_2U(SCH_1):PAGE222
 R2991    1      A Q_RES_0402LF-33.2,1%,1/16W,CHIA    I27 @S9S_MB_2U_LIB.S9S_MB_2U(SCH_1):PAGE222

SMB_2_BMC_GPU_BUF_SCL @S9S_MB_2U_LIB.S9S_MB_2U(SCH_1):SMB_2_BMC_GPU_BUF_SCL
  J112   R3     R3 CONN160_10131762101LF-CONN160_A    I76 @S9S_MB_2U_LIB.S9S_MB_2U(SCH_1):PAGE149
 R2990    2      B Q_RES_0402LF-33.2,1%,1/16W,CHIA    I26 @S9S_MB_2U_LIB.S9S_MB_2U(SCH_1):PAGE222

SMB_2_BMC_GPU_BUF_SDA @S9S_MB_2U_LIB.S9S_MB_2U(SCH_1):SMB_2_BMC_GPU_BUF_SDA
  J112   S3     S3 CONN160_10131762101LF-CONN160_A    I76 @S9S_MB_2U_LIB.S9S_MB_2U(SCH_1):PAGE149
 R2991    2      B Q_RES_0402LF-33.2,1%,1/16W,CHIA    I27 @S9S_MB_2U_LIB.S9S_MB_2U(SCH_1):PAGE222

SMB_2_BMC_GPU_R_SCL @S9S_MB_2U_LIB.S9S_MB_2U(SCH_1):SMB_2_BMC_GPU_R_SCL
 R3107    2      B Q_RES_0402LF-0,5%,1/16W,CHIP,CA     I8 @S9S_MB_2U_LIB.S9S_MB_2U(SCH_1):PAGE222
  U200    3 SCL_IN LTC4307CMS8-LTC4307CMS8,SMLF,IA    I11 @S9S_MB_2U_LIB.S9S_MB_2U(SCH_1):PAGE222
 R2986    1      A Q_RES_0402LF-0,5%,1/16W,EMPTY,A    I13 @S9S_MB_2U_LIB.S9S_MB_2U(SCH_1):PAGE222

SMB_2_BMC_GPU_R_SDA @S9S_MB_2U_LIB.S9S_MB_2U(SCH_1):SMB_2_BMC_GPU_R_SDA
 R2987    1      A Q_RES_0402LF-0,5%,1/16W,EMPTY,A    I12 @S9S_MB_2U_LIB.S9S_MB_2U(SCH_1):PAGE222
 R3108    2      B Q_RES_0402LF-0,5%,1/16W,CHIP,CA     I7 @S9S_MB_2U_LIB.S9S_MB_2U(SCH_1):PAGE222
  U200    6 SDA_IN LTC4307CMS8-LTC4307CMS8,SMLF,IA    I11 @S9S_MB_2U_LIB.S9S_MB_2U(SCH_1):PAGE222

SMB_2_BMC_GPU_SCL @S9S_MB_2U_LIB.S9S_MB_2U(SCH_1):SMB_2_BMC_GPU_SCL
 R2999    1      A Q_RES_0402LF-2.2K,5%,1/16W,EMPA   I231 @S9S_MB_2U_LIB.S9S_MB_2U(SCH_1):PAGE228
 R3107    1      A Q_RES_0402LF-0,5%,1/16W,CHIP,CA     I8 @S9S_MB_2U_LIB.S9S_MB_2U(SCH_1):PAGE222
 R2413    1      A Q_RES_0402LF-0,5%,1/16W,CHIP,CA    I86 @S9S_MB_2U_LIB.S9S_MB_2U(SCH_1):PAGE227

SMB_2_BMC_GPU_SDA @S9S_MB_2U_LIB.S9S_MB_2U(SCH_1):SMB_2_BMC_GPU_SDA
 R3004    1      A Q_RES_0402LF-2.2K,5%,1/16W,EMPA   I230 @S9S_MB_2U_LIB.S9S_MB_2U(SCH_1):PAGE228
 R3108    1      A Q_RES_0402LF-0,5%,1/16W,CHIP,CA     I7 @S9S_MB_2U_LIB.S9S_MB_2U(SCH_1):PAGE222
 R2414    1      A Q_RES_0402LF-0,5%,1/16W,CHIP,CA    I85 @S9S_MB_2U_LIB.S9S_MB_2U(SCH_1):PAGE227

SMB_2_PLD_3V3AUX_SCL_R1 @S9S_MB_2U_LIB.S9S_MB_2U(SCH_1):SMB_2_PLD_3V3AUX_SCL_R1
  U249  M22 PR17A||PCLKT1_0 LCMXO3LF9400C5BG484C-LCMXO3LF-A     I1 @S9S_MB_2U_LIB.S9S_MB_2U(SCH_1):PAGE313
 R4151    2      B Q_RES_0402LF-33.2,1%,1/16W,CHIA   I274 @S9S_MB_2U_LIB.S9S_MB_2U(SCH_1):PAGE228

SMB_2_PLD_3V3AUX_SDA_R1 @S9S_MB_2U_LIB.S9S_MB_2U(SCH_1):SMB_2_PLD_3V3AUX_SDA_R1
  U249  M21 PR17B||PCLKC1_0 LCMXO3LF9400C5BG484C-LCMXO3LF-A     I1 @S9S_MB_2U_LIB.S9S_MB_2U(SCH_1):PAGE313
 R4152    2      B Q_RES_0402LF-33.2,1%,1/16W,CHIA   I273 @S9S_MB_2U_LIB.S9S_MB_2U(SCH_1):PAGE228

SMB_BMC_GPU_EN @S9S_MB_2U_LIB.S9S_MB_2U(SCH_1):SMB_BMC_GPU_EN
  U249   G8  PT11D LCMXO3LF9400C5BG484C-LCMXO3LF-A   I188 @S9S_MB_2U_LIB.S9S_MB_2U(SCH_1):PAGE314
 R2992    1      A Q_RES_0402LF-0,5%,1/16W,CHIP,CA     I9 @S9S_MB_2U_LIB.S9S_MB_2U(SCH_1):PAGE222
 R4603    1      A Q_RES_0402LF-10K,1%,1/16W,CHIPA    I48 @S9S_MB_2U_LIB.S9S_MB_2U(SCH_1):PAGE222
 R2899    1      A Q_RES_0402LF-0,5%,1/16W,CHIP,CA    I53 @S9S_MB_2U_LIB.S9S_MB_2U(SCH_1):PAGE222

SMB_BMC_GPU_EN_R1 @S9S_MB_2U_LIB.S9S_MB_2U(SCH_1):SMB_BMC_GPU_EN_R1
 R2899    2      B Q_RES_0402LF-0,5%,1/16W,CHIP,CA    I53 @S9S_MB_2U_LIB.S9S_MB_2U(SCH_1):PAGE222
  U194    1 ENABLE LTC4307CMS8-LTC4307CMS8,SMLF,IA    I63 @S9S_MB_2U_LIB.S9S_MB_2U(SCH_1):PAGE222

SMB_BMC_GPU_EN_R3 @S9S_MB_2U_LIB.S9S_MB_2U(SCH_1):SMB_BMC_GPU_EN_R3
 R2992    2      B Q_RES_0402LF-0,5%,1/16W,CHIP,CA     I9 @S9S_MB_2U_LIB.S9S_MB_2U(SCH_1):PAGE222
  U200    1 ENABLE LTC4307CMS8-LTC4307CMS8,SMLF,IA    I11 @S9S_MB_2U_LIB.S9S_MB_2U(SCH_1):PAGE222

SMB_BMC_SWB_BUF_R_SCL @S9S_MB_2U_LIB.S9S_MB_2U(SCH_1):SMB_BMC_SWB_BUF_R_SCL
 R2705    2      B Q_RES_0402LF-0,5%,1/16W,EMPTY,A    I55 @S9S_MB_2U_LIB.S9S_MB_2U(SCH_1):PAGE222
 R2671    1      A Q_RES_0402LF-33.2,1%,1/16W,CHIA    I65 @S9S_MB_2U_LIB.S9S_MB_2U(SCH_1):PAGE222
  U175    2 SCL_OUT LTC4307CMS8-LTC4307CMS8,SMLF,IA    I50 @S9S_MB_2U_LIB.S9S_MB_2U(SCH_1):PAGE222
 R2667    2      B Q_RES_0402LF-10K,1%,1/16W,CHIPA    I59 @S9S_MB_2U_LIB.S9S_MB_2U(SCH_1):PAGE222

SMB_BMC_SWB_BUF_R_SDA @S9S_MB_2U_LIB.S9S_MB_2U(SCH_1):SMB_BMC_SWB_BUF_R_SDA
 R2724    2      B Q_RES_0402LF-0,5%,1/16W,EMPTY,A    I54 @S9S_MB_2U_LIB.S9S_MB_2U(SCH_1):PAGE222
  U175    7 SDA_OUT LTC4307CMS8-LTC4307CMS8,SMLF,IA    I50 @S9S_MB_2U_LIB.S9S_MB_2U(SCH_1):PAGE222
 R2669    2      B Q_RES_0402LF-10K,1%,1/16W,CHIPA    I61 @S9S_MB_2U_LIB.S9S_MB_2U(SCH_1):PAGE222
 R2672    1      A Q_RES_0402LF-33.2,1%,1/16W,CHIA    I64 @S9S_MB_2U_LIB.S9S_MB_2U(SCH_1):PAGE222

SMB_BMC_SWB_BUF_SCL @S9S_MB_2U_LIB.S9S_MB_2U(SCH_1):SMB_BMC_SWB_BUF_SCL
 R2671    2      B Q_RES_0402LF-33.2,1%,1/16W,CHIA    I65 @S9S_MB_2U_LIB.S9S_MB_2U(SCH_1):PAGE222
  J109   A5     A5 CONN112_10137002101LF-CONN112_A    I76 @S9S_MB_2U_LIB.S9S_MB_2U(SCH_1):PAGE319

SMB_BMC_SWB_BUF_SDA @S9S_MB_2U_LIB.S9S_MB_2U(SCH_1):SMB_BMC_SWB_BUF_SDA
  J109   A7     A7 CONN112_10137002101LF-CONN112_A    I76 @S9S_MB_2U_LIB.S9S_MB_2U(SCH_1):PAGE319
 R2672    2      B Q_RES_0402LF-33.2,1%,1/16W,CHIA    I64 @S9S_MB_2U_LIB.S9S_MB_2U(SCH_1):PAGE222

SMB_BMC_SWB_EN @S9S_MB_2U_LIB.S9S_MB_2U(SCH_1):SMB_BMC_SWB_EN
 R2666    1      A Q_RES_0402LF-10K,1%,1/16W,CHIPA    I16 @S9S_MB_2U_LIB.S9S_MB_2U(SCH_1):PAGE222
  U249   A4  PT11B LCMXO3LF9400C5BG484C-LCMXO3LF-A   I188 @S9S_MB_2U_LIB.S9S_MB_2U(SCH_1):PAGE314
 R2676    1      A Q_RES_0402LF-0,5%,1/16W,CHIP,CA    I19 @S9S_MB_2U_LIB.S9S_MB_2U(SCH_1):PAGE222
 R2707    1      A Q_RES_0402LF-0,5%,1/16W,CHIP,CA    I44 @S9S_MB_2U_LIB.S9S_MB_2U(SCH_1):PAGE222

SMB_BMC_SWB_EN_R @S9S_MB_2U_LIB.S9S_MB_2U(SCH_1):SMB_BMC_SWB_EN_R
 R2707    2      B Q_RES_0402LF-0,5%,1/16W,CHIP,CA    I44 @S9S_MB_2U_LIB.S9S_MB_2U(SCH_1):PAGE222
  U175    1 ENABLE LTC4307CMS8-LTC4307CMS8,SMLF,IA    I50 @S9S_MB_2U_LIB.S9S_MB_2U(SCH_1):PAGE222

SMB_BMC_SWB_EN_R2 @S9S_MB_2U_LIB.S9S_MB_2U(SCH_1):SMB_BMC_SWB_EN_R2
 R2676    2      B Q_RES_0402LF-0,5%,1/16W,CHIP,CA    I19 @S9S_MB_2U_LIB.S9S_MB_2U(SCH_1):PAGE222
  U176    1 ENABLE LTC4307CMS8-LTC4307CMS8,SMLF,EA    I31 @S9S_MB_2U_LIB.S9S_MB_2U(SCH_1):PAGE222

SMB_BMC_SWB_R_SCL @S9S_MB_2U_LIB.S9S_MB_2U(SCH_1):SMB_BMC_SWB_R_SCL
 R2705    1      A Q_RES_0402LF-0,5%,1/16W,EMPTY,A    I55 @S9S_MB_2U_LIB.S9S_MB_2U(SCH_1):PAGE222
 R3105    2      B Q_RES_0402LF-0,5%,1/16W,CHIP,CA    I43 @S9S_MB_2U_LIB.S9S_MB_2U(SCH_1):PAGE222
  U175    3 SCL_IN LTC4307CMS8-LTC4307CMS8,SMLF,IA    I50 @S9S_MB_2U_LIB.S9S_MB_2U(SCH_1):PAGE222

SMB_BMC_SWB_R_SDA @S9S_MB_2U_LIB.S9S_MB_2U(SCH_1):SMB_BMC_SWB_R_SDA
 R2724    1      A Q_RES_0402LF-0,5%,1/16W,EMPTY,A    I54 @S9S_MB_2U_LIB.S9S_MB_2U(SCH_1):PAGE222
 R3106    2      B Q_RES_0402LF-0,5%,1/16W,CHIP,CA    I42 @S9S_MB_2U_LIB.S9S_MB_2U(SCH_1):PAGE222
  U175    6 SDA_IN LTC4307CMS8-LTC4307CMS8,SMLF,IA    I50 @S9S_MB_2U_LIB.S9S_MB_2U(SCH_1):PAGE222

SMB_BMC_SWB_SCL @S9S_MB_2U_LIB.S9S_MB_2U(SCH_1):SMB_BMC_SWB_SCL
 R3105    1      A Q_RES_0402LF-0,5%,1/16W,CHIP,CA    I43 @S9S_MB_2U_LIB.S9S_MB_2U(SCH_1):PAGE222
 R2984    2      B Q_RES_0402LF-10K,1%,1/16W,CHIPA    I25 @S9S_MB_2U_LIB.S9S_MB_2U(SCH_1):PAGE219
 R2703    2      B Q_RES_0402LF-0,5%,1/16W,CHIP,CA    I63 @S9S_MB_2U_LIB.S9S_MB_2U(SCH_1):PAGE219

SMB_BMC_SWB_SCL_R4 @S9S_MB_2U_LIB.S9S_MB_2U(SCH_1):SMB_BMC_SWB_SCL_R4
   U36   14    SC4 TCA9548APWR-TCA9548APWR,SMLF,IA    I45 @S9S_MB_2U_LIB.S9S_MB_2U(SCH_1):PAGE219
 R2703    1      A Q_RES_0402LF-0,5%,1/16W,CHIP,CA    I63 @S9S_MB_2U_LIB.S9S_MB_2U(SCH_1):PAGE219

SMB_BMC_SWB_SDA @S9S_MB_2U_LIB.S9S_MB_2U(SCH_1):SMB_BMC_SWB_SDA
 R3106    1      A Q_RES_0402LF-0,5%,1/16W,CHIP,CA    I42 @S9S_MB_2U_LIB.S9S_MB_2U(SCH_1):PAGE222
 R2985    2      B Q_RES_0402LF-10K,1%,1/16W,CHIPA    I24 @S9S_MB_2U_LIB.S9S_MB_2U(SCH_1):PAGE219
 R2704    2      B Q_RES_0402LF-0,5%,1/16W,CHIP,CA    I64 @S9S_MB_2U_LIB.S9S_MB_2U(SCH_1):PAGE219

SMB_BMC_SWB_SDA_R4 @S9S_MB_2U_LIB.S9S_MB_2U(SCH_1):SMB_BMC_SWB_SDA_R4
   U36   13    SD4 TCA9548APWR-TCA9548APWR,SMLF,IA    I45 @S9S_MB_2U_LIB.S9S_MB_2U(SCH_1):PAGE219
 R2704    1      A Q_RES_0402LF-0,5%,1/16W,CHIP,CA    I64 @S9S_MB_2U_LIB.S9S_MB_2U(SCH_1):PAGE219

SMB_CLK_PVCCD_HV_CPU0 @S9S_MB_2U_LIB.S9S_MB_2U(SCH_1):SMB_CLK_PVCCD_HV_CPU0
  PU35   10  PMSCL ISL69260IRAZT-ISL69260IRAZ-T,SA    I53 @S9S_MB_2U_LIB.S9S_MB_2U(SCH_1):PAGE264
 R2402    2      B Q_RES_0402LF-0,5%,1/16W,CHIP,CA    I39 @S9S_MB_2U_LIB.S9S_MB_2U(SCH_1):PAGE264

SMB_CLK_PVCCD_HV_CPU1 @S9S_MB_2U_LIB.S9S_MB_2U(SCH_1):SMB_CLK_PVCCD_HV_CPU1
  PU18   10  PMSCL ISL69260IRAZT-ISL69260IRAZ-T,SA    I53 @S9S_MB_2U_LIB.S9S_MB_2U(SCH_1):PAGE282
 R4595    2      B Q_RES_0402LF-0,5%,1/16W,CHIP,CA    I39 @S9S_MB_2U_LIB.S9S_MB_2U(SCH_1):PAGE282

SMB_CLK_PVCCINFAON_CPU0 @S9S_MB_2U_LIB.S9S_MB_2U(SCH_1):SMB_CLK_PVCCINFAON_CPU0
   PU5   10  PMSCL ISL69260IRAZT-ISL69260IRAZ-T,SA    I65 @S9S_MB_2U_LIB.S9S_MB_2U(SCH_1):PAGE260
 R2390    2      B Q_RES_0402LF-0,5%,1/16W,CHIP,CA    I53 @S9S_MB_2U_LIB.S9S_MB_2U(SCH_1):PAGE260

SMB_CLK_PVCCINFAON_CPU1 @S9S_MB_2U_LIB.S9S_MB_2U(SCH_1):SMB_CLK_PVCCINFAON_CPU1
  PU22   10  PMSCL ISL69260IRAZT-ISL69260IRAZ-T,SA    I38 @S9S_MB_2U_LIB.S9S_MB_2U(SCH_1):PAGE278
 R4594    2      B Q_RES_0402LF-0,5%,1/16W,CHIP,CA    I58 @S9S_MB_2U_LIB.S9S_MB_2U(SCH_1):PAGE278

SMB_CLK_PVCCIN_CPU0 @S9S_MB_2U_LIB.S9S_MB_2U(SCH_1):SMB_CLK_PVCCIN_CPU0
  PU14   14  PMSCL RAA229126GNPHA0-RAA229126GNP#HA    I63 @S9S_MB_2U_LIB.S9S_MB_2U(SCH_1):PAGE252
 R2371    2      B Q_RES_0402LF-33.2,1%,1/16W,CHIA    I80 @S9S_MB_2U_LIB.S9S_MB_2U(SCH_1):PAGE252

SMB_CLK_PVCCIN_CPU1 @S9S_MB_2U_LIB.S9S_MB_2U(SCH_1):SMB_CLK_PVCCIN_CPU1
 R2520    2      B Q_RES_0402LF-0,5%,1/16W,CHIP,CA    I65 @S9S_MB_2U_LIB.S9S_MB_2U(SCH_1):PAGE270
  PU29   14  PMSCL RAA229126GNPHA0-RAA229126GNP#HA    I33 @S9S_MB_2U_LIB.S9S_MB_2U(SCH_1):PAGE270

SMB_DIO_PVCCD_HV_CPU0 @S9S_MB_2U_LIB.S9S_MB_2U(SCH_1):SMB_DIO_PVCCD_HV_CPU0
 R2403    2      B Q_RES_0402LF-0,5%,1/16W,CHIP,CA    I38 @S9S_MB_2U_LIB.S9S_MB_2U(SCH_1):PAGE264
  PU35    9  PMSDA ISL69260IRAZT-ISL69260IRAZ-T,SA    I53 @S9S_MB_2U_LIB.S9S_MB_2U(SCH_1):PAGE264

SMB_DIO_PVCCD_HV_CPU1 @S9S_MB_2U_LIB.S9S_MB_2U(SCH_1):SMB_DIO_PVCCD_HV_CPU1
 R2582    2      B Q_RES_0402LF-0,5%,1/16W,CHIP,CA    I38 @S9S_MB_2U_LIB.S9S_MB_2U(SCH_1):PAGE282
  PU18    9  PMSDA ISL69260IRAZT-ISL69260IRAZ-T,SA    I53 @S9S_MB_2U_LIB.S9S_MB_2U(SCH_1):PAGE282

SMB_DIO_PVCCINFAON_CPU0 @S9S_MB_2U_LIB.S9S_MB_2U(SCH_1):SMB_DIO_PVCCINFAON_CPU0
   PU5    9  PMSDA ISL69260IRAZT-ISL69260IRAZ-T,SA    I65 @S9S_MB_2U_LIB.S9S_MB_2U(SCH_1):PAGE260
 R2391    2      B Q_RES_0402LF-0,5%,1/16W,CHIP,CA    I51 @S9S_MB_2U_LIB.S9S_MB_2U(SCH_1):PAGE260

SMB_DIO_PVCCINFAON_CPU1 @S9S_MB_2U_LIB.S9S_MB_2U(SCH_1):SMB_DIO_PVCCINFAON_CPU1
 R2563    2      B Q_RES_0402LF-0,5%,1/16W,CHIP,CA    I57 @S9S_MB_2U_LIB.S9S_MB_2U(SCH_1):PAGE278
  PU22    9  PMSDA ISL69260IRAZT-ISL69260IRAZ-T,SA    I38 @S9S_MB_2U_LIB.S9S_MB_2U(SCH_1):PAGE278

SMB_DIO_PVCCIN_CPU0 @S9S_MB_2U_LIB.S9S_MB_2U(SCH_1):SMB_DIO_PVCCIN_CPU0
  PU14   13  PMSDA RAA229126GNPHA0-RAA229126GNP#HA    I63 @S9S_MB_2U_LIB.S9S_MB_2U(SCH_1):PAGE252
 R2372    2      B Q_RES_0402LF-33.2,1%,1/16W,CHIA    I78 @S9S_MB_2U_LIB.S9S_MB_2U(SCH_1):PAGE252

SMB_DIO_PVCCIN_CPU1 @S9S_MB_2U_LIB.S9S_MB_2U(SCH_1):SMB_DIO_PVCCIN_CPU1
 R2521    2      B Q_RES_0402LF-0,5%,1/16W,CHIP,CA    I66 @S9S_MB_2U_LIB.S9S_MB_2U(SCH_1):PAGE270
  PU29   13  PMSDA RAA229126GNPHA0-RAA229126GNP#HA    I33 @S9S_MB_2U_LIB.S9S_MB_2U(SCH_1):PAGE270

SMB_E1S_3V3AUX_ISO_SCL @S9S_MB_2U_LIB.S9S_MB_2U(SCH_1):SMB_E1S_3V3AUX_ISO_SCL
 R3533    2      B Q_RES_0402LF-33.2,1%,1/16W,CHIA    I76 @S9S_MB_2U_LIB.S9S_MB_2U(SCH_1):PAGE183
   J90   A7 SMBCLK SCONN56_123276793-SCONN56_1-23A   I318 @S9S_MB_2U_LIB.S9S_MB_2U(SCH_1):PAGE297

SMB_E1S_3V3AUX_ISO_SCL_R @S9S_MB_2U_LIB.S9S_MB_2U(SCH_1):SMB_E1S_3V3AUX_ISO_SCL_R
 R3533    1      A Q_RES_0402LF-33.2,1%,1/16W,CHIA    I76 @S9S_MB_2U_LIB.S9S_MB_2U(SCH_1):PAGE183
 R3530    2      B Q_RES_0402LF-4.7K,5%,1/16W,CHIA    I80 @S9S_MB_2U_LIB.S9S_MB_2U(SCH_1):PAGE183
  U279    2   SCLA PCA9617ADP-PCA9617ADP,SMLF,IC,A    I93 @S9S_MB_2U_LIB.S9S_MB_2U(SCH_1):PAGE183

SMB_E1S_3V3AUX_ISO_SDA @S9S_MB_2U_LIB.S9S_MB_2U(SCH_1):SMB_E1S_3V3AUX_ISO_SDA
 R3534    2      B Q_RES_0402LF-33.2,1%,1/16W,CHIA    I77 @S9S_MB_2U_LIB.S9S_MB_2U(SCH_1):PAGE183
   J90   A8 SMBDAT SCONN56_123276793-SCONN56_1-23A   I318 @S9S_MB_2U_LIB.S9S_MB_2U(SCH_1):PAGE297

SMB_E1S_3V3AUX_ISO_SDA_R @S9S_MB_2U_LIB.S9S_MB_2U(SCH_1):SMB_E1S_3V3AUX_ISO_SDA_R
 R3534    1      A Q_RES_0402LF-33.2,1%,1/16W,CHIA    I77 @S9S_MB_2U_LIB.S9S_MB_2U(SCH_1):PAGE183
 R3532    2      B Q_RES_0402LF-4.7K,5%,1/16W,CHIA    I78 @S9S_MB_2U_LIB.S9S_MB_2U(SCH_1):PAGE183
  U279    3   SDAA PCA9617ADP-PCA9617ADP,SMLF,IC,A    I93 @S9S_MB_2U_LIB.S9S_MB_2U(SCH_1):PAGE183

SMB_FAN_3V3AUX_BUF_R_SCL @S9S_MB_2U_LIB.S9S_MB_2U(SCH_1):SMB_FAN_3V3AUX_BUF_R_SCL
   J45   C1     C1 CONN60_101062636003K02LF-CONN6A    I12 @S9S_MB_2U_LIB.S9S_MB_2U(SCH_1):PAGE233
 R2811    2      B Q_RES_0402LF-33.2,1%,1/16W,CHIA    I21 @S9S_MB_2U_LIB.S9S_MB_2U(SCH_1):PAGE233

SMB_FAN_3V3AUX_BUF_R_SDA @S9S_MB_2U_LIB.S9S_MB_2U(SCH_1):SMB_FAN_3V3AUX_BUF_R_SDA
   J45   C2     C2 CONN60_101062636003K02LF-CONN6A    I12 @S9S_MB_2U_LIB.S9S_MB_2U(SCH_1):PAGE233
 R2812    2      B Q_RES_0402LF-33.2,1%,1/16W,CHIA    I20 @S9S_MB_2U_LIB.S9S_MB_2U(SCH_1):PAGE233

SMB_FAN_3V3AUX_BUF_SCL @S9S_MB_2U_LIB.S9S_MB_2U(SCH_1):SMB_FAN_3V3AUX_BUF_SCL
 R2800    2      B Q_RES_0402LF-0,5%,1/16W,EMPTY,A    I15 @S9S_MB_2U_LIB.S9S_MB_2U(SCH_1):PAGE233
  U192    2 SCL_OUT LTC4307CMS8-LTC4307CMS8,SMLF,IA    I16 @S9S_MB_2U_LIB.S9S_MB_2U(SCH_1):PAGE233
 R2811    1      A Q_RES_0402LF-33.2,1%,1/16W,CHIA    I21 @S9S_MB_2U_LIB.S9S_MB_2U(SCH_1):PAGE233
 R2805    2      B Q_RES_0402LF-4.7K,5%,1/16W,EMPA    I22 @S9S_MB_2U_LIB.S9S_MB_2U(SCH_1):PAGE233

SMB_FAN_3V3AUX_BUF_SDA @S9S_MB_2U_LIB.S9S_MB_2U(SCH_1):SMB_FAN_3V3AUX_BUF_SDA
 R2801    2      B Q_RES_0402LF-0,5%,1/16W,EMPTY,A    I14 @S9S_MB_2U_LIB.S9S_MB_2U(SCH_1):PAGE233
  U192    7 SDA_OUT LTC4307CMS8-LTC4307CMS8,SMLF,IA    I16 @S9S_MB_2U_LIB.S9S_MB_2U(SCH_1):PAGE233
 R2812    1      A Q_RES_0402LF-33.2,1%,1/16W,CHIA    I20 @S9S_MB_2U_LIB.S9S_MB_2U(SCH_1):PAGE233
 R2807    2      B Q_RES_0402LF-4.7K,5%,1/16W,EMPA    I24 @S9S_MB_2U_LIB.S9S_MB_2U(SCH_1):PAGE233

SMB_FAN_3V3AUX_R_SCL @S9S_MB_2U_LIB.S9S_MB_2U(SCH_1):SMB_FAN_3V3AUX_R_SCL
 R3113    2      B Q_RES_0402LF-33.2,1%,1/16W,CHIA     I9 @S9S_MB_2U_LIB.S9S_MB_2U(SCH_1):PAGE233
 R2800    1      A Q_RES_0402LF-0,5%,1/16W,EMPTY,A    I15 @S9S_MB_2U_LIB.S9S_MB_2U(SCH_1):PAGE233
  U192    3 SCL_IN LTC4307CMS8-LTC4307CMS8,SMLF,IA    I16 @S9S_MB_2U_LIB.S9S_MB_2U(SCH_1):PAGE233

SMB_FAN_3V3AUX_R_SDA @S9S_MB_2U_LIB.S9S_MB_2U(SCH_1):SMB_FAN_3V3AUX_R_SDA
 R3114    2      B Q_RES_0402LF-33.2,1%,1/16W,CHIA     I8 @S9S_MB_2U_LIB.S9S_MB_2U(SCH_1):PAGE233
 R2801    1      A Q_RES_0402LF-0,5%,1/16W,EMPTY,A    I14 @S9S_MB_2U_LIB.S9S_MB_2U(SCH_1):PAGE233
  U192    6 SDA_IN LTC4307CMS8-LTC4307CMS8,SMLF,IA    I16 @S9S_MB_2U_LIB.S9S_MB_2U(SCH_1):PAGE233

SMB_FAN_3V3AUX_SCL @S9S_MB_2U_LIB.S9S_MB_2U(SCH_1):SMB_FAN_3V3AUX_SCL
  R592    1      A Q_RES_0402LF-2.2K,5%,1/16W,EMPA   I173 @S9S_MB_2U_LIB.S9S_MB_2U(SCH_1):PAGE228
 R3113    1      A Q_RES_0402LF-33.2,1%,1/16W,CHIA     I9 @S9S_MB_2U_LIB.S9S_MB_2U(SCH_1):PAGE233
   J41  A29 GND_A29 SCONN168_ME1016810202011-SCONNA   I173 @S9S_MB_2U_LIB.S9S_MB_2U(SCH_1):PAGE227

SMB_FAN_3V3AUX_SDA @S9S_MB_2U_LIB.S9S_MB_2U(SCH_1):SMB_FAN_3V3AUX_SDA
  R601    1      A Q_RES_0402LF-2.2K,5%,1/16W,EMPA   I172 @S9S_MB_2U_LIB.S9S_MB_2U(SCH_1):PAGE228
 R3114    1      A Q_RES_0402LF-33.2,1%,1/16W,CHIA     I8 @S9S_MB_2U_LIB.S9S_MB_2U(SCH_1):PAGE233
   J41  A30  PERN4 SCONN168_ME1016810202011-SCONNA   I173 @S9S_MB_2U_LIB.S9S_MB_2U(SCH_1):PAGE227

SMB_FRU_3V3AUX_SCL @S9S_MB_2U_LIB.S9S_MB_2U(SCH_1):SMB_FRU_3V3AUX_SCL
   U64    6    SCL M24128BWMN6TP-M24128-BWMN6TP,SA    I35 @S9S_MB_2U_LIB.S9S_MB_2U(SCH_1):PAGE231
 R1331    2      B Q_RES_0402LF-4.7K,5%,1/16W,EMPA    I95 @S9S_MB_2U_LIB.S9S_MB_2U(SCH_1):PAGE231
  R651    2      B Q_RES_0402LF-2.2K,5%,1/16W,CHIA    I22 @S9S_MB_2U_LIB.S9S_MB_2U(SCH_1):PAGE219
 R2565    2      B Q_RES_0402LF-0,5%,1/16W,CHIP,CA    I61 @S9S_MB_2U_LIB.S9S_MB_2U(SCH_1):PAGE219

SMB_FRU_3V3AUX_SCL_R @S9S_MB_2U_LIB.S9S_MB_2U(SCH_1):SMB_FRU_3V3AUX_SCL_R
   U36   16    SC5 TCA9548APWR-TCA9548APWR,SMLF,IA    I45 @S9S_MB_2U_LIB.S9S_MB_2U(SCH_1):PAGE219
 R2565    1      A Q_RES_0402LF-0,5%,1/16W,CHIP,CA    I61 @S9S_MB_2U_LIB.S9S_MB_2U(SCH_1):PAGE219

SMB_FRU_3V3AUX_SDA @S9S_MB_2U_LIB.S9S_MB_2U(SCH_1):SMB_FRU_3V3AUX_SDA
   U64    5    SDA M24128BWMN6TP-M24128-BWMN6TP,SA    I35 @S9S_MB_2U_LIB.S9S_MB_2U(SCH_1):PAGE231
 R1332    2      B Q_RES_0402LF-4.7K,5%,1/16W,EMPA    I93 @S9S_MB_2U_LIB.S9S_MB_2U(SCH_1):PAGE231
  R652    2      B Q_RES_0402LF-2.2K,5%,1/16W,CHIA    I23 @S9S_MB_2U_LIB.S9S_MB_2U(SCH_1):PAGE219
 R2566    2      B Q_RES_0402LF-0,5%,1/16W,CHIP,CA    I62 @S9S_MB_2U_LIB.S9S_MB_2U(SCH_1):PAGE219

SMB_FRU_3V3AUX_SDA_R @S9S_MB_2U_LIB.S9S_MB_2U(SCH_1):SMB_FRU_3V3AUX_SDA_R
   U36   15    SD5 TCA9548APWR-TCA9548APWR,SMLF,IA    I45 @S9S_MB_2U_LIB.S9S_MB_2U(SCH_1):PAGE219
 R2566    1      A Q_RES_0402LF-0,5%,1/16W,CHIP,CA    I62 @S9S_MB_2U_LIB.S9S_MB_2U(SCH_1):PAGE219

SMB_HOST_3V3AUX_PLD_SCL @S9S_MB_2U_LIB.S9S_MB_2U(SCH_1):SMB_HOST_3V3AUX_PLD_SCL
  U249  A10 PT23B||PCLKC0_1 LCMXO3LF9400C5BG484C-LCMXO3LF-A   I188 @S9S_MB_2U_LIB.S9S_MB_2U(SCH_1):PAGE314
 R4715    2      B Q_RES_0402LF-33.2,1%,1/16W,CHIA   I198 @S9S_MB_2U_LIB.S9S_MB_2U(SCH_1):PAGE314

SMB_HOST_3V3AUX_PLD_SDA @S9S_MB_2U_LIB.S9S_MB_2U(SCH_1):SMB_HOST_3V3AUX_PLD_SDA
  U249  B10 PT23A||PCLKT0_1 LCMXO3LF9400C5BG484C-LCMXO3LF-A   I188 @S9S_MB_2U_LIB.S9S_MB_2U(SCH_1):PAGE314
 R4714    2      B Q_RES_0402LF-33.2,1%,1/16W,CHIA   I197 @S9S_MB_2U_LIB.S9S_MB_2U(SCH_1):PAGE314

SMB_HOST_3V3AUX_SCL @S9S_MB_2U_LIB.S9S_MB_2U(SCH_1):SMB_HOST_3V3AUX_SCL
 R1319    1      A Q_RES_0402LF-2K,1%,1/16W,EMPTYA     I2 @S9S_MB_2U_LIB.S9S_MB_2U(SCH_1):PAGE228
 R4510    1      A Q_RES_0402LF-33.2,1%,1/16W,CHIA   I285 @S9S_MB_2U_LIB.S9S_MB_2U(SCH_1):PAGE228
 R4512    1      A Q_RES_0402LF-33.2,1%,1/16W,CHIA   I305 @S9S_MB_2U_LIB.S9S_MB_2U(SCH_1):PAGE228
 R2419    1      A Q_RES_0402LF-33.2,1%,1/16W,CHIA   I100 @S9S_MB_2U_LIB.S9S_MB_2U(SCH_1):PAGE227

SMB_HOST_3V3AUX_SCL_R @S9S_MB_2U_LIB.S9S_MB_2U(SCH_1):SMB_HOST_3V3AUX_SCL_R
 R1525    1      A Q_RES_0402LF-0,5%,1/16W,CHIP,CA    I40 @S9S_MB_2U_LIB.S9S_MB_2U(SCH_1):PAGE228
  R107    1      A Q_RES_0402LF-33.2,1%,1/16W,CHIA    I43 @S9S_MB_2U_LIB.S9S_MB_2U(SCH_1):PAGE228
  R577    2      B Q_RES_0402LF-33.2,1%,1/16W,CHIA   I303 @S9S_MB_2U_LIB.S9S_MB_2U(SCH_1):PAGE228

SMB_HOST_3V3AUX_SCL_R0 @S9S_MB_2U_LIB.S9S_MB_2U(SCH_1):SMB_HOST_3V3AUX_SCL_R0
 R2419    2      B Q_RES_0402LF-33.2,1%,1/16W,CHIA   I100 @S9S_MB_2U_LIB.S9S_MB_2U(SCH_1):PAGE227
   J41   A3 GND_A3 SCONN168_ME1016810202011-SCONNA   I173 @S9S_MB_2U_LIB.S9S_MB_2U(SCH_1):PAGE227

SMB_HOST_3V3AUX_SCL_R4 @S9S_MB_2U_LIB.S9S_MB_2U(SCH_1):SMB_HOST_3V3AUX_SCL_R4
 R4502    1      A Q_RES_0402LF-33.2,1%,1/16W,CHIA   I148 @S9S_MB_2U_LIB.S9S_MB_2U(SCH_1):PAGE133
 R4510    2      B Q_RES_0402LF-33.2,1%,1/16W,CHIA   I285 @S9S_MB_2U_LIB.S9S_MB_2U(SCH_1):PAGE228
  R577    1      A Q_RES_0402LF-33.2,1%,1/16W,CHIA   I303 @S9S_MB_2U_LIB.S9S_MB_2U(SCH_1):PAGE228
 R4715    1      A Q_RES_0402LF-33.2,1%,1/16W,CHIA   I198 @S9S_MB_2U_LIB.S9S_MB_2U(SCH_1):PAGE314

SMB_HOST_3V3AUX_SCL_R5 @S9S_MB_2U_LIB.S9S_MB_2U(SCH_1):SMB_HOST_3V3AUX_SCL_R5
  R579    1      A Q_RES_0402LF-33.2,1%,1/16W,CHIA    I38 @S9S_MB_2U_LIB.S9S_MB_2U(SCH_1):PAGE228
 R3052    1      A Q_RES_0402LF-33.2,1%,1/16W,CHIA    I13 @S9S_MB_2U_LIB.S9S_MB_2U(SCH_1):PAGE215
 R4512    2      B Q_RES_0402LF-33.2,1%,1/16W,CHIA   I305 @S9S_MB_2U_LIB.S9S_MB_2U(SCH_1):PAGE228

SMB_HOST_3V3AUX_SDA @S9S_MB_2U_LIB.S9S_MB_2U(SCH_1):SMB_HOST_3V3AUX_SDA
 R3062    1      A Q_RES_0402LF-2K,1%,1/16W,EMPTYA     I3 @S9S_MB_2U_LIB.S9S_MB_2U(SCH_1):PAGE228
 R4511    1      A Q_RES_0402LF-0,5%,1/16W,CHIP,CA   I284 @S9S_MB_2U_LIB.S9S_MB_2U(SCH_1):PAGE228
 R4513    1      A Q_RES_0402LF-0,5%,1/16W,CHIP,CA   I306 @S9S_MB_2U_LIB.S9S_MB_2U(SCH_1):PAGE228
 R2420    1      A Q_RES_0402LF-33.2,1%,1/16W,CHIA    I98 @S9S_MB_2U_LIB.S9S_MB_2U(SCH_1):PAGE227

SMB_HOST_3V3AUX_SDA_R @S9S_MB_2U_LIB.S9S_MB_2U(SCH_1):SMB_HOST_3V3AUX_SDA_R
 R1526    1      A Q_RES_0402LF-33.2,1%,1/16W,CHIA    I41 @S9S_MB_2U_LIB.S9S_MB_2U(SCH_1):PAGE228
  R108    1      A Q_RES_0402LF-33.2,1%,1/16W,CHIA    I42 @S9S_MB_2U_LIB.S9S_MB_2U(SCH_1):PAGE228
  R578    2      B Q_RES_0402LF-33.2,1%,1/16W,CHIA   I304 @S9S_MB_2U_LIB.S9S_MB_2U(SCH_1):PAGE228

SMB_HOST_3V3AUX_SDA_R0 @S9S_MB_2U_LIB.S9S_MB_2U(SCH_1):SMB_HOST_3V3AUX_SDA_R0
 R2420    2      B Q_RES_0402LF-33.2,1%,1/16W,CHIA    I98 @S9S_MB_2U_LIB.S9S_MB_2U(SCH_1):PAGE227
   J41   A4 GND_A4 SCONN168_ME1016810202011-SCONNA   I173 @S9S_MB_2U_LIB.S9S_MB_2U(SCH_1):PAGE227

SMB_HOST_3V3AUX_SDA_R4 @S9S_MB_2U_LIB.S9S_MB_2U(SCH_1):SMB_HOST_3V3AUX_SDA_R4
 R4503    1      A Q_RES_0402LF-0,5%,1/16W,CHIP,CA   I153 @S9S_MB_2U_LIB.S9S_MB_2U(SCH_1):PAGE133
 R4511    2      B Q_RES_0402LF-0,5%,1/16W,CHIP,CA   I284 @S9S_MB_2U_LIB.S9S_MB_2U(SCH_1):PAGE228
  R578    1      A Q_RES_0402LF-33.2,1%,1/16W,CHIA   I304 @S9S_MB_2U_LIB.S9S_MB_2U(SCH_1):PAGE228
 R4714    1      A Q_RES_0402LF-33.2,1%,1/16W,CHIA   I197 @S9S_MB_2U_LIB.S9S_MB_2U(SCH_1):PAGE314

SMB_HOST_3V3AUX_SDA_R5 @S9S_MB_2U_LIB.S9S_MB_2U(SCH_1):SMB_HOST_3V3AUX_SDA_R5
  R580    1      A Q_RES_0402LF-33.2,1%,1/16W,CHIA    I39 @S9S_MB_2U_LIB.S9S_MB_2U(SCH_1):PAGE228
 R3053    1      A Q_RES_0402LF-33.2,1%,1/16W,CHIA    I12 @S9S_MB_2U_LIB.S9S_MB_2U(SCH_1):PAGE215
 R4513    2      B Q_RES_0402LF-0,5%,1/16W,CHIP,CA   I306 @S9S_MB_2U_LIB.S9S_MB_2U(SCH_1):PAGE228

SMB_HOST_3V3AUX_XDP_R_SCL @S9S_MB_2U_LIB.S9S_MB_2U(SCH_1):SMB_HOST_3V3AUX_XDP_R_SCL
   J42   48     48 SCONN60_ASP21410801-SCONN60_ASA    I44 @S9S_MB_2U_LIB.S9S_MB_2U(SCH_1):PAGE133
 R4502    2      B Q_RES_0402LF-33.2,1%,1/16W,CHIA   I148 @S9S_MB_2U_LIB.S9S_MB_2U(SCH_1):PAGE133

SMB_HOST_3V3AUX_XDP_R_SDA @S9S_MB_2U_LIB.S9S_MB_2U(SCH_1):SMB_HOST_3V3AUX_XDP_R_SDA
   J42   50     50 SCONN60_ASP21410801-SCONN60_ASA    I44 @S9S_MB_2U_LIB.S9S_MB_2U(SCH_1):PAGE133
 R4503    2      B Q_RES_0402LF-0,5%,1/16W,CHIP,CA   I153 @S9S_MB_2U_LIB.S9S_MB_2U(SCH_1):PAGE133

SMB_HOST_9ZXL045_3V3AUX_SCL @S9S_MB_2U_LIB.S9S_MB_2U(SCH_1):SMB_HOST_9ZXL045_3V3AUX_SCL
  U314    7 SMBCLK 9ZXL0451EKILFT-9ZXL0451EKILFT,A     I1 @S9S_MB_2U_LIB.S9S_MB_2U(SCH_1):PAGE200
 R4480    2      B Q_RES_0402LF-33.2,1%,1/16W,CHIA    I24 @S9S_MB_2U_LIB.S9S_MB_2U(SCH_1):PAGE225

SMB_HOST_9ZXL045_3V3AUX_SDA @S9S_MB_2U_LIB.S9S_MB_2U(SCH_1):SMB_HOST_9ZXL045_3V3AUX_SDA
  U314    6 SMBDAT 9ZXL0451EKILFT-9ZXL0451EKILFT,A     I1 @S9S_MB_2U_LIB.S9S_MB_2U(SCH_1):PAGE200
 R4481    2      B Q_RES_0402LF-33.2,1%,1/16W,CHIA    I25 @S9S_MB_2U_LIB.S9S_MB_2U(SCH_1):PAGE225

SMB_HOST_BMC_3V3AUX_SCL @S9S_MB_2U_LIB.S9S_MB_2U(SCH_1):SMB_HOST_BMC_3V3AUX_SCL
    U4  AF2 GPP_D_0_HS_SMBCLK_DMA_SMBCLK EMMITSBURG_REV0P9-GFNOCPU04302A    I93 @S9S_MB_2U_LIB.S9S_MB_2U(SCH_1):PAGE175
  R579    2      B Q_RES_0402LF-33.2,1%,1/16W,CHIA    I38 @S9S_MB_2U_LIB.S9S_MB_2U(SCH_1):PAGE228

SMB_HOST_BMC_3V3AUX_SDA @S9S_MB_2U_LIB.S9S_MB_2U(SCH_1):SMB_HOST_BMC_3V3AUX_SDA
    U4  AE1 GPP_D_1_HS_SMBDATA_DMA_SMBDATA EMMITSBURG_REV0P9-GFNOCPU04302A    I93 @S9S_MB_2U_LIB.S9S_MB_2U(SCH_1):PAGE175
  R580    2      B Q_RES_0402LF-33.2,1%,1/16W,CHIA    I39 @S9S_MB_2U_LIB.S9S_MB_2U(SCH_1):PAGE228

SMB_HOST_CLK_3V3AUX_SCL @S9S_MB_2U_LIB.S9S_MB_2U(SCH_1):SMB_HOST_CLK_3V3AUX_SCL
   U13  A10   SCLK 9SQ440NQQI8-9SQ440NQQI8,SMLF,IA   I180 @S9S_MB_2U_LIB.S9S_MB_2U(SCH_1):PAGE197
 R1525    2      B Q_RES_0402LF-0,5%,1/16W,CHIP,CA    I40 @S9S_MB_2U_LIB.S9S_MB_2U(SCH_1):PAGE228
 R3340    1      A Q_RES_0402LF-33.2,1%,1/16W,CHIA   I268 @S9S_MB_2U_LIB.S9S_MB_2U(SCH_1):PAGE228

SMB_HOST_CLK_3V3AUX_SDA @S9S_MB_2U_LIB.S9S_MB_2U(SCH_1):SMB_HOST_CLK_3V3AUX_SDA
   U13   B8 SMBDATTA 9SQ440NQQI8-9SQ440NQQI8,SMLF,IA   I180 @S9S_MB_2U_LIB.S9S_MB_2U(SCH_1):PAGE197
 R1526    2      B Q_RES_0402LF-33.2,1%,1/16W,CHIA    I41 @S9S_MB_2U_LIB.S9S_MB_2U(SCH_1):PAGE228
 R3341    1      A Q_RES_0402LF-33.2,1%,1/16W,CHIA   I264 @S9S_MB_2U_LIB.S9S_MB_2U(SCH_1):PAGE228

SMB_HOST_CLK_BUF_3V3AUX_SCL @S9S_MB_2U_LIB.S9S_MB_2U(SCH_1):SMB_HOST_CLK_BUF_3V3AUX_SCL
  R107    2      B Q_RES_0402LF-33.2,1%,1/16W,CHIA    I43 @S9S_MB_2U_LIB.S9S_MB_2U(SCH_1):PAGE228
  U315    2   SCLA PCA9617ADP-PCA9617ADP,SMLF,IC,A    I17 @S9S_MB_2U_LIB.S9S_MB_2U(SCH_1):PAGE225

SMB_HOST_CLK_BUF_3V3AUX_SDA @S9S_MB_2U_LIB.S9S_MB_2U(SCH_1):SMB_HOST_CLK_BUF_3V3AUX_SDA
  R108    2      B Q_RES_0402LF-33.2,1%,1/16W,CHIA    I42 @S9S_MB_2U_LIB.S9S_MB_2U(SCH_1):PAGE228
  U315    3   SDAA PCA9617ADP-PCA9617ADP,SMLF,IC,A    I17 @S9S_MB_2U_LIB.S9S_MB_2U(SCH_1):PAGE225

SMB_HOST_CLK_BUF_ISO_3V3AUX_SCL @S9S_MB_2U_LIB.S9S_MB_2U(SCH_1):SMB_HOST_CLK_BUF_ISO_3V3AUX_SCL
 R4480    1      A Q_RES_0402LF-33.2,1%,1/16W,CHIA    I24 @S9S_MB_2U_LIB.S9S_MB_2U(SCH_1):PAGE225
 R4496    1      A Q_RES_0402LF-33.2,1%,1/16W,CHIA    I27 @S9S_MB_2U_LIB.S9S_MB_2U(SCH_1):PAGE225
 R4540    2      B Q_RES_0402LF-33.2,1%,1/16W,CHIA    I33 @S9S_MB_2U_LIB.S9S_MB_2U(SCH_1):PAGE225

SMB_HOST_CLK_BUF_ISO_3V3AUX_SDA @S9S_MB_2U_LIB.S9S_MB_2U(SCH_1):SMB_HOST_CLK_BUF_ISO_3V3AUX_SDA
 R4481    1      A Q_RES_0402LF-33.2,1%,1/16W,CHIA    I25 @S9S_MB_2U_LIB.S9S_MB_2U(SCH_1):PAGE225
 R4497    1      A Q_RES_0402LF-33.2,1%,1/16W,CHIA    I26 @S9S_MB_2U_LIB.S9S_MB_2U(SCH_1):PAGE225
 R4541    2      B Q_RES_0402LF-33.2,1%,1/16W,CHIA    I34 @S9S_MB_2U_LIB.S9S_MB_2U(SCH_1):PAGE225

SMB_HOST_CLK_BUF_ISO_3V3AUX_S_1 @S9S_MB_2U_LIB.S9S_MB_2U(SCH_1):SMB_HOST_CLK_BUF_ISO_3V3AUX_SCL_R
 R4498    2      B Q_RES_0402LF-4.7K,5%,1/16W,CHIA    I11 @S9S_MB_2U_LIB.S9S_MB_2U(SCH_1):PAGE225
  U315    7   SCLB PCA9617ADP-PCA9617ADP,SMLF,IC,A    I17 @S9S_MB_2U_LIB.S9S_MB_2U(SCH_1):PAGE225
 R4540    1      A Q_RES_0402LF-33.2,1%,1/16W,CHIA    I33 @S9S_MB_2U_LIB.S9S_MB_2U(SCH_1):PAGE225

SMB_HOST_CLK_BUF_ISO_3V3AUX_S_2 @S9S_MB_2U_LIB.S9S_MB_2U(SCH_1):SMB_HOST_CLK_BUF_ISO_3V3AUX_SDA_R
 R4499    2      B Q_RES_0402LF-4.7K,5%,1/16W,CHIA    I12 @S9S_MB_2U_LIB.S9S_MB_2U(SCH_1):PAGE225
  U315    6   SDAB PCA9617ADP-PCA9617ADP,SMLF,IC,A    I17 @S9S_MB_2U_LIB.S9S_MB_2U(SCH_1):PAGE225
 R4541    1      A Q_RES_0402LF-33.2,1%,1/16W,CHIA    I34 @S9S_MB_2U_LIB.S9S_MB_2U(SCH_1):PAGE225

SMB_HOST_CLK_GEN2_3V3AUX_SCL @S9S_MB_2U_LIB.S9S_MB_2U(SCH_1):SMB_HOST_CLK_GEN2_3V3AUX_SCL
 R3340    2      B Q_RES_0402LF-33.2,1%,1/16W,CHIA   I268 @S9S_MB_2U_LIB.S9S_MB_2U(SCH_1):PAGE228
  U247    8 SCLK_3.3 9FGL0251DKILFT-9FGL0251DKILFT,A   I167 @S9S_MB_2U_LIB.S9S_MB_2U(SCH_1):PAGE201

SMB_HOST_CLK_GEN2_3V3AUX_SDA @S9S_MB_2U_LIB.S9S_MB_2U(SCH_1):SMB_HOST_CLK_GEN2_3V3AUX_SDA
 R3341    2      B Q_RES_0402LF-33.2,1%,1/16W,CHIA   I264 @S9S_MB_2U_LIB.S9S_MB_2U(SCH_1):PAGE228
  U247    9 SDATA_3.3 9FGL0251DKILFT-9FGL0251DKILFT,A   I167 @S9S_MB_2U_LIB.S9S_MB_2U(SCH_1):PAGE201

SMB_HOST_DB2000_3V3AUX_SCL @S9S_MB_2U_LIB.S9S_MB_2U(SCH_1):SMB_HOST_DB2000_3V3AUX_SCL
   U38   L5 SMBCLK 9QXL2001BNHGI8-9QXL2001BNHGI8,A   I119 @S9S_MB_2U_LIB.S9S_MB_2U(SCH_1):PAGE195
 R4496    2      B Q_RES_0402LF-33.2,1%,1/16W,CHIA    I27 @S9S_MB_2U_LIB.S9S_MB_2U(SCH_1):PAGE225

SMB_HOST_DB2000_3V3AUX_SDA @S9S_MB_2U_LIB.S9S_MB_2U(SCH_1):SMB_HOST_DB2000_3V3AUX_SDA
   U38   L4 SMBDAT 9QXL2001BNHGI8-9QXL2001BNHGI8,A   I119 @S9S_MB_2U_LIB.S9S_MB_2U(SCH_1):PAGE195
 R4497    2      B Q_RES_0402LF-33.2,1%,1/16W,CHIA    I26 @S9S_MB_2U_LIB.S9S_MB_2U(SCH_1):PAGE225

SMB_HOST_ME_SCL @S9S_MB_2U_LIB.S9S_MB_2U(SCH_1):SMB_HOST_ME_SCL
 R3052    2      B Q_RES_0402LF-33.2,1%,1/16W,CHIA    I13 @S9S_MB_2U_LIB.S9S_MB_2U(SCH_1):PAGE215
  J100   11     11 SCONN20_513860200CV01-SCONN20_A    I32 @S9S_MB_2U_LIB.S9S_MB_2U(SCH_1):PAGE215

SMB_HOST_ME_SDA @S9S_MB_2U_LIB.S9S_MB_2U(SCH_1):SMB_HOST_ME_SDA
 R3053    2      B Q_RES_0402LF-33.2,1%,1/16W,CHIA    I12 @S9S_MB_2U_LIB.S9S_MB_2U(SCH_1):PAGE215
  J100   13     13 SCONN20_513860200CV01-SCONN20_A    I32 @S9S_MB_2U_LIB.S9S_MB_2U(SCH_1):PAGE215

SMB_HSC_TYPE_ADC_SCL @S9S_MB_2U_LIB.S9S_MB_2U(SCH_1):SMB_HSC_TYPE_ADC_SCL
 R4689    2      B Q_RES_0402LF-33.2,1%,1/16W,EMPA    I38 @S9S_MB_2U_LIB.S9S_MB_2U(SCH_1):PAGE240
  U331    5    SCL INA230AIRGTR-INA230AIRGTR,SMLFA    I39 @S9S_MB_2U_LIB.S9S_MB_2U(SCH_1):PAGE240

SMB_HSC_TYPE_ADC_SDA @S9S_MB_2U_LIB.S9S_MB_2U(SCH_1):SMB_HSC_TYPE_ADC_SDA
 R4691    2      B Q_RES_0402LF-0,5%,1/16W,EMPTY,A    I16 @S9S_MB_2U_LIB.S9S_MB_2U(SCH_1):PAGE240
 R4690    2      B Q_RES_0402LF-33.2,1%,1/16W,EMPA    I37 @S9S_MB_2U_LIB.S9S_MB_2U(SCH_1):PAGE240
  U331    4    SDA INA230AIRGTR-INA230AIRGTR,SMLFA    I39 @S9S_MB_2U_LIB.S9S_MB_2U(SCH_1):PAGE240

SMB_INA230_1_3V3AUX_SCL_R @S9S_MB_2U_LIB.S9S_MB_2U(SCH_1):SMB_INA230_1_3V3AUX_SCL_R
 R3586    2      B Q_RES_0402LF-33.2,1%,1/16W,CHIA     I4 @S9S_MB_2U_LIB.S9S_MB_2U(SCH_1):PAGE220
 R3600    1      A Q_RES_0402LF-33.2,1%,1/16W,CHIA    I38 @S9S_MB_2U_LIB.S9S_MB_2U(SCH_1):PAGE295

SMB_INA230_1_3V3AUX_SCL_R1 @S9S_MB_2U_LIB.S9S_MB_2U(SCH_1):SMB_INA230_1_3V3AUX_SCL_R1
  U266    5    SCL INA230AIRGTR-INA230AIRGTR,SMLFB    I30 @S9S_MB_2U_LIB.S9S_MB_2U(SCH_1):PAGE295
 R3600    2      B Q_RES_0402LF-33.2,1%,1/16W,CHIA    I38 @S9S_MB_2U_LIB.S9S_MB_2U(SCH_1):PAGE295

SMB_INA230_1_3V3AUX_SDA_R @S9S_MB_2U_LIB.S9S_MB_2U(SCH_1):SMB_INA230_1_3V3AUX_SDA_R
 R3587    2      B Q_RES_0402LF-33.2,1%,1/16W,CHIA     I3 @S9S_MB_2U_LIB.S9S_MB_2U(SCH_1):PAGE220
 R3601    1      A Q_RES_0402LF-33.2,1%,1/16W,CHIA    I39 @S9S_MB_2U_LIB.S9S_MB_2U(SCH_1):PAGE295

SMB_INA230_1_3V3AUX_SDA_R1 @S9S_MB_2U_LIB.S9S_MB_2U(SCH_1):SMB_INA230_1_3V3AUX_SDA_R1
  U266    4    SDA INA230AIRGTR-INA230AIRGTR,SMLFB    I30 @S9S_MB_2U_LIB.S9S_MB_2U(SCH_1):PAGE295
 R3601    2      B Q_RES_0402LF-33.2,1%,1/16W,CHIA    I39 @S9S_MB_2U_LIB.S9S_MB_2U(SCH_1):PAGE295

SMB_INA230_2_3V3AUX_SCL_R @S9S_MB_2U_LIB.S9S_MB_2U(SCH_1):SMB_INA230_2_3V3AUX_SCL_R
 R3588    2      B Q_RES_0402LF-33.2,1%,1/16W,CHIA    I16 @S9S_MB_2U_LIB.S9S_MB_2U(SCH_1):PAGE220
 R3754    1      A Q_RES_0402LF-33.2,1%,1/16W,CHIA   I130 @S9S_MB_2U_LIB.S9S_MB_2U(SCH_1):PAGE295

SMB_INA230_2_3V3AUX_SCL_R1 @S9S_MB_2U_LIB.S9S_MB_2U(SCH_1):SMB_INA230_2_3V3AUX_SCL_R1
  U276    5    SCL INA230AIRGTR-INA230AIRGTR,SMLFB   I129 @S9S_MB_2U_LIB.S9S_MB_2U(SCH_1):PAGE295
 R3754    2      B Q_RES_0402LF-33.2,1%,1/16W,CHIA   I130 @S9S_MB_2U_LIB.S9S_MB_2U(SCH_1):PAGE295

SMB_INA230_2_3V3AUX_SDA_R @S9S_MB_2U_LIB.S9S_MB_2U(SCH_1):SMB_INA230_2_3V3AUX_SDA_R
 R3589    2      B Q_RES_0402LF-33.2,1%,1/16W,CHIA    I11 @S9S_MB_2U_LIB.S9S_MB_2U(SCH_1):PAGE220
 R3756    1      A Q_RES_0402LF-33.2,1%,1/16W,CHIA   I131 @S9S_MB_2U_LIB.S9S_MB_2U(SCH_1):PAGE295

SMB_INA230_2_3V3AUX_SDA_R1 @S9S_MB_2U_LIB.S9S_MB_2U(SCH_1):SMB_INA230_2_3V3AUX_SDA_R1
  U276    4    SDA INA230AIRGTR-INA230AIRGTR,SMLFB   I129 @S9S_MB_2U_LIB.S9S_MB_2U(SCH_1):PAGE295
 R3756    2      B Q_RES_0402LF-33.2,1%,1/16W,CHIA   I131 @S9S_MB_2U_LIB.S9S_MB_2U(SCH_1):PAGE295
 R3751    2      B Q_RES_0402LF-0,5%,1/16W,CHIP,CA   I146 @S9S_MB_2U_LIB.S9S_MB_2U(SCH_1):PAGE295

SMB_INA230_3V3AUX_SCL @S9S_MB_2U_LIB.S9S_MB_2U(SCH_1):SMB_INA230_3V3AUX_SCL
 R3586    1      A Q_RES_0402LF-33.2,1%,1/16W,CHIA     I4 @S9S_MB_2U_LIB.S9S_MB_2U(SCH_1):PAGE220
 R3588    1      A Q_RES_0402LF-33.2,1%,1/16W,CHIA    I16 @S9S_MB_2U_LIB.S9S_MB_2U(SCH_1):PAGE220
 R3590    1      A Q_RES_0402LF-33.2,1%,1/16W,CHIA    I17 @S9S_MB_2U_LIB.S9S_MB_2U(SCH_1):PAGE220
 R3592    1      A Q_RES_0402LF-33.2,1%,1/16W,CHIA    I20 @S9S_MB_2U_LIB.S9S_MB_2U(SCH_1):PAGE220
 R3594    1      A Q_RES_0402LF-33.2,1%,1/16W,CHIA    I21 @S9S_MB_2U_LIB.S9S_MB_2U(SCH_1):PAGE220
 R3395    2      B Q_RES_0402LF-2.2K,5%,1/16W,CHIA    I54 @S9S_MB_2U_LIB.S9S_MB_2U(SCH_1):PAGE219
 R3580    2      B Q_RES_0402LF-0,5%,1/16W,CHIP,CA    I59 @S9S_MB_2U_LIB.S9S_MB_2U(SCH_1):PAGE219

SMB_INA230_3V3AUX_SCL_R @S9S_MB_2U_LIB.S9S_MB_2U(SCH_1):SMB_INA230_3V3AUX_SCL_R
   U36   18    SC6 TCA9548APWR-TCA9548APWR,SMLF,IA    I45 @S9S_MB_2U_LIB.S9S_MB_2U(SCH_1):PAGE219
 R3580    1      A Q_RES_0402LF-0,5%,1/16W,CHIP,CA    I59 @S9S_MB_2U_LIB.S9S_MB_2U(SCH_1):PAGE219

SMB_INA230_3V3AUX_SDA @S9S_MB_2U_LIB.S9S_MB_2U(SCH_1):SMB_INA230_3V3AUX_SDA
 R3587    1      A Q_RES_0402LF-33.2,1%,1/16W,CHIA     I3 @S9S_MB_2U_LIB.S9S_MB_2U(SCH_1):PAGE220
 R3589    1      A Q_RES_0402LF-33.2,1%,1/16W,CHIA    I11 @S9S_MB_2U_LIB.S9S_MB_2U(SCH_1):PAGE220
 R3591    1      A Q_RES_0402LF-33.2,1%,1/16W,CHIA    I18 @S9S_MB_2U_LIB.S9S_MB_2U(SCH_1):PAGE220
 R3593    1      A Q_RES_0402LF-33.2,1%,1/16W,CHIA    I19 @S9S_MB_2U_LIB.S9S_MB_2U(SCH_1):PAGE220
 R3595    1      A Q_RES_0402LF-33.2,1%,1/16W,CHIA    I26 @S9S_MB_2U_LIB.S9S_MB_2U(SCH_1):PAGE220
 R3396    2      B Q_RES_0402LF-2.2K,5%,1/16W,CHIA    I53 @S9S_MB_2U_LIB.S9S_MB_2U(SCH_1):PAGE219
 R3581    2      B Q_RES_0402LF-0,5%,1/16W,CHIP,CA    I60 @S9S_MB_2U_LIB.S9S_MB_2U(SCH_1):PAGE219

SMB_INA230_3V3AUX_SDA_R @S9S_MB_2U_LIB.S9S_MB_2U(SCH_1):SMB_INA230_3V3AUX_SDA_R
   U36   17    SD6 TCA9548APWR-TCA9548APWR,SMLF,IA    I45 @S9S_MB_2U_LIB.S9S_MB_2U(SCH_1):PAGE219
 R3581    1      A Q_RES_0402LF-0,5%,1/16W,CHIP,CA    I60 @S9S_MB_2U_LIB.S9S_MB_2U(SCH_1):PAGE219

SMB_INA230_3_3V3AUX_SCL_R @S9S_MB_2U_LIB.S9S_MB_2U(SCH_1):SMB_INA230_3_3V3AUX_SCL_R
 R3590    2      B Q_RES_0402LF-33.2,1%,1/16W,CHIA    I17 @S9S_MB_2U_LIB.S9S_MB_2U(SCH_1):PAGE220
 R3568    1      A Q_RES_0402LF-33.2,1%,1/16W,CHIA   I101 @S9S_MB_2U_LIB.S9S_MB_2U(SCH_1):PAGE163

SMB_INA230_3_3V3AUX_SCL_R1 @S9S_MB_2U_LIB.S9S_MB_2U(SCH_1):SMB_INA230_3_3V3AUX_SCL_R1
  U263    5    SCL INA230AIRGTR-INA230AIRGTR,SMLFB    I94 @S9S_MB_2U_LIB.S9S_MB_2U(SCH_1):PAGE163
 R3620    2      B Q_RES_0402LF-0,5%,1/16W,CHIP,CA   I100 @S9S_MB_2U_LIB.S9S_MB_2U(SCH_1):PAGE163
 R3568    2      B Q_RES_0402LF-33.2,1%,1/16W,CHIA   I101 @S9S_MB_2U_LIB.S9S_MB_2U(SCH_1):PAGE163

SMB_INA230_3_3V3AUX_SDA_R @S9S_MB_2U_LIB.S9S_MB_2U(SCH_1):SMB_INA230_3_3V3AUX_SDA_R
 R3591    2      B Q_RES_0402LF-33.2,1%,1/16W,CHIA    I18 @S9S_MB_2U_LIB.S9S_MB_2U(SCH_1):PAGE220
 R3569    1      A Q_RES_0402LF-33.2,1%,1/16W,CHIA   I102 @S9S_MB_2U_LIB.S9S_MB_2U(SCH_1):PAGE163

SMB_INA230_3_3V3AUX_SDA_R1 @S9S_MB_2U_LIB.S9S_MB_2U(SCH_1):SMB_INA230_3_3V3AUX_SDA_R1
  U263    4    SDA INA230AIRGTR-INA230AIRGTR,SMLFB    I94 @S9S_MB_2U_LIB.S9S_MB_2U(SCH_1):PAGE163
 R3569    2      B Q_RES_0402LF-33.2,1%,1/16W,CHIA   I102 @S9S_MB_2U_LIB.S9S_MB_2U(SCH_1):PAGE163

SMB_INA230_4_3V3AUX_SCL_R @S9S_MB_2U_LIB.S9S_MB_2U(SCH_1):SMB_INA230_4_3V3AUX_SCL_R
 R3594    2      B Q_RES_0402LF-33.2,1%,1/16W,CHIA    I21 @S9S_MB_2U_LIB.S9S_MB_2U(SCH_1):PAGE220
 R3572    1      A Q_RES_0402LF-33.2,1%,1/16W,CHIA    I38 @S9S_MB_2U_LIB.S9S_MB_2U(SCH_1):PAGE163

SMB_INA230_4_3V3AUX_SCL_R1 @S9S_MB_2U_LIB.S9S_MB_2U(SCH_1):SMB_INA230_4_3V3AUX_SCL_R1
 R3572    2      B Q_RES_0402LF-33.2,1%,1/16W,CHIA    I38 @S9S_MB_2U_LIB.S9S_MB_2U(SCH_1):PAGE163
  U264    5    SCL INA230AIRGTR-INA230AIRGTR,SMLFB    I46 @S9S_MB_2U_LIB.S9S_MB_2U(SCH_1):PAGE163

SMB_INA230_4_3V3AUX_SDA_R @S9S_MB_2U_LIB.S9S_MB_2U(SCH_1):SMB_INA230_4_3V3AUX_SDA_R
 R3595    2      B Q_RES_0402LF-33.2,1%,1/16W,CHIA    I26 @S9S_MB_2U_LIB.S9S_MB_2U(SCH_1):PAGE220
 R3573    1      A Q_RES_0402LF-33.2,1%,1/16W,CHIA    I37 @S9S_MB_2U_LIB.S9S_MB_2U(SCH_1):PAGE163

SMB_INA230_4_3V3AUX_SDA_R1 @S9S_MB_2U_LIB.S9S_MB_2U(SCH_1):SMB_INA230_4_3V3AUX_SDA_R1
 R3573    2      B Q_RES_0402LF-33.2,1%,1/16W,CHIA    I37 @S9S_MB_2U_LIB.S9S_MB_2U(SCH_1):PAGE163
  U264    4    SDA INA230AIRGTR-INA230AIRGTR,SMLFB    I46 @S9S_MB_2U_LIB.S9S_MB_2U(SCH_1):PAGE163

SMB_INA230_5_3V3AUX_SCL_R @S9S_MB_2U_LIB.S9S_MB_2U(SCH_1):SMB_INA230_5_3V3AUX_SCL_R
 R3592    2      B Q_RES_0402LF-33.2,1%,1/16W,CHIA    I20 @S9S_MB_2U_LIB.S9S_MB_2U(SCH_1):PAGE220
 R3576    1      A Q_RES_0402LF-33.2,1%,1/16W,CHIA    I61 @S9S_MB_2U_LIB.S9S_MB_2U(SCH_1):PAGE163

SMB_INA230_5_3V3AUX_SCL_R1 @S9S_MB_2U_LIB.S9S_MB_2U(SCH_1):SMB_INA230_5_3V3AUX_SCL_R1
 R3576    2      B Q_RES_0402LF-33.2,1%,1/16W,CHIA    I61 @S9S_MB_2U_LIB.S9S_MB_2U(SCH_1):PAGE163
  U265    5    SCL INA230AIRGTR-INA230AIRGTR,SMLFB    I69 @S9S_MB_2U_LIB.S9S_MB_2U(SCH_1):PAGE163

SMB_INA230_5_3V3AUX_SDA_R @S9S_MB_2U_LIB.S9S_MB_2U(SCH_1):SMB_INA230_5_3V3AUX_SDA_R
 R3593    2      B Q_RES_0402LF-33.2,1%,1/16W,CHIA    I19 @S9S_MB_2U_LIB.S9S_MB_2U(SCH_1):PAGE220
 R3577    1      A Q_RES_0402LF-33.2,1%,1/16W,CHIA    I60 @S9S_MB_2U_LIB.S9S_MB_2U(SCH_1):PAGE163

SMB_INA230_5_3V3AUX_SDA_R1 @S9S_MB_2U_LIB.S9S_MB_2U(SCH_1):SMB_INA230_5_3V3AUX_SDA_R1
 R3577    2      B Q_RES_0402LF-33.2,1%,1/16W,CHIA    I60 @S9S_MB_2U_LIB.S9S_MB_2U(SCH_1):PAGE163
  U265    4    SDA INA230AIRGTR-INA230AIRGTR,SMLFB    I69 @S9S_MB_2U_LIB.S9S_MB_2U(SCH_1):PAGE163

SMB_IOEXP_3V3AUX_SCL @S9S_MB_2U_LIB.S9S_MB_2U(SCH_1):SMB_IOEXP_3V3AUX_SCL
 R2982    1      A Q_RES_0402LF-0,5%,1/16W,CHIP,CA    I96 @S9S_MB_2U_LIB.S9S_MB_2U(SCH_1):PAGE214
 R3393    2      B Q_RES_0402LF-0,5%,1/16W,CHIP,CA    I38 @S9S_MB_2U_LIB.S9S_MB_2U(SCH_1):PAGE219
 R3582    2      B Q_RES_0402LF-2.2K,5%,1/16W,CHIA    I52 @S9S_MB_2U_LIB.S9S_MB_2U(SCH_1):PAGE219

SMB_IOEXP_3V3AUX_SCL_R @S9S_MB_2U_LIB.S9S_MB_2U(SCH_1):SMB_IOEXP_3V3AUX_SCL_R
 R3393    1      A Q_RES_0402LF-0,5%,1/16W,CHIP,CA    I38 @S9S_MB_2U_LIB.S9S_MB_2U(SCH_1):PAGE219
   U36    7    SC1 TCA9548APWR-TCA9548APWR,SMLF,IA    I45 @S9S_MB_2U_LIB.S9S_MB_2U(SCH_1):PAGE219

SMB_IOEXP_3V3AUX_SCL_R1 @S9S_MB_2U_LIB.S9S_MB_2U(SCH_1):SMB_IOEXP_3V3AUX_SCL_R1
  U181   22    SCL PCA9539RPW-PCA9539RPW,SMLF,IC,A    I66 @S9S_MB_2U_LIB.S9S_MB_2U(SCH_1):PAGE214
 R2982    2      B Q_RES_0402LF-0,5%,1/16W,CHIP,CA    I96 @S9S_MB_2U_LIB.S9S_MB_2U(SCH_1):PAGE214

SMB_IOEXP_3V3AUX_SDA @S9S_MB_2U_LIB.S9S_MB_2U(SCH_1):SMB_IOEXP_3V3AUX_SDA
 R2983    1      A Q_RES_0402LF-0,5%,1/16W,CHIP,CA   I101 @S9S_MB_2U_LIB.S9S_MB_2U(SCH_1):PAGE214
 R3394    2      B Q_RES_0402LF-0,5%,1/16W,CHIP,CA    I40 @S9S_MB_2U_LIB.S9S_MB_2U(SCH_1):PAGE219
 R3583    2      B Q_RES_0402LF-2.2K,5%,1/16W,CHIA    I51 @S9S_MB_2U_LIB.S9S_MB_2U(SCH_1):PAGE219

SMB_IOEXP_3V3AUX_SDA_R @S9S_MB_2U_LIB.S9S_MB_2U(SCH_1):SMB_IOEXP_3V3AUX_SDA_R
 R3394    1      A Q_RES_0402LF-0,5%,1/16W,CHIP,CA    I40 @S9S_MB_2U_LIB.S9S_MB_2U(SCH_1):PAGE219
   U36    6    SD1 TCA9548APWR-TCA9548APWR,SMLF,IA    I45 @S9S_MB_2U_LIB.S9S_MB_2U(SCH_1):PAGE219

SMB_IOEXP_3V3AUX_SDA_R1 @S9S_MB_2U_LIB.S9S_MB_2U(SCH_1):SMB_IOEXP_3V3AUX_SDA_R1
  U181   23    SDA PCA9539RPW-PCA9539RPW,SMLF,IC,A    I66 @S9S_MB_2U_LIB.S9S_MB_2U(SCH_1):PAGE214
 R2983    2      B Q_RES_0402LF-0,5%,1/16W,CHIP,CA   I101 @S9S_MB_2U_LIB.S9S_MB_2U(SCH_1):PAGE214

SMB_LM75_0_3V3AUX_SCL @S9S_MB_2U_LIB.S9S_MB_2U(SCH_1):SMB_LM75_0_3V3AUX_SCL
 R3725    2      B Q_RES_0402LF-2.2K,5%,1/16W,CHIA    I53 @S9S_MB_2U_LIB.S9S_MB_2U(SCH_1):PAGE221
 R4180    1      A Q_RES_0402LF-33.2,1%,1/16W,CHIA    I77 @S9S_MB_2U_LIB.S9S_MB_2U(SCH_1):PAGE161
 R3715    2      B Q_RES_0402LF-0,5%,1/16W,CHIP,CA   I139 @S9S_MB_2U_LIB.S9S_MB_2U(SCH_1):PAGE221
 R4689    1      A Q_RES_0402LF-33.2,1%,1/16W,EMPA    I38 @S9S_MB_2U_LIB.S9S_MB_2U(SCH_1):PAGE240
 R4894    2      B Q_RES_0402LF-0,5%,1/16W,EMPTY,A    I15 @S9S_MB_2U_LIB.S9S_MB_2U(SCH_1):PAGE327

SMB_LM75_0_3V3AUX_SCL_R @S9S_MB_2U_LIB.S9S_MB_2U(SCH_1):SMB_LM75_0_3V3AUX_SCL_R
   U39    7    SC1 TCA9548APWR-TCA9548APWR,SMLF,IA   I103 @S9S_MB_2U_LIB.S9S_MB_2U(SCH_1):PAGE221
 R3715    1      A Q_RES_0402LF-0,5%,1/16W,CHIP,CA   I139 @S9S_MB_2U_LIB.S9S_MB_2U(SCH_1):PAGE221

SMB_LM75_0_3V3AUX_SCL_R1 @S9S_MB_2U_LIB.S9S_MB_2U(SCH_1):SMB_LM75_0_3V3AUX_SCL_R1
 R4180    2      B Q_RES_0402LF-33.2,1%,1/16W,CHIA    I77 @S9S_MB_2U_LIB.S9S_MB_2U(SCH_1):PAGE161
  U270    2    SCL LM75BD-LM75BD,SMLF,IC,AL0075BDA   I164 @S9S_MB_2U_LIB.S9S_MB_2U(SCH_1):PAGE161

SMB_LM75_0_3V3AUX_SDA @S9S_MB_2U_LIB.S9S_MB_2U(SCH_1):SMB_LM75_0_3V3AUX_SDA
 R3726    2      B Q_RES_0402LF-2.2K,5%,1/16W,CHIA    I52 @S9S_MB_2U_LIB.S9S_MB_2U(SCH_1):PAGE221
 R4183    1      A Q_RES_0402LF-33.2,1%,1/16W,CHIA    I78 @S9S_MB_2U_LIB.S9S_MB_2U(SCH_1):PAGE161
 R3716    2      B Q_RES_0402LF-0,5%,1/16W,CHIP,CA   I140 @S9S_MB_2U_LIB.S9S_MB_2U(SCH_1):PAGE221
 R4690    1      A Q_RES_0402LF-33.2,1%,1/16W,EMPA    I37 @S9S_MB_2U_LIB.S9S_MB_2U(SCH_1):PAGE240
 R4895    2      B Q_RES_0402LF-0,5%,1/16W,EMPTY,A    I16 @S9S_MB_2U_LIB.S9S_MB_2U(SCH_1):PAGE327

SMB_LM75_0_3V3AUX_SDA_R @S9S_MB_2U_LIB.S9S_MB_2U(SCH_1):SMB_LM75_0_3V3AUX_SDA_R
   U39    6    SD1 TCA9548APWR-TCA9548APWR,SMLF,IA   I103 @S9S_MB_2U_LIB.S9S_MB_2U(SCH_1):PAGE221
 R3716    1      A Q_RES_0402LF-0,5%,1/16W,CHIP,CA   I140 @S9S_MB_2U_LIB.S9S_MB_2U(SCH_1):PAGE221

SMB_LM75_0_3V3AUX_SDA_R1 @S9S_MB_2U_LIB.S9S_MB_2U(SCH_1):SMB_LM75_0_3V3AUX_SDA_R1
 R4183    2      B Q_RES_0402LF-33.2,1%,1/16W,CHIA    I78 @S9S_MB_2U_LIB.S9S_MB_2U(SCH_1):PAGE161
  U270    1    SDA LM75BD-LM75BD,SMLF,IC,AL0075BDA   I164 @S9S_MB_2U_LIB.S9S_MB_2U(SCH_1):PAGE161

SMB_LM75_1_3V3AUX_SCL @S9S_MB_2U_LIB.S9S_MB_2U(SCH_1):SMB_LM75_1_3V3AUX_SCL
 R3727    2      B Q_RES_0402LF-2.2K,5%,1/16W,CHIA    I51 @S9S_MB_2U_LIB.S9S_MB_2U(SCH_1):PAGE221
 R4179    1      A Q_RES_0402LF-33.2,1%,1/16W,CHIA   I109 @S9S_MB_2U_LIB.S9S_MB_2U(SCH_1):PAGE161
 R3717    2      B Q_RES_0402LF-0,5%,1/16W,CHIP,CA   I141 @S9S_MB_2U_LIB.S9S_MB_2U(SCH_1):PAGE221

SMB_LM75_1_3V3AUX_SCL_R @S9S_MB_2U_LIB.S9S_MB_2U(SCH_1):SMB_LM75_1_3V3AUX_SCL_R
   U39    9    SC2 TCA9548APWR-TCA9548APWR,SMLF,IA   I103 @S9S_MB_2U_LIB.S9S_MB_2U(SCH_1):PAGE221
 R3717    1      A Q_RES_0402LF-0,5%,1/16W,CHIP,CA   I141 @S9S_MB_2U_LIB.S9S_MB_2U(SCH_1):PAGE221

SMB_LM75_1_3V3AUX_SCL_R1 @S9S_MB_2U_LIB.S9S_MB_2U(SCH_1):SMB_LM75_1_3V3AUX_SCL_R1
 R4179    2      B Q_RES_0402LF-33.2,1%,1/16W,CHIA   I109 @S9S_MB_2U_LIB.S9S_MB_2U(SCH_1):PAGE161
  U271    2    SCL LM75BD-LM75BD,SMLF,IC,AL0075BDA   I165 @S9S_MB_2U_LIB.S9S_MB_2U(SCH_1):PAGE161

SMB_LM75_1_3V3AUX_SDA @S9S_MB_2U_LIB.S9S_MB_2U(SCH_1):SMB_LM75_1_3V3AUX_SDA
 R3728    2      B Q_RES_0402LF-2.2K,5%,1/16W,CHIA    I50 @S9S_MB_2U_LIB.S9S_MB_2U(SCH_1):PAGE221
 R4182    1      A Q_RES_0402LF-33.2,1%,1/16W,CHIA   I107 @S9S_MB_2U_LIB.S9S_MB_2U(SCH_1):PAGE161
 R3718    2      B Q_RES_0402LF-0,5%,1/16W,CHIP,CA   I142 @S9S_MB_2U_LIB.S9S_MB_2U(SCH_1):PAGE221

SMB_LM75_1_3V3AUX_SDA_R @S9S_MB_2U_LIB.S9S_MB_2U(SCH_1):SMB_LM75_1_3V3AUX_SDA_R
   U39    8    SD2 TCA9548APWR-TCA9548APWR,SMLF,IA   I103 @S9S_MB_2U_LIB.S9S_MB_2U(SCH_1):PAGE221
 R3718    1      A Q_RES_0402LF-0,5%,1/16W,CHIP,CA   I142 @S9S_MB_2U_LIB.S9S_MB_2U(SCH_1):PAGE221

SMB_LM75_1_3V3AUX_SDA_R1 @S9S_MB_2U_LIB.S9S_MB_2U(SCH_1):SMB_LM75_1_3V3AUX_SDA_R1
 R4182    2      B Q_RES_0402LF-33.2,1%,1/16W,CHIA   I107 @S9S_MB_2U_LIB.S9S_MB_2U(SCH_1):PAGE161
  U271    1    SDA LM75BD-LM75BD,SMLF,IC,AL0075BDA   I165 @S9S_MB_2U_LIB.S9S_MB_2U(SCH_1):PAGE161

SMB_LM75_2_3V3AUX_SCL @S9S_MB_2U_LIB.S9S_MB_2U(SCH_1):SMB_LM75_2_3V3AUX_SCL
 R3729    2      B Q_RES_0402LF-2.2K,5%,1/16W,CHIA    I48 @S9S_MB_2U_LIB.S9S_MB_2U(SCH_1):PAGE221
 R4178    1      A Q_RES_0402LF-33.2,1%,1/16W,CHIA   I114 @S9S_MB_2U_LIB.S9S_MB_2U(SCH_1):PAGE161
 R3719    2      B Q_RES_0402LF-0,5%,1/16W,CHIP,CA   I143 @S9S_MB_2U_LIB.S9S_MB_2U(SCH_1):PAGE221

SMB_LM75_2_3V3AUX_SCL_R @S9S_MB_2U_LIB.S9S_MB_2U(SCH_1):SMB_LM75_2_3V3AUX_SCL_R
   U39   11    SC3 TCA9548APWR-TCA9548APWR,SMLF,IA   I103 @S9S_MB_2U_LIB.S9S_MB_2U(SCH_1):PAGE221
 R3719    1      A Q_RES_0402LF-0,5%,1/16W,CHIP,CA   I143 @S9S_MB_2U_LIB.S9S_MB_2U(SCH_1):PAGE221

SMB_LM75_2_3V3AUX_SCL_R1 @S9S_MB_2U_LIB.S9S_MB_2U(SCH_1):SMB_LM75_2_3V3AUX_SCL_R1
 R4178    2      B Q_RES_0402LF-33.2,1%,1/16W,CHIA   I114 @S9S_MB_2U_LIB.S9S_MB_2U(SCH_1):PAGE161
  U272    2    SCL LM75BD-LM75BD,SMLF,IC,AL0075BDA   I166 @S9S_MB_2U_LIB.S9S_MB_2U(SCH_1):PAGE161

SMB_LM75_2_3V3AUX_SDA @S9S_MB_2U_LIB.S9S_MB_2U(SCH_1):SMB_LM75_2_3V3AUX_SDA
 R3730    2      B Q_RES_0402LF-2.2K,5%,1/16W,CHIA    I49 @S9S_MB_2U_LIB.S9S_MB_2U(SCH_1):PAGE221
 R4181    1      A Q_RES_0402LF-33.2,1%,1/16W,CHIA   I116 @S9S_MB_2U_LIB.S9S_MB_2U(SCH_1):PAGE161
 R3720    2      B Q_RES_0402LF-0,5%,1/16W,CHIP,CA   I144 @S9S_MB_2U_LIB.S9S_MB_2U(SCH_1):PAGE221

SMB_LM75_2_3V3AUX_SDA_R @S9S_MB_2U_LIB.S9S_MB_2U(SCH_1):SMB_LM75_2_3V3AUX_SDA_R
   U39   10    SD3 TCA9548APWR-TCA9548APWR,SMLF,IA   I103 @S9S_MB_2U_LIB.S9S_MB_2U(SCH_1):PAGE221
 R3720    1      A Q_RES_0402LF-0,5%,1/16W,CHIP,CA   I144 @S9S_MB_2U_LIB.S9S_MB_2U(SCH_1):PAGE221

SMB_LM75_2_3V3AUX_SDA_R1 @S9S_MB_2U_LIB.S9S_MB_2U(SCH_1):SMB_LM75_2_3V3AUX_SDA_R1
 R4181    2      B Q_RES_0402LF-33.2,1%,1/16W,CHIA   I116 @S9S_MB_2U_LIB.S9S_MB_2U(SCH_1):PAGE161
  U272    1    SDA LM75BD-LM75BD,SMLF,IC,AL0075BDA   I166 @S9S_MB_2U_LIB.S9S_MB_2U(SCH_1):PAGE161

SMB_LM75_3_3V3AUX_SCL @S9S_MB_2U_LIB.S9S_MB_2U(SCH_1):SMB_LM75_3_3V3AUX_SCL
 R3731    2      B Q_RES_0402LF-2.2K,5%,1/16W,CHIA    I98 @S9S_MB_2U_LIB.S9S_MB_2U(SCH_1):PAGE221
 R3553    1      A Q_RES_0402LF-33.2,1%,1/16W,CHIA   I134 @S9S_MB_2U_LIB.S9S_MB_2U(SCH_1):PAGE161
 R3721    2      B Q_RES_0402LF-0,5%,1/16W,CHIP,CA   I120 @S9S_MB_2U_LIB.S9S_MB_2U(SCH_1):PAGE221

SMB_LM75_3_3V3AUX_SCL_R @S9S_MB_2U_LIB.S9S_MB_2U(SCH_1):SMB_LM75_3_3V3AUX_SCL_R
   U39   14    SC4 TCA9548APWR-TCA9548APWR,SMLF,IA   I103 @S9S_MB_2U_LIB.S9S_MB_2U(SCH_1):PAGE221
 R3721    1      A Q_RES_0402LF-0,5%,1/16W,CHIP,CA   I120 @S9S_MB_2U_LIB.S9S_MB_2U(SCH_1):PAGE221

SMB_LM75_3_3V3AUX_SCL_R1 @S9S_MB_2U_LIB.S9S_MB_2U(SCH_1):SMB_LM75_3_3V3AUX_SCL_R1
 R3553    2      B Q_RES_0402LF-33.2,1%,1/16W,CHIA   I134 @S9S_MB_2U_LIB.S9S_MB_2U(SCH_1):PAGE161
  U273    2    SCL LM75BD-LM75BD,SMLF,IC,AL0075BDA   I167 @S9S_MB_2U_LIB.S9S_MB_2U(SCH_1):PAGE161

SMB_LM75_3_3V3AUX_SDA @S9S_MB_2U_LIB.S9S_MB_2U(SCH_1):SMB_LM75_3_3V3AUX_SDA
 R3732    2      B Q_RES_0402LF-2.2K,5%,1/16W,CHIA    I34 @S9S_MB_2U_LIB.S9S_MB_2U(SCH_1):PAGE221
 R3554    1      A Q_RES_0402LF-33.2,1%,1/16W,CHIA   I136 @S9S_MB_2U_LIB.S9S_MB_2U(SCH_1):PAGE161
 R3722    2      B Q_RES_0402LF-0,5%,1/16W,CHIP,CA   I119 @S9S_MB_2U_LIB.S9S_MB_2U(SCH_1):PAGE221

SMB_LM75_3_3V3AUX_SDA_R @S9S_MB_2U_LIB.S9S_MB_2U(SCH_1):SMB_LM75_3_3V3AUX_SDA_R
   U39   13    SD4 TCA9548APWR-TCA9548APWR,SMLF,IA   I103 @S9S_MB_2U_LIB.S9S_MB_2U(SCH_1):PAGE221
 R3722    1      A Q_RES_0402LF-0,5%,1/16W,CHIP,CA   I119 @S9S_MB_2U_LIB.S9S_MB_2U(SCH_1):PAGE221

SMB_LM75_3_3V3AUX_SDA_R1 @S9S_MB_2U_LIB.S9S_MB_2U(SCH_1):SMB_LM75_3_3V3AUX_SDA_R1
 R3554    2      B Q_RES_0402LF-33.2,1%,1/16W,CHIA   I136 @S9S_MB_2U_LIB.S9S_MB_2U(SCH_1):PAGE161
  U273    1    SDA LM75BD-LM75BD,SMLF,IC,AL0075BDA   I167 @S9S_MB_2U_LIB.S9S_MB_2U(SCH_1):PAGE161

SMB_M2_P0_1V8AUX_SCL @S9S_MB_2U_LIB.S9S_MB_2U(SCH_1):SMB_M2_P0_1V8AUX_SCL
   J59   40   NC12 SCONN75K_APCI0155P004A-SCONN75A   I178 @S9S_MB_2U_LIB.S9S_MB_2U(SCH_1):PAGE182
 R2411    2      B Q_RES_0402LF-33.2,1%,1/16W,CHIA    I66 @S9S_MB_2U_LIB.S9S_MB_2U(SCH_1):PAGE183

SMB_M2_P0_1V8AUX_SCL_R @S9S_MB_2U_LIB.S9S_MB_2U(SCH_1):SMB_M2_P0_1V8AUX_SCL_R
   U98    3   SCL1 PCA9306DP1-PCA9306DP1,SMLF,IC,A    I27 @S9S_MB_2U_LIB.S9S_MB_2U(SCH_1):PAGE183
 R1703    2      B Q_RES_0402LF-4.7K,5%,1/16W,CHIA    I45 @S9S_MB_2U_LIB.S9S_MB_2U(SCH_1):PAGE183
 R2411    1      A Q_RES_0402LF-33.2,1%,1/16W,CHIA    I66 @S9S_MB_2U_LIB.S9S_MB_2U(SCH_1):PAGE183

SMB_M2_P0_1V8AUX_SDA @S9S_MB_2U_LIB.S9S_MB_2U(SCH_1):SMB_M2_P0_1V8AUX_SDA
   J59   42   NC13 SCONN75K_APCI0155P004A-SCONN75A   I178 @S9S_MB_2U_LIB.S9S_MB_2U(SCH_1):PAGE182
 R2410    2      B Q_RES_0402LF-33.2,1%,1/16W,CHIA    I65 @S9S_MB_2U_LIB.S9S_MB_2U(SCH_1):PAGE183

SMB_M2_P0_1V8AUX_SDA_R @S9S_MB_2U_LIB.S9S_MB_2U(SCH_1):SMB_M2_P0_1V8AUX_SDA_R
   U98    4   SDA1 PCA9306DP1-PCA9306DP1,SMLF,IC,A    I27 @S9S_MB_2U_LIB.S9S_MB_2U(SCH_1):PAGE183
 R1702    2      B Q_RES_0402LF-4.7K,5%,1/16W,CHIA    I43 @S9S_MB_2U_LIB.S9S_MB_2U(SCH_1):PAGE183
 R2410    1      A Q_RES_0402LF-33.2,1%,1/16W,CHIA    I65 @S9S_MB_2U_LIB.S9S_MB_2U(SCH_1):PAGE183

SMB_OCP_SFF_3V3AUX_BUF_R_SCL @S9S_MB_2U_LIB.S9S_MB_2U(SCH_1):SMB_OCP_SFF_3V3AUX_BUF_R_SCL
  R424    1      A Q_RES_0402LF-33.2,1%,1/16W,CHIA   I151 @S9S_MB_2U_LIB.S9S_MB_2U(SCH_1):PAGE150
   J37   A7  SMCLK SCONN168_ME1016810202011-SCONNA   I199 @S9S_MB_2U_LIB.S9S_MB_2U(SCH_1):PAGE150

SMB_OCP_SFF_3V3AUX_BUF_R_SDA @S9S_MB_2U_LIB.S9S_MB_2U(SCH_1):SMB_OCP_SFF_3V3AUX_BUF_R_SDA
   J37   A8  SMDAT SCONN168_ME1016810202011-SCONNA   I199 @S9S_MB_2U_LIB.S9S_MB_2U(SCH_1):PAGE150
  R425    1      A Q_RES_0402LF-200,1%,1/16W,CHIPA   I220 @S9S_MB_2U_LIB.S9S_MB_2U(SCH_1):PAGE150

SMB_OCP_SFF_3V3AUX_BUF_SCL @S9S_MB_2U_LIB.S9S_MB_2U(SCH_1):SMB_OCP_SFF_3V3AUX_BUF_SCL
  R424    2      B Q_RES_0402LF-33.2,1%,1/16W,CHIA   I151 @S9S_MB_2U_LIB.S9S_MB_2U(SCH_1):PAGE150
  U236    7   SCLB PCA9617ADP-PCA9617ADP,SMLF,IC,A    I28 @S9S_MB_2U_LIB.S9S_MB_2U(SCH_1):PAGE216
 R3500    2      B Q_RES_0402LF-4.7K,5%,1/16W,CHIA    I31 @S9S_MB_2U_LIB.S9S_MB_2U(SCH_1):PAGE216

SMB_OCP_SFF_3V3AUX_BUF_SDA @S9S_MB_2U_LIB.S9S_MB_2U(SCH_1):SMB_OCP_SFF_3V3AUX_BUF_SDA
  U236    6   SDAB PCA9617ADP-PCA9617ADP,SMLF,IC,A    I28 @S9S_MB_2U_LIB.S9S_MB_2U(SCH_1):PAGE216
 R3501    2      B Q_RES_0402LF-4.7K,5%,1/16W,CHIA    I30 @S9S_MB_2U_LIB.S9S_MB_2U(SCH_1):PAGE216
  R425    2      B Q_RES_0402LF-200,1%,1/16W,CHIPA   I220 @S9S_MB_2U_LIB.S9S_MB_2U(SCH_1):PAGE150

SMB_OCP_SFF_3V3AUX_SCL @S9S_MB_2U_LIB.S9S_MB_2U(SCH_1):SMB_OCP_SFF_3V3AUX_SCL
 R3240    1      A Q_RES_0402LF-2.2K,5%,1/16W,EMPA   I259 @S9S_MB_2U_LIB.S9S_MB_2U(SCH_1):PAGE228
  U236    2   SCLA PCA9617ADP-PCA9617ADP,SMLF,IC,A    I28 @S9S_MB_2U_LIB.S9S_MB_2U(SCH_1):PAGE216
 R3238    1      A Q_RES_0402LF-33.2,1%,1/16W,CHIA   I101 @S9S_MB_2U_LIB.S9S_MB_2U(SCH_1):PAGE227

SMB_OCP_SFF_3V3AUX_SCL_R0 @S9S_MB_2U_LIB.S9S_MB_2U(SCH_1):SMB_OCP_SFF_3V3AUX_SCL_R0
 R3238    2      B Q_RES_0402LF-33.2,1%,1/16W,CHIA   I101 @S9S_MB_2U_LIB.S9S_MB_2U(SCH_1):PAGE227
   J41   A1 GND_A1 SCONN168_ME1016810202011-SCONNA   I173 @S9S_MB_2U_LIB.S9S_MB_2U(SCH_1):PAGE227

SMB_OCP_SFF_3V3AUX_SDA @S9S_MB_2U_LIB.S9S_MB_2U(SCH_1):SMB_OCP_SFF_3V3AUX_SDA
 R3241    1      A Q_RES_0402LF-2.2K,5%,1/16W,EMPA   I258 @S9S_MB_2U_LIB.S9S_MB_2U(SCH_1):PAGE228
  U236    3   SDAA PCA9617ADP-PCA9617ADP,SMLF,IC,A    I28 @S9S_MB_2U_LIB.S9S_MB_2U(SCH_1):PAGE216
 R3239    1      A Q_RES_0402LF-33.2,1%,1/16W,CHIA   I102 @S9S_MB_2U_LIB.S9S_MB_2U(SCH_1):PAGE227

SMB_OCP_SFF_3V3AUX_SDA_R0 @S9S_MB_2U_LIB.S9S_MB_2U(SCH_1):SMB_OCP_SFF_3V3AUX_SDA_R0
 R3239    2      B Q_RES_0402LF-33.2,1%,1/16W,CHIA   I102 @S9S_MB_2U_LIB.S9S_MB_2U(SCH_1):PAGE227
   J41   A2 GND_A2 SCONN168_ME1016810202011-SCONNA   I173 @S9S_MB_2U_LIB.S9S_MB_2U(SCH_1):PAGE227

SMB_OCP_V3_2_3V3AUX_BUF_R_SCL @S9S_MB_2U_LIB.S9S_MB_2U(SCH_1):SMB_OCP_V3_2_3V3AUX_BUF_R_SCL
   J35   A7  SMCLK SCONN168_ME1016810202011-SCONNA   I303 @S9S_MB_2U_LIB.S9S_MB_2U(SCH_1):PAGE146
 R3228    1      A Q_RES_0402LF-200,1%,1/16W,CHIPA   I339 @S9S_MB_2U_LIB.S9S_MB_2U(SCH_1):PAGE146

SMB_OCP_V3_2_3V3AUX_BUF_R_SDA @S9S_MB_2U_LIB.S9S_MB_2U(SCH_1):SMB_OCP_V3_2_3V3AUX_BUF_R_SDA
   J35   A8  SMDAT SCONN168_ME1016810202011-SCONNA   I303 @S9S_MB_2U_LIB.S9S_MB_2U(SCH_1):PAGE146
 R3229    1      A Q_RES_0402LF-200,1%,1/16W,CHIPA   I338 @S9S_MB_2U_LIB.S9S_MB_2U(SCH_1):PAGE146

SMB_OCP_V3_2_3V3AUX_BUF_SCL @S9S_MB_2U_LIB.S9S_MB_2U(SCH_1):SMB_OCP_V3_2_3V3AUX_BUF_SCL
  U235    7   SCLB PCA9617ADP-PCA9617ADP,SMLF,IC,A     I5 @S9S_MB_2U_LIB.S9S_MB_2U(SCH_1):PAGE216
 R3519    2      B Q_RES_0402LF-4.7K,5%,1/16W,CHIA    I34 @S9S_MB_2U_LIB.S9S_MB_2U(SCH_1):PAGE216
 R3228    2      B Q_RES_0402LF-200,1%,1/16W,CHIPA   I339 @S9S_MB_2U_LIB.S9S_MB_2U(SCH_1):PAGE146

SMB_OCP_V3_2_3V3AUX_BUF_SDA @S9S_MB_2U_LIB.S9S_MB_2U(SCH_1):SMB_OCP_V3_2_3V3AUX_BUF_SDA
  U235    6   SDAB PCA9617ADP-PCA9617ADP,SMLF,IC,A     I5 @S9S_MB_2U_LIB.S9S_MB_2U(SCH_1):PAGE216
 R3520    2      B Q_RES_0402LF-4.7K,5%,1/16W,CHIA    I33 @S9S_MB_2U_LIB.S9S_MB_2U(SCH_1):PAGE216
 R3229    2      B Q_RES_0402LF-200,1%,1/16W,CHIPA   I338 @S9S_MB_2U_LIB.S9S_MB_2U(SCH_1):PAGE146

SMB_OCP_V3_2_3V3AUX_SCL @S9S_MB_2U_LIB.S9S_MB_2U(SCH_1):SMB_OCP_V3_2_3V3AUX_SCL
 R3242    1      A Q_RES_0402LF-2.2K,5%,1/16W,EMPA   I260 @S9S_MB_2U_LIB.S9S_MB_2U(SCH_1):PAGE228
  U235    2   SCLA PCA9617ADP-PCA9617ADP,SMLF,IC,A     I5 @S9S_MB_2U_LIB.S9S_MB_2U(SCH_1):PAGE216
 R2425    1      A Q_RES_0402LF-33.2,1%,1/16W,CHIA    I93 @S9S_MB_2U_LIB.S9S_MB_2U(SCH_1):PAGE227

SMB_OCP_V3_2_3V3AUX_SCL_R0 @S9S_MB_2U_LIB.S9S_MB_2U(SCH_1):SMB_OCP_V3_2_3V3AUX_SCL_R0
 R2425    2      B Q_RES_0402LF-33.2,1%,1/16W,CHIA    I93 @S9S_MB_2U_LIB.S9S_MB_2U(SCH_1):PAGE227
   J41  A11 PERST1# SCONN168_ME1016810202011-SCONNA   I173 @S9S_MB_2U_LIB.S9S_MB_2U(SCH_1):PAGE227

SMB_OCP_V3_2_3V3AUX_SDA @S9S_MB_2U_LIB.S9S_MB_2U(SCH_1):SMB_OCP_V3_2_3V3AUX_SDA
 R3243    1      A Q_RES_0402LF-2.2K,5%,1/16W,EMPA   I261 @S9S_MB_2U_LIB.S9S_MB_2U(SCH_1):PAGE228
  U235    3   SDAA PCA9617ADP-PCA9617ADP,SMLF,IC,A     I5 @S9S_MB_2U_LIB.S9S_MB_2U(SCH_1):PAGE216
 R3858    1      A Q_RES_0402LF-33.2,1%,1/16W,CHIA    I94 @S9S_MB_2U_LIB.S9S_MB_2U(SCH_1):PAGE227

SMB_OCP_V3_2_3V3AUX_SDA_R0 @S9S_MB_2U_LIB.S9S_MB_2U(SCH_1):SMB_OCP_V3_2_3V3AUX_SDA_R0
 R3858    2      B Q_RES_0402LF-33.2,1%,1/16W,CHIA    I94 @S9S_MB_2U_LIB.S9S_MB_2U(SCH_1):PAGE227
   J41  A12 PRSNTB2# SCONN168_ME1016810202011-SCONNA   I173 @S9S_MB_2U_LIB.S9S_MB_2U(SCH_1):PAGE227

SMB_PCIE0_3V3AUX_SCL @S9S_MB_2U_LIB.S9S_MB_2U(SCH_1):SMB_PCIE0_3V3AUX_SCL
 R2204    2      B Q_RES_0402LF-2.2K,5%,1/16W,EMPA    I57 @S9S_MB_2U_LIB.S9S_MB_2U(SCH_1):PAGE219
  R588    1      A Q_RES_0402LF-33.2,1%,1/16W,CHIA    I65 @S9S_MB_2U_LIB.S9S_MB_2U(SCH_1):PAGE219
   J41  A23  PERN2 SCONN168_ME1016810202011-SCONNA   I173 @S9S_MB_2U_LIB.S9S_MB_2U(SCH_1):PAGE227

SMB_PCIE0_3V3AUX_SCL_R @S9S_MB_2U_LIB.S9S_MB_2U(SCH_1):SMB_PCIE0_3V3AUX_SCL_R
   U36   22    SCL TCA9548APWR-TCA9548APWR,SMLF,IA    I45 @S9S_MB_2U_LIB.S9S_MB_2U(SCH_1):PAGE219
  R588    2      B Q_RES_0402LF-33.2,1%,1/16W,CHIA    I65 @S9S_MB_2U_LIB.S9S_MB_2U(SCH_1):PAGE219

SMB_PCIE0_3V3AUX_SCL_R3 @S9S_MB_2U_LIB.S9S_MB_2U(SCH_1):SMB_PCIE0_3V3AUX_SCL_R3
 R2967    1      A Q_RES_0402LF-0,5%,1/16W,CHIP,CA    I36 @S9S_MB_2U_LIB.S9S_MB_2U(SCH_1):PAGE219
   U36    9    SC2 TCA9548APWR-TCA9548APWR,SMLF,IA    I45 @S9S_MB_2U_LIB.S9S_MB_2U(SCH_1):PAGE219

SMB_PCIE0_3V3AUX_SCL_R5 @S9S_MB_2U_LIB.S9S_MB_2U(SCH_1):SMB_PCIE0_3V3AUX_SCL_R5
 R3526    1      A Q_RES_0402LF-0,5%,1/16W,CHIP,CA    I35 @S9S_MB_2U_LIB.S9S_MB_2U(SCH_1):PAGE219
   U36   11    SC3 TCA9548APWR-TCA9548APWR,SMLF,IA    I45 @S9S_MB_2U_LIB.S9S_MB_2U(SCH_1):PAGE219

SMB_PCIE0_3V3AUX_SDA @S9S_MB_2U_LIB.S9S_MB_2U(SCH_1):SMB_PCIE0_3V3AUX_SDA
 R2205    2      B Q_RES_0402LF-2.2K,5%,1/16W,EMPA    I56 @S9S_MB_2U_LIB.S9S_MB_2U(SCH_1):PAGE219
  R589    1      A Q_RES_0402LF-33.2,1%,1/16W,CHIA    I66 @S9S_MB_2U_LIB.S9S_MB_2U(SCH_1):PAGE219
   J41  A24  PERP2 SCONN168_ME1016810202011-SCONNA   I173 @S9S_MB_2U_LIB.S9S_MB_2U(SCH_1):PAGE227

SMB_PCIE0_3V3AUX_SDA_R @S9S_MB_2U_LIB.S9S_MB_2U(SCH_1):SMB_PCIE0_3V3AUX_SDA_R
   U36   23    SDA TCA9548APWR-TCA9548APWR,SMLF,IA    I45 @S9S_MB_2U_LIB.S9S_MB_2U(SCH_1):PAGE219
  R589    2      B Q_RES_0402LF-33.2,1%,1/16W,CHIA    I66 @S9S_MB_2U_LIB.S9S_MB_2U(SCH_1):PAGE219

SMB_PCIE0_3V3AUX_SDA_R3 @S9S_MB_2U_LIB.S9S_MB_2U(SCH_1):SMB_PCIE0_3V3AUX_SDA_R3
 R2968    1      A Q_RES_0402LF-0,5%,1/16W,CHIP,CA    I39 @S9S_MB_2U_LIB.S9S_MB_2U(SCH_1):PAGE219
   U36    8    SD2 TCA9548APWR-TCA9548APWR,SMLF,IA    I45 @S9S_MB_2U_LIB.S9S_MB_2U(SCH_1):PAGE219

SMB_PCIE0_3V3AUX_SDA_R5 @S9S_MB_2U_LIB.S9S_MB_2U(SCH_1):SMB_PCIE0_3V3AUX_SDA_R5
 R3527    1      A Q_RES_0402LF-0,5%,1/16W,CHIP,CA    I37 @S9S_MB_2U_LIB.S9S_MB_2U(SCH_1):PAGE219
   U36   10    SD3 TCA9548APWR-TCA9548APWR,SMLF,IA    I45 @S9S_MB_2U_LIB.S9S_MB_2U(SCH_1):PAGE219

SMB_PCIE2_3V3AUX_SCL_R0 @S9S_MB_2U_LIB.S9S_MB_2U(SCH_1):SMB_PCIE2_3V3AUX_SCL_R0
 R2413    2      B Q_RES_0402LF-0,5%,1/16W,CHIP,CA    I86 @S9S_MB_2U_LIB.S9S_MB_2U(SCH_1):PAGE227
   J41  A31  PERP4 SCONN168_ME1016810202011-SCONNA   I173 @S9S_MB_2U_LIB.S9S_MB_2U(SCH_1):PAGE227

SMB_PCIE2_3V3AUX_SDA_R0 @S9S_MB_2U_LIB.S9S_MB_2U(SCH_1):SMB_PCIE2_3V3AUX_SDA_R0
 R2414    2      B Q_RES_0402LF-0,5%,1/16W,CHIP,CA    I85 @S9S_MB_2U_LIB.S9S_MB_2U(SCH_1):PAGE227
   J41  A32 GND_A32 SCONN168_ME1016810202011-SCONNA   I173 @S9S_MB_2U_LIB.S9S_MB_2U(SCH_1):PAGE227

SMB_PCIE3_3V3AUX_SCL_R @S9S_MB_2U_LIB.S9S_MB_2U(SCH_1):SMB_PCIE3_3V3AUX_SCL_R
 R2415    2      B Q_RES_0402LF-0,5%,1/16W,CHIP,CA    I25 @S9S_MB_2U_LIB.S9S_MB_2U(SCH_1):PAGE227
   J41  A38 GND_A38 SCONN168_ME1016810202011-SCONNA   I173 @S9S_MB_2U_LIB.S9S_MB_2U(SCH_1):PAGE227

SMB_PCIE3_3V3AUX_SDA_R @S9S_MB_2U_LIB.S9S_MB_2U(SCH_1):SMB_PCIE3_3V3AUX_SDA_R
 R2416    2      B Q_RES_0402LF-0,5%,1/16W,CHIP,CA    I24 @S9S_MB_2U_LIB.S9S_MB_2U(SCH_1):PAGE227
   J41  A39  PERN7 SCONN168_ME1016810202011-SCONNA   I173 @S9S_MB_2U_LIB.S9S_MB_2U(SCH_1):PAGE227

SMB_PCIE_E1S_ISO_EN @S9S_MB_2U_LIB.S9S_MB_2U(SCH_1):SMB_PCIE_E1S_ISO_EN
 R3531    1      A Q_RES_0402LF-200K,1%,1/16W,EMPA    I96 @S9S_MB_2U_LIB.S9S_MB_2U(SCH_1):PAGE183
 R2125    2      B Q_RES_0402LF-4.7K,5%,1/16W,CHIA   I296 @S9S_MB_2U_LIB.S9S_MB_2U(SCH_1):PAGE297
 R2114    2      B Q_RES_0402LF-0,5%,1/16W,CHIP,CA   I302 @S9S_MB_2U_LIB.S9S_MB_2U(SCH_1):PAGE297

SMB_PCIE_E1S_ISO_EN_R @S9S_MB_2U_LIB.S9S_MB_2U(SCH_1):SMB_PCIE_E1S_ISO_EN_R
  U279    5     EN PCA9617ADP-PCA9617ADP,SMLF,IC,A    I93 @S9S_MB_2U_LIB.S9S_MB_2U(SCH_1):PAGE183
 R3531    2      B Q_RES_0402LF-200K,1%,1/16W,EMPA    I96 @S9S_MB_2U_LIB.S9S_MB_2U(SCH_1):PAGE183
 R3529    2      B Q_RES_0402LF-10K,1%,1/16W,CHIPA    I99 @S9S_MB_2U_LIB.S9S_MB_2U(SCH_1):PAGE183

SMB_PCIE_E1S_ISO_EN_R2 @S9S_MB_2U_LIB.S9S_MB_2U(SCH_1):SMB_PCIE_E1S_ISO_EN_R2
 R2114    1      A Q_RES_0402LF-0,5%,1/16W,CHIP,CA   I302 @S9S_MB_2U_LIB.S9S_MB_2U(SCH_1):PAGE297
  U134    4     2Y 74LVC2G07DW7-74LVC2G07DW-7,SMLA   I305 @S9S_MB_2U_LIB.S9S_MB_2U(SCH_1):PAGE297

SMB_PCIE_M2_0_EN @S9S_MB_2U_LIB.S9S_MB_2U(SCH_1):SMB_PCIE_M2_0_EN
   U98    8     EN PCA9306DP1-PCA9306DP1,SMLF,IC,A    I27 @S9S_MB_2U_LIB.S9S_MB_2U(SCH_1):PAGE183
   U98    7  VREF2 PCA9306DP1-PCA9306DP1,SMLF,IC,A    I27 @S9S_MB_2U_LIB.S9S_MB_2U(SCH_1):PAGE183
 R2476    1      A Q_RES_0402LF-200K,1%,1/16W,EMPA    I70 @S9S_MB_2U_LIB.S9S_MB_2U(SCH_1):PAGE183
 R1700    2      B Q_RES_0402LF-200K,1%,1/16W,CHIA    I72 @S9S_MB_2U_LIB.S9S_MB_2U(SCH_1):PAGE183

SMB_PEHPCPU0_GTL_R_SCL @S9S_MB_2U_LIB.S9S_MB_2U(SCH_1):SMB_PEHPCPU0_GTL_R_SCL
  R910    2      B Q_RES_0402LF-240,1%,1/16W,CHIPA    I24 @S9S_MB_2U_LIB.S9S_MB_2U(SCH_1):PAGE223
   U28    2   SCLA PCA9617ADP-PCA9617ADP,SMLF,IC,A    I39 @S9S_MB_2U_LIB.S9S_MB_2U(SCH_1):PAGE223
  R960    2      B Q_RES_0402LF-33.2,1%,1/16W,CHIA   I101 @S9S_MB_2U_LIB.S9S_MB_2U(SCH_1):PAGE223

SMB_PEHPCPU0_GTL_R_SDA @S9S_MB_2U_LIB.S9S_MB_2U(SCH_1):SMB_PEHPCPU0_GTL_R_SDA
  R911    2      B Q_RES_0402LF-240,1%,1/16W,CHIPA    I22 @S9S_MB_2U_LIB.S9S_MB_2U(SCH_1):PAGE223
   U28    3   SDAA PCA9617ADP-PCA9617ADP,SMLF,IC,A    I39 @S9S_MB_2U_LIB.S9S_MB_2U(SCH_1):PAGE223
  R909    2      B Q_RES_0402LF-33.2,1%,1/16W,CHIA   I102 @S9S_MB_2U_LIB.S9S_MB_2U(SCH_1):PAGE223

SMB_PEHPCPU0_GTL_SCL @S9S_MB_2U_LIB.S9S_MB_2U(SCH_1):SMB_PEHPCPU0_GTL_SCL
    U2 CA25 CXPSMBUSSCL SOCKET4677_AZIF0045P001C01CS-SA     I1 @S9S_MB_2U_LIB.S9S_MB_2U(SCH_1):PAGE14
  R960    1      A Q_RES_0402LF-33.2,1%,1/16W,CHIA   I101 @S9S_MB_2U_LIB.S9S_MB_2U(SCH_1):PAGE223

SMB_PEHPCPU0_GTL_SDA @S9S_MB_2U_LIB.S9S_MB_2U(SCH_1):SMB_PEHPCPU0_GTL_SDA
    U2 BY26 CXPSMBUSSDA SOCKET4677_AZIF0045P001C01CS-SA     I1 @S9S_MB_2U_LIB.S9S_MB_2U(SCH_1):PAGE14
  R909    1      A Q_RES_0402LF-33.2,1%,1/16W,CHIA   I102 @S9S_MB_2U_LIB.S9S_MB_2U(SCH_1):PAGE223

SMB_PEHPCPU0_LVC3_R_SCL @S9S_MB_2U_LIB.S9S_MB_2U(SCH_1):SMB_PEHPCPU0_LVC3_R_SCL
 R1130    2      B Q_RES_0402LF-33.2,1%,1/16W,CHIA   I130 @S9S_MB_2U_LIB.S9S_MB_2U(SCH_1):PAGE154
  U209   22    SCL PCA9555APW-PCA9555APW,SMLF,IC,A   I206 @S9S_MB_2U_LIB.S9S_MB_2U(SCH_1):PAGE154

SMB_PEHPCPU0_LVC3_R_SDA @S9S_MB_2U_LIB.S9S_MB_2U(SCH_1):SMB_PEHPCPU0_LVC3_R_SDA
 R1131    2      B Q_RES_0402LF-33.2,1%,1/16W,CHIA   I131 @S9S_MB_2U_LIB.S9S_MB_2U(SCH_1):PAGE154
  U209   23    SDA PCA9555APW-PCA9555APW,SMLF,IC,A   I206 @S9S_MB_2U_LIB.S9S_MB_2U(SCH_1):PAGE154

SMB_PEHPCPU0_LVC3_SCL @S9S_MB_2U_LIB.S9S_MB_2U(SCH_1):SMB_PEHPCPU0_LVC3_SCL
 R1130    1      A Q_RES_0402LF-33.2,1%,1/16W,CHIA   I130 @S9S_MB_2U_LIB.S9S_MB_2U(SCH_1):PAGE154
 R2477    2      B Q_RES_0402LF-33.2,1%,1/16W,CHIA    I88 @S9S_MB_2U_LIB.S9S_MB_2U(SCH_1):PAGE223
  R965    2      B Q_RES_0402LF-1K,1%,1/16W,CHIP,A    I93 @S9S_MB_2U_LIB.S9S_MB_2U(SCH_1):PAGE223

SMB_PEHPCPU0_LVC3_SCL_R0 @S9S_MB_2U_LIB.S9S_MB_2U(SCH_1):SMB_PEHPCPU0_LVC3_SCL_R0
   U28    7   SCLB PCA9617ADP-PCA9617ADP,SMLF,IC,A    I39 @S9S_MB_2U_LIB.S9S_MB_2U(SCH_1):PAGE223
 R2477    1      A Q_RES_0402LF-33.2,1%,1/16W,CHIA    I88 @S9S_MB_2U_LIB.S9S_MB_2U(SCH_1):PAGE223

SMB_PEHPCPU0_LVC3_SDA @S9S_MB_2U_LIB.S9S_MB_2U(SCH_1):SMB_PEHPCPU0_LVC3_SDA
 R1131    1      A Q_RES_0402LF-33.2,1%,1/16W,CHIA   I131 @S9S_MB_2U_LIB.S9S_MB_2U(SCH_1):PAGE154
 R2478    2      B Q_RES_0402LF-33.2,1%,1/16W,CHIA    I89 @S9S_MB_2U_LIB.S9S_MB_2U(SCH_1):PAGE223
  R967    2      B Q_RES_0402LF-1K,1%,1/16W,CHIP,A    I94 @S9S_MB_2U_LIB.S9S_MB_2U(SCH_1):PAGE223

SMB_PEHPCPU0_LVC3_SDA_R0 @S9S_MB_2U_LIB.S9S_MB_2U(SCH_1):SMB_PEHPCPU0_LVC3_SDA_R0
   U28    6   SDAB PCA9617ADP-PCA9617ADP,SMLF,IC,A    I39 @S9S_MB_2U_LIB.S9S_MB_2U(SCH_1):PAGE223
 R2478    1      A Q_RES_0402LF-33.2,1%,1/16W,CHIA    I89 @S9S_MB_2U_LIB.S9S_MB_2U(SCH_1):PAGE223

SMB_PEHPCPU1_GTL_R_SCL @S9S_MB_2U_LIB.S9S_MB_2U(SCH_1):SMB_PEHPCPU1_GTL_R_SCL
   U29    2   SCLA PCA9617ADP-PCA9617ADP,SMLF,IC,A    I43 @S9S_MB_2U_LIB.S9S_MB_2U(SCH_1):PAGE223
  R963    2      B Q_RES_0402LF-240,1%,1/16W,CHIPA    I48 @S9S_MB_2U_LIB.S9S_MB_2U(SCH_1):PAGE223
  R961    2      B Q_RES_0402LF-33.2,1%,1/16W,CHIA    I99 @S9S_MB_2U_LIB.S9S_MB_2U(SCH_1):PAGE223

SMB_PEHPCPU1_GTL_R_SDA @S9S_MB_2U_LIB.S9S_MB_2U(SCH_1):SMB_PEHPCPU1_GTL_R_SDA
   U29    3   SDAA PCA9617ADP-PCA9617ADP,SMLF,IC,A    I43 @S9S_MB_2U_LIB.S9S_MB_2U(SCH_1):PAGE223
  R964    2      B Q_RES_0402LF-240,1%,1/16W,CHIPA    I46 @S9S_MB_2U_LIB.S9S_MB_2U(SCH_1):PAGE223
  R962    2      B Q_RES_0402LF-33.2,1%,1/16W,CHIA   I100 @S9S_MB_2U_LIB.S9S_MB_2U(SCH_1):PAGE223

SMB_PEHPCPU1_GTL_SCL @S9S_MB_2U_LIB.S9S_MB_2U(SCH_1):SMB_PEHPCPU1_GTL_SCL
    U1 CA25 CXPSMBUSSCL SOCKET4677_AZIF0045P001C01CS-SA    I29 @S9S_MB_2U_LIB.S9S_MB_2U(SCH_1):PAGE45
  R961    1      A Q_RES_0402LF-33.2,1%,1/16W,CHIA    I99 @S9S_MB_2U_LIB.S9S_MB_2U(SCH_1):PAGE223

SMB_PEHPCPU1_GTL_SDA @S9S_MB_2U_LIB.S9S_MB_2U(SCH_1):SMB_PEHPCPU1_GTL_SDA
    U1 BY26 CXPSMBUSSDA SOCKET4677_AZIF0045P001C01CS-SA    I29 @S9S_MB_2U_LIB.S9S_MB_2U(SCH_1):PAGE45
  R962    1      A Q_RES_0402LF-33.2,1%,1/16W,CHIA   I100 @S9S_MB_2U_LIB.S9S_MB_2U(SCH_1):PAGE223

SMB_PEHPCPU1_LVC3_R3_SCL @S9S_MB_2U_LIB.S9S_MB_2U(SCH_1):SMB_PEHPCPU1_LVC3_R3_SCL
 R3156    2      B Q_RES_0402LF-33.2,1%,1/16W,CHIA    I34 @S9S_MB_2U_LIB.S9S_MB_2U(SCH_1):PAGE132
   U51   22    SCL PCA9555APW-PCA9555APW,SMLF,IC,A    I66 @S9S_MB_2U_LIB.S9S_MB_2U(SCH_1):PAGE132

SMB_PEHPCPU1_LVC3_R3_SDA @S9S_MB_2U_LIB.S9S_MB_2U(SCH_1):SMB_PEHPCPU1_LVC3_R3_SDA
 R3157    2      B Q_RES_0402LF-33.2,1%,1/16W,CHIA    I33 @S9S_MB_2U_LIB.S9S_MB_2U(SCH_1):PAGE132
   U51   23    SDA PCA9555APW-PCA9555APW,SMLF,IC,A    I66 @S9S_MB_2U_LIB.S9S_MB_2U(SCH_1):PAGE132

SMB_PEHPCPU1_LVC3_SCL @S9S_MB_2U_LIB.S9S_MB_2U(SCH_1):SMB_PEHPCPU1_LVC3_SCL
 R2479    2      B Q_RES_0402LF-33.2,1%,1/16W,CHIA    I76 @S9S_MB_2U_LIB.S9S_MB_2U(SCH_1):PAGE223
  R966    2      B Q_RES_0402LF-1K,1%,1/16W,CHIP,A    I82 @S9S_MB_2U_LIB.S9S_MB_2U(SCH_1):PAGE223
 R3156    1      A Q_RES_0402LF-33.2,1%,1/16W,CHIA    I34 @S9S_MB_2U_LIB.S9S_MB_2U(SCH_1):PAGE132

SMB_PEHPCPU1_LVC3_SCL_R0 @S9S_MB_2U_LIB.S9S_MB_2U(SCH_1):SMB_PEHPCPU1_LVC3_SCL_R0
   U29    7   SCLB PCA9617ADP-PCA9617ADP,SMLF,IC,A    I43 @S9S_MB_2U_LIB.S9S_MB_2U(SCH_1):PAGE223
 R2479    1      A Q_RES_0402LF-33.2,1%,1/16W,CHIA    I76 @S9S_MB_2U_LIB.S9S_MB_2U(SCH_1):PAGE223

SMB_PEHPCPU1_LVC3_SDA @S9S_MB_2U_LIB.S9S_MB_2U(SCH_1):SMB_PEHPCPU1_LVC3_SDA
 R2480    2      B Q_RES_0402LF-33.2,1%,1/16W,CHIA    I77 @S9S_MB_2U_LIB.S9S_MB_2U(SCH_1):PAGE223
  R968    2      B Q_RES_0402LF-1K,1%,1/16W,CHIP,A    I81 @S9S_MB_2U_LIB.S9S_MB_2U(SCH_1):PAGE223
 R3157    1      A Q_RES_0402LF-33.2,1%,1/16W,CHIA    I33 @S9S_MB_2U_LIB.S9S_MB_2U(SCH_1):PAGE132

SMB_PEHPCPU1_LVC3_SDA_R0 @S9S_MB_2U_LIB.S9S_MB_2U(SCH_1):SMB_PEHPCPU1_LVC3_SDA_R0
   U29    6   SDAB PCA9617ADP-PCA9617ADP,SMLF,IC,A    I43 @S9S_MB_2U_LIB.S9S_MB_2U(SCH_1):PAGE223
 R2480    1      A Q_RES_0402LF-33.2,1%,1/16W,CHIA    I77 @S9S_MB_2U_LIB.S9S_MB_2U(SCH_1):PAGE223

SMB_PMBUS_SML1_ME_SCL @S9S_MB_2U_LIB.S9S_MB_2U(SCH_1):SMB_PMBUS_SML1_ME_SCL
 R3060    2      B Q_RES_0402LF-33.2,1%,1/16W,CHIA   I237 @S9S_MB_2U_LIB.S9S_MB_2U(SCH_1):PAGE228
  J100    5      5 SCONN20_513860200CV01-SCONN20_A    I32 @S9S_MB_2U_LIB.S9S_MB_2U(SCH_1):PAGE215

SMB_PMBUS_SML1_ME_SDA @S9S_MB_2U_LIB.S9S_MB_2U(SCH_1):SMB_PMBUS_SML1_ME_SDA
 R3061    2      B Q_RES_0402LF-33.2,1%,1/16W,CHIA   I234 @S9S_MB_2U_LIB.S9S_MB_2U(SCH_1):PAGE228
  J100    7      7 SCONN20_513860200CV01-SCONN20_A    I32 @S9S_MB_2U_LIB.S9S_MB_2U(SCH_1):PAGE215

SMB_S3M_CPU0_3V3AUX_SCL @S9S_MB_2U_LIB.S9S_MB_2U(SCH_1):SMB_S3M_CPU0_3V3AUX_SCL
  R977    2      B Q_RES_0402LF-560,1%,1/16W,CHIPA     I8 @S9S_MB_2U_LIB.S9S_MB_2U(SCH_1):PAGE224
  R448    1      A Q_RES_0402LF-0,5%,1/16W,EMPTY,A    I13 @S9S_MB_2U_LIB.S9S_MB_2U(SCH_1):PAGE224
   U30    7   SCLB PCA9517AD-PCA9517AD,SMLF,IC,ALA    I28 @S9S_MB_2U_LIB.S9S_MB_2U(SCH_1):PAGE224
 R2209    2      B Q_RES_0402LF-0,5%,1/16W,CHIP,CA    I63 @S9S_MB_2U_LIB.S9S_MB_2U(SCH_1):PAGE224

SMB_S3M_CPU0_3V3AUX_SCL_R @S9S_MB_2U_LIB.S9S_MB_2U(SCH_1):SMB_S3M_CPU0_3V3AUX_SCL_R
 R2209    1      A Q_RES_0402LF-0,5%,1/16W,CHIP,CA    I63 @S9S_MB_2U_LIB.S9S_MB_2U(SCH_1):PAGE224
  U143    6    SC0 PCA9545APW-PCA9545APW,SMLF,IC,A   I106 @S9S_MB_2U_LIB.S9S_MB_2U(SCH_1):PAGE224

SMB_S3M_CPU0_3V3AUX_SDA @S9S_MB_2U_LIB.S9S_MB_2U(SCH_1):SMB_S3M_CPU0_3V3AUX_SDA
 R1648    1      A Q_RES_0402LF-0,5%,1/16W,EMPTY,A     I3 @S9S_MB_2U_LIB.S9S_MB_2U(SCH_1):PAGE224
  R979    2      B Q_RES_0402LF-560,1%,1/16W,CHIPA     I6 @S9S_MB_2U_LIB.S9S_MB_2U(SCH_1):PAGE224
   U30    6   SDAB PCA9517AD-PCA9517AD,SMLF,IC,ALA    I28 @S9S_MB_2U_LIB.S9S_MB_2U(SCH_1):PAGE224
 R2208    2      B Q_RES_0402LF-0,5%,1/16W,CHIP,CA    I62 @S9S_MB_2U_LIB.S9S_MB_2U(SCH_1):PAGE224

SMB_S3M_CPU0_3V3AUX_SDA_R @S9S_MB_2U_LIB.S9S_MB_2U(SCH_1):SMB_S3M_CPU0_3V3AUX_SDA_R
 R2208    1      A Q_RES_0402LF-0,5%,1/16W,CHIP,CA    I62 @S9S_MB_2U_LIB.S9S_MB_2U(SCH_1):PAGE224
  U143    5    SD0 PCA9545APW-PCA9545APW,SMLF,IC,A   I106 @S9S_MB_2U_LIB.S9S_MB_2U(SCH_1):PAGE224

SMB_S3M_CPU0_PIROM_3V3AUX_SCL @S9S_MB_2U_LIB.S9S_MB_2U(SCH_1):SMB_S3M_CPU0_PIROM_3V3AUX_SCL
 R1932    1      A Q_RES_0402LF-33.2,1%,1/16W,CHIA   I109 @S9S_MB_2U_LIB.S9S_MB_2U(SCH_1):PAGE14
 R3123    2      B Q_RES_0402LF-0,5%,1/16W,CHIP,CA   I115 @S9S_MB_2U_LIB.S9S_MB_2U(SCH_1):PAGE224
 R3222    1      A Q_RES_0402LF-2K,1%,1/16W,CHIP,A   I132 @S9S_MB_2U_LIB.S9S_MB_2U(SCH_1):PAGE224

SMB_S3M_CPU0_PIROM_3V3AUX_SCL_1 @S9S_MB_2U_LIB.S9S_MB_2U(SCH_1):SMB_S3M_CPU0_PIROM_3V3AUX_SCL_R1
    U2 CU70 PIROM_SCL SOCKET4677_AZIF0045P001C01CS-SA     I1 @S9S_MB_2U_LIB.S9S_MB_2U(SCH_1):PAGE14
 R1932    2      B Q_RES_0402LF-33.2,1%,1/16W,CHIA   I109 @S9S_MB_2U_LIB.S9S_MB_2U(SCH_1):PAGE14

SMB_S3M_CPU0_PIROM_3V3AUX_SCL_R @S9S_MB_2U_LIB.S9S_MB_2U(SCH_1):SMB_S3M_CPU0_PIROM_3V3AUX_SCL_R
  U143   13    SC2 PCA9545APW-PCA9545APW,SMLF,IC,A   I106 @S9S_MB_2U_LIB.S9S_MB_2U(SCH_1):PAGE224
 R3123    1      A Q_RES_0402LF-0,5%,1/16W,CHIP,CA   I115 @S9S_MB_2U_LIB.S9S_MB_2U(SCH_1):PAGE224

SMB_S3M_CPU0_PIROM_3V3AUX_SDA @S9S_MB_2U_LIB.S9S_MB_2U(SCH_1):SMB_S3M_CPU0_PIROM_3V3AUX_SDA
 R1933    1      A Q_RES_0402LF-33.2,1%,1/16W,CHIA   I110 @S9S_MB_2U_LIB.S9S_MB_2U(SCH_1):PAGE14
 R3124    2      B Q_RES_0402LF-0,5%,1/16W,CHIP,CA   I114 @S9S_MB_2U_LIB.S9S_MB_2U(SCH_1):PAGE224
 R3223    1      A Q_RES_0402LF-2K,1%,1/16W,CHIP,A   I133 @S9S_MB_2U_LIB.S9S_MB_2U(SCH_1):PAGE224

SMB_S3M_CPU0_PIROM_3V3AUX_SDA_1 @S9S_MB_2U_LIB.S9S_MB_2U(SCH_1):SMB_S3M_CPU0_PIROM_3V3AUX_SDA_R1
    U2 CM71 PIROM_SDA SOCKET4677_AZIF0045P001C01CS-SA     I1 @S9S_MB_2U_LIB.S9S_MB_2U(SCH_1):PAGE14
 R1933    2      B Q_RES_0402LF-33.2,1%,1/16W,CHIA   I110 @S9S_MB_2U_LIB.S9S_MB_2U(SCH_1):PAGE14

SMB_S3M_CPU0_PIROM_3V3AUX_SDA_R @S9S_MB_2U_LIB.S9S_MB_2U(SCH_1):SMB_S3M_CPU0_PIROM_3V3AUX_SDA_R
  U143   12    SD2 PCA9545APW-PCA9545APW,SMLF,IC,A   I106 @S9S_MB_2U_LIB.S9S_MB_2U(SCH_1):PAGE224
 R3124    1      A Q_RES_0402LF-0,5%,1/16W,CHIP,CA   I114 @S9S_MB_2U_LIB.S9S_MB_2U(SCH_1):PAGE224

SMB_S3M_CPU0_R_SCL @S9S_MB_2U_LIB.S9S_MB_2U(SCH_1):SMB_S3M_CPU0_R_SCL
   U30    2   SCLA PCA9517AD-PCA9517AD,SMLF,IC,ALA    I28 @S9S_MB_2U_LIB.S9S_MB_2U(SCH_1):PAGE224
  R969    2      B Q_RES_0402LF-240,1%,1/16W,CHIPA    I43 @S9S_MB_2U_LIB.S9S_MB_2U(SCH_1):PAGE224
  R993    2      B Q_RES_0402LF-33.2,1%,1/16W,CHIA    I44 @S9S_MB_2U_LIB.S9S_MB_2U(SCH_1):PAGE224

SMB_S3M_CPU0_R_SDA @S9S_MB_2U_LIB.S9S_MB_2U(SCH_1):SMB_S3M_CPU0_R_SDA
   U30    3   SDAA PCA9517AD-PCA9517AD,SMLF,IC,ALA    I28 @S9S_MB_2U_LIB.S9S_MB_2U(SCH_1):PAGE224
  R971    2      B Q_RES_0402LF-240,1%,1/16W,CHIPA    I42 @S9S_MB_2U_LIB.S9S_MB_2U(SCH_1):PAGE224
  R994    2      B Q_RES_0402LF-33.2,1%,1/16W,CHIA   I142 @S9S_MB_2U_LIB.S9S_MB_2U(SCH_1):PAGE224

SMB_S3M_CPU0_SCL @S9S_MB_2U_LIB.S9S_MB_2U(SCH_1):SMB_S3M_CPU0_SCL
    U2 CE64 SMB_CLK SOCKET4677_AZIF0045P001C01CS-SA     I1 @S9S_MB_2U_LIB.S9S_MB_2U(SCH_1):PAGE15
  R993    1      A Q_RES_0402LF-33.2,1%,1/16W,CHIA    I44 @S9S_MB_2U_LIB.S9S_MB_2U(SCH_1):PAGE224

SMB_S3M_CPU0_SDA @S9S_MB_2U_LIB.S9S_MB_2U(SCH_1):SMB_S3M_CPU0_SDA
    U2 CD63 SMB_DATA SOCKET4677_AZIF0045P001C01CS-SA     I1 @S9S_MB_2U_LIB.S9S_MB_2U(SCH_1):PAGE15
  R994    1      A Q_RES_0402LF-33.2,1%,1/16W,CHIA   I142 @S9S_MB_2U_LIB.S9S_MB_2U(SCH_1):PAGE224

SMB_S3M_CPU1_3V3AUX_SCL @S9S_MB_2U_LIB.S9S_MB_2U(SCH_1):SMB_S3M_CPU1_3V3AUX_SCL
  R448    2      B Q_RES_0402LF-0,5%,1/16W,EMPTY,A    I13 @S9S_MB_2U_LIB.S9S_MB_2U(SCH_1):PAGE224
  R978    2      B Q_RES_0402LF-560,1%,1/16W,CHIPA    I16 @S9S_MB_2U_LIB.S9S_MB_2U(SCH_1):PAGE224
   U31    7   SCLB PCA9517AD-PCA9517AD,SMLF,IC,ALA    I37 @S9S_MB_2U_LIB.S9S_MB_2U(SCH_1):PAGE224
 R2211    2      B Q_RES_0402LF-0,5%,1/16W,CHIP,CA    I65 @S9S_MB_2U_LIB.S9S_MB_2U(SCH_1):PAGE224

SMB_S3M_CPU1_3V3AUX_SCL_R @S9S_MB_2U_LIB.S9S_MB_2U(SCH_1):SMB_S3M_CPU1_3V3AUX_SCL_R
 R2211    1      A Q_RES_0402LF-0,5%,1/16W,CHIP,CA    I65 @S9S_MB_2U_LIB.S9S_MB_2U(SCH_1):PAGE224
  U143    9    SC1 PCA9545APW-PCA9545APW,SMLF,IC,A   I106 @S9S_MB_2U_LIB.S9S_MB_2U(SCH_1):PAGE224

SMB_S3M_CPU1_3V3AUX_SDA @S9S_MB_2U_LIB.S9S_MB_2U(SCH_1):SMB_S3M_CPU1_3V3AUX_SDA
 R1648    2      B Q_RES_0402LF-0,5%,1/16W,EMPTY,A     I3 @S9S_MB_2U_LIB.S9S_MB_2U(SCH_1):PAGE224
  R980    2      B Q_RES_0402LF-560,1%,1/16W,CHIPA    I14 @S9S_MB_2U_LIB.S9S_MB_2U(SCH_1):PAGE224
   U31    6   SDAB PCA9517AD-PCA9517AD,SMLF,IC,ALA    I37 @S9S_MB_2U_LIB.S9S_MB_2U(SCH_1):PAGE224
 R2210    2      B Q_RES_0402LF-0,5%,1/16W,CHIP,CA    I64 @S9S_MB_2U_LIB.S9S_MB_2U(SCH_1):PAGE224

SMB_S3M_CPU1_3V3AUX_SDA_R @S9S_MB_2U_LIB.S9S_MB_2U(SCH_1):SMB_S3M_CPU1_3V3AUX_SDA_R
 R2210    1      A Q_RES_0402LF-0,5%,1/16W,CHIP,CA    I64 @S9S_MB_2U_LIB.S9S_MB_2U(SCH_1):PAGE224
  U143    8    SD1 PCA9545APW-PCA9545APW,SMLF,IC,A   I106 @S9S_MB_2U_LIB.S9S_MB_2U(SCH_1):PAGE224

SMB_S3M_CPU1_PIROM_3V3AUX_SCL @S9S_MB_2U_LIB.S9S_MB_2U(SCH_1):SMB_S3M_CPU1_PIROM_3V3AUX_SCL
 R1934    1      A Q_RES_0402LF-33.2,1%,1/16W,CHIA    I81 @S9S_MB_2U_LIB.S9S_MB_2U(SCH_1):PAGE45
 R3125    2      B Q_RES_0402LF-0,5%,1/16W,CHIP,CA   I116 @S9S_MB_2U_LIB.S9S_MB_2U(SCH_1):PAGE224
 R3224    1      A Q_RES_0402LF-2K,1%,1/16W,CHIP,A   I131 @S9S_MB_2U_LIB.S9S_MB_2U(SCH_1):PAGE224

SMB_S3M_CPU1_PIROM_3V3AUX_SCL_1 @S9S_MB_2U_LIB.S9S_MB_2U(SCH_1):SMB_S3M_CPU1_PIROM_3V3AUX_SCL_R1
    U1 CU70 PIROM_SCL SOCKET4677_AZIF0045P001C01CS-SA    I29 @S9S_MB_2U_LIB.S9S_MB_2U(SCH_1):PAGE45
 R1934    2      B Q_RES_0402LF-33.2,1%,1/16W,CHIA    I81 @S9S_MB_2U_LIB.S9S_MB_2U(SCH_1):PAGE45

SMB_S3M_CPU1_PIROM_3V3AUX_SCL_R @S9S_MB_2U_LIB.S9S_MB_2U(SCH_1):SMB_S3M_CPU1_PIROM_3V3AUX_SCL_R
  U143   16    SC3 PCA9545APW-PCA9545APW,SMLF,IC,A   I106 @S9S_MB_2U_LIB.S9S_MB_2U(SCH_1):PAGE224
 R3125    1      A Q_RES_0402LF-0,5%,1/16W,CHIP,CA   I116 @S9S_MB_2U_LIB.S9S_MB_2U(SCH_1):PAGE224

SMB_S3M_CPU1_PIROM_3V3AUX_SDA @S9S_MB_2U_LIB.S9S_MB_2U(SCH_1):SMB_S3M_CPU1_PIROM_3V3AUX_SDA
 R1935    1      A Q_RES_0402LF-33.2,1%,1/16W,CHIA    I82 @S9S_MB_2U_LIB.S9S_MB_2U(SCH_1):PAGE45
 R3126    2      B Q_RES_0402LF-0,5%,1/16W,CHIP,CA   I117 @S9S_MB_2U_LIB.S9S_MB_2U(SCH_1):PAGE224
 R3225    1      A Q_RES_0402LF-2K,1%,1/16W,CHIP,A   I130 @S9S_MB_2U_LIB.S9S_MB_2U(SCH_1):PAGE224

SMB_S3M_CPU1_PIROM_3V3AUX_SDA_1 @S9S_MB_2U_LIB.S9S_MB_2U(SCH_1):SMB_S3M_CPU1_PIROM_3V3AUX_SDA_R1
    U1 CM71 PIROM_SDA SOCKET4677_AZIF0045P001C01CS-SA    I29 @S9S_MB_2U_LIB.S9S_MB_2U(SCH_1):PAGE45
 R1935    2      B Q_RES_0402LF-33.2,1%,1/16W,CHIA    I82 @S9S_MB_2U_LIB.S9S_MB_2U(SCH_1):PAGE45

SMB_S3M_CPU1_PIROM_3V3AUX_SDA_R @S9S_MB_2U_LIB.S9S_MB_2U(SCH_1):SMB_S3M_CPU1_PIROM_3V3AUX_SDA_R
  U143   15    SD3 PCA9545APW-PCA9545APW,SMLF,IC,A   I106 @S9S_MB_2U_LIB.S9S_MB_2U(SCH_1):PAGE224
 R3126    1      A Q_RES_0402LF-0,5%,1/16W,CHIP,CA   I117 @S9S_MB_2U_LIB.S9S_MB_2U(SCH_1):PAGE224

SMB_S3M_CPU1_R_SCL @S9S_MB_2U_LIB.S9S_MB_2U(SCH_1):SMB_S3M_CPU1_R_SCL
   U31    2   SCLA PCA9517AD-PCA9517AD,SMLF,IC,ALA    I37 @S9S_MB_2U_LIB.S9S_MB_2U(SCH_1):PAGE224
  R970    2      B Q_RES_0402LF-240,1%,1/16W,CHIPA    I50 @S9S_MB_2U_LIB.S9S_MB_2U(SCH_1):PAGE224
  R995    2      B Q_RES_0402LF-33.2,1%,1/16W,CHIA    I51 @S9S_MB_2U_LIB.S9S_MB_2U(SCH_1):PAGE224

SMB_S3M_CPU1_R_SDA @S9S_MB_2U_LIB.S9S_MB_2U(SCH_1):SMB_S3M_CPU1_R_SDA
   U31    3   SDAA PCA9517AD-PCA9517AD,SMLF,IC,ALA    I37 @S9S_MB_2U_LIB.S9S_MB_2U(SCH_1):PAGE224
  R972    2      B Q_RES_0402LF-240,1%,1/16W,CHIPA    I49 @S9S_MB_2U_LIB.S9S_MB_2U(SCH_1):PAGE224
  R996    2      B Q_RES_0402LF-33.2,1%,1/16W,CHIA   I143 @S9S_MB_2U_LIB.S9S_MB_2U(SCH_1):PAGE224

SMB_S3M_CPU1_SCL @S9S_MB_2U_LIB.S9S_MB_2U(SCH_1):SMB_S3M_CPU1_SCL
    U1 CE64 SMB_CLK SOCKET4677_AZIF0045P001C01CS-SA     I5 @S9S_MB_2U_LIB.S9S_MB_2U(SCH_1):PAGE46
  R995    1      A Q_RES_0402LF-33.2,1%,1/16W,CHIA    I51 @S9S_MB_2U_LIB.S9S_MB_2U(SCH_1):PAGE224

SMB_S3M_CPU1_SDA @S9S_MB_2U_LIB.S9S_MB_2U(SCH_1):SMB_S3M_CPU1_SDA
    U1 CD63 SMB_DATA SOCKET4677_AZIF0045P001C01CS-SA     I5 @S9S_MB_2U_LIB.S9S_MB_2U(SCH_1):PAGE46
  R996    1      A Q_RES_0402LF-33.2,1%,1/16W,CHIA   I143 @S9S_MB_2U_LIB.S9S_MB_2U(SCH_1):PAGE224

SMB_S3M_CPU_3V3AUX_SCL @S9S_MB_2U_LIB.S9S_MB_2U(SCH_1):SMB_S3M_CPU_3V3AUX_SCL
 R2212    1      A Q_RES_0402LF-2.2K,5%,1/16W,EMPA   I202 @S9S_MB_2U_LIB.S9S_MB_2U(SCH_1):PAGE228
  U143   18    SCL PCA9545APW-PCA9545APW,SMLF,IC,A   I106 @S9S_MB_2U_LIB.S9S_MB_2U(SCH_1):PAGE224
 R2417    1      A Q_RES_0402LF-33.2,1%,1/16W,CHIA    I22 @S9S_MB_2U_LIB.S9S_MB_2U(SCH_1):PAGE227

SMB_S3M_CPU_3V3AUX_SCL_R0 @S9S_MB_2U_LIB.S9S_MB_2U(SCH_1):SMB_S3M_CPU_3V3AUX_SCL_R0
 R2417    2      B Q_RES_0402LF-33.2,1%,1/16W,CHIA    I22 @S9S_MB_2U_LIB.S9S_MB_2U(SCH_1):PAGE227
   J41  A40  PERP7 SCONN168_ME1016810202011-SCONNA   I173 @S9S_MB_2U_LIB.S9S_MB_2U(SCH_1):PAGE227

SMB_S3M_CPU_3V3AUX_SDA @S9S_MB_2U_LIB.S9S_MB_2U(SCH_1):SMB_S3M_CPU_3V3AUX_SDA
 R2213    1      A Q_RES_0402LF-2.2K,5%,1/16W,EMPA   I203 @S9S_MB_2U_LIB.S9S_MB_2U(SCH_1):PAGE228
  U143   19    SDA PCA9545APW-PCA9545APW,SMLF,IC,A   I106 @S9S_MB_2U_LIB.S9S_MB_2U(SCH_1):PAGE224
 R2418    1      A Q_RES_0402LF-33.2,1%,1/16W,CHIA    I23 @S9S_MB_2U_LIB.S9S_MB_2U(SCH_1):PAGE227

SMB_S3M_CPU_3V3AUX_SDA_R0 @S9S_MB_2U_LIB.S9S_MB_2U(SCH_1):SMB_S3M_CPU_3V3AUX_SDA_R0
 R2418    2      B Q_RES_0402LF-33.2,1%,1/16W,CHIA    I23 @S9S_MB_2U_LIB.S9S_MB_2U(SCH_1):PAGE227
   J41  A41 GND_A41 SCONN168_ME1016810202011-SCONNA   I173 @S9S_MB_2U_LIB.S9S_MB_2U(SCH_1):PAGE227

SMB_SENSOR_E1S_3V3AUX_SCL @S9S_MB_2U_LIB.S9S_MB_2U(SCH_1):SMB_SENSOR_E1S_3V3AUX_SCL
  U279    7   SCLB PCA9617ADP-PCA9617ADP,SMLF,IC,A    I93 @S9S_MB_2U_LIB.S9S_MB_2U(SCH_1):PAGE183
 R3526    2      B Q_RES_0402LF-0,5%,1/16W,CHIP,CA    I35 @S9S_MB_2U_LIB.S9S_MB_2U(SCH_1):PAGE219
 R3535    2      B Q_RES_0402LF-2.2K,5%,1/16W,CHIA    I49 @S9S_MB_2U_LIB.S9S_MB_2U(SCH_1):PAGE219

SMB_SENSOR_E1S_3V3AUX_SDA @S9S_MB_2U_LIB.S9S_MB_2U(SCH_1):SMB_SENSOR_E1S_3V3AUX_SDA
  U279    6   SDAB PCA9617ADP-PCA9617ADP,SMLF,IC,A    I93 @S9S_MB_2U_LIB.S9S_MB_2U(SCH_1):PAGE183
 R3527    2      B Q_RES_0402LF-0,5%,1/16W,CHIP,CA    I37 @S9S_MB_2U_LIB.S9S_MB_2U(SCH_1):PAGE219
 R3536    2      B Q_RES_0402LF-2.2K,5%,1/16W,CHIA    I50 @S9S_MB_2U_LIB.S9S_MB_2U(SCH_1):PAGE219

SMB_SENSOR_M2_P0_3V3AUX_SCL @S9S_MB_2U_LIB.S9S_MB_2U(SCH_1):SMB_SENSOR_M2_P0_3V3AUX_SCL
   U98    6   SCL2 PCA9306DP1-PCA9306DP1,SMLF,IC,A    I27 @S9S_MB_2U_LIB.S9S_MB_2U(SCH_1):PAGE183
 R1089    2      B Q_RES_0402LF-2.2K,5%,1/16W,CHIA    I21 @S9S_MB_2U_LIB.S9S_MB_2U(SCH_1):PAGE219
 R2967    2      B Q_RES_0402LF-0,5%,1/16W,CHIP,CA    I36 @S9S_MB_2U_LIB.S9S_MB_2U(SCH_1):PAGE219

SMB_SENSOR_M2_P0_3V3AUX_SDA @S9S_MB_2U_LIB.S9S_MB_2U(SCH_1):SMB_SENSOR_M2_P0_3V3AUX_SDA
   U98    5   SDA2 PCA9306DP1-PCA9306DP1,SMLF,IC,A    I27 @S9S_MB_2U_LIB.S9S_MB_2U(SCH_1):PAGE183
 R1090    2      B Q_RES_0402LF-2.2K,5%,1/16W,CHIA    I20 @S9S_MB_2U_LIB.S9S_MB_2U(SCH_1):PAGE219
 R2968    2      B Q_RES_0402LF-0,5%,1/16W,CHIP,CA    I39 @S9S_MB_2U_LIB.S9S_MB_2U(SCH_1):PAGE219

SMB_SEN_MAM_3V3AUX_SCL @S9S_MB_2U_LIB.S9S_MB_2U(SCH_1):SMB_SEN_MAM_3V3AUX_SCL
 R1793    2      B Q_RES_0402LF-0,5%,1/16W,EMPTY,A    I19 @S9S_MB_2U_LIB.S9S_MB_2U(SCH_1):PAGE239
  U193   13    SCL MAX11617EEET-MAX11617EEE+T,SMLA    I57 @S9S_MB_2U_LIB.S9S_MB_2U(SCH_1):PAGE239

SMB_SEN_MAM_3V3AUX_SDA @S9S_MB_2U_LIB.S9S_MB_2U(SCH_1):SMB_SEN_MAM_3V3AUX_SDA
 R1792    2      B Q_RES_0402LF-0,5%,1/16W,EMPTY,A    I20 @S9S_MB_2U_LIB.S9S_MB_2U(SCH_1):PAGE239
  U193   14    SDA MAX11617EEET-MAX11617EEE+T,SMLA    I57 @S9S_MB_2U_LIB.S9S_MB_2U(SCH_1):PAGE239

SMB_SEN_TIC_3V3AUX_SCL @S9S_MB_2U_LIB.S9S_MB_2U(SCH_1):SMB_SEN_TIC_3V3AUX_SCL
  U269    3    SCL ADC128D818CIMTXNOPB-ADC128D818A   I103 @S9S_MB_2U_LIB.S9S_MB_2U(SCH_1):PAGE239
 R3672    2      B Q_RES_0402LF-0,5%,1/16W,CHIP,CA   I111 @S9S_MB_2U_LIB.S9S_MB_2U(SCH_1):PAGE239

SMB_SEN_TIC_3V3AUX_SDA @S9S_MB_2U_LIB.S9S_MB_2U(SCH_1):SMB_SEN_TIC_3V3AUX_SDA
  U269    2    SDA ADC128D818CIMTXNOPB-ADC128D818A   I103 @S9S_MB_2U_LIB.S9S_MB_2U(SCH_1):PAGE239
 R3671    2      B Q_RES_0402LF-0,5%,1/16W,CHIP,CA   I110 @S9S_MB_2U_LIB.S9S_MB_2U(SCH_1):PAGE239

SMB_SML0B_3V3AUX_SCL @S9S_MB_2U_LIB.S9S_MB_2U(SCH_1):SMB_SML0B_3V3AUX_SCL
    U4  BB3 GPPC_C_4_ME_SML0BCLK EMMITSBURG_REV0P9-GFNOCPU04302A    I93 @S9S_MB_2U_LIB.S9S_MB_2U(SCH_1):PAGE175
 R1545    1      A Q_RES_0402LF-2K,1%,1/16W,CHIP,A   I137 @S9S_MB_2U_LIB.S9S_MB_2U(SCH_1):PAGE175

SMB_SML0B_3V3AUX_SDA @S9S_MB_2U_LIB.S9S_MB_2U(SCH_1):SMB_SML0B_3V3AUX_SDA
    U4  AU4 GPPC_C_3_ME_SML0BDATA EMMITSBURG_REV0P9-GFNOCPU04302A    I93 @S9S_MB_2U_LIB.S9S_MB_2U(SCH_1):PAGE175
 R1546    1      A Q_RES_0402LF-2K,1%,1/16W,CHIP,A   I138 @S9S_MB_2U_LIB.S9S_MB_2U(SCH_1):PAGE175

SMB_SML0_3V3AUX_PCH_SCL @S9S_MB_2U_LIB.S9S_MB_2U(SCH_1):SMB_SML0_3V3AUX_PCH_SCL
    U4  BC4 GPPC_C_0_ME_SML0CLK EMMITSBURG_REV0P9-GFNOCPU04302A    I93 @S9S_MB_2U_LIB.S9S_MB_2U(SCH_1):PAGE175
   JP4    1      1 CONN3_210HP1030BR1-CONN3_210-HA   I256 @S9S_MB_2U_LIB.S9S_MB_2U(SCH_1):PAGE175
  R581    2      B Q_RES_0402LF-33.2,1%,1/16W,CHIA    I44 @S9S_MB_2U_LIB.S9S_MB_2U(SCH_1):PAGE228

SMB_SML0_3V3AUX_PCH_SDA @S9S_MB_2U_LIB.S9S_MB_2U(SCH_1):SMB_SML0_3V3AUX_PCH_SDA
    U4  BA4 GPPC_C_1_ME_SML0DATA EMMITSBURG_REV0P9-GFNOCPU04302A    I93 @S9S_MB_2U_LIB.S9S_MB_2U(SCH_1):PAGE175
   JP4    3      3 CONN3_210HP1030BR1-CONN3_210-HA   I256 @S9S_MB_2U_LIB.S9S_MB_2U(SCH_1):PAGE175
  R582    2      B Q_RES_0402LF-33.2,1%,1/16W,CHIA    I45 @S9S_MB_2U_LIB.S9S_MB_2U(SCH_1):PAGE228

SMB_SML0_3V3AUX_SCL @S9S_MB_2U_LIB.S9S_MB_2U(SCH_1):SMB_SML0_3V3AUX_SCL
 R1384    1      A Q_RES_0402LF-2K,1%,1/16W,EMPTYA     I4 @S9S_MB_2U_LIB.S9S_MB_2U(SCH_1):PAGE228
  R581    1      A Q_RES_0402LF-33.2,1%,1/16W,CHIA    I44 @S9S_MB_2U_LIB.S9S_MB_2U(SCH_1):PAGE228
 R3058    1      A Q_RES_0402LF-33.2,1%,1/16W,CHIA   I242 @S9S_MB_2U_LIB.S9S_MB_2U(SCH_1):PAGE228
 R4506    1      A Q_RES_0402LF-33.2,1%,1/16W,CHIA    I90 @S9S_MB_2U_LIB.S9S_MB_2U(SCH_1):PAGE227

SMB_SML0_3V3AUX_SCL_R1 @S9S_MB_2U_LIB.S9S_MB_2U(SCH_1):SMB_SML0_3V3AUX_SCL_R1
 R4506    2      B Q_RES_0402LF-33.2,1%,1/16W,CHIA    I90 @S9S_MB_2U_LIB.S9S_MB_2U(SCH_1):PAGE227
   J41  A25 GND_A25 SCONN168_ME1016810202011-SCONNA   I173 @S9S_MB_2U_LIB.S9S_MB_2U(SCH_1):PAGE227

SMB_SML0_3V3AUX_SDA @S9S_MB_2U_LIB.S9S_MB_2U(SCH_1):SMB_SML0_3V3AUX_SDA
 R1385    1      A Q_RES_0402LF-2K,1%,1/16W,EMPTYA     I5 @S9S_MB_2U_LIB.S9S_MB_2U(SCH_1):PAGE228
  R582    1      A Q_RES_0402LF-33.2,1%,1/16W,CHIA    I45 @S9S_MB_2U_LIB.S9S_MB_2U(SCH_1):PAGE228
 R3059    1      A Q_RES_0402LF-33.2,1%,1/16W,CHIA   I243 @S9S_MB_2U_LIB.S9S_MB_2U(SCH_1):PAGE228
 R4507    1      A Q_RES_0402LF-33.2,1%,1/16W,CHIA    I89 @S9S_MB_2U_LIB.S9S_MB_2U(SCH_1):PAGE227

SMB_SML0_3V3AUX_SDA_R1 @S9S_MB_2U_LIB.S9S_MB_2U(SCH_1):SMB_SML0_3V3AUX_SDA_R1
 R4507    2      B Q_RES_0402LF-33.2,1%,1/16W,CHIA    I89 @S9S_MB_2U_LIB.S9S_MB_2U(SCH_1):PAGE227
   J41  A26  PERN3 SCONN168_ME1016810202011-SCONNA   I173 @S9S_MB_2U_LIB.S9S_MB_2U(SCH_1):PAGE227

SMB_SML0_ME_SCL @S9S_MB_2U_LIB.S9S_MB_2U(SCH_1):SMB_SML0_ME_SCL
 R3058    2      B Q_RES_0402LF-33.2,1%,1/16W,CHIA   I242 @S9S_MB_2U_LIB.S9S_MB_2U(SCH_1):PAGE228
  J100    1      1 SCONN20_513860200CV01-SCONN20_A    I32 @S9S_MB_2U_LIB.S9S_MB_2U(SCH_1):PAGE215

SMB_SML0_ME_SDA @S9S_MB_2U_LIB.S9S_MB_2U(SCH_1):SMB_SML0_ME_SDA
 R3059    2      B Q_RES_0402LF-33.2,1%,1/16W,CHIA   I243 @S9S_MB_2U_LIB.S9S_MB_2U(SCH_1):PAGE228
  J100    3      3 SCONN20_513860200CV01-SCONN20_A    I32 @S9S_MB_2U_LIB.S9S_MB_2U(SCH_1):PAGE215

SMB_SML1_PMBUS_3V3AUX_PCH_SCL @S9S_MB_2U_LIB.S9S_MB_2U(SCH_1):SMB_SML1_PMBUS_3V3AUX_PCH_SCL
 R1386    1      A Q_RES_0402LF-2K,1%,1/16W,EMPTYA     I6 @S9S_MB_2U_LIB.S9S_MB_2U(SCH_1):PAGE228
 R2995    1      A Q_RES_0402LF-33.2,1%,1/16W,CHIA   I228 @S9S_MB_2U_LIB.S9S_MB_2U(SCH_1):PAGE228
 R3060    1      A Q_RES_0402LF-33.2,1%,1/16W,CHIA   I237 @S9S_MB_2U_LIB.S9S_MB_2U(SCH_1):PAGE228
 R4505    1      A Q_RES_0402LF-33.2,1%,1/16W,CHIA   I305 @S9S_MB_2U_LIB.S9S_MB_2U(SCH_1):PAGE175
 R2423    1      A Q_RES_0402LF-33.2,1%,1/16W,CHIA    I97 @S9S_MB_2U_LIB.S9S_MB_2U(SCH_1):PAGE227

SMB_SML1_PMBUS_3V3AUX_PCH_SCL_1 @S9S_MB_2U_LIB.S9S_MB_2U(SCH_1):SMB_SML1_PMBUS_3V3AUX_PCH_SCL_R1
    U4  AP1 GPPC_C_6_ME_SML1CLK EMMITSBURG_REV0P9-GFNOCPU04302A    I93 @S9S_MB_2U_LIB.S9S_MB_2U(SCH_1):PAGE175
   JP9    1      1 CONN3_210HP1030BR1-CONN3_210-HA   I263 @S9S_MB_2U_LIB.S9S_MB_2U(SCH_1):PAGE175
 R4505    2      B Q_RES_0402LF-33.2,1%,1/16W,CHIA   I305 @S9S_MB_2U_LIB.S9S_MB_2U(SCH_1):PAGE175

SMB_SML1_PMBUS_3V3AUX_PCH_SCL_R @S9S_MB_2U_LIB.S9S_MB_2U(SCH_1):SMB_SML1_PMBUS_3V3AUX_PCH_SCL_R0
 R2423    2      B Q_RES_0402LF-33.2,1%,1/16W,CHIA    I97 @S9S_MB_2U_LIB.S9S_MB_2U(SCH_1):PAGE227
   J41   A7  SMCLK SCONN168_ME1016810202011-SCONNA   I173 @S9S_MB_2U_LIB.S9S_MB_2U(SCH_1):PAGE227

SMB_SML1_PMBUS_3V3AUX_PCH_SDA @S9S_MB_2U_LIB.S9S_MB_2U(SCH_1):SMB_SML1_PMBUS_3V3AUX_PCH_SDA
 R1387    1      A Q_RES_0402LF-2K,1%,1/16W,EMPTYA     I7 @S9S_MB_2U_LIB.S9S_MB_2U(SCH_1):PAGE228
 R2996    1      A Q_RES_0402LF-33.2,1%,1/16W,CHIA   I229 @S9S_MB_2U_LIB.S9S_MB_2U(SCH_1):PAGE228
 R3061    1      A Q_RES_0402LF-33.2,1%,1/16W,CHIA   I234 @S9S_MB_2U_LIB.S9S_MB_2U(SCH_1):PAGE228
 R4504    1      A Q_RES_0402LF-0,5%,1/16W,CHIP,CA   I308 @S9S_MB_2U_LIB.S9S_MB_2U(SCH_1):PAGE175
 R2424    1      A Q_RES_0402LF-33.2,1%,1/16W,CHIA    I96 @S9S_MB_2U_LIB.S9S_MB_2U(SCH_1):PAGE227

SMB_SML1_PMBUS_3V3AUX_PCH_SDA_1 @S9S_MB_2U_LIB.S9S_MB_2U(SCH_1):SMB_SML1_PMBUS_3V3AUX_PCH_SDA_R1
    U4  AW4 GPPC_C_7_ME_SML1DATA EMMITSBURG_REV0P9-GFNOCPU04302A    I93 @S9S_MB_2U_LIB.S9S_MB_2U(SCH_1):PAGE175
   JP9    3      3 CONN3_210HP1030BR1-CONN3_210-HA   I263 @S9S_MB_2U_LIB.S9S_MB_2U(SCH_1):PAGE175
 R4504    2      B Q_RES_0402LF-0,5%,1/16W,CHIP,CA   I308 @S9S_MB_2U_LIB.S9S_MB_2U(SCH_1):PAGE175

SMB_SML1_PMBUS_3V3AUX_PCH_SDA_R @S9S_MB_2U_LIB.S9S_MB_2U(SCH_1):SMB_SML1_PMBUS_3V3AUX_PCH_SDA_R0
 R2424    2      B Q_RES_0402LF-33.2,1%,1/16W,CHIA    I96 @S9S_MB_2U_LIB.S9S_MB_2U(SCH_1):PAGE227
   J41   A8  SMDAT SCONN168_ME1016810202011-SCONNA   I173 @S9S_MB_2U_LIB.S9S_MB_2U(SCH_1):PAGE227

SMB_SML1_PMBUS_HSC_L_SCL @S9S_MB_2U_LIB.S9S_MB_2U(SCH_1):SMB_SML1_PMBUS_HSC_L_SCL
 PU289   11    SCL MP5990GMA1111Z-MP5990GMA-1111-A    I56 @S9S_MB_2U_LIB.S9S_MB_2U(SCH_1):PAGE303
 R3909    2      B Q_RES_0402LF-33.2,1%,1/16W,CHIA    I38 @S9S_MB_2U_LIB.S9S_MB_2U(SCH_1):PAGE303

SMB_SML1_PMBUS_HSC_MODULE_SCL @S9S_MB_2U_LIB.S9S_MB_2U(SCH_1):SMB_SML1_PMBUS_HSC_MODULE_SCL
 R4695    2      B Q_RES_0402LF-0,5%,1/16W,CHIP,CA    I26 @S9S_MB_2U_LIB.S9S_MB_2U(SCH_1):PAGE327
  PJ42   18     18 SCONN21_9193031121LF-SCONN21_9A    I34 @S9S_MB_2U_LIB.S9S_MB_2U(SCH_1):PAGE327
  JP10    1      1 CONN3_210HP1030BR1-CONN3_210-HB    I51 @S9S_MB_2U_LIB.S9S_MB_2U(SCH_1):PAGE327

SMB_SML1_PMBUS_HSC_MODULE_SDA @S9S_MB_2U_LIB.S9S_MB_2U(SCH_1):SMB_SML1_PMBUS_HSC_MODULE_SDA
 R4696    2      B Q_RES_0402LF-0,5%,1/16W,CHIP,CA    I25 @S9S_MB_2U_LIB.S9S_MB_2U(SCH_1):PAGE327
  PJ42   19     19 SCONN21_9193031121LF-SCONN21_9A    I34 @S9S_MB_2U_LIB.S9S_MB_2U(SCH_1):PAGE327
  JP10    2      2 CONN3_210HP1030BR1-CONN3_210-HB    I51 @S9S_MB_2U_LIB.S9S_MB_2U(SCH_1):PAGE327

SMB_SML1_PMBUS_HSC_R_SDA @S9S_MB_2U_LIB.S9S_MB_2U(SCH_1):SMB_SML1_PMBUS_HSC_R_SDA
 PU289   12    SDA MP5990GMA1111Z-MP5990GMA-1111-A    I56 @S9S_MB_2U_LIB.S9S_MB_2U(SCH_1):PAGE303
 R1714    2      B Q_RES_0402LF-0,5%,1/16W,CHIP,CA    I37 @S9S_MB_2U_LIB.S9S_MB_2U(SCH_1):PAGE303

SMB_SML1_PMBUS_HSC_SCL @S9S_MB_2U_LIB.S9S_MB_2U(SCH_1):SMB_SML1_PMBUS_HSC_SCL
 R4530    2      B Q_RES_0402LF-33.2,1%,1/16W,CHIA   I293 @S9S_MB_2U_LIB.S9S_MB_2U(SCH_1):PAGE228
 R3909    1      A Q_RES_0402LF-33.2,1%,1/16W,CHIA    I38 @S9S_MB_2U_LIB.S9S_MB_2U(SCH_1):PAGE303
 R4695    1      A Q_RES_0402LF-0,5%,1/16W,CHIP,CA    I26 @S9S_MB_2U_LIB.S9S_MB_2U(SCH_1):PAGE327

SMB_SML1_PMBUS_HSC_SCL_R3 @S9S_MB_2U_LIB.S9S_MB_2U(SCH_1):SMB_SML1_PMBUS_HSC_SCL_R3
 R2995    2      B Q_RES_0402LF-33.2,1%,1/16W,CHIA   I228 @S9S_MB_2U_LIB.S9S_MB_2U(SCH_1):PAGE228
 R4530    1      A Q_RES_0402LF-33.2,1%,1/16W,CHIA   I293 @S9S_MB_2U_LIB.S9S_MB_2U(SCH_1):PAGE228

SMB_SML1_PMBUS_HSC_SDA @S9S_MB_2U_LIB.S9S_MB_2U(SCH_1):SMB_SML1_PMBUS_HSC_SDA
 R4531    2      B Q_RES_0402LF-0,5%,1/16W,CHIP,CA   I296 @S9S_MB_2U_LIB.S9S_MB_2U(SCH_1):PAGE228
 R4696    1      A Q_RES_0402LF-0,5%,1/16W,CHIP,CA    I25 @S9S_MB_2U_LIB.S9S_MB_2U(SCH_1):PAGE327
 R1714    1      A Q_RES_0402LF-0,5%,1/16W,CHIP,CA    I37 @S9S_MB_2U_LIB.S9S_MB_2U(SCH_1):PAGE303

SMB_SML1_PMBUS_HSC_SDA_R3 @S9S_MB_2U_LIB.S9S_MB_2U(SCH_1):SMB_SML1_PMBUS_HSC_SDA_R3
 R2996    2      B Q_RES_0402LF-33.2,1%,1/16W,CHIA   I229 @S9S_MB_2U_LIB.S9S_MB_2U(SCH_1):PAGE228
 R4531    1      A Q_RES_0402LF-0,5%,1/16W,CHIP,CA   I296 @S9S_MB_2U_LIB.S9S_MB_2U(SCH_1):PAGE228

SMB_VR_3V3AUX_SCL @S9S_MB_2U_LIB.S9S_MB_2U(SCH_1):SMB_VR_3V3AUX_SCL
 R1661    1      A Q_RES_0402LF-33.2,1%,1/16W,CHIA    I89 @S9S_MB_2U_LIB.S9S_MB_2U(SCH_1):PAGE228
 R2449    1      A Q_RES_0402LF-33.2,1%,1/16W,CHIA   I206 @S9S_MB_2U_LIB.S9S_MB_2U(SCH_1):PAGE228
 R3723    2      B Q_RES_0402LF-2.2K,5%,1/16W,CHIA    I55 @S9S_MB_2U_LIB.S9S_MB_2U(SCH_1):PAGE221
 R3713    2      B Q_RES_0402LF-0,5%,1/16W,CHIP,CA   I137 @S9S_MB_2U_LIB.S9S_MB_2U(SCH_1):PAGE221

SMB_VR_3V3AUX_SCL_R @S9S_MB_2U_LIB.S9S_MB_2U(SCH_1):SMB_VR_3V3AUX_SCL_R
 R1661    2      B Q_RES_0402LF-33.2,1%,1/16W,CHIA    I89 @S9S_MB_2U_LIB.S9S_MB_2U(SCH_1):PAGE228
 R2455    1      A Q_RES_0402LF-33.2,1%,1/16W,CHIA   I217 @S9S_MB_2U_LIB.S9S_MB_2U(SCH_1):PAGE228
 R2453    1      A Q_RES_0402LF-33.2,1%,1/16W,CHIA   I219 @S9S_MB_2U_LIB.S9S_MB_2U(SCH_1):PAGE228
 R4595    1      A Q_RES_0402LF-0,5%,1/16W,CHIP,CA    I39 @S9S_MB_2U_LIB.S9S_MB_2U(SCH_1):PAGE282
 R4594    1      A Q_RES_0402LF-0,5%,1/16W,CHIP,CA    I58 @S9S_MB_2U_LIB.S9S_MB_2U(SCH_1):PAGE278

SMB_VR_3V3AUX_SCL_R0 @S9S_MB_2U_LIB.S9S_MB_2U(SCH_1):SMB_VR_3V3AUX_SCL_R0
 R2421    2      B Q_RES_0402LF-33.2,1%,1/16W,CHIA    I99 @S9S_MB_2U_LIB.S9S_MB_2U(SCH_1):PAGE227
   J41   A5 GND_A5 SCONN168_ME1016810202011-SCONNA   I173 @S9S_MB_2U_LIB.S9S_MB_2U(SCH_1):PAGE227

SMB_VR_3V3AUX_SCL_R1 @S9S_MB_2U_LIB.S9S_MB_2U(SCH_1):SMB_VR_3V3AUX_SCL_R1
 R2449    2      B Q_RES_0402LF-33.2,1%,1/16W,CHIA   I206 @S9S_MB_2U_LIB.S9S_MB_2U(SCH_1):PAGE228
 R1793    1      A Q_RES_0402LF-0,5%,1/16W,EMPTY,A    I19 @S9S_MB_2U_LIB.S9S_MB_2U(SCH_1):PAGE239
 R3672    1      A Q_RES_0402LF-0,5%,1/16W,CHIP,CA   I111 @S9S_MB_2U_LIB.S9S_MB_2U(SCH_1):PAGE239

SMB_VR_3V3AUX_SCL_R2 @S9S_MB_2U_LIB.S9S_MB_2U(SCH_1):SMB_VR_3V3AUX_SCL_R2
 R2453    2      B Q_RES_0402LF-33.2,1%,1/16W,CHIA   I219 @S9S_MB_2U_LIB.S9S_MB_2U(SCH_1):PAGE228
 R2402    1      A Q_RES_0402LF-0,5%,1/16W,CHIP,CA    I39 @S9S_MB_2U_LIB.S9S_MB_2U(SCH_1):PAGE264
 R2390    1      A Q_RES_0402LF-0,5%,1/16W,CHIP,CA    I53 @S9S_MB_2U_LIB.S9S_MB_2U(SCH_1):PAGE260

SMB_VR_3V3AUX_SCL_R3 @S9S_MB_2U_LIB.S9S_MB_2U(SCH_1):SMB_VR_3V3AUX_SCL_R3
 R2455    2      B Q_RES_0402LF-33.2,1%,1/16W,CHIA   I217 @S9S_MB_2U_LIB.S9S_MB_2U(SCH_1):PAGE228
 R2520    1      A Q_RES_0402LF-0,5%,1/16W,CHIP,CA    I65 @S9S_MB_2U_LIB.S9S_MB_2U(SCH_1):PAGE270
 R1713    1      A Q_RES_0402LF-4.7K,5%,1/16W,EMPA    I40 @S9S_MB_2U_LIB.S9S_MB_2U(SCH_1):PAGE252
  PJP1    1      1 CONN3_210HP1030BR1-CONN3_210-HB    I32 @S9S_MB_2U_LIB.S9S_MB_2U(SCH_1):PAGE252
 R2371    1      A Q_RES_0402LF-33.2,1%,1/16W,CHIA    I80 @S9S_MB_2U_LIB.S9S_MB_2U(SCH_1):PAGE252

SMB_VR_3V3AUX_SCL_R6 @S9S_MB_2U_LIB.S9S_MB_2U(SCH_1):SMB_VR_3V3AUX_SCL_R6
   U39    5    SC0 TCA9548APWR-TCA9548APWR,SMLF,IA   I103 @S9S_MB_2U_LIB.S9S_MB_2U(SCH_1):PAGE221
 R3713    1      A Q_RES_0402LF-0,5%,1/16W,CHIP,CA   I137 @S9S_MB_2U_LIB.S9S_MB_2U(SCH_1):PAGE221

SMB_VR_3V3AUX_SDA @S9S_MB_2U_LIB.S9S_MB_2U(SCH_1):SMB_VR_3V3AUX_SDA
 R1662    1      A Q_RES_0402LF-33.2,1%,1/16W,CHIA    I90 @S9S_MB_2U_LIB.S9S_MB_2U(SCH_1):PAGE228
 R2450    1      A Q_RES_0402LF-33.2,1%,1/16W,CHIA   I207 @S9S_MB_2U_LIB.S9S_MB_2U(SCH_1):PAGE228
 R3724    2      B Q_RES_0402LF-2.2K,5%,1/16W,CHIA    I56 @S9S_MB_2U_LIB.S9S_MB_2U(SCH_1):PAGE221
 R3714    2      B Q_RES_0402LF-0,5%,1/16W,CHIP,CA   I138 @S9S_MB_2U_LIB.S9S_MB_2U(SCH_1):PAGE221

SMB_VR_3V3AUX_SDA_R @S9S_MB_2U_LIB.S9S_MB_2U(SCH_1):SMB_VR_3V3AUX_SDA_R
 R1662    2      B Q_RES_0402LF-33.2,1%,1/16W,CHIA    I90 @S9S_MB_2U_LIB.S9S_MB_2U(SCH_1):PAGE228
 R2456    1      A Q_RES_0402LF-33.2,1%,1/16W,CHIA   I216 @S9S_MB_2U_LIB.S9S_MB_2U(SCH_1):PAGE228
 R2454    1      A Q_RES_0402LF-33.2,1%,1/16W,CHIA   I218 @S9S_MB_2U_LIB.S9S_MB_2U(SCH_1):PAGE228
 R2563    1      A Q_RES_0402LF-0,5%,1/16W,CHIP,CA    I57 @S9S_MB_2U_LIB.S9S_MB_2U(SCH_1):PAGE278
 R2582    1      A Q_RES_0402LF-0,5%,1/16W,CHIP,CA    I38 @S9S_MB_2U_LIB.S9S_MB_2U(SCH_1):PAGE282

SMB_VR_3V3AUX_SDA_R0 @S9S_MB_2U_LIB.S9S_MB_2U(SCH_1):SMB_VR_3V3AUX_SDA_R0
 R2422    2      B Q_RES_0402LF-33.2,1%,1/16W,CHIA    I95 @S9S_MB_2U_LIB.S9S_MB_2U(SCH_1):PAGE227
   J41   A6 GND_A6 SCONN168_ME1016810202011-SCONNA   I173 @S9S_MB_2U_LIB.S9S_MB_2U(SCH_1):PAGE227

SMB_VR_3V3AUX_SDA_R1 @S9S_MB_2U_LIB.S9S_MB_2U(SCH_1):SMB_VR_3V3AUX_SDA_R1
 R2450    2      B Q_RES_0402LF-33.2,1%,1/16W,CHIA   I207 @S9S_MB_2U_LIB.S9S_MB_2U(SCH_1):PAGE228
 R1792    1      A Q_RES_0402LF-0,5%,1/16W,EMPTY,A    I20 @S9S_MB_2U_LIB.S9S_MB_2U(SCH_1):PAGE239
 R3671    1      A Q_RES_0402LF-0,5%,1/16W,CHIP,CA   I110 @S9S_MB_2U_LIB.S9S_MB_2U(SCH_1):PAGE239

SMB_VR_3V3AUX_SDA_R2 @S9S_MB_2U_LIB.S9S_MB_2U(SCH_1):SMB_VR_3V3AUX_SDA_R2
 R2454    2      B Q_RES_0402LF-33.2,1%,1/16W,CHIA   I218 @S9S_MB_2U_LIB.S9S_MB_2U(SCH_1):PAGE228
 R2403    1      A Q_RES_0402LF-0,5%,1/16W,CHIP,CA    I38 @S9S_MB_2U_LIB.S9S_MB_2U(SCH_1):PAGE264
 R2391    1      A Q_RES_0402LF-0,5%,1/16W,CHIP,CA    I51 @S9S_MB_2U_LIB.S9S_MB_2U(SCH_1):PAGE260

SMB_VR_3V3AUX_SDA_R3 @S9S_MB_2U_LIB.S9S_MB_2U(SCH_1):SMB_VR_3V3AUX_SDA_R3
 R2456    2      B Q_RES_0402LF-33.2,1%,1/16W,CHIA   I216 @S9S_MB_2U_LIB.S9S_MB_2U(SCH_1):PAGE228
 R2521    1      A Q_RES_0402LF-0,5%,1/16W,CHIP,CA    I66 @S9S_MB_2U_LIB.S9S_MB_2U(SCH_1):PAGE270
  PJP1    3      3 CONN3_210HP1030BR1-CONN3_210-HB    I32 @S9S_MB_2U_LIB.S9S_MB_2U(SCH_1):PAGE252
 R1712    1      A Q_RES_0402LF-4.7K,5%,1/16W,EMPA    I42 @S9S_MB_2U_LIB.S9S_MB_2U(SCH_1):PAGE252
 R2372    1      A Q_RES_0402LF-33.2,1%,1/16W,CHIA    I78 @S9S_MB_2U_LIB.S9S_MB_2U(SCH_1):PAGE252

SMB_VR_3V3AUX_SDA_R6 @S9S_MB_2U_LIB.S9S_MB_2U(SCH_1):SMB_VR_3V3AUX_SDA_R6
   U39    4    SD0 TCA9548APWR-TCA9548APWR,SMLF,IA   I103 @S9S_MB_2U_LIB.S9S_MB_2U(SCH_1):PAGE221
 R3714    1      A Q_RES_0402LF-0,5%,1/16W,CHIP,CA   I138 @S9S_MB_2U_LIB.S9S_MB_2U(SCH_1):PAGE221

SMB_VR_SENSOR_3V3AUX_SCL @S9S_MB_2U_LIB.S9S_MB_2U(SCH_1):SMB_VR_SENSOR_3V3AUX_SCL
 R2421    1      A Q_RES_0402LF-33.2,1%,1/16W,CHIA    I99 @S9S_MB_2U_LIB.S9S_MB_2U(SCH_1):PAGE227
 R4269    2      B Q_RES_0402LF-2.2K,5%,1/16W,EMPA   I102 @S9S_MB_2U_LIB.S9S_MB_2U(SCH_1):PAGE221
 R3711    1      A Q_RES_0402LF-33.2,1%,1/16W,CHIA   I116 @S9S_MB_2U_LIB.S9S_MB_2U(SCH_1):PAGE221

SMB_VR_SENSOR_3V3AUX_SCL_R @S9S_MB_2U_LIB.S9S_MB_2U(SCH_1):SMB_VR_SENSOR_3V3AUX_SCL_R
   U39   22    SCL TCA9548APWR-TCA9548APWR,SMLF,IA   I103 @S9S_MB_2U_LIB.S9S_MB_2U(SCH_1):PAGE221
 R3711    2      B Q_RES_0402LF-33.2,1%,1/16W,CHIA   I116 @S9S_MB_2U_LIB.S9S_MB_2U(SCH_1):PAGE221

SMB_VR_SENSOR_3V3AUX_SDA @S9S_MB_2U_LIB.S9S_MB_2U(SCH_1):SMB_VR_SENSOR_3V3AUX_SDA
 R4270    2      B Q_RES_0402LF-2.2K,5%,1/16W,EMPA    I99 @S9S_MB_2U_LIB.S9S_MB_2U(SCH_1):PAGE221
 R3712    1      A Q_RES_0402LF-33.2,1%,1/16W,CHIA   I115 @S9S_MB_2U_LIB.S9S_MB_2U(SCH_1):PAGE221
 R2422    1      A Q_RES_0402LF-33.2,1%,1/16W,CHIA    I95 @S9S_MB_2U_LIB.S9S_MB_2U(SCH_1):PAGE227

SMB_VR_SENSOR_3V3AUX_SDA_R @S9S_MB_2U_LIB.S9S_MB_2U(SCH_1):SMB_VR_SENSOR_3V3AUX_SDA_R
   U39   23    SDA TCA9548APWR-TCA9548APWR,SMLF,IA   I103 @S9S_MB_2U_LIB.S9S_MB_2U(SCH_1):PAGE221
 R3712    2      B Q_RES_0402LF-33.2,1%,1/16W,CHIA   I115 @S9S_MB_2U_LIB.S9S_MB_2U(SCH_1):PAGE221

SPI_PCH_CLK @S9S_MB_2U_LIB.S9S_MB_2U(SCH_1):SPI_PCH_CLK
    U4 BB15 SPI0_CLK EMMITSBURG_REV0P9-GFNOCPU04302A    I27 @S9S_MB_2U_LIB.S9S_MB_2U(SCH_1):PAGE177
  R499    1      A Q_RES_0402LF-33.2,1%,1/16W,CHIA   I106 @S9S_MB_2U_LIB.S9S_MB_2U(SCH_1):PAGE177

SPI_PCH_CS0_R_N @S9S_MB_2U_LIB.S9S_MB_2U(SCH_1):SPI_PCH_CS0_R_N
    U4 AW13 SPI0_FLASH_0_CS_N EMMITSBURG_REV0P9-GFNOCPU04302A    I27 @S9S_MB_2U_LIB.S9S_MB_2U(SCH_1):PAGE177
  R501    1      A Q_RES_0402LF-33.2,1%,1/16W,CHIA   I100 @S9S_MB_2U_LIB.S9S_MB_2U(SCH_1):PAGE177

SPI_PCH_IO0 @S9S_MB_2U_LIB.S9S_MB_2U(SCH_1):SPI_PCH_IO0
    U4 BA13 SPI0_MOSI_IO_0 EMMITSBURG_REV0P9-GFNOCPU04302A    I27 @S9S_MB_2U_LIB.S9S_MB_2U(SCH_1):PAGE177
  R915    1      A Q_RES_0402LF-0,5%,1/16W,CHIP,CA   I118 @S9S_MB_2U_LIB.S9S_MB_2U(SCH_1):PAGE177

SPI_PCH_IO1 @S9S_MB_2U_LIB.S9S_MB_2U(SCH_1):SPI_PCH_IO1
    U4 AW16 SPI0_MISO_IO_1 EMMITSBURG_REV0P9-GFNOCPU04302A    I27 @S9S_MB_2U_LIB.S9S_MB_2U(SCH_1):PAGE177
  R916    1      A Q_RES_0402LF-0,5%,1/16W,CHIP,CA   I119 @S9S_MB_2U_LIB.S9S_MB_2U(SCH_1):PAGE177

SPI_PCH_IO2 @S9S_MB_2U_LIB.S9S_MB_2U(SCH_1):SPI_PCH_IO2
    U4 AV15 SPI0_IO_2 EMMITSBURG_REV0P9-GFNOCPU04302A    I27 @S9S_MB_2U_LIB.S9S_MB_2U(SCH_1):PAGE177
  R918    1      A Q_RES_0402LF-0,5%,1/16W,CHIP,CA   I120 @S9S_MB_2U_LIB.S9S_MB_2U(SCH_1):PAGE177

SPI_PCH_IO3 @S9S_MB_2U_LIB.S9S_MB_2U(SCH_1):SPI_PCH_IO3
    U4 BA16 SPI0_IO_3 EMMITSBURG_REV0P9-GFNOCPU04302A    I27 @S9S_MB_2U_LIB.S9S_MB_2U(SCH_1):PAGE177
  R917    1      A Q_RES_0402LF-0,5%,1/16W,CHIP,CA   I121 @S9S_MB_2U_LIB.S9S_MB_2U(SCH_1):PAGE177

SPI_PCH_TPM_CS_N @S9S_MB_2U_LIB.S9S_MB_2U(SCH_1):SPI_PCH_TPM_CS_N
    U4 BB11 SPI0_TPM_CS_N EMMITSBURG_REV0P9-GFNOCPU04302A    I27 @S9S_MB_2U_LIB.S9S_MB_2U(SCH_1):PAGE177
 R1395    1      A Q_RES_0402LF-33.2,1%,1/16W,CHIA   I102 @S9S_MB_2U_LIB.S9S_MB_2U(SCH_1):PAGE177

SPI_SYS_CLK @S9S_MB_2U_LIB.S9S_MB_2U(SCH_1):SPI_SYS_CLK
  R499    2      B Q_RES_0402LF-33.2,1%,1/16W,CHIA   I106 @S9S_MB_2U_LIB.S9S_MB_2U(SCH_1):PAGE177
   J41  B11 +3.3V_EDGE SCONN168_ME1016810202011-SCONNA   I173 @S9S_MB_2U_LIB.S9S_MB_2U(SCH_1):PAGE227

SPI_SYS_CS0_N @S9S_MB_2U_LIB.S9S_MB_2U(SCH_1):SPI_SYS_CS0_N
  R501    2      B Q_RES_0402LF-33.2,1%,1/16W,CHIA   I100 @S9S_MB_2U_LIB.S9S_MB_2U(SCH_1):PAGE177
   J41  B12 AUX_PWR_EN SCONN168_ME1016810202011-SCONNA   I173 @S9S_MB_2U_LIB.S9S_MB_2U(SCH_1):PAGE227

SPI_SYS_HOLD_IO3 @S9S_MB_2U_LIB.S9S_MB_2U(SCH_1):SPI_SYS_HOLD_IO3
  R917    2      B Q_RES_0402LF-0,5%,1/16W,CHIP,CA   I121 @S9S_MB_2U_LIB.S9S_MB_2U(SCH_1):PAGE177
   J41  B16 GND_B16 SCONN168_ME1016810202011-SCONNA   I173 @S9S_MB_2U_LIB.S9S_MB_2U(SCH_1):PAGE227

SPI_SYS_MISO @S9S_MB_2U_LIB.S9S_MB_2U(SCH_1):SPI_SYS_MISO
  R916    2      B Q_RES_0402LF-0,5%,1/16W,CHIP,CA   I119 @S9S_MB_2U_LIB.S9S_MB_2U(SCH_1):PAGE177
   J41  B14 REFCLKN0 SCONN168_ME1016810202011-SCONNA   I173 @S9S_MB_2U_LIB.S9S_MB_2U(SCH_1):PAGE227

SPI_SYS_MOSI @S9S_MB_2U_LIB.S9S_MB_2U(SCH_1):SPI_SYS_MOSI
  R915    2      B Q_RES_0402LF-0,5%,1/16W,CHIP,CA   I118 @S9S_MB_2U_LIB.S9S_MB_2U(SCH_1):PAGE177
   J41  B13 GND_B13 SCONN168_ME1016810202011-SCONNA   I173 @S9S_MB_2U_LIB.S9S_MB_2U(SCH_1):PAGE227

SPI_SYS_WP_IO2 @S9S_MB_2U_LIB.S9S_MB_2U(SCH_1):SPI_SYS_WP_IO2
  R918    2      B Q_RES_0402LF-0,5%,1/16W,CHIP,CA   I120 @S9S_MB_2U_LIB.S9S_MB_2U(SCH_1):PAGE177
   J41  B15 REFCLKP0 SCONN168_ME1016810202011-SCONNA   I173 @S9S_MB_2U_LIB.S9S_MB_2U(SCH_1):PAGE227

SPI_TPM_CS_N @S9S_MB_2U_LIB.S9S_MB_2U(SCH_1):SPI_TPM_CS_N
 R1395    2      B Q_RES_0402LF-33.2,1%,1/16W,CHIA   I102 @S9S_MB_2U_LIB.S9S_MB_2U(SCH_1):PAGE177
   J41 OB12 REFCLKP2 SCONN168_ME1016810202011-SCONNA   I173 @S9S_MB_2U_LIB.S9S_MB_2U(SCH_1):PAGE227

SVID_ALERT0_CPU0_N @S9S_MB_2U_LIB.S9S_MB_2U(SCH_1):SVID_ALERT0_CPU0_N
    U2 BK26 SVIDALERT0_N SOCKET4677_AZIF0045P001C01CS-SA     I1 @S9S_MB_2U_LIB.S9S_MB_2U(SCH_1):PAGE14
   R14    1      A Q_RES_0402LF-200,1%,1/16W,CHIPA    I61 @S9S_MB_2U_LIB.S9S_MB_2U(SCH_1):PAGE14

SVID_ALERT0_CPU0_R_N @S9S_MB_2U_LIB.S9S_MB_2U(SCH_1):SVID_ALERT0_CPU0_R_N
   R14    2      B Q_RES_0402LF-200,1%,1/16W,CHIPA    I61 @S9S_MB_2U_LIB.S9S_MB_2U(SCH_1):PAGE14
  R548    1      A Q_RES_0402LF-49.9,1%,1/16W,CHIA    I94 @S9S_MB_2U_LIB.S9S_MB_2U(SCH_1):PAGE14
 R2389    1      A Q_RES_0402LF-0,5%,1/16W,CHIP,CA    I52 @S9S_MB_2U_LIB.S9S_MB_2U(SCH_1):PAGE260
 R2370    1      A Q_RES_0402LF-0,5%,1/16W,CHIP,CA    I41 @S9S_MB_2U_LIB.S9S_MB_2U(SCH_1):PAGE252
 R2382    1      A Q_RES_0402LF-49.9,1%,1/16W,EMPA   I123 @S9S_MB_2U_LIB.S9S_MB_2U(SCH_1):PAGE252

SVID_ALERT0_CPU1_N @S9S_MB_2U_LIB.S9S_MB_2U(SCH_1):SVID_ALERT0_CPU1_N
    U1 BK26 SVIDALERT0_N SOCKET4677_AZIF0045P001C01CS-SA    I29 @S9S_MB_2U_LIB.S9S_MB_2U(SCH_1):PAGE45
   R57    1      A Q_RES_0402LF-200,1%,1/16W,CHIPA    I56 @S9S_MB_2U_LIB.S9S_MB_2U(SCH_1):PAGE45

SVID_ALERT0_CPU1_R_N @S9S_MB_2U_LIB.S9S_MB_2U(SCH_1):SVID_ALERT0_CPU1_R_N
   R57    2      B Q_RES_0402LF-200,1%,1/16W,CHIPA    I56 @S9S_MB_2U_LIB.S9S_MB_2U(SCH_1):PAGE45
  R558    1      A Q_RES_0402LF-49.9,1%,1/16W,CHIA    I73 @S9S_MB_2U_LIB.S9S_MB_2U(SCH_1):PAGE45
 R2561    1      A Q_RES_0402LF-0,5%,1/16W,CHIP,CA    I59 @S9S_MB_2U_LIB.S9S_MB_2U(SCH_1):PAGE278
 R2555    1      A Q_RES_0402LF-49.9,1%,1/16W,EMPA   I101 @S9S_MB_2U_LIB.S9S_MB_2U(SCH_1):PAGE270
  R312    1      A Q_RES_0402LF-0,5%,1/16W,CHIP,CA    I57 @S9S_MB_2U_LIB.S9S_MB_2U(SCH_1):PAGE270

SVID_ALERT1_CPU0_N @S9S_MB_2U_LIB.S9S_MB_2U(SCH_1):SVID_ALERT1_CPU0_N
    U2 BJ25 SVIDALERT1_N SOCKET4677_AZIF0045P001C01CS-SA     I1 @S9S_MB_2U_LIB.S9S_MB_2U(SCH_1):PAGE14
   R17    1      A Q_RES_0402LF-200,1%,1/16W,CHIPA    I64 @S9S_MB_2U_LIB.S9S_MB_2U(SCH_1):PAGE14

SVID_ALERT1_CPU0_R_N @S9S_MB_2U_LIB.S9S_MB_2U(SCH_1):SVID_ALERT1_CPU0_R_N
   R17    2      B Q_RES_0402LF-200,1%,1/16W,CHIPA    I64 @S9S_MB_2U_LIB.S9S_MB_2U(SCH_1):PAGE14
  R556    1      A Q_RES_0402LF-49.9,1%,1/16W,CHIA   I100 @S9S_MB_2U_LIB.S9S_MB_2U(SCH_1):PAGE14
 R2401    1      A Q_RES_0402LF-0,5%,1/16W,CHIP,CA    I40 @S9S_MB_2U_LIB.S9S_MB_2U(SCH_1):PAGE264

SVID_ALERT1_CPU1_N @S9S_MB_2U_LIB.S9S_MB_2U(SCH_1):SVID_ALERT1_CPU1_N
    U1 BJ25 SVIDALERT1_N SOCKET4677_AZIF0045P001C01CS-SA    I29 @S9S_MB_2U_LIB.S9S_MB_2U(SCH_1):PAGE45
   R60    1      A Q_RES_0402LF-200,1%,1/16W,CHIPA    I53 @S9S_MB_2U_LIB.S9S_MB_2U(SCH_1):PAGE45

SVID_ALERT1_CPU1_R_N @S9S_MB_2U_LIB.S9S_MB_2U(SCH_1):SVID_ALERT1_CPU1_R_N
   R60    2      B Q_RES_0402LF-200,1%,1/16W,CHIPA    I53 @S9S_MB_2U_LIB.S9S_MB_2U(SCH_1):PAGE45
  R560    1      A Q_RES_0402LF-49.9,1%,1/16W,CHIA    I70 @S9S_MB_2U_LIB.S9S_MB_2U(SCH_1):PAGE45
 R2580    1      A Q_RES_0402LF-0,5%,1/16W,CHIP,CA    I40 @S9S_MB_2U_LIB.S9S_MB_2U(SCH_1):PAGE282

SVID_ALERT_PVCCD_HV_CPU0_R @S9S_MB_2U_LIB.S9S_MB_2U(SCH_1):SVID_ALERT_PVCCD_HV_CPU0_R
  PU35   19 NSVALERT# ISL69260IRAZT-ISL69260IRAZ-T,SA    I53 @S9S_MB_2U_LIB.S9S_MB_2U(SCH_1):PAGE264
 R2401    2      B Q_RES_0402LF-0,5%,1/16W,CHIP,CA    I40 @S9S_MB_2U_LIB.S9S_MB_2U(SCH_1):PAGE264

SVID_ALERT_PVCCD_HV_CPU1_R @S9S_MB_2U_LIB.S9S_MB_2U(SCH_1):SVID_ALERT_PVCCD_HV_CPU1_R
  PU18   19 NSVALERT# ISL69260IRAZT-ISL69260IRAZ-T,SA    I53 @S9S_MB_2U_LIB.S9S_MB_2U(SCH_1):PAGE282
 R2580    2      B Q_RES_0402LF-0,5%,1/16W,CHIP,CA    I40 @S9S_MB_2U_LIB.S9S_MB_2U(SCH_1):PAGE282

SVID_ALERT_PVCCINFAON_CPU0_R @S9S_MB_2U_LIB.S9S_MB_2U(SCH_1):SVID_ALERT_PVCCINFAON_CPU0_R
   PU5   19 NSVALERT# ISL69260IRAZT-ISL69260IRAZ-T,SA    I65 @S9S_MB_2U_LIB.S9S_MB_2U(SCH_1):PAGE260
 R2389    2      B Q_RES_0402LF-0,5%,1/16W,CHIP,CA    I52 @S9S_MB_2U_LIB.S9S_MB_2U(SCH_1):PAGE260

SVID_ALERT_PVCCINFAON_CPU1_R @S9S_MB_2U_LIB.S9S_MB_2U(SCH_1):SVID_ALERT_PVCCINFAON_CPU1_R
 R2561    2      B Q_RES_0402LF-0,5%,1/16W,CHIP,CA    I59 @S9S_MB_2U_LIB.S9S_MB_2U(SCH_1):PAGE278
  PU22   19 NSVALERT# ISL69260IRAZT-ISL69260IRAZ-T,SA    I38 @S9S_MB_2U_LIB.S9S_MB_2U(SCH_1):PAGE278

SVID_ALERT_PVCCIN_CPU0_R @S9S_MB_2U_LIB.S9S_MB_2U(SCH_1):SVID_ALERT_PVCCIN_CPU0_R
  PU14   23 NSVALERT RAA229126GNPHA0-RAA229126GNP#HA    I63 @S9S_MB_2U_LIB.S9S_MB_2U(SCH_1):PAGE252
 R2370    2      B Q_RES_0402LF-0,5%,1/16W,CHIP,CA    I41 @S9S_MB_2U_LIB.S9S_MB_2U(SCH_1):PAGE252

SVID_ALERT_PVCCIN_CPU1_R @S9S_MB_2U_LIB.S9S_MB_2U(SCH_1):SVID_ALERT_PVCCIN_CPU1_R
  PU29   23 NSVALERT RAA229126GNPHA0-RAA229126GNP#HA    I33 @S9S_MB_2U_LIB.S9S_MB_2U(SCH_1):PAGE270
  R312    2      B Q_RES_0402LF-0,5%,1/16W,CHIP,CA    I57 @S9S_MB_2U_LIB.S9S_MB_2U(SCH_1):PAGE270

SVID_CLK0_CPU0 @S9S_MB_2U_LIB.S9S_MB_2U(SCH_1):SVID_CLK0_CPU0
    U2 BH26 SVIDCLK0 SOCKET4677_AZIF0045P001C01CS-SA     I1 @S9S_MB_2U_LIB.S9S_MB_2U(SCH_1):PAGE14
   R13    1      A Q_RES_0402LF-0,5%,1/16W,CHIP,CA    I60 @S9S_MB_2U_LIB.S9S_MB_2U(SCH_1):PAGE14

SVID_CLK0_CPU0_R @S9S_MB_2U_LIB.S9S_MB_2U(SCH_1):SVID_CLK0_CPU0_R
   R13    2      B Q_RES_0402LF-0,5%,1/16W,CHIP,CA    I60 @S9S_MB_2U_LIB.S9S_MB_2U(SCH_1):PAGE14
 R2322    2      B Q_RES_0402LF-49.9,1%,1/16W,EMPA    I36 @S9S_MB_2U_LIB.S9S_MB_2U(SCH_1):PAGE260
 R2368    1      A Q_RES_0402LF-150,1%,1/16W,CHIPA    I44 @S9S_MB_2U_LIB.S9S_MB_2U(SCH_1):PAGE252
 R2381    1      A Q_RES_0402LF-49.9,1%,1/16W,CHIA   I125 @S9S_MB_2U_LIB.S9S_MB_2U(SCH_1):PAGE252
 R2596    1      A Q_RES_0402LF-150,1%,1/16W,CHIPA    I56 @S9S_MB_2U_LIB.S9S_MB_2U(SCH_1):PAGE260

SVID_CLK0_CPU1 @S9S_MB_2U_LIB.S9S_MB_2U(SCH_1):SVID_CLK0_CPU1
    U1 BH26 SVIDCLK0 SOCKET4677_AZIF0045P001C01CS-SA    I29 @S9S_MB_2U_LIB.S9S_MB_2U(SCH_1):PAGE45
   R56    1      A Q_RES_0402LF-0,5%,1/16W,CHIP,CA    I55 @S9S_MB_2U_LIB.S9S_MB_2U(SCH_1):PAGE45

SVID_CLK0_CPU1_R @S9S_MB_2U_LIB.S9S_MB_2U(SCH_1):SVID_CLK0_CPU1_R
   R56    2      B Q_RES_0402LF-0,5%,1/16W,CHIP,CA    I55 @S9S_MB_2U_LIB.S9S_MB_2U(SCH_1):PAGE45
 R2559    1      A Q_RES_0402LF-150,1%,1/16W,CHIPA    I61 @S9S_MB_2U_LIB.S9S_MB_2U(SCH_1):PAGE278
 R2345    2      B Q_RES_0402LF-49.9,1%,1/16W,EMPA    I15 @S9S_MB_2U_LIB.S9S_MB_2U(SCH_1):PAGE278
  R310    1      A Q_RES_0402LF-150,1%,1/16W,CHIPA    I58 @S9S_MB_2U_LIB.S9S_MB_2U(SCH_1):PAGE270
 R2554    1      A Q_RES_0402LF-49.9,1%,1/16W,CHIA   I100 @S9S_MB_2U_LIB.S9S_MB_2U(SCH_1):PAGE270

SVID_CLK1_CPU0 @S9S_MB_2U_LIB.S9S_MB_2U(SCH_1):SVID_CLK1_CPU0
    U2 BF26 SVIDCLK1 SOCKET4677_AZIF0045P001C01CS-SA     I1 @S9S_MB_2U_LIB.S9S_MB_2U(SCH_1):PAGE14
   R16    1      A Q_RES_0402LF-0,5%,1/16W,CHIP,CA    I63 @S9S_MB_2U_LIB.S9S_MB_2U(SCH_1):PAGE14

SVID_CLK1_CPU0_R @S9S_MB_2U_LIB.S9S_MB_2U(SCH_1):SVID_CLK1_CPU0_R
   R16    2      B Q_RES_0402LF-0,5%,1/16W,CHIP,CA    I63 @S9S_MB_2U_LIB.S9S_MB_2U(SCH_1):PAGE14
 R1717    2      B Q_RES_0402LF-49.9,1%,1/16W,CHIA    I25 @S9S_MB_2U_LIB.S9S_MB_2U(SCH_1):PAGE264
 R2399    1      A Q_RES_0402LF-150,1%,1/16W,CHIPA    I43 @S9S_MB_2U_LIB.S9S_MB_2U(SCH_1):PAGE264

SVID_CLK1_CPU1 @S9S_MB_2U_LIB.S9S_MB_2U(SCH_1):SVID_CLK1_CPU1
    U1 BF26 SVIDCLK1 SOCKET4677_AZIF0045P001C01CS-SA    I29 @S9S_MB_2U_LIB.S9S_MB_2U(SCH_1):PAGE45
   R59    1      A Q_RES_0402LF-0,5%,1/16W,CHIP,CA    I52 @S9S_MB_2U_LIB.S9S_MB_2U(SCH_1):PAGE45

SVID_CLK1_CPU1_R @S9S_MB_2U_LIB.S9S_MB_2U(SCH_1):SVID_CLK1_CPU1_R
   R59    2      B Q_RES_0402LF-0,5%,1/16W,CHIP,CA    I52 @S9S_MB_2U_LIB.S9S_MB_2U(SCH_1):PAGE45
 R1718    2      B Q_RES_0402LF-49.9,1%,1/16W,CHIA    I33 @S9S_MB_2U_LIB.S9S_MB_2U(SCH_1):PAGE282
 R2578    1      A Q_RES_0402LF-150,1%,1/16W,CHIPA    I42 @S9S_MB_2U_LIB.S9S_MB_2U(SCH_1):PAGE282

SVID_CLK_PVCCD_HV_CPU0_R @S9S_MB_2U_LIB.S9S_MB_2U(SCH_1):SVID_CLK_PVCCD_HV_CPU0_R
  PU35   17  SVCLK ISL69260IRAZT-ISL69260IRAZ-T,SA    I53 @S9S_MB_2U_LIB.S9S_MB_2U(SCH_1):PAGE264
 R2399    2      B Q_RES_0402LF-150,1%,1/16W,CHIPA    I43 @S9S_MB_2U_LIB.S9S_MB_2U(SCH_1):PAGE264

SVID_CLK_PVCCD_HV_CPU1_R @S9S_MB_2U_LIB.S9S_MB_2U(SCH_1):SVID_CLK_PVCCD_HV_CPU1_R
  PU18   17  SVCLK ISL69260IRAZT-ISL69260IRAZ-T,SA    I53 @S9S_MB_2U_LIB.S9S_MB_2U(SCH_1):PAGE282
 R2578    2      B Q_RES_0402LF-150,1%,1/16W,CHIPA    I42 @S9S_MB_2U_LIB.S9S_MB_2U(SCH_1):PAGE282

SVID_CLK_PVCCINFAON_CPU0_R @S9S_MB_2U_LIB.S9S_MB_2U(SCH_1):SVID_CLK_PVCCINFAON_CPU0_R
   PU5   17  SVCLK ISL69260IRAZT-ISL69260IRAZ-T,SA    I65 @S9S_MB_2U_LIB.S9S_MB_2U(SCH_1):PAGE260
 R2596    2      B Q_RES_0402LF-150,1%,1/16W,CHIPA    I56 @S9S_MB_2U_LIB.S9S_MB_2U(SCH_1):PAGE260

SVID_CLK_PVCCINFAON_CPU1_R @S9S_MB_2U_LIB.S9S_MB_2U(SCH_1):SVID_CLK_PVCCINFAON_CPU1_R
 R2559    2      B Q_RES_0402LF-150,1%,1/16W,CHIPA    I61 @S9S_MB_2U_LIB.S9S_MB_2U(SCH_1):PAGE278
  PU22   17  SVCLK ISL69260IRAZT-ISL69260IRAZ-T,SA    I38 @S9S_MB_2U_LIB.S9S_MB_2U(SCH_1):PAGE278

SVID_CLK_PVCCIN_CPU0_R @S9S_MB_2U_LIB.S9S_MB_2U(SCH_1):SVID_CLK_PVCCIN_CPU0_R
  PU14   21  SVCLK RAA229126GNPHA0-RAA229126GNP#HA    I63 @S9S_MB_2U_LIB.S9S_MB_2U(SCH_1):PAGE252
 R2368    2      B Q_RES_0402LF-150,1%,1/16W,CHIPA    I44 @S9S_MB_2U_LIB.S9S_MB_2U(SCH_1):PAGE252

SVID_CLK_PVCCIN_CPU1_R @S9S_MB_2U_LIB.S9S_MB_2U(SCH_1):SVID_CLK_PVCCIN_CPU1_R
  R310    2      B Q_RES_0402LF-150,1%,1/16W,CHIPA    I58 @S9S_MB_2U_LIB.S9S_MB_2U(SCH_1):PAGE270
  PU29   21  SVCLK RAA229126GNPHA0-RAA229126GNP#HA    I33 @S9S_MB_2U_LIB.S9S_MB_2U(SCH_1):PAGE270

SVID_DIO0_CPU0 @S9S_MB_2U_LIB.S9S_MB_2U(SCH_1):SVID_DIO0_CPU0
    U2 BD26 SVIDDATA0 SOCKET4677_AZIF0045P001C01CS-SA     I1 @S9S_MB_2U_LIB.S9S_MB_2U(SCH_1):PAGE14
   R12    1      A Q_RES_0402LF-0,5%,1/16W,CHIP,CA    I59 @S9S_MB_2U_LIB.S9S_MB_2U(SCH_1):PAGE14

SVID_DIO0_CPU0_R @S9S_MB_2U_LIB.S9S_MB_2U(SCH_1):SVID_DIO0_CPU0_R
   R12    2      B Q_RES_0402LF-0,5%,1/16W,CHIP,CA    I59 @S9S_MB_2U_LIB.S9S_MB_2U(SCH_1):PAGE14
  R328    1      A Q_RES_0402LF-100,1%,1/16W,CHIPA    I93 @S9S_MB_2U_LIB.S9S_MB_2U(SCH_1):PAGE14
 R2386    2      B Q_RES_0402LF-100,1%,1/16W,EMPTA    I37 @S9S_MB_2U_LIB.S9S_MB_2U(SCH_1):PAGE260
 R2388    1      A Q_RES_0402LF-0,5%,1/16W,CHIP,CA    I57 @S9S_MB_2U_LIB.S9S_MB_2U(SCH_1):PAGE260
 R2369    1      A Q_RES_0402LF-0,5%,1/16W,CHIP,CA    I43 @S9S_MB_2U_LIB.S9S_MB_2U(SCH_1):PAGE252
 R2590    1      A Q_RES_0402LF-100,1%,1/16W,CHIPA   I124 @S9S_MB_2U_LIB.S9S_MB_2U(SCH_1):PAGE252

SVID_DIO0_CPU1 @S9S_MB_2U_LIB.S9S_MB_2U(SCH_1):SVID_DIO0_CPU1
    U1 BD26 SVIDDATA0 SOCKET4677_AZIF0045P001C01CS-SA    I29 @S9S_MB_2U_LIB.S9S_MB_2U(SCH_1):PAGE45
   R55    1      A Q_RES_0402LF-0,5%,1/16W,CHIP,CA    I54 @S9S_MB_2U_LIB.S9S_MB_2U(SCH_1):PAGE45

SVID_DIO0_CPU1_R @S9S_MB_2U_LIB.S9S_MB_2U(SCH_1):SVID_DIO0_CPU1_R
   R55    2      B Q_RES_0402LF-0,5%,1/16W,CHIP,CA    I54 @S9S_MB_2U_LIB.S9S_MB_2U(SCH_1):PAGE45
  R557    1      A Q_RES_0402LF-100,1%,1/16W,CHIPA    I74 @S9S_MB_2U_LIB.S9S_MB_2U(SCH_1):PAGE45
 R2560    1      A Q_RES_0402LF-0,5%,1/16W,CHIP,CA    I60 @S9S_MB_2U_LIB.S9S_MB_2U(SCH_1):PAGE278
 R2354    2      B Q_RES_0402LF-100,1%,1/16W,EMPTA    I14 @S9S_MB_2U_LIB.S9S_MB_2U(SCH_1):PAGE278
  R311    1      A Q_RES_0402LF-0,5%,1/16W,CHIP,CA    I56 @S9S_MB_2U_LIB.S9S_MB_2U(SCH_1):PAGE270
 R2553    1      A Q_RES_0402LF-100,1%,1/16W,CHIPA    I99 @S9S_MB_2U_LIB.S9S_MB_2U(SCH_1):PAGE270

SVID_DIO1_CPU0 @S9S_MB_2U_LIB.S9S_MB_2U(SCH_1):SVID_DIO1_CPU0
    U2 BL25 SVIDDATA1 SOCKET4677_AZIF0045P001C01CS-SA     I1 @S9S_MB_2U_LIB.S9S_MB_2U(SCH_1):PAGE14
   R15    1      A Q_RES_0402LF-0,5%,1/16W,CHIP,CA    I62 @S9S_MB_2U_LIB.S9S_MB_2U(SCH_1):PAGE14

SVID_DIO1_CPU0_R @S9S_MB_2U_LIB.S9S_MB_2U(SCH_1):SVID_DIO1_CPU0_R
   R15    2      B Q_RES_0402LF-0,5%,1/16W,CHIP,CA    I62 @S9S_MB_2U_LIB.S9S_MB_2U(SCH_1):PAGE14
  R555    1      A Q_RES_0402LF-100,1%,1/16W,CHIPA    I98 @S9S_MB_2U_LIB.S9S_MB_2U(SCH_1):PAGE14
 R2400    1      A Q_RES_0402LF-0,5%,1/16W,CHIP,CA    I42 @S9S_MB_2U_LIB.S9S_MB_2U(SCH_1):PAGE264
 R1735    2      B Q_RES_0402LF-100,1%,1/16W,CHIPA    I24 @S9S_MB_2U_LIB.S9S_MB_2U(SCH_1):PAGE264

SVID_DIO1_CPU1 @S9S_MB_2U_LIB.S9S_MB_2U(SCH_1):SVID_DIO1_CPU1
    U1 BL25 SVIDDATA1 SOCKET4677_AZIF0045P001C01CS-SA    I29 @S9S_MB_2U_LIB.S9S_MB_2U(SCH_1):PAGE45
   R58    1      A Q_RES_0402LF-0,5%,1/16W,CHIP,CA    I51 @S9S_MB_2U_LIB.S9S_MB_2U(SCH_1):PAGE45

SVID_DIO1_CPU1_R @S9S_MB_2U_LIB.S9S_MB_2U(SCH_1):SVID_DIO1_CPU1_R
   R58    2      B Q_RES_0402LF-0,5%,1/16W,CHIP,CA    I51 @S9S_MB_2U_LIB.S9S_MB_2U(SCH_1):PAGE45
  R559    1      A Q_RES_0402LF-100,1%,1/16W,CHIPA    I69 @S9S_MB_2U_LIB.S9S_MB_2U(SCH_1):PAGE45
 R2593    2      B Q_RES_0402LF-100,1%,1/16W,CHIPA    I29 @S9S_MB_2U_LIB.S9S_MB_2U(SCH_1):PAGE282
 R2579    1      A Q_RES_0402LF-0,5%,1/16W,CHIP,CA    I41 @S9S_MB_2U_LIB.S9S_MB_2U(SCH_1):PAGE282

SVID_DIO_PVCCD_HV_CPU0_R @S9S_MB_2U_LIB.S9S_MB_2U(SCH_1):SVID_DIO_PVCCD_HV_CPU0_R
  PU35   18 SVDATA ISL69260IRAZT-ISL69260IRAZ-T,SA    I53 @S9S_MB_2U_LIB.S9S_MB_2U(SCH_1):PAGE264
 R2400    2      B Q_RES_0402LF-0,5%,1/16W,CHIP,CA    I42 @S9S_MB_2U_LIB.S9S_MB_2U(SCH_1):PAGE264

SVID_DIO_PVCCD_HV_CPU1_R @S9S_MB_2U_LIB.S9S_MB_2U(SCH_1):SVID_DIO_PVCCD_HV_CPU1_R
  PU18   18 SVDATA ISL69260IRAZT-ISL69260IRAZ-T,SA    I53 @S9S_MB_2U_LIB.S9S_MB_2U(SCH_1):PAGE282
 R2579    2      B Q_RES_0402LF-0,5%,1/16W,CHIP,CA    I41 @S9S_MB_2U_LIB.S9S_MB_2U(SCH_1):PAGE282

SVID_DIO_PVCCINFAON_CPU0_R @S9S_MB_2U_LIB.S9S_MB_2U(SCH_1):SVID_DIO_PVCCINFAON_CPU0_R
   PU5   18 SVDATA ISL69260IRAZT-ISL69260IRAZ-T,SA    I65 @S9S_MB_2U_LIB.S9S_MB_2U(SCH_1):PAGE260
 R2388    2      B Q_RES_0402LF-0,5%,1/16W,CHIP,CA    I57 @S9S_MB_2U_LIB.S9S_MB_2U(SCH_1):PAGE260

SVID_DIO_PVCCINFAON_CPU1_R @S9S_MB_2U_LIB.S9S_MB_2U(SCH_1):SVID_DIO_PVCCINFAON_CPU1_R
 R2560    2      B Q_RES_0402LF-0,5%,1/16W,CHIP,CA    I60 @S9S_MB_2U_LIB.S9S_MB_2U(SCH_1):PAGE278
  PU22   18 SVDATA ISL69260IRAZT-ISL69260IRAZ-T,SA    I38 @S9S_MB_2U_LIB.S9S_MB_2U(SCH_1):PAGE278

SVID_DIO_PVCCIN_CPU0_R @S9S_MB_2U_LIB.S9S_MB_2U(SCH_1):SVID_DIO_PVCCIN_CPU0_R
  PU14   22 SVDATA RAA229126GNPHA0-RAA229126GNP#HA    I63 @S9S_MB_2U_LIB.S9S_MB_2U(SCH_1):PAGE252
 R2369    2      B Q_RES_0402LF-0,5%,1/16W,CHIP,CA    I43 @S9S_MB_2U_LIB.S9S_MB_2U(SCH_1):PAGE252

SVID_DIO_PVCCIN_CPU1_R @S9S_MB_2U_LIB.S9S_MB_2U(SCH_1):SVID_DIO_PVCCIN_CPU1_R
  PU29   22 SVDATA RAA229126GNPHA0-RAA229126GNP#HA    I33 @S9S_MB_2U_LIB.S9S_MB_2U(SCH_1):PAGE270
  R311    2      B Q_RES_0402LF-0,5%,1/16W,CHIP,CA    I56 @S9S_MB_2U_LIB.S9S_MB_2U(SCH_1):PAGE270

SWB_HSC_EN @S9S_MB_2U_LIB.S9S_MB_2U(SCH_1):SWB_HSC_EN
 R4558    1      A Q_RES_0402LF-33.2,1%,1/16W,CHIA   I150 @S9S_MB_2U_LIB.S9S_MB_2U(SCH_1):PAGE312
  U316    1     A0 74LVC2G17GW-74LVC2G17GW,SMLF,IA    I86 @S9S_MB_2U_LIB.S9S_MB_2U(SCH_1):PAGE139
 R4548    1      A Q_RES_0402LF-100K,1%,1/16W,CHIA    I87 @S9S_MB_2U_LIB.S9S_MB_2U(SCH_1):PAGE139
 R4547    2      B Q_RES_0402LF-100K,1%,1/16W,EMPA    I89 @S9S_MB_2U_LIB.S9S_MB_2U(SCH_1):PAGE139

SWB_HSC_EN_BUF @S9S_MB_2U_LIB.S9S_MB_2U(SCH_1):SWB_HSC_EN_BUF
  J107   N8     N8 CONN112_10137002101LF-CONN112_A    I38 @S9S_MB_2U_LIB.S9S_MB_2U(SCH_1):PAGE317
 R4550    2      B Q_RES_0402LF-49.9,1%,1/16W,CHIA   I110 @S9S_MB_2U_LIB.S9S_MB_2U(SCH_1):PAGE139

SWB_HSC_EN_BUF_R @S9S_MB_2U_LIB.S9S_MB_2U(SCH_1):SWB_HSC_EN_BUF_R
  U316    6     B0 74LVC2G17GW-74LVC2G17GW,SMLF,IA    I86 @S9S_MB_2U_LIB.S9S_MB_2U(SCH_1):PAGE139
 R4549    2      B Q_RES_0402LF-4.7K,5%,1/16W,EMPA    I98 @S9S_MB_2U_LIB.S9S_MB_2U(SCH_1):PAGE139
 R4555    1      A Q_RES_0402LF-4.7K,5%,1/16W,EMPA    I99 @S9S_MB_2U_LIB.S9S_MB_2U(SCH_1):PAGE139
 R4550    1      A Q_RES_0402LF-49.9,1%,1/16W,CHIA   I110 @S9S_MB_2U_LIB.S9S_MB_2U(SCH_1):PAGE139

SWB_HSC_EN_R @S9S_MB_2U_LIB.S9S_MB_2U(SCH_1):SWB_HSC_EN_R
  U249  Y19  PB44C LCMXO3LF9400C5BG484C-LCMXO3LF-A     I1 @S9S_MB_2U_LIB.S9S_MB_2U(SCH_1):PAGE312
 R4558    2      B Q_RES_0402LF-33.2,1%,1/16W,CHIA   I150 @S9S_MB_2U_LIB.S9S_MB_2U(SCH_1):PAGE312

SWB_HSC_PWRGD @S9S_MB_2U_LIB.S9S_MB_2U(SCH_1):SWB_HSC_PWRGD
  J107   A7     A7 CONN112_10137002101LF-CONN112_A    I38 @S9S_MB_2U_LIB.S9S_MB_2U(SCH_1):PAGE317
  Q146    2     G1 MOSFET_NCH_DUAL-PJT138K,SMLF,IA   I126 @S9S_MB_2U_LIB.S9S_MB_2U(SCH_1):PAGE143
 R4559    1      A Q_RES_0402LF-100K,1%,1/16W,CHIA   I129 @S9S_MB_2U_LIB.S9S_MB_2U(SCH_1):PAGE143
 R4562    2      B Q_RES_0402LF-100K,1%,1/16W,EMPA   I132 @S9S_MB_2U_LIB.S9S_MB_2U(SCH_1):PAGE143

SWB_HSC_PWRGD_ISO @S9S_MB_2U_LIB.S9S_MB_2U(SCH_1):SWB_HSC_PWRGD_ISO
 R4561    2      B Q_RES_0402LF-4.7K,5%,1/16W,CHIA   I116 @S9S_MB_2U_LIB.S9S_MB_2U(SCH_1):PAGE143
 C2343    1      A Q_CAP_0402-1000PF,50V,5%,EMPTYA   I118 @S9S_MB_2U_LIB.S9S_MB_2U(SCH_1):PAGE143
  Q146    3     D2 MOSFET_NCH_DUAL-PJT138K,SMLF,IA   I121 @S9S_MB_2U_LIB.S9S_MB_2U(SCH_1):PAGE143
 R4563    2      B Q_RES_0402LF-33.2,1%,1/16W,CHIA   I158 @S9S_MB_2U_LIB.S9S_MB_2U(SCH_1):PAGE312

SWB_HSC_PWRGD_ISO_R @S9S_MB_2U_LIB.S9S_MB_2U(SCH_1):SWB_HSC_PWRGD_ISO_R
  U249  W18  PB44D LCMXO3LF9400C5BG484C-LCMXO3LF-A     I1 @S9S_MB_2U_LIB.S9S_MB_2U(SCH_1):PAGE312
 R4563    1      A Q_RES_0402LF-33.2,1%,1/16W,CHIA   I158 @S9S_MB_2U_LIB.S9S_MB_2U(SCH_1):PAGE312

SWB_HSC_PWRGD_N @S9S_MB_2U_LIB.S9S_MB_2U(SCH_1):SWB_HSC_PWRGD_N
  Q146    5     G2 MOSFET_NCH_DUAL-PJT138K,SMLF,IA   I121 @S9S_MB_2U_LIB.S9S_MB_2U(SCH_1):PAGE143
 R4560    2      B Q_RES_0402LF-4.7K,5%,1/16W,CHIA   I124 @S9S_MB_2U_LIB.S9S_MB_2U(SCH_1):PAGE143
  Q146    6     D1 MOSFET_NCH_DUAL-PJT138K,SMLF,IA   I126 @S9S_MB_2U_LIB.S9S_MB_2U(SCH_1):PAGE143

SW_P12V_AUX_P1V05_PCH_AUX_FLT @S9S_MB_2U_LIB.S9S_MB_2U(SCH_1):SW_P12V_AUX_P1V05_PCH_AUX_FLT
PC1219    1      A Q_CAP_C0402-1UF,16V,10%,X6S,CHA    I30 @S9S_MB_2U_LIB.S9S_MB_2U(SCH_1):PAGE248
PC1215    1      A Q_CAPP_SMLF-100UF,16V,20%,OSCOA    I23 @S9S_MB_2U_LIB.S9S_MB_2U(SCH_1):PAGE248
PC1218    1      A Q_CAP_C0805-22UF,16V,20%,X6S,CA    I29 @S9S_MB_2U_LIB.S9S_MB_2U(SCH_1):PAGE248
  PU73   10   VIN1 RS53319LR-RS53319LR,SMLF,IC,ALA    I11 @S9S_MB_2U_LIB.S9S_MB_2U(SCH_1):PAGE248
  PU73   21   VIN2 RS53319LR-RS53319LR,SMLF,IC,ALA    I11 @S9S_MB_2U_LIB.S9S_MB_2U(SCH_1):PAGE248
PC1217    1      A Q_CAP_C0805-22UF,16V,20%,X6S,CA    I28 @S9S_MB_2U_LIB.S9S_MB_2U(SCH_1):PAGE248
 PL110    2      2 Q_INDUCTOR_SMLF-100NH/16A,IND,A    I19 @S9S_MB_2U_LIB.S9S_MB_2U(SCH_1):PAGE248
PC1216    1      A Q_CAP_C0805-22UF,16V,20%,X6S,CA    I25 @S9S_MB_2U_LIB.S9S_MB_2U(SCH_1):PAGE248

SW_P12V_PVCCFA_EHV_FIVRA_CPU0_L @S9S_MB_2U_LIB.S9S_MB_2U(SCH_1):SW_P12V_PVCCFA_EHV_FIVRA_CPU0_L
PC1182_P0_4    1      A Q_CAP_C0805-22UF,16V,20%,X6S,CA    I36 @S9S_MB_2U_LIB.S9S_MB_2U(SCH_1):PAGE258
PC603_P0_2    1      A Q_CAP_0402-3300PF,50V,10%,X7R,A    I27 @S9S_MB_2U_LIB.S9S_MB_2U(SCH_1):PAGE257
PC723_P0_4    1      A Q_CAP_C0805-22UF,16V,20%,X6S,CA    I41 @S9S_MB_2U_LIB.S9S_MB_2U(SCH_1):PAGE258
PC1670    1      A Q_CAP_C0805-22UF,16V,20%,X6S,CA    I84 @S9S_MB_2U_LIB.S9S_MB_2U(SCH_1):PAGE257
PC1174_P0_4    1      A Q_CAP_0402-3300PF,50V,10%,X7R,A    I31 @S9S_MB_2U_LIB.S9S_MB_2U(SCH_1):PAGE258
PU70_P0_2 25_29   VIN1 ISL99390FRZTR5935-ISL99390FRZ-A    I16 @S9S_MB_2U_LIB.S9S_MB_2U(SCH_1):PAGE257
PU70_P0_2   30   VIN2 ISL99390FRZTR5935-ISL99390FRZ-A    I16 @S9S_MB_2U_LIB.S9S_MB_2U(SCH_1):PAGE257
PC609_P0_2    1      A Q_CAP_C0805-22UF,16V,20%,X6S,CA    I31 @S9S_MB_2U_LIB.S9S_MB_2U(SCH_1):PAGE257
  PL44    2      2 Q_INDUCTOR_SMLF-100NH/16A,IND,A    I80 @S9S_MB_2U_LIB.S9S_MB_2U(SCH_1):PAGE257
PC1669    1      A Q_CAP_C0805-22UF,16V,20%,X6S,CA    I83 @S9S_MB_2U_LIB.S9S_MB_2U(SCH_1):PAGE257
PC1671    1      A Q_CAP_C0805-22UF,16V,20%,X6S,CA    I85 @S9S_MB_2U_LIB.S9S_MB_2U(SCH_1):PAGE257
PC605_P0_2    1      A Q_CAP_C0402-1UF,16V,10%,X6S,CHA    I28 @S9S_MB_2U_LIB.S9S_MB_2U(SCH_1):PAGE257
PC611_P0_2    1      A Q_CAP_C0805-22UF,16V,20%,X6S,CA    I32 @S9S_MB_2U_LIB.S9S_MB_2U(SCH_1):PAGE257
PC721_P0_2    1      A Q_CAP_C0805-22UF,16V,20%,X6S,CA    I55 @S9S_MB_2U_LIB.S9S_MB_2U(SCH_1):PAGE257
PC1672    1      A Q_CAP_C0805-22UF,16V,20%,X6S,CA    I86 @S9S_MB_2U_LIB.S9S_MB_2U(SCH_1):PAGE257
 PC622    1      A Q_CAPP_THLF-270UF,16V,20%,OSCOA    I88 @S9S_MB_2U_LIB.S9S_MB_2U(SCH_1):PAGE257
PU72_P0_4 25_29   VIN1 ISL99390FRZTR5935-ISL99390FRZ-A    I10 @S9S_MB_2U_LIB.S9S_MB_2U(SCH_1):PAGE258
PU72_P0_4   30   VIN2 ISL99390FRZTR5935-ISL99390FRZ-A    I10 @S9S_MB_2U_LIB.S9S_MB_2U(SCH_1):PAGE258
PC1176_P0_4    1      A Q_CAP_C0402-1UF,16V,10%,X6S,CHA    I34 @S9S_MB_2U_LIB.S9S_MB_2U(SCH_1):PAGE258
PC1180_P0_4    1      A Q_CAP_C0805-22UF,16V,20%,X6S,CA    I35 @S9S_MB_2U_LIB.S9S_MB_2U(SCH_1):PAGE258

SW_P12V_PVCCFA_EHV_FIVRA_CPU0_R @S9S_MB_2U_LIB.S9S_MB_2U(SCH_1):SW_P12V_PVCCFA_EHV_FIVRA_CPU0_R
PC610_P0_1    1      A Q_CAP_C0805-22UF,16V,20%,X6S,CA    I48 @S9S_MB_2U_LIB.S9S_MB_2U(SCH_1):PAGE257
PC1173_P0_3    1      A Q_CAP_0402-3300PF,50V,10%,X7R,A    I44 @S9S_MB_2U_LIB.S9S_MB_2U(SCH_1):PAGE258
PC1175_P0_3    1      A Q_CAP_C0402-1UF,16V,10%,X6S,CHA    I46 @S9S_MB_2U_LIB.S9S_MB_2U(SCH_1):PAGE258
PC602_P0_1    1      A Q_CAP_0402-3300PF,50V,10%,X7R,A    I44 @S9S_MB_2U_LIB.S9S_MB_2U(SCH_1):PAGE257
PC604_P0_1    1      A Q_CAP_C0402-1UF,16V,10%,X6S,CHA    I45 @S9S_MB_2U_LIB.S9S_MB_2U(SCH_1):PAGE257
PC1675    1      A Q_CAP_C0805-22UF,16V,20%,X6S,CA    I77 @S9S_MB_2U_LIB.S9S_MB_2U(SCH_1):PAGE258
PC608_P0_1    1      A Q_CAP_C0805-22UF,16V,20%,X6S,CA    I47 @S9S_MB_2U_LIB.S9S_MB_2U(SCH_1):PAGE257
PC1674    1      A Q_CAP_C0805-22UF,16V,20%,X6S,CA    I76 @S9S_MB_2U_LIB.S9S_MB_2U(SCH_1):PAGE258
PC1181_P0_3    1      A Q_CAP_C0805-22UF,16V,20%,X6S,CA    I48 @S9S_MB_2U_LIB.S9S_MB_2U(SCH_1):PAGE258
PC1673    1      A Q_CAP_C0805-22UF,16V,20%,X6S,CA    I75 @S9S_MB_2U_LIB.S9S_MB_2U(SCH_1):PAGE258
PC1189    1      A Q_CAPP_THLF-270UF,16V,20%,OSCOA    I80 @S9S_MB_2U_LIB.S9S_MB_2U(SCH_1):PAGE258
PU71_P0_3 25_29   VIN1 ISL99390FRZTR5935-ISL99390FRZ-A    I82 @S9S_MB_2U_LIB.S9S_MB_2U(SCH_1):PAGE258
PU71_P0_3   30   VIN2 ISL99390FRZTR5935-ISL99390FRZ-A    I82 @S9S_MB_2U_LIB.S9S_MB_2U(SCH_1):PAGE258
PU69_P0_1 25_29   VIN1 ISL99390FRZTR5935-ISL99390FRZ-A    I25 @S9S_MB_2U_LIB.S9S_MB_2U(SCH_1):PAGE257
PU69_P0_1   30   VIN2 ISL99390FRZTR5935-ISL99390FRZ-A    I25 @S9S_MB_2U_LIB.S9S_MB_2U(SCH_1):PAGE257
PC720_P0_1    1      A Q_CAP_C0805-22UF,16V,20%,X6S,CA    I73 @S9S_MB_2U_LIB.S9S_MB_2U(SCH_1):PAGE257
PC1179_P0_3    1      A Q_CAP_C0805-22UF,16V,20%,X6S,CA    I47 @S9S_MB_2U_LIB.S9S_MB_2U(SCH_1):PAGE258
PC722_P0_3    1      A Q_CAP_C0805-22UF,16V,20%,X6S,CA    I53 @S9S_MB_2U_LIB.S9S_MB_2U(SCH_1):PAGE258
 PL101    2      2 Q_INDUCTOR_SMLF-100NH/16A,IND,A    I59 @S9S_MB_2U_LIB.S9S_MB_2U(SCH_1):PAGE258
PC1676    1      A Q_CAP_C0805-22UF,16V,20%,X6S,CA    I79 @S9S_MB_2U_LIB.S9S_MB_2U(SCH_1):PAGE258

SW_P12V_PVCCFA_EHV_FIVRA_CPU1_L @S9S_MB_2U_LIB.S9S_MB_2U(SCH_1):SW_P12V_PVCCFA_EHV_FIVRA_CPU1_L
PC1194_P1_4    1      A Q_CAP_0402-3300PF,50V,10%,X7R,A    I33 @S9S_MB_2U_LIB.S9S_MB_2U(SCH_1):PAGE276
PC1200_P1_4    1      A Q_CAP_C0805-22UF,16V,20%,X6S,CA    I36 @S9S_MB_2U_LIB.S9S_MB_2U(SCH_1):PAGE276
PU76_P1_2 25_29   VIN1 ISL99390FRZTR5935-ISL99390FRZ-A     I9 @S9S_MB_2U_LIB.S9S_MB_2U(SCH_1):PAGE275
PU76_P1_2   30   VIN2 ISL99390FRZTR5935-ISL99390FRZ-A     I9 @S9S_MB_2U_LIB.S9S_MB_2U(SCH_1):PAGE275
PC398_P1_2    1      A Q_CAP_0402-3300PF,50V,10%,X7R,A    I37 @S9S_MB_2U_LIB.S9S_MB_2U(SCH_1):PAGE275
PC400_P1_2    1      A Q_CAP_C0402-1UF,16V,10%,X6S,CHA    I39 @S9S_MB_2U_LIB.S9S_MB_2U(SCH_1):PAGE275
PC725_P1_2    1      A Q_CAP_C0805-22UF,16V,20%,X6S,CA    I46 @S9S_MB_2U_LIB.S9S_MB_2U(SCH_1):PAGE275
PC1679    1      A Q_CAP_C0805-22UF,16V,20%,X6S,CA    I84 @S9S_MB_2U_LIB.S9S_MB_2U(SCH_1):PAGE275
PC404_P1_2    1      A Q_CAP_C0805-22UF,16V,20%,X6S,CA    I40 @S9S_MB_2U_LIB.S9S_MB_2U(SCH_1):PAGE275
PC1678    1      A Q_CAP_C0805-22UF,16V,20%,X6S,CA    I83 @S9S_MB_2U_LIB.S9S_MB_2U(SCH_1):PAGE275
PU78_P1_4 25_29   VIN1 ISL99390FRZTR5935-ISL99390FRZ-A    I15 @S9S_MB_2U_LIB.S9S_MB_2U(SCH_1):PAGE276
PU78_P1_4   30   VIN2 ISL99390FRZTR5935-ISL99390FRZ-A    I15 @S9S_MB_2U_LIB.S9S_MB_2U(SCH_1):PAGE276
PC1202_P1_4    1      A Q_CAP_C0805-22UF,16V,20%,X6S,CA    I37 @S9S_MB_2U_LIB.S9S_MB_2U(SCH_1):PAGE276
PC1677    1      A Q_CAP_C0805-22UF,16V,20%,X6S,CA    I80 @S9S_MB_2U_LIB.S9S_MB_2U(SCH_1):PAGE275
PC1196_P1_4    1      A Q_CAP_C0402-1UF,16V,10%,X6S,CHA    I35 @S9S_MB_2U_LIB.S9S_MB_2U(SCH_1):PAGE276
PC727_P1_4    1      A Q_CAP_C0805-22UF,16V,20%,X6S,CA    I52 @S9S_MB_2U_LIB.S9S_MB_2U(SCH_1):PAGE276
PC406_P1_2    1      A Q_CAP_C0805-22UF,16V,20%,X6S,CA    I42 @S9S_MB_2U_LIB.S9S_MB_2U(SCH_1):PAGE275
  PL43    2      2 Q_INDUCTOR_SMLF-100NH/16A,IND,A    I79 @S9S_MB_2U_LIB.S9S_MB_2U(SCH_1):PAGE275
PC1680    1      A Q_CAP_C0805-22UF,16V,20%,X6S,CA    I85 @S9S_MB_2U_LIB.S9S_MB_2U(SCH_1):PAGE275
 PC417    1      A Q_CAPP_THLF-270UF,16V,20%,OSCOA    I87 @S9S_MB_2U_LIB.S9S_MB_2U(SCH_1):PAGE275

SW_P12V_PVCCFA_EHV_FIVRA_CPU1_R @S9S_MB_2U_LIB.S9S_MB_2U(SCH_1):SW_P12V_PVCCFA_EHV_FIVRA_CPU1_R
PC1682    1      A Q_CAP_C0805-22UF,16V,20%,X6S,CA    I77 @S9S_MB_2U_LIB.S9S_MB_2U(SCH_1):PAGE276
PC397_P1_1    1      A Q_CAP_0402-3300PF,50V,10%,X7R,A    I49 @S9S_MB_2U_LIB.S9S_MB_2U(SCH_1):PAGE275
PC1193_P1_3    1      A Q_CAP_0402-3300PF,50V,10%,X7R,A    I38 @S9S_MB_2U_LIB.S9S_MB_2U(SCH_1):PAGE276
PC1199_P1_3    1      A Q_CAP_C0805-22UF,16V,20%,X6S,CA    I41 @S9S_MB_2U_LIB.S9S_MB_2U(SCH_1):PAGE276
PC399_P1_1    1      A Q_CAP_C0402-1UF,16V,10%,X6S,CHA    I51 @S9S_MB_2U_LIB.S9S_MB_2U(SCH_1):PAGE275
PC403_P1_1    1      A Q_CAP_C0805-22UF,16V,20%,X6S,CA    I52 @S9S_MB_2U_LIB.S9S_MB_2U(SCH_1):PAGE275
PC1195_P1_3    1      A Q_CAP_C0402-1UF,16V,10%,X6S,CHA    I39 @S9S_MB_2U_LIB.S9S_MB_2U(SCH_1):PAGE276
PC1201_P1_3    1      A Q_CAP_C0805-22UF,16V,20%,X6S,CA    I42 @S9S_MB_2U_LIB.S9S_MB_2U(SCH_1):PAGE276
  PL14    2      2 Q_INDUCTOR_SMLF-100NH/16A,IND,A    I64 @S9S_MB_2U_LIB.S9S_MB_2U(SCH_1):PAGE276
PC1684    1      A Q_CAP_C0805-22UF,16V,20%,X6S,CA    I80 @S9S_MB_2U_LIB.S9S_MB_2U(SCH_1):PAGE276
PC405_P1_1    1      A Q_CAP_C0805-22UF,16V,20%,X6S,CA    I56 @S9S_MB_2U_LIB.S9S_MB_2U(SCH_1):PAGE275
PU77_P1_3 25_29   VIN1 ISL99390FRZTR5935-ISL99390FRZ-A    I24 @S9S_MB_2U_LIB.S9S_MB_2U(SCH_1):PAGE276
PU77_P1_3   30   VIN2 ISL99390FRZTR5935-ISL99390FRZ-A    I24 @S9S_MB_2U_LIB.S9S_MB_2U(SCH_1):PAGE276
PC724_P1_1    1      A Q_CAP_C0805-22UF,16V,20%,X6S,CA    I58 @S9S_MB_2U_LIB.S9S_MB_2U(SCH_1):PAGE275
PU75_P1_1 25_29   VIN1 ISL99390FRZTR5935-ISL99390FRZ-A    I89 @S9S_MB_2U_LIB.S9S_MB_2U(SCH_1):PAGE275
PU75_P1_1   30   VIN2 ISL99390FRZTR5935-ISL99390FRZ-A    I89 @S9S_MB_2U_LIB.S9S_MB_2U(SCH_1):PAGE275
PC726_P1_3    1      A Q_CAP_C0805-22UF,16V,20%,X6S,CA    I60 @S9S_MB_2U_LIB.S9S_MB_2U(SCH_1):PAGE276
PC1681    1      A Q_CAP_C0805-22UF,16V,20%,X6S,CA    I75 @S9S_MB_2U_LIB.S9S_MB_2U(SCH_1):PAGE276
PC1683    1      A Q_CAP_C0805-22UF,16V,20%,X6S,CA    I78 @S9S_MB_2U_LIB.S9S_MB_2U(SCH_1):PAGE276
PC1210    1      A Q_CAPP_THLF-270UF,16V,20%,OSCOA    I81 @S9S_MB_2U_LIB.S9S_MB_2U(SCH_1):PAGE276

SW_P12V_PVCCINFAON_CPU0_FLT @S9S_MB_2U_LIB.S9S_MB_2U(SCH_1):SW_P12V_PVCCINFAON_CPU0_FLT
 PC176    1      A Q_CAP_0402-3300PF,50V,10%,X7R,A    I24 @S9S_MB_2U_LIB.S9S_MB_2U(SCH_1):PAGE262
 PC177    1      A Q_CAP_C0402-1UF,16V,10%,X6S,CHA    I25 @S9S_MB_2U_LIB.S9S_MB_2U(SCH_1):PAGE262
 PC180    1      A Q_CAP_C0805-22UF,16V,20%,X6S,CA    I27 @S9S_MB_2U_LIB.S9S_MB_2U(SCH_1):PAGE262
PU44_P0_2 25_29   VIN1 ISL99390FRZTR5935-ISL99390FRZ-A    I12 @S9S_MB_2U_LIB.S9S_MB_2U(SCH_1):PAGE261
PU44_P0_2   30   VIN2 ISL99390FRZTR5935-ISL99390FRZ-A    I12 @S9S_MB_2U_LIB.S9S_MB_2U(SCH_1):PAGE261
PC190_P0_2    1      A Q_CAP_0402-3300PF,50V,10%,X7R,A    I32 @S9S_MB_2U_LIB.S9S_MB_2U(SCH_1):PAGE261
PC192_P0_2    1      A Q_CAP_C0402-1UF,16V,10%,X6S,CHA    I35 @S9S_MB_2U_LIB.S9S_MB_2U(SCH_1):PAGE261
PC196_P0_2    1      A Q_CAP_C0805-22UF,16V,20%,X6S,CA    I36 @S9S_MB_2U_LIB.S9S_MB_2U(SCH_1):PAGE261
PC198_P0_2    1      A Q_CAP_C0805-22UF,16V,20%,X6S,CA    I37 @S9S_MB_2U_LIB.S9S_MB_2U(SCH_1):PAGE261
PC189_P0_1    1      A Q_CAP_0402-3300PF,50V,10%,X7R,A    I45 @S9S_MB_2U_LIB.S9S_MB_2U(SCH_1):PAGE261
PC191_P0_1    1      A Q_CAP_C0402-1UF,16V,10%,X6S,CHA    I48 @S9S_MB_2U_LIB.S9S_MB_2U(SCH_1):PAGE261
PC195_P0_1    1      A Q_CAP_C0805-22UF,16V,20%,X6S,CA    I49 @S9S_MB_2U_LIB.S9S_MB_2U(SCH_1):PAGE261
PC197_P0_1    1      A Q_CAP_C0805-22UF,16V,20%,X6S,CA    I50 @S9S_MB_2U_LIB.S9S_MB_2U(SCH_1):PAGE261
 PC207    1      A Q_CAPP_THLF-270UF,16V,20%,OSCOA    I74 @S9S_MB_2U_LIB.S9S_MB_2U(SCH_1):PAGE261
  PU36 25_29   VIN1 ISL99390FRZTR5935-ISL99390FRZ-A     I8 @S9S_MB_2U_LIB.S9S_MB_2U(SCH_1):PAGE265
  PU36   30   VIN2 ISL99390FRZTR5935-ISL99390FRZ-A     I8 @S9S_MB_2U_LIB.S9S_MB_2U(SCH_1):PAGE265
 PC634    1      A Q_CAP_0402-3300PF,50V,10%,X7R,A    I18 @S9S_MB_2U_LIB.S9S_MB_2U(SCH_1):PAGE265
 PC635    1      A Q_CAP_C0402-1UF,16V,10%,X6S,CHA    I20 @S9S_MB_2U_LIB.S9S_MB_2U(SCH_1):PAGE265
 PC637    1      A Q_CAP_C0805-22UF,16V,20%,X6S,CA    I21 @S9S_MB_2U_LIB.S9S_MB_2U(SCH_1):PAGE265
 PC638    1      A Q_CAP_C0805-22UF,16V,20%,X6S,CA    I23 @S9S_MB_2U_LIB.S9S_MB_2U(SCH_1):PAGE265
   PL6    2      2 Q_INDUCTOR_SMLF-100NH/16A,IND,A    I62 @S9S_MB_2U_LIB.S9S_MB_2U(SCH_1):PAGE261
 PC208    1      A Q_CAPP_THLF-270UF,16V,20%,OSCOA    I75 @S9S_MB_2U_LIB.S9S_MB_2U(SCH_1):PAGE261
PU43_P0_1 25_29   VIN1 ISL99390FRZTR5935-ISL99390FRZ-A    I79 @S9S_MB_2U_LIB.S9S_MB_2U(SCH_1):PAGE261
PU43_P0_1   30   VIN2 ISL99390FRZTR5935-ISL99390FRZ-A    I79 @S9S_MB_2U_LIB.S9S_MB_2U(SCH_1):PAGE261
 PC179    1      A Q_CAP_C0805-22UF,16V,20%,X6S,CA    I26 @S9S_MB_2U_LIB.S9S_MB_2U(SCH_1):PAGE262
  PU42 16_18-28    VIN RAA2213404GNPHB0-RAA2213404GNPA    I14 @S9S_MB_2U_LIB.S9S_MB_2U(SCH_1):PAGE262
PC1273    1      A Q_CAP_C0805-22UF,16V,20%,X6S,CA    I15 @S9S_MB_2U_LIB.S9S_MB_2U(SCH_1):PAGE268
PC1274    1      A Q_CAP_C0402-1UF,16V,10%,X6S,CHA    I23 @S9S_MB_2U_LIB.S9S_MB_2U(SCH_1):PAGE268
PC1272    1      A Q_CAP_C0805-22UF,16V,20%,X6S,CA    I13 @S9S_MB_2U_LIB.S9S_MB_2U(SCH_1):PAGE268
  PU81    3    VIN RS53317LR-RS53317LR,SMLF,IC,ALA    I22 @S9S_MB_2U_LIB.S9S_MB_2U(SCH_1):PAGE268

SW_P12V_PVCCINFAON_CPU1_FLT @S9S_MB_2U_LIB.S9S_MB_2U(SCH_1):SW_P12V_PVCCINFAON_CPU1_FLT
PC443_P1_2    1      A Q_CAP_0402-3300PF,50V,10%,X7R,A    I36 @S9S_MB_2U_LIB.S9S_MB_2U(SCH_1):PAGE279
PU50_P1_1 25_29   VIN1 ISL99390FRZTR5935-ISL99390FRZ-A    I38 @S9S_MB_2U_LIB.S9S_MB_2U(SCH_1):PAGE279
PU50_P1_1   30   VIN2 ISL99390FRZTR5935-ISL99390FRZ-A    I38 @S9S_MB_2U_LIB.S9S_MB_2U(SCH_1):PAGE279
PC444_P1_1    1      A Q_CAP_C0402-1UF,16V,10%,X6S,CHA    I41 @S9S_MB_2U_LIB.S9S_MB_2U(SCH_1):PAGE279
PC449_P1_2    1      A Q_CAP_C0805-22UF,16V,20%,X6S,CA    I43 @S9S_MB_2U_LIB.S9S_MB_2U(SCH_1):PAGE279
PC448_P1_1    1      A Q_CAP_C0805-22UF,16V,20%,X6S,CA    I51 @S9S_MB_2U_LIB.S9S_MB_2U(SCH_1):PAGE279
 PC460    1      A Q_CAPP_THLF-270UF,16V,20%,OSCOA    I69 @S9S_MB_2U_LIB.S9S_MB_2U(SCH_1):PAGE279
  PU49 16_18-28    VIN RAA2213404GNPHB0-RAA2213404GNPA    I14 @S9S_MB_2U_LIB.S9S_MB_2U(SCH_1):PAGE280
 PC429    1      A Q_CAP_0402-3300PF,50V,10%,X7R,A    I24 @S9S_MB_2U_LIB.S9S_MB_2U(SCH_1):PAGE280
 PC432    1      A Q_CAP_C0805-22UF,16V,20%,X6S,CA    I27 @S9S_MB_2U_LIB.S9S_MB_2U(SCH_1):PAGE280
 PC374    1      A Q_CAP_0402-3300PF,50V,10%,X7R,A    I20 @S9S_MB_2U_LIB.S9S_MB_2U(SCH_1):PAGE283
 PC377    1      A Q_CAP_C0805-22UF,16V,20%,X6S,CA    I23 @S9S_MB_2U_LIB.S9S_MB_2U(SCH_1):PAGE283
PU51_P1_2 25_29   VIN1 ISL99390FRZTR5935-ISL99390FRZ-A    I29 @S9S_MB_2U_LIB.S9S_MB_2U(SCH_1):PAGE279
PU51_P1_2   30   VIN2 ISL99390FRZTR5935-ISL99390FRZ-A    I29 @S9S_MB_2U_LIB.S9S_MB_2U(SCH_1):PAGE279
PC445_P1_2    1      A Q_CAP_C0402-1UF,16V,10%,X6S,CHA    I37 @S9S_MB_2U_LIB.S9S_MB_2U(SCH_1):PAGE279
PC451_P1_2    1      A Q_CAP_C0805-22UF,16V,20%,X6S,CA    I45 @S9S_MB_2U_LIB.S9S_MB_2U(SCH_1):PAGE279
PC450_P1_1    1      A Q_CAP_C0805-22UF,16V,20%,X6S,CA    I53 @S9S_MB_2U_LIB.S9S_MB_2U(SCH_1):PAGE279
 PC461    1      A Q_CAPP_THLF-270UF,16V,20%,OSCOA    I70 @S9S_MB_2U_LIB.S9S_MB_2U(SCH_1):PAGE279
 PC430    1      A Q_CAP_C0402-1UF,16V,10%,X6S,CHA    I26 @S9S_MB_2U_LIB.S9S_MB_2U(SCH_1):PAGE280
 PC433    1      A Q_CAP_C0805-22UF,16V,20%,X6S,CA    I28 @S9S_MB_2U_LIB.S9S_MB_2U(SCH_1):PAGE280
 PC375    1      A Q_CAP_C0402-1UF,16V,10%,X6S,CHA    I22 @S9S_MB_2U_LIB.S9S_MB_2U(SCH_1):PAGE283
PC442_P1_1    1      A Q_CAP_0402-3300PF,50V,10%,X7R,A    I40 @S9S_MB_2U_LIB.S9S_MB_2U(SCH_1):PAGE279
PC1282    1      A Q_CAP_C0402-1UF,16V,10%,X6S,CHA    I16 @S9S_MB_2U_LIB.S9S_MB_2U(SCH_1):PAGE286
  PU17 25_29   VIN1 ISL99390FRZTR5935-ISL99390FRZ-A    I10 @S9S_MB_2U_LIB.S9S_MB_2U(SCH_1):PAGE283
  PU17   30   VIN2 ISL99390FRZTR5935-ISL99390FRZ-A    I10 @S9S_MB_2U_LIB.S9S_MB_2U(SCH_1):PAGE283
PC1280    1      A Q_CAP_C0805-22UF,16V,20%,X6S,CA     I9 @S9S_MB_2U_LIB.S9S_MB_2U(SCH_1):PAGE286
  PU82    3    VIN RS53317LR-RS53317LR,SMLF,IC,ALA    I20 @S9S_MB_2U_LIB.S9S_MB_2U(SCH_1):PAGE286
 PC378    1      A Q_CAP_C0805-22UF,16V,20%,X6S,CA    I24 @S9S_MB_2U_LIB.S9S_MB_2U(SCH_1):PAGE283
  PL23    2      2 Q_INDUCTOR_SMLF-100NH/16A,IND,A    I78 @S9S_MB_2U_LIB.S9S_MB_2U(SCH_1):PAGE279
PC1281    1      A Q_CAP_C0805-22UF,16V,20%,X6S,CA    I14 @S9S_MB_2U_LIB.S9S_MB_2U(SCH_1):PAGE286

SW_P12V_PVCCIN_CPU0_FLT @S9S_MB_2U_LIB.S9S_MB_2U(SCH_1):SW_P12V_PVCCIN_CPU0_FLT
PC298_P0_2    1      A Q_CAP_C0402-1UF,16V,10%,X6S,CHA    I22 @S9S_MB_2U_LIB.S9S_MB_2U(SCH_1):PAGE253
PC304_P0_2    1      A Q_CAP_C0805-22UF,16V,20%,X6S,CA    I24 @S9S_MB_2U_LIB.S9S_MB_2U(SCH_1):PAGE253
PU13_P0_1 25_29   VIN1 ISL99390FRZTR5935-ISL99390FRZ-A    I40 @S9S_MB_2U_LIB.S9S_MB_2U(SCH_1):PAGE253
PU13_P0_1   30   VIN2 ISL99390FRZTR5935-ISL99390FRZ-A    I40 @S9S_MB_2U_LIB.S9S_MB_2U(SCH_1):PAGE253
PC306_P0_2    1      A Q_CAP_C0805-22UF,16V,20%,X6S,CA    I54 @S9S_MB_2U_LIB.S9S_MB_2U(SCH_1):PAGE253
PU10_P0_4 25_29   VIN1 ISL99390FRZTR5935-ISL99390FRZ-A    I13 @S9S_MB_2U_LIB.S9S_MB_2U(SCH_1):PAGE254
PU10_P0_4   30   VIN2 ISL99390FRZTR5935-ISL99390FRZ-A    I13 @S9S_MB_2U_LIB.S9S_MB_2U(SCH_1):PAGE254
PC274_P0_4    1      A Q_CAP_0402-3300PF,50V,10%,X7R,A    I35 @S9S_MB_2U_LIB.S9S_MB_2U(SCH_1):PAGE254
PC276_P0_4    1      A Q_CAP_C0402-1UF,16V,10%,X6S,CHA    I38 @S9S_MB_2U_LIB.S9S_MB_2U(SCH_1):PAGE254
PC280_P0_4    1      A Q_CAP_C0805-22UF,16V,20%,X6S,CA    I39 @S9S_MB_2U_LIB.S9S_MB_2U(SCH_1):PAGE254
PC282_P0_4    1      A Q_CAP_C0805-22UF,16V,20%,X6S,CA    I40 @S9S_MB_2U_LIB.S9S_MB_2U(SCH_1):PAGE254
PC275_P0_3    1      A Q_CAP_0402-3300PF,50V,10%,X7R,A    I48 @S9S_MB_2U_LIB.S9S_MB_2U(SCH_1):PAGE254
PC281_P0_3    1      A Q_CAP_C0805-22UF,16V,20%,X6S,CA    I53 @S9S_MB_2U_LIB.S9S_MB_2U(SCH_1):PAGE254
PC285_P0_3    1      A Q_CAP_C0805-22UF,16V,20%,X6S,CA    I56 @S9S_MB_2U_LIB.S9S_MB_2U(SCH_1):PAGE254
PU8_P0_6 25_29   VIN1 ISL99390FRZTR5935-ISL99390FRZ-A    I12 @S9S_MB_2U_LIB.S9S_MB_2U(SCH_1):PAGE255
PU8_P0_6   30   VIN2 ISL99390FRZTR5935-ISL99390FRZ-A    I12 @S9S_MB_2U_LIB.S9S_MB_2U(SCH_1):PAGE255
PC252_P0_6    1      A Q_CAP_0402-3300PF,50V,10%,X7R,A    I34 @S9S_MB_2U_LIB.S9S_MB_2U(SCH_1):PAGE255
PC254_P0_6    1      A Q_CAP_C0402-1UF,16V,10%,X6S,CHA    I37 @S9S_MB_2U_LIB.S9S_MB_2U(SCH_1):PAGE255
PC258_P0_6    1      A Q_CAP_C0805-22UF,16V,20%,X6S,CA    I38 @S9S_MB_2U_LIB.S9S_MB_2U(SCH_1):PAGE255
PC260_P0_6    1      A Q_CAP_C0805-22UF,16V,20%,X6S,CA    I39 @S9S_MB_2U_LIB.S9S_MB_2U(SCH_1):PAGE255
PU6_P0_8 25_29   VIN1 ISL99390FRZTR5935-ISL99390FRZ-A     I2 @S9S_MB_2U_LIB.S9S_MB_2U(SCH_1):PAGE256
PU6_P0_8   30   VIN2 ISL99390FRZTR5935-ISL99390FRZ-A     I2 @S9S_MB_2U_LIB.S9S_MB_2U(SCH_1):PAGE256
PC232_P0_8    1      A Q_CAP_C0402-1UF,16V,10%,X6S,CHA    I20 @S9S_MB_2U_LIB.S9S_MB_2U(SCH_1):PAGE256
PC241_P0_7    1      A Q_CAP_C0805-22UF,16V,20%,X6S,CA    I64 @S9S_MB_2U_LIB.S9S_MB_2U(SCH_1):PAGE256
PC1248    1      A Q_CAP_C0805-22UF,16V,20%,X6S,CA    I16 @S9S_MB_2U_LIB.S9S_MB_2U(SCH_1):PAGE267
PC1249    1      A Q_CAP_C0402-1UF,16V,10%,X6S,CHA    I17 @S9S_MB_2U_LIB.S9S_MB_2U(SCH_1):PAGE267
PC305_P0_1    1      A Q_CAP_C0805-22UF,16V,20%,X6S,CA    I50 @S9S_MB_2U_LIB.S9S_MB_2U(SCH_1):PAGE253
 PC315    1      A Q_CAPP_THLF-270UF,16V,20%,OSCOA    I91 @S9S_MB_2U_LIB.S9S_MB_2U(SCH_1):PAGE253
 PC318    1      A Q_CAPP_THLF-270UF,16V,20%,OSCOA    I92 @S9S_MB_2U_LIB.S9S_MB_2U(SCH_1):PAGE253
PC2345    1      A Q_CAPP_THLF-270UF,16V,20%,OSCOA    I95 @S9S_MB_2U_LIB.S9S_MB_2U(SCH_1):PAGE253
PU11_P0_3 25_29   VIN1 ISL99390FRZTR5935-ISL99390FRZ-A    I20 @S9S_MB_2U_LIB.S9S_MB_2U(SCH_1):PAGE254
PU11_P0_3   30   VIN2 ISL99390FRZTR5935-ISL99390FRZ-A    I20 @S9S_MB_2U_LIB.S9S_MB_2U(SCH_1):PAGE254
PC284_P0_4    1      A Q_CAP_C0805-22UF,16V,20%,X6S,CA    I43 @S9S_MB_2U_LIB.S9S_MB_2U(SCH_1):PAGE254
PC277_P0_3    1      A Q_CAP_C0402-1UF,16V,10%,X6S,CHA    I52 @S9S_MB_2U_LIB.S9S_MB_2U(SCH_1):PAGE254
PC283_P0_3    1      A Q_CAP_C0805-22UF,16V,20%,X6S,CA    I54 @S9S_MB_2U_LIB.S9S_MB_2U(SCH_1):PAGE254
PC262_P0_6    1      A Q_CAP_C0805-22UF,16V,20%,X6S,CA    I43 @S9S_MB_2U_LIB.S9S_MB_2U(SCH_1):PAGE255
PC253_P0_5    1      A Q_CAP_0402-3300PF,50V,10%,X7R,A    I48 @S9S_MB_2U_LIB.S9S_MB_2U(SCH_1):PAGE255
PC255_P0_5    1      A Q_CAP_C0402-1UF,16V,10%,X6S,CHA    I52 @S9S_MB_2U_LIB.S9S_MB_2U(SCH_1):PAGE255
PC259_P0_5    1      A Q_CAP_C0805-22UF,16V,20%,X6S,CA    I53 @S9S_MB_2U_LIB.S9S_MB_2U(SCH_1):PAGE255
PC261_P0_5    1      A Q_CAP_C0805-22UF,16V,20%,X6S,CA    I54 @S9S_MB_2U_LIB.S9S_MB_2U(SCH_1):PAGE255
PC263_P0_5    1      A Q_CAP_C0805-22UF,16V,20%,X6S,CA    I56 @S9S_MB_2U_LIB.S9S_MB_2U(SCH_1):PAGE255
PU9_P0_5 25_29   VIN1 ISL99390FRZTR5935-ISL99390FRZ-A    I66 @S9S_MB_2U_LIB.S9S_MB_2U(SCH_1):PAGE255
PU9_P0_5   30   VIN2 ISL99390FRZTR5935-ISL99390FRZ-A    I66 @S9S_MB_2U_LIB.S9S_MB_2U(SCH_1):PAGE255
PC230_P0_8    1      A Q_CAP_0402-3300PF,50V,10%,X7R,A    I17 @S9S_MB_2U_LIB.S9S_MB_2U(SCH_1):PAGE256
PC236_P0_8    1      A Q_CAP_C0805-22UF,16V,20%,X6S,CA    I21 @S9S_MB_2U_LIB.S9S_MB_2U(SCH_1):PAGE256
PU7_P0_7 25_29   VIN1 ISL99390FRZTR5935-ISL99390FRZ-A    I32 @S9S_MB_2U_LIB.S9S_MB_2U(SCH_1):PAGE256
PU7_P0_7   30   VIN2 ISL99390FRZTR5935-ISL99390FRZ-A    I32 @S9S_MB_2U_LIB.S9S_MB_2U(SCH_1):PAGE256
PC231_P0_7    1      A Q_CAP_0402-3300PF,50V,10%,X7R,A    I41 @S9S_MB_2U_LIB.S9S_MB_2U(SCH_1):PAGE256
PC233_P0_7    1      A Q_CAP_C0402-1UF,16V,10%,X6S,CHA    I42 @S9S_MB_2U_LIB.S9S_MB_2U(SCH_1):PAGE256
PC237_P0_7    1      A Q_CAP_C0805-22UF,16V,20%,X6S,CA    I43 @S9S_MB_2U_LIB.S9S_MB_2U(SCH_1):PAGE256
PC238_P0_8    1      A Q_CAP_C0805-22UF,16V,20%,X6S,CA    I47 @S9S_MB_2U_LIB.S9S_MB_2U(SCH_1):PAGE256
PC240_P0_8    1      A Q_CAP_C0805-22UF,16V,20%,X6S,CA    I48 @S9S_MB_2U_LIB.S9S_MB_2U(SCH_1):PAGE256
PC239_P0_7    1      A Q_CAP_C0805-22UF,16V,20%,X6S,CA    I63 @S9S_MB_2U_LIB.S9S_MB_2U(SCH_1):PAGE256
PC296_P0_2    1      A Q_CAP_0402-3300PF,50V,10%,X7R,A    I19 @S9S_MB_2U_LIB.S9S_MB_2U(SCH_1):PAGE253
PC303_P0_1    1      A Q_CAP_C0805-22UF,16V,20%,X6S,CA    I49 @S9S_MB_2U_LIB.S9S_MB_2U(SCH_1):PAGE253
PC307_P0_1    1      A Q_CAP_C0805-22UF,16V,20%,X6S,CA    I75 @S9S_MB_2U_LIB.S9S_MB_2U(SCH_1):PAGE253
PR2554    2      B Q_RES_2512LF-0.03,0.1%,1W,EMPTA    I81 @S9S_MB_2U_LIB.S9S_MB_2U(SCH_1):PAGE253
PU12_P0_2 25_29   VIN1 ISL99390FRZTR5935-ISL99390FRZ-A     I6 @S9S_MB_2U_LIB.S9S_MB_2U(SCH_1):PAGE253
PU12_P0_2   30   VIN2 ISL99390FRZTR5935-ISL99390FRZ-A     I6 @S9S_MB_2U_LIB.S9S_MB_2U(SCH_1):PAGE253
PC302_P0_2    1      A Q_CAP_C0805-22UF,16V,20%,X6S,CA    I23 @S9S_MB_2U_LIB.S9S_MB_2U(SCH_1):PAGE253
PC297_P0_1    1      A Q_CAP_0402-3300PF,50V,10%,X7R,A    I44 @S9S_MB_2U_LIB.S9S_MB_2U(SCH_1):PAGE253
PC299_P0_1    1      A Q_CAP_C0402-1UF,16V,10%,X6S,CHA    I47 @S9S_MB_2U_LIB.S9S_MB_2U(SCH_1):PAGE253
  PL15    2      2 Q_INDUCTOR_SMLF-50NH/148A,IND,A    I82 @S9S_MB_2U_LIB.S9S_MB_2U(SCH_1):PAGE253
 PC321    1      A Q_CAPP_THLF-270UF,16V,20%,OSCOA    I93 @S9S_MB_2U_LIB.S9S_MB_2U(SCH_1):PAGE253
 PC324    1      A Q_CAPP_THLF-270UF,16V,20%,OSCOA    I94 @S9S_MB_2U_LIB.S9S_MB_2U(SCH_1):PAGE253
 PC831    1      A Q_CAP_C0805-22UF,16V,20%,X6S,CA     I7 @S9S_MB_2U_LIB.S9S_MB_2U(SCH_1):PAGE267
PC1247    1      A Q_CAP_C0805-22UF,16V,20%,X6S,CA    I10 @S9S_MB_2U_LIB.S9S_MB_2U(SCH_1):PAGE267
  PU79   10   VIN1 RS53318LR-RS53318LR,SMLF,IC,ALA    I19 @S9S_MB_2U_LIB.S9S_MB_2U(SCH_1):PAGE267
  PU79   21   VIN2 RS53318LR-RS53318LR,SMLF,IC,ALA    I19 @S9S_MB_2U_LIB.S9S_MB_2U(SCH_1):PAGE267

SW_P12V_PVCCIN_CPU1_FLT @S9S_MB_2U_LIB.S9S_MB_2U(SCH_1):SW_P12V_PVCCIN_CPU1_FLT
PC566_P1_2    1      A Q_CAP_C0805-22UF,16V,20%,X6S,CA    I22 @S9S_MB_2U_LIB.S9S_MB_2U(SCH_1):PAGE271
  PL32    2      2 Q_INDUCTOR_SMLF-50NH/148A,IND,A    I83 @S9S_MB_2U_LIB.S9S_MB_2U(SCH_1):PAGE271
PC529_P1_4    1      A Q_CAP_C0402-1UF,16V,10%,X6S,CHA    I35 @S9S_MB_2U_LIB.S9S_MB_2U(SCH_1):PAGE272
PC533_P1_4    1      A Q_CAP_C0805-22UF,16V,20%,X6S,CA    I36 @S9S_MB_2U_LIB.S9S_MB_2U(SCH_1):PAGE272
PC535_P1_4    1      A Q_CAP_C0805-22UF,16V,20%,X6S,CA    I41 @S9S_MB_2U_LIB.S9S_MB_2U(SCH_1):PAGE272
PC537_P1_4    1      A Q_CAP_C0805-22UF,16V,20%,X6S,CA    I42 @S9S_MB_2U_LIB.S9S_MB_2U(SCH_1):PAGE272
PC528_P1_3    1      A Q_CAP_0402-3300PF,50V,10%,X7R,A    I48 @S9S_MB_2U_LIB.S9S_MB_2U(SCH_1):PAGE272
PC530_P1_3    1      A Q_CAP_C0402-1UF,16V,10%,X6S,CHA    I49 @S9S_MB_2U_LIB.S9S_MB_2U(SCH_1):PAGE272
PC536_P1_3    1      A Q_CAP_C0805-22UF,16V,20%,X6S,CA    I54 @S9S_MB_2U_LIB.S9S_MB_2U(SCH_1):PAGE272
PU26_P1_5 25_29   VIN1 ISL99390FRZTR5935-ISL99390FRZ-A    I23 @S9S_MB_2U_LIB.S9S_MB_2U(SCH_1):PAGE273
PU26_P1_5   30   VIN2 ISL99390FRZTR5935-ISL99390FRZ-A    I23 @S9S_MB_2U_LIB.S9S_MB_2U(SCH_1):PAGE273
PC505_P1_6    1      A Q_CAP_0402-3300PF,50V,10%,X7R,A    I29 @S9S_MB_2U_LIB.S9S_MB_2U(SCH_1):PAGE273
PC507_P1_6    1      A Q_CAP_C0402-1UF,16V,10%,X6S,CHA    I31 @S9S_MB_2U_LIB.S9S_MB_2U(SCH_1):PAGE273
PC513_P1_6    1      A Q_CAP_C0805-22UF,16V,20%,X6S,CA    I34 @S9S_MB_2U_LIB.S9S_MB_2U(SCH_1):PAGE273
PC506_P1_5    1      A Q_CAP_0402-3300PF,50V,10%,X7R,A    I45 @S9S_MB_2U_LIB.S9S_MB_2U(SCH_1):PAGE273
PC512_P1_5    1      A Q_CAP_C0805-22UF,16V,20%,X6S,CA    I50 @S9S_MB_2U_LIB.S9S_MB_2U(SCH_1):PAGE273
PC489_P1_8    1      A Q_CAP_C0805-22UF,16V,20%,X6S,CA    I28 @S9S_MB_2U_LIB.S9S_MB_2U(SCH_1):PAGE274
PC484_P1_7    1      A Q_CAP_0402-3300PF,50V,10%,X7R,A    I37 @S9S_MB_2U_LIB.S9S_MB_2U(SCH_1):PAGE274
PC486_P1_7    1      A Q_CAP_C0402-1UF,16V,10%,X6S,CHA    I40 @S9S_MB_2U_LIB.S9S_MB_2U(SCH_1):PAGE274
PC490_P1_7    1      A Q_CAP_C0805-22UF,16V,20%,X6S,CA    I41 @S9S_MB_2U_LIB.S9S_MB_2U(SCH_1):PAGE274
PC491_P1_8    1      A Q_CAP_C0805-22UF,16V,20%,X6S,CA    I46 @S9S_MB_2U_LIB.S9S_MB_2U(SCH_1):PAGE274
PC493_P1_8    1      A Q_CAP_C0805-22UF,16V,20%,X6S,CA    I47 @S9S_MB_2U_LIB.S9S_MB_2U(SCH_1):PAGE274
PC1260    1      A Q_CAP_C0805-22UF,16V,20%,X6S,CA    I15 @S9S_MB_2U_LIB.S9S_MB_2U(SCH_1):PAGE285
PC568_P1_2    1      A Q_CAP_C0805-22UF,16V,20%,X6S,CA    I24 @S9S_MB_2U_LIB.S9S_MB_2U(SCH_1):PAGE271
PC563_P1_1    1      A Q_CAP_C0402-1UF,16V,10%,X6S,CHA    I47 @S9S_MB_2U_LIB.S9S_MB_2U(SCH_1):PAGE271
PC567_P1_1    1      A Q_CAP_C0805-22UF,16V,20%,X6S,CA    I48 @S9S_MB_2U_LIB.S9S_MB_2U(SCH_1):PAGE271
PC569_P1_1    1      A Q_CAP_C0805-22UF,16V,20%,X6S,CA    I50 @S9S_MB_2U_LIB.S9S_MB_2U(SCH_1):PAGE271
PR2556    2      B Q_RES_2512LF-0.03,0.1%,1W,EMPTA    I82 @S9S_MB_2U_LIB.S9S_MB_2U(SCH_1):PAGE271
PU27_P1_4 25_29   VIN1 ISL99390FRZTR5935-ISL99390FRZ-A    I10 @S9S_MB_2U_LIB.S9S_MB_2U(SCH_1):PAGE272
PU27_P1_4   30   VIN2 ISL99390FRZTR5935-ISL99390FRZ-A    I10 @S9S_MB_2U_LIB.S9S_MB_2U(SCH_1):PAGE272
PC527_P1_4    1      A Q_CAP_0402-3300PF,50V,10%,X7R,A    I33 @S9S_MB_2U_LIB.S9S_MB_2U(SCH_1):PAGE272
PC534_P1_3    1      A Q_CAP_C0805-22UF,16V,20%,X6S,CA    I50 @S9S_MB_2U_LIB.S9S_MB_2U(SCH_1):PAGE272
PC538_P1_3    1      A Q_CAP_C0805-22UF,16V,20%,X6S,CA    I55 @S9S_MB_2U_LIB.S9S_MB_2U(SCH_1):PAGE272
PU28_P1_3 25_29   VIN1 ISL99390FRZTR5935-ISL99390FRZ-A    I66 @S9S_MB_2U_LIB.S9S_MB_2U(SCH_1):PAGE272
PU28_P1_3   30   VIN2 ISL99390FRZTR5935-ISL99390FRZ-A    I66 @S9S_MB_2U_LIB.S9S_MB_2U(SCH_1):PAGE272
PU25_P1_6 25_29   VIN1 ISL99390FRZTR5935-ISL99390FRZ-A    I16 @S9S_MB_2U_LIB.S9S_MB_2U(SCH_1):PAGE273
PU25_P1_6   30   VIN2 ISL99390FRZTR5935-ISL99390FRZ-A    I16 @S9S_MB_2U_LIB.S9S_MB_2U(SCH_1):PAGE273
PC511_P1_6    1      A Q_CAP_C0805-22UF,16V,20%,X6S,CA    I33 @S9S_MB_2U_LIB.S9S_MB_2U(SCH_1):PAGE273
PC515_P1_6    1      A Q_CAP_C0805-22UF,16V,20%,X6S,CA    I35 @S9S_MB_2U_LIB.S9S_MB_2U(SCH_1):PAGE273
PC508_P1_5    1      A Q_CAP_C0402-1UF,16V,10%,X6S,CHA    I46 @S9S_MB_2U_LIB.S9S_MB_2U(SCH_1):PAGE273
PC514_P1_5    1      A Q_CAP_C0805-22UF,16V,20%,X6S,CA    I51 @S9S_MB_2U_LIB.S9S_MB_2U(SCH_1):PAGE273
PC516_P1_5    1      A Q_CAP_C0805-22UF,16V,20%,X6S,CA    I52 @S9S_MB_2U_LIB.S9S_MB_2U(SCH_1):PAGE273
PU23_P1_8 25_29   VIN1 ISL99390FRZTR5935-ISL99390FRZ-A    I11 @S9S_MB_2U_LIB.S9S_MB_2U(SCH_1):PAGE274
PU23_P1_8   30   VIN2 ISL99390FRZTR5935-ISL99390FRZ-A    I11 @S9S_MB_2U_LIB.S9S_MB_2U(SCH_1):PAGE274
PU24_P1_7 25_29   VIN1 ISL99390FRZTR5935-ISL99390FRZ-A    I20 @S9S_MB_2U_LIB.S9S_MB_2U(SCH_1):PAGE274
PU24_P1_7   30   VIN2 ISL99390FRZTR5935-ISL99390FRZ-A    I20 @S9S_MB_2U_LIB.S9S_MB_2U(SCH_1):PAGE274
PC483_P1_8    1      A Q_CAP_0402-3300PF,50V,10%,X7R,A    I24 @S9S_MB_2U_LIB.S9S_MB_2U(SCH_1):PAGE274
PC485_P1_8    1      A Q_CAP_C0402-1UF,16V,10%,X6S,CHA    I27 @S9S_MB_2U_LIB.S9S_MB_2U(SCH_1):PAGE274
PC492_P1_7    1      A Q_CAP_C0805-22UF,16V,20%,X6S,CA    I61 @S9S_MB_2U_LIB.S9S_MB_2U(SCH_1):PAGE274
PC494_P1_7    1      A Q_CAP_C0805-22UF,16V,20%,X6S,CA    I62 @S9S_MB_2U_LIB.S9S_MB_2U(SCH_1):PAGE274
PC1262    1      A Q_CAP_C0402-1UF,16V,10%,X6S,CHA    I17 @S9S_MB_2U_LIB.S9S_MB_2U(SCH_1):PAGE285
PC560_P1_2    1      A Q_CAP_0402-3300PF,50V,10%,X7R,A    I19 @S9S_MB_2U_LIB.S9S_MB_2U(SCH_1):PAGE271
PC562_P1_2    1      A Q_CAP_C0402-1UF,16V,10%,X6S,CHA    I21 @S9S_MB_2U_LIB.S9S_MB_2U(SCH_1):PAGE271
PU31_P1_1 25_29   VIN1 ISL99390FRZTR5935-ISL99390FRZ-A    I40 @S9S_MB_2U_LIB.S9S_MB_2U(SCH_1):PAGE271
PU31_P1_1   30   VIN2 ISL99390FRZTR5935-ISL99390FRZ-A    I40 @S9S_MB_2U_LIB.S9S_MB_2U(SCH_1):PAGE271
 PC582    1      A Q_CAPP_THLF-270UF,16V,20%,OSCOA    I87 @S9S_MB_2U_LIB.S9S_MB_2U(SCH_1):PAGE271
PC2346    1      A Q_CAPP_THLF-270UF,16V,20%,OSCOA    I96 @S9S_MB_2U_LIB.S9S_MB_2U(SCH_1):PAGE271
  PU80   10   VIN1 RS53318LR-RS53318LR,SMLF,IC,ALA    I25 @S9S_MB_2U_LIB.S9S_MB_2U(SCH_1):PAGE285
  PU80   21   VIN2 RS53318LR-RS53318LR,SMLF,IC,ALA    I25 @S9S_MB_2U_LIB.S9S_MB_2U(SCH_1):PAGE285
PU30_P1_2 25_29   VIN1 ISL99390FRZTR5935-ISL99390FRZ-A     I7 @S9S_MB_2U_LIB.S9S_MB_2U(SCH_1):PAGE271
PU30_P1_2   30   VIN2 ISL99390FRZTR5935-ISL99390FRZ-A     I7 @S9S_MB_2U_LIB.S9S_MB_2U(SCH_1):PAGE271
PC561_P1_1    1      A Q_CAP_0402-3300PF,50V,10%,X7R,A    I44 @S9S_MB_2U_LIB.S9S_MB_2U(SCH_1):PAGE271
PC570_P1_2    1      A Q_CAP_C0805-22UF,16V,20%,X6S,CA    I53 @S9S_MB_2U_LIB.S9S_MB_2U(SCH_1):PAGE271
PC571_P1_1    1      A Q_CAP_C0805-22UF,16V,20%,X6S,CA    I76 @S9S_MB_2U_LIB.S9S_MB_2U(SCH_1):PAGE271
 PC579    1      A Q_CAPP_THLF-270UF,16V,20%,OSCOA    I86 @S9S_MB_2U_LIB.S9S_MB_2U(SCH_1):PAGE271
 PC585    1      A Q_CAPP_THLF-270UF,16V,20%,OSCOA    I92 @S9S_MB_2U_LIB.S9S_MB_2U(SCH_1):PAGE271
 PC588    1      A Q_CAPP_THLF-270UF,16V,20%,OSCOA    I94 @S9S_MB_2U_LIB.S9S_MB_2U(SCH_1):PAGE271
PC1261    1      A Q_CAP_C0805-22UF,16V,20%,X6S,CA    I16 @S9S_MB_2U_LIB.S9S_MB_2U(SCH_1):PAGE285
PC1259    1      A Q_CAP_C0805-22UF,16V,20%,X6S,CA     I8 @S9S_MB_2U_LIB.S9S_MB_2U(SCH_1):PAGE285

SW_P1V05_PCH_AUX_BST @S9S_MB_2U_LIB.S9S_MB_2U(SCH_1):SW_P1V05_PCH_AUX_BST
PC1222    1      A Q_CAP_C0402-0.22UF,25V,10%,X7RA    I31 @S9S_MB_2U_LIB.S9S_MB_2U(SCH_1):PAGE248
  PU73    1    BST RS53319LR-RS53319LR,SMLF,IC,ALA    I11 @S9S_MB_2U_LIB.S9S_MB_2U(SCH_1):PAGE248

SW_P1V05_PCH_AUX_SW @S9S_MB_2U_LIB.S9S_MB_2U(SCH_1):SW_P1V05_PCH_AUX_SW
PC1222    2      B Q_CAP_C0402-0.22UF,25V,10%,X7RA    I31 @S9S_MB_2U_LIB.S9S_MB_2U(SCH_1):PAGE248
 PL150    1      1 Q_INDUCTOR_SMLF-300NH/33A,IND,A    I53 @S9S_MB_2U_LIB.S9S_MB_2U(SCH_1):PAGE248
  PU73   20     SW RS53319LR-RS53319LR,SMLF,IC,ALA    I11 @S9S_MB_2U_LIB.S9S_MB_2U(SCH_1):PAGE248

SW_P1V8_PCH_AUX_BST @S9S_MB_2U_LIB.S9S_MB_2U(SCH_1):SW_P1V8_PCH_AUX_BST
  PU74    9    BST NB682GDZ-NB682GD-Z,SMLF,IC,AL0A    I26 @S9S_MB_2U_LIB.S9S_MB_2U(SCH_1):PAGE249
PC1235    1      A Q_CAP_C0402-0.22UF,25V,10%,X7RA    I30 @S9S_MB_2U_LIB.S9S_MB_2U(SCH_1):PAGE249

SW_P1V8_PCH_AUX_FLT @S9S_MB_2U_LIB.S9S_MB_2U(SCH_1):SW_P1V8_PCH_AUX_FLT
  PU74    1    VIN NB682GDZ-NB682GD-Z,SMLF,IC,AL0A    I26 @S9S_MB_2U_LIB.S9S_MB_2U(SCH_1):PAGE249
PC1234    1      A Q_CAP_C0402-100NF,50V,10%,X7R,A    I21 @S9S_MB_2U_LIB.S9S_MB_2U(SCH_1):PAGE249
  PL16    2      2 Q_INDUCTOR_SMLF-BLM18SN220TN1DA    I16 @S9S_MB_2U_LIB.S9S_MB_2U(SCH_1):PAGE249
PC1232    1      A Q_CAP_C0805-10UF,16V,10%,X6S,CB    I19 @S9S_MB_2U_LIB.S9S_MB_2U(SCH_1):PAGE249
PC1233    1      A Q_CAP_C0805-10UF,16V,10%,X6S,CB    I20 @S9S_MB_2U_LIB.S9S_MB_2U(SCH_1):PAGE249

SW_P1V8_PCH_AUX_SW @S9S_MB_2U_LIB.S9S_MB_2U(SCH_1):SW_P1V8_PCH_AUX_SW
  PU74    8     SW NB682GDZ-NB682GD-Z,SMLF,IC,AL0A    I26 @S9S_MB_2U_LIB.S9S_MB_2U(SCH_1):PAGE249
PC1235    2      B Q_CAP_C0402-0.22UF,25V,10%,X7RA    I30 @S9S_MB_2U_LIB.S9S_MB_2U(SCH_1):PAGE249
 PL170    1      1 Q_INDUCTOR_SMLF-2.2UH,IND,CV-2A    I45 @S9S_MB_2U_LIB.S9S_MB_2U(SCH_1):PAGE249

SW_P3V3_AUX_BOOT @S9S_MB_2U_LIB.S9S_MB_2U(SCH_1):SW_P3V3_AUX_BOOT
   PU9   26   BOOT IR3889MTRPBF-IR3889MTRPBF,SMLFA    I95 @S9S_MB_2U_LIB.S9S_MB_2U(SCH_1):PAGE245
 PR835    1      A Q_RES_0402LF-0,5%,1/16W,CHIP,CA   I123 @S9S_MB_2U_LIB.S9S_MB_2U(SCH_1):PAGE245

SW_P3V3_AUX_BOOTR @S9S_MB_2U_LIB.S9S_MB_2U(SCH_1):SW_P3V3_AUX_BOOTR
   PU9   25  PHASE IR3889MTRPBF-IR3889MTRPBF,SMLFA    I95 @S9S_MB_2U_LIB.S9S_MB_2U(SCH_1):PAGE245
 PC568    1      A Q_CAP_C0402-0.22UF,25V,10%,X7RA   I122 @S9S_MB_2U_LIB.S9S_MB_2U(SCH_1):PAGE245

SW_P3V3_AUX_BOOT_R @S9S_MB_2U_LIB.S9S_MB_2U(SCH_1):SW_P3V3_AUX_BOOT_R
 PC568    2      B Q_CAP_C0402-0.22UF,25V,10%,X7RA   I122 @S9S_MB_2U_LIB.S9S_MB_2U(SCH_1):PAGE245
 PR835    2      B Q_RES_0402LF-0,5%,1/16W,CHIP,CA   I123 @S9S_MB_2U_LIB.S9S_MB_2U(SCH_1):PAGE245

SW_P3V3_AUX_FLT @S9S_MB_2U_LIB.S9S_MB_2U(SCH_1):SW_P3V3_AUX_FLT
   PU9 20_24   PVIN IR3889MTRPBF-IR3889MTRPBF,SMLFA    I95 @S9S_MB_2U_LIB.S9S_MB_2U(SCH_1):PAGE245
  PL45    2      2 Q_INDUCTOR_SMLF-100NH/16A,IND,A    I98 @S9S_MB_2U_LIB.S9S_MB_2U(SCH_1):PAGE245
PC2260    1      A Q_CAP_C0805-22UF,16V,20%,X6S,CA   I100 @S9S_MB_2U_LIB.S9S_MB_2U(SCH_1):PAGE245
PC2261    1      A Q_CAP_C0805-22UF,16V,20%,X6S,CA   I101 @S9S_MB_2U_LIB.S9S_MB_2U(SCH_1):PAGE245
   PC3    1      A Q_CAPP_THLF-270UF,16V,20%,OSCOA   I103 @S9S_MB_2U_LIB.S9S_MB_2U(SCH_1):PAGE245
 PC566    1      A Q_CAPP_THLF-270UF,16V,20%,OSCOA   I104 @S9S_MB_2U_LIB.S9S_MB_2U(SCH_1):PAGE245
PC2262    1      A Q_CAP_C0805-22UF,16V,20%,X6S,CA   I105 @S9S_MB_2U_LIB.S9S_MB_2U(SCH_1):PAGE245
 PC567    1      A Q_CAP_C0805-22UF,16V,20%,X6S,CA   I106 @S9S_MB_2U_LIB.S9S_MB_2U(SCH_1):PAGE245
PC2263    1      A Q_CAP_C0805-22UF,16V,20%,X6S,CA   I107 @S9S_MB_2U_LIB.S9S_MB_2U(SCH_1):PAGE245
PC2342    1      A Q_CAP_C0805-22UF,16V,20%,X6S,CA   I108 @S9S_MB_2U_LIB.S9S_MB_2U(SCH_1):PAGE245
 PC570    1      A Q_CAP_C0805-22UF,16V,20%,X6S,CA   I109 @S9S_MB_2U_LIB.S9S_MB_2U(SCH_1):PAGE245
 PC571    1      A Q_CAP_C0805-22UF,16V,20%,X6S,CA   I110 @S9S_MB_2U_LIB.S9S_MB_2U(SCH_1):PAGE245
PC2343    1      A Q_CAP_C0805-22UF,16V,20%,X6S,CA   I111 @S9S_MB_2U_LIB.S9S_MB_2U(SCH_1):PAGE245
PC2344    1      A Q_CAP_C0805-22UF,16V,20%,X6S,CA   I112 @S9S_MB_2U_LIB.S9S_MB_2U(SCH_1):PAGE245
 PC576    1      A Q_CAP_C0805-22UF,16V,20%,X6S,CA   I113 @S9S_MB_2U_LIB.S9S_MB_2U(SCH_1):PAGE245
  PC71    1      A Q_CAP_C0805-22UF,16V,20%,X6S,CA   I114 @S9S_MB_2U_LIB.S9S_MB_2U(SCH_1):PAGE245
 PC577    1      A Q_CAP_0402-0.1UF,25V,10%,X7R,CA   I115 @S9S_MB_2U_LIB.S9S_MB_2U(SCH_1):PAGE245

SW_P3V3_AUX_SW @S9S_MB_2U_LIB.S9S_MB_2U(SCH_1):SW_P3V3_AUX_SW
   PU9 11_18     SW IR3889MTRPBF-IR3889MTRPBF,SMLFA    I95 @S9S_MB_2U_LIB.S9S_MB_2U(SCH_1):PAGE245
  PL66    1      1 Q_INDUCTOR_SMLF-1.5UH/53A,IND,A   I129 @S9S_MB_2U_LIB.S9S_MB_2U(SCH_1):PAGE245

SW_P5V_AUX_BST @S9S_MB_2U_LIB.S9S_MB_2U(SCH_1):SW_P5V_AUX_BST
PC1847    1      A Q_CAP_C0402-0.22UF,25V,10%,X7RA    I26 @S9S_MB_2U_LIB.S9S_MB_2U(SCH_1):PAGE244
 PU181    1    BST RS53318LR-RS53318LR,SMLF,IC,ALA    I20 @S9S_MB_2U_LIB.S9S_MB_2U(SCH_1):PAGE244

SW_P5V_AUX_FLT @S9S_MB_2U_LIB.S9S_MB_2U(SCH_1):SW_P5V_AUX_FLT
PC1898    1      A Q_CAP_C0805-22UF,16V,20%,X6S,CA    I12 @S9S_MB_2U_LIB.S9S_MB_2U(SCH_1):PAGE244
  PL64    2      2 Q_INDUCTOR_SMLF-BLM18SN220TN1DA     I5 @S9S_MB_2U_LIB.S9S_MB_2U(SCH_1):PAGE244
PC1849    1      A Q_CAP_C0805-22UF,16V,20%,X6S,CA     I7 @S9S_MB_2U_LIB.S9S_MB_2U(SCH_1):PAGE244
PC1850    1      A Q_CAP_C0805-22UF,16V,20%,X6S,CA    I11 @S9S_MB_2U_LIB.S9S_MB_2U(SCH_1):PAGE244
PC1846    1      A Q_CAP_C0402-1UF,16V,10%,X6S,CHA    I14 @S9S_MB_2U_LIB.S9S_MB_2U(SCH_1):PAGE244
 PU181   10   VIN1 RS53318LR-RS53318LR,SMLF,IC,ALA    I20 @S9S_MB_2U_LIB.S9S_MB_2U(SCH_1):PAGE244
 PU181   21   VIN2 RS53318LR-RS53318LR,SMLF,IC,ALA    I20 @S9S_MB_2U_LIB.S9S_MB_2U(SCH_1):PAGE244

SW_P5V_AUX_SW @S9S_MB_2U_LIB.S9S_MB_2U(SCH_1):SW_P5V_AUX_SW
  PL65    1      1 Q_INDUCTOR_SMLF-4.7UH,IND,CV-4A    I30 @S9S_MB_2U_LIB.S9S_MB_2U(SCH_1):PAGE244
PC1847    2      B Q_CAP_C0402-0.22UF,25V,10%,X7RA    I26 @S9S_MB_2U_LIB.S9S_MB_2U(SCH_1):PAGE244
 PU181   20     SW RS53318LR-RS53318LR,SMLF,IC,ALA    I20 @S9S_MB_2U_LIB.S9S_MB_2U(SCH_1):PAGE244

SW_PVCCD_HV_CPU0_BOOT1 @S9S_MB_2U_LIB.S9S_MB_2U(SCH_1):SW_PVCCD_HV_CPU0_BOOT1
  PU36   33   BOOT ISL99390FRZTR5935-ISL99390FRZ-A     I8 @S9S_MB_2U_LIB.S9S_MB_2U(SCH_1):PAGE265
PR1784    1      A Q_RES_0402LF-3.3,1%,1/16W,CHIPA    I19 @S9S_MB_2U_LIB.S9S_MB_2U(SCH_1):PAGE265

SW_PVCCD_HV_CPU0_BOOT1_R @S9S_MB_2U_LIB.S9S_MB_2U(SCH_1):SW_PVCCD_HV_CPU0_BOOT1_R
PR1784    2      B Q_RES_0402LF-3.3,1%,1/16W,CHIPA    I19 @S9S_MB_2U_LIB.S9S_MB_2U(SCH_1):PAGE265
 PC636    1      A Q_CAP_C0402-100NF,50V,10%,X7R,A    I22 @S9S_MB_2U_LIB.S9S_MB_2U(SCH_1):PAGE265

SW_PVCCD_HV_CPU0_BOOTR1 @S9S_MB_2U_LIB.S9S_MB_2U(SCH_1):SW_PVCCD_HV_CPU0_BOOTR1
  PU36   32  PHASE ISL99390FRZTR5935-ISL99390FRZ-A     I8 @S9S_MB_2U_LIB.S9S_MB_2U(SCH_1):PAGE265
 PC636    2      B Q_CAP_C0402-100NF,50V,10%,X7R,A    I22 @S9S_MB_2U_LIB.S9S_MB_2U(SCH_1):PAGE265

SW_PVCCD_HV_CPU0_SW1 @S9S_MB_2U_LIB.S9S_MB_2U(SCH_1):SW_PVCCD_HV_CPU0_SW1
  PU36 10_19     SW ISL99390FRZTR5935-ISL99390FRZ-A     I8 @S9S_MB_2U_LIB.S9S_MB_2U(SCH_1):PAGE265
  PL35    1      1 Q_INDUCTOR_SMLF-120NH/69A,IND,A    I30 @S9S_MB_2U_LIB.S9S_MB_2U(SCH_1):PAGE265

SW_PVCCD_HV_CPU1_BOOT1 @S9S_MB_2U_LIB.S9S_MB_2U(SCH_1):SW_PVCCD_HV_CPU1_BOOT1
PR1804    1      A Q_RES_0402LF-3.3,1%,1/16W,CHIPA    I21 @S9S_MB_2U_LIB.S9S_MB_2U(SCH_1):PAGE283
  PU17   33   BOOT ISL99390FRZTR5935-ISL99390FRZ-A    I10 @S9S_MB_2U_LIB.S9S_MB_2U(SCH_1):PAGE283

SW_PVCCD_HV_CPU1_BOOT1_R @S9S_MB_2U_LIB.S9S_MB_2U(SCH_1):SW_PVCCD_HV_CPU1_BOOT1_R
PR1804    2      B Q_RES_0402LF-3.3,1%,1/16W,CHIPA    I21 @S9S_MB_2U_LIB.S9S_MB_2U(SCH_1):PAGE283
 PC376    1      A Q_CAP_C0402-100NF,50V,10%,X7R,A    I13 @S9S_MB_2U_LIB.S9S_MB_2U(SCH_1):PAGE283

SW_PVCCD_HV_CPU1_BOOTR1 @S9S_MB_2U_LIB.S9S_MB_2U(SCH_1):SW_PVCCD_HV_CPU1_BOOTR1
  PU17   32  PHASE ISL99390FRZTR5935-ISL99390FRZ-A    I10 @S9S_MB_2U_LIB.S9S_MB_2U(SCH_1):PAGE283
 PC376    2      B Q_CAP_C0402-100NF,50V,10%,X7R,A    I13 @S9S_MB_2U_LIB.S9S_MB_2U(SCH_1):PAGE283

SW_PVCCD_HV_CPU1_SW1 @S9S_MB_2U_LIB.S9S_MB_2U(SCH_1):SW_PVCCD_HV_CPU1_SW1
  PL17    1      1 Q_INDUCTOR_SMLF-120NH/69A,IND,A    I14 @S9S_MB_2U_LIB.S9S_MB_2U(SCH_1):PAGE283
  PU17 10_19     SW ISL99390FRZTR5935-ISL99390FRZ-A    I10 @S9S_MB_2U_LIB.S9S_MB_2U(SCH_1):PAGE283

SW_PVCCFA_EHV_CPU0_BOOT1 @S9S_MB_2U_LIB.S9S_MB_2U(SCH_1):SW_PVCCFA_EHV_CPU0_BOOT1
PR1778    1      A Q_RES_0402LF-3.3,1%,1/16W,CHIPA    I17 @S9S_MB_2U_LIB.S9S_MB_2U(SCH_1):PAGE262
  PU42   20   BOOT RAA2213404GNPHB0-RAA2213404GNPA    I14 @S9S_MB_2U_LIB.S9S_MB_2U(SCH_1):PAGE262

SW_PVCCFA_EHV_CPU0_BOOT1_R @S9S_MB_2U_LIB.S9S_MB_2U(SCH_1):SW_PVCCFA_EHV_CPU0_BOOT1_R
PR1778    2      B Q_RES_0402LF-3.3,1%,1/16W,CHIPA    I17 @S9S_MB_2U_LIB.S9S_MB_2U(SCH_1):PAGE262
 PC178    1      A Q_CAP_C0402-100NF,50V,10%,X7R,A    I20 @S9S_MB_2U_LIB.S9S_MB_2U(SCH_1):PAGE262

SW_PVCCFA_EHV_CPU0_BOOTR1 @S9S_MB_2U_LIB.S9S_MB_2U(SCH_1):SW_PVCCFA_EHV_CPU0_BOOTR1
  PU42   19  PHASE RAA2213404GNPHB0-RAA2213404GNPA    I14 @S9S_MB_2U_LIB.S9S_MB_2U(SCH_1):PAGE262
 PC178    2      B Q_CAP_C0402-100NF,50V,10%,X7R,A    I20 @S9S_MB_2U_LIB.S9S_MB_2U(SCH_1):PAGE262

SW_PVCCFA_EHV_CPU0_SW1 @S9S_MB_2U_LIB.S9S_MB_2U(SCH_1):SW_PVCCFA_EHV_CPU0_SW1
   PL3    1      1 Q_INDUCTOR_SMLF-300NH/33A,IND,A    I29 @S9S_MB_2U_LIB.S9S_MB_2U(SCH_1):PAGE262
  PU42 8_12     SW RAA2213404GNPHB0-RAA2213404GNPA    I14 @S9S_MB_2U_LIB.S9S_MB_2U(SCH_1):PAGE262

SW_PVCCFA_EHV_CPU1_BOOT1 @S9S_MB_2U_LIB.S9S_MB_2U(SCH_1):SW_PVCCFA_EHV_CPU1_BOOT1
  PU49   20   BOOT RAA2213404GNPHB0-RAA2213404GNPA    I14 @S9S_MB_2U_LIB.S9S_MB_2U(SCH_1):PAGE280
PR1798    1      A Q_RES_0402LF-3.3,1%,1/16W,CHIPA    I25 @S9S_MB_2U_LIB.S9S_MB_2U(SCH_1):PAGE280

SW_PVCCFA_EHV_CPU1_BOOT1_R @S9S_MB_2U_LIB.S9S_MB_2U(SCH_1):SW_PVCCFA_EHV_CPU1_BOOT1_R
 PC431    1      A Q_CAP_C0402-100NF,50V,10%,X7R,A    I22 @S9S_MB_2U_LIB.S9S_MB_2U(SCH_1):PAGE280
PR1798    2      B Q_RES_0402LF-3.3,1%,1/16W,CHIPA    I25 @S9S_MB_2U_LIB.S9S_MB_2U(SCH_1):PAGE280

SW_PVCCFA_EHV_CPU1_BOOTR1 @S9S_MB_2U_LIB.S9S_MB_2U(SCH_1):SW_PVCCFA_EHV_CPU1_BOOTR1
  PU49   19  PHASE RAA2213404GNPHB0-RAA2213404GNPA    I14 @S9S_MB_2U_LIB.S9S_MB_2U(SCH_1):PAGE280
 PC431    2      B Q_CAP_C0402-100NF,50V,10%,X7R,A    I22 @S9S_MB_2U_LIB.S9S_MB_2U(SCH_1):PAGE280

SW_PVCCFA_EHV_CPU1_SW1 @S9S_MB_2U_LIB.S9S_MB_2U(SCH_1):SW_PVCCFA_EHV_CPU1_SW1
  PU49 8_12     SW RAA2213404GNPHB0-RAA2213404GNPA    I14 @S9S_MB_2U_LIB.S9S_MB_2U(SCH_1):PAGE280
  PL20    1      1 Q_INDUCTOR_SMLF-300NH/33A,IND,A    I23 @S9S_MB_2U_LIB.S9S_MB_2U(SCH_1):PAGE280

SW_PVCCFA_EHV_FIVRA_CPU0_BOOT1 @S9S_MB_2U_LIB.S9S_MB_2U(SCH_1):SW_PVCCFA_EHV_FIVRA_CPU0_BOOT1
PR1780    1      A Q_RES_0402LF-3.3,1%,1/16W,CHIPA    I46 @S9S_MB_2U_LIB.S9S_MB_2U(SCH_1):PAGE257
PU69_P0_1   33   BOOT ISL99390FRZTR5935-ISL99390FRZ-A    I25 @S9S_MB_2U_LIB.S9S_MB_2U(SCH_1):PAGE257

SW_PVCCFA_EHV_FIVRA_CPU0_BOOT1_ @S9S_MB_2U_LIB.S9S_MB_2U(SCH_1):SW_PVCCFA_EHV_FIVRA_CPU0_BOOT1_R
PR1780    2      B Q_RES_0402LF-3.3,1%,1/16W,CHIPA    I46 @S9S_MB_2U_LIB.S9S_MB_2U(SCH_1):PAGE257
 PC606    1      A Q_CAP_C0402-100NF,50V,10%,X7R,A    I71 @S9S_MB_2U_LIB.S9S_MB_2U(SCH_1):PAGE257

SW_PVCCFA_EHV_FIVRA_CPU0_BOOT2 @S9S_MB_2U_LIB.S9S_MB_2U(SCH_1):SW_PVCCFA_EHV_FIVRA_CPU0_BOOT2
PU70_P0_2   33   BOOT ISL99390FRZTR5935-ISL99390FRZ-A    I16 @S9S_MB_2U_LIB.S9S_MB_2U(SCH_1):PAGE257
PR1781    1      A Q_RES_0402LF-3.3,1%,1/16W,CHIPA    I30 @S9S_MB_2U_LIB.S9S_MB_2U(SCH_1):PAGE257

SW_PVCCFA_EHV_FIVRA_CPU0_BOOT2_ @S9S_MB_2U_LIB.S9S_MB_2U(SCH_1):SW_PVCCFA_EHV_FIVRA_CPU0_BOOT2_R
PR1781    2      B Q_RES_0402LF-3.3,1%,1/16W,CHIPA    I30 @S9S_MB_2U_LIB.S9S_MB_2U(SCH_1):PAGE257
 PC607    1      A Q_CAP_C0402-100NF,50V,10%,X7R,A    I53 @S9S_MB_2U_LIB.S9S_MB_2U(SCH_1):PAGE257

SW_PVCCFA_EHV_FIVRA_CPU0_BOOT3 @S9S_MB_2U_LIB.S9S_MB_2U(SCH_1):SW_PVCCFA_EHV_FIVRA_CPU0_BOOT3
PR1782    1      A Q_RES_0402LF-3.3,1%,1/16W,CHIPA    I45 @S9S_MB_2U_LIB.S9S_MB_2U(SCH_1):PAGE258
PU71_P0_3   33   BOOT ISL99390FRZTR5935-ISL99390FRZ-A    I82 @S9S_MB_2U_LIB.S9S_MB_2U(SCH_1):PAGE258

SW_PVCCFA_EHV_FIVRA_CPU0_BOOT3_ @S9S_MB_2U_LIB.S9S_MB_2U(SCH_1):SW_PVCCFA_EHV_FIVRA_CPU0_BOOT3_R
PR1782    2      B Q_RES_0402LF-3.3,1%,1/16W,CHIPA    I45 @S9S_MB_2U_LIB.S9S_MB_2U(SCH_1):PAGE258
PC1177    1      A Q_CAP_C0402-100NF,50V,10%,X7R,A    I49 @S9S_MB_2U_LIB.S9S_MB_2U(SCH_1):PAGE258

SW_PVCCFA_EHV_FIVRA_CPU0_BOOT4 @S9S_MB_2U_LIB.S9S_MB_2U(SCH_1):SW_PVCCFA_EHV_FIVRA_CPU0_BOOT4
PR1783    1      A Q_RES_0402LF-3.3,1%,1/16W,CHIPA    I33 @S9S_MB_2U_LIB.S9S_MB_2U(SCH_1):PAGE258
PU72_P0_4   33   BOOT ISL99390FRZTR5935-ISL99390FRZ-A    I10 @S9S_MB_2U_LIB.S9S_MB_2U(SCH_1):PAGE258

SW_PVCCFA_EHV_FIVRA_CPU0_BOOT4_ @S9S_MB_2U_LIB.S9S_MB_2U(SCH_1):SW_PVCCFA_EHV_FIVRA_CPU0_BOOT4_R
PR1783    2      B Q_RES_0402LF-3.3,1%,1/16W,CHIPA    I33 @S9S_MB_2U_LIB.S9S_MB_2U(SCH_1):PAGE258
PC1178    1      A Q_CAP_C0402-100NF,50V,10%,X7R,A    I37 @S9S_MB_2U_LIB.S9S_MB_2U(SCH_1):PAGE258

SW_PVCCFA_EHV_FIVRA_CPU0_BOOTR1 @S9S_MB_2U_LIB.S9S_MB_2U(SCH_1):SW_PVCCFA_EHV_FIVRA_CPU0_BOOTR1
PU69_P0_1   32  PHASE ISL99390FRZTR5935-ISL99390FRZ-A    I25 @S9S_MB_2U_LIB.S9S_MB_2U(SCH_1):PAGE257
 PC606    2      B Q_CAP_C0402-100NF,50V,10%,X7R,A    I71 @S9S_MB_2U_LIB.S9S_MB_2U(SCH_1):PAGE257

SW_PVCCFA_EHV_FIVRA_CPU0_BOOTR2 @S9S_MB_2U_LIB.S9S_MB_2U(SCH_1):SW_PVCCFA_EHV_FIVRA_CPU0_BOOTR2
PU70_P0_2   32  PHASE ISL99390FRZTR5935-ISL99390FRZ-A    I16 @S9S_MB_2U_LIB.S9S_MB_2U(SCH_1):PAGE257
 PC607    2      B Q_CAP_C0402-100NF,50V,10%,X7R,A    I53 @S9S_MB_2U_LIB.S9S_MB_2U(SCH_1):PAGE257

SW_PVCCFA_EHV_FIVRA_CPU0_BOOTR3 @S9S_MB_2U_LIB.S9S_MB_2U(SCH_1):SW_PVCCFA_EHV_FIVRA_CPU0_BOOTR3
PU71_P0_3   32  PHASE ISL99390FRZTR5935-ISL99390FRZ-A    I82 @S9S_MB_2U_LIB.S9S_MB_2U(SCH_1):PAGE258
PC1177    2      B Q_CAP_C0402-100NF,50V,10%,X7R,A    I49 @S9S_MB_2U_LIB.S9S_MB_2U(SCH_1):PAGE258

SW_PVCCFA_EHV_FIVRA_CPU0_BOOTR4 @S9S_MB_2U_LIB.S9S_MB_2U(SCH_1):SW_PVCCFA_EHV_FIVRA_CPU0_BOOTR4
PC1178    2      B Q_CAP_C0402-100NF,50V,10%,X7R,A    I37 @S9S_MB_2U_LIB.S9S_MB_2U(SCH_1):PAGE258
PU72_P0_4   32  PHASE ISL99390FRZTR5935-ISL99390FRZ-A    I10 @S9S_MB_2U_LIB.S9S_MB_2U(SCH_1):PAGE258

SW_PVCCFA_EHV_FIVRA_CPU0_SW1 @S9S_MB_2U_LIB.S9S_MB_2U(SCH_1):SW_PVCCFA_EHV_FIVRA_CPU0_SW1
  PL33    1      1 Q_INDUCTOR_SMLF-130NH/106A,INDA    I70 @S9S_MB_2U_LIB.S9S_MB_2U(SCH_1):PAGE257
PU69_P0_1 10_19     SW ISL99390FRZTR5935-ISL99390FRZ-A    I25 @S9S_MB_2U_LIB.S9S_MB_2U(SCH_1):PAGE257

SW_PVCCFA_EHV_FIVRA_CPU0_SW2 @S9S_MB_2U_LIB.S9S_MB_2U(SCH_1):SW_PVCCFA_EHV_FIVRA_CPU0_SW2
  PL34    1      1 Q_INDUCTOR_SMLF-130NH/106A,INDA    I49 @S9S_MB_2U_LIB.S9S_MB_2U(SCH_1):PAGE257
PU70_P0_2 10_19     SW ISL99390FRZTR5935-ISL99390FRZ-A    I16 @S9S_MB_2U_LIB.S9S_MB_2U(SCH_1):PAGE257

SW_PVCCFA_EHV_FIVRA_CPU0_SW3 @S9S_MB_2U_LIB.S9S_MB_2U(SCH_1):SW_PVCCFA_EHV_FIVRA_CPU0_SW3
   PL2    1      1 Q_INDUCTOR_SMLF-130NH/106A,INDA    I51 @S9S_MB_2U_LIB.S9S_MB_2U(SCH_1):PAGE258
PU71_P0_3 10_19     SW ISL99390FRZTR5935-ISL99390FRZ-A    I82 @S9S_MB_2U_LIB.S9S_MB_2U(SCH_1):PAGE258

SW_PVCCFA_EHV_FIVRA_CPU0_SW4 @S9S_MB_2U_LIB.S9S_MB_2U(SCH_1):SW_PVCCFA_EHV_FIVRA_CPU0_SW4
 PL210    1      1 Q_INDUCTOR_SMLF-130NH/106A,INDA    I39 @S9S_MB_2U_LIB.S9S_MB_2U(SCH_1):PAGE258
PU72_P0_4 10_19     SW ISL99390FRZTR5935-ISL99390FRZ-A    I10 @S9S_MB_2U_LIB.S9S_MB_2U(SCH_1):PAGE258

SW_PVCCFA_EHV_FIVRA_CPU1_BOOT1 @S9S_MB_2U_LIB.S9S_MB_2U(SCH_1):SW_PVCCFA_EHV_FIVRA_CPU1_BOOT1
PR1800    1      A Q_RES_0402LF-3.3,1%,1/16W,CHIPA    I50 @S9S_MB_2U_LIB.S9S_MB_2U(SCH_1):PAGE275
PU75_P1_1   33   BOOT ISL99390FRZTR5935-ISL99390FRZ-A    I89 @S9S_MB_2U_LIB.S9S_MB_2U(SCH_1):PAGE275

SW_PVCCFA_EHV_FIVRA_CPU1_BOOT1_ @S9S_MB_2U_LIB.S9S_MB_2U(SCH_1):SW_PVCCFA_EHV_FIVRA_CPU1_BOOT1_R
PR1800    2      B Q_RES_0402LF-3.3,1%,1/16W,CHIPA    I50 @S9S_MB_2U_LIB.S9S_MB_2U(SCH_1):PAGE275
 PC401    1      A Q_CAP_C0402-100NF,50V,10%,X7R,A    I54 @S9S_MB_2U_LIB.S9S_MB_2U(SCH_1):PAGE275

SW_PVCCFA_EHV_FIVRA_CPU1_BOOT2 @S9S_MB_2U_LIB.S9S_MB_2U(SCH_1):SW_PVCCFA_EHV_FIVRA_CPU1_BOOT2
PU76_P1_2   33   BOOT ISL99390FRZTR5935-ISL99390FRZ-A     I9 @S9S_MB_2U_LIB.S9S_MB_2U(SCH_1):PAGE275
PR1801    1      A Q_RES_0402LF-3.3,1%,1/16W,CHIPA    I38 @S9S_MB_2U_LIB.S9S_MB_2U(SCH_1):PAGE275

SW_PVCCFA_EHV_FIVRA_CPU1_BOOT2_ @S9S_MB_2U_LIB.S9S_MB_2U(SCH_1):SW_PVCCFA_EHV_FIVRA_CPU1_BOOT2_R
PR1801    2      B Q_RES_0402LF-3.3,1%,1/16W,CHIPA    I38 @S9S_MB_2U_LIB.S9S_MB_2U(SCH_1):PAGE275
 PC402    1      A Q_CAP_C0402-100NF,50V,10%,X7R,A    I43 @S9S_MB_2U_LIB.S9S_MB_2U(SCH_1):PAGE275

SW_PVCCFA_EHV_FIVRA_CPU1_BOOT3 @S9S_MB_2U_LIB.S9S_MB_2U(SCH_1):SW_PVCCFA_EHV_FIVRA_CPU1_BOOT3
PR1802    1      A Q_RES_0402LF-3.3,1%,1/16W,CHIPA    I40 @S9S_MB_2U_LIB.S9S_MB_2U(SCH_1):PAGE276
PU77_P1_3   33   BOOT ISL99390FRZTR5935-ISL99390FRZ-A    I24 @S9S_MB_2U_LIB.S9S_MB_2U(SCH_1):PAGE276

SW_PVCCFA_EHV_FIVRA_CPU1_BOOT3_ @S9S_MB_2U_LIB.S9S_MB_2U(SCH_1):SW_PVCCFA_EHV_FIVRA_CPU1_BOOT3_R
PR1802    2      B Q_RES_0402LF-3.3,1%,1/16W,CHIPA    I40 @S9S_MB_2U_LIB.S9S_MB_2U(SCH_1):PAGE276
PC1197    1      A Q_CAP_C0402-100NF,50V,10%,X7R,A    I58 @S9S_MB_2U_LIB.S9S_MB_2U(SCH_1):PAGE276

SW_PVCCFA_EHV_FIVRA_CPU1_BOOT4 @S9S_MB_2U_LIB.S9S_MB_2U(SCH_1):SW_PVCCFA_EHV_FIVRA_CPU1_BOOT4
PU78_P1_4   33   BOOT ISL99390FRZTR5935-ISL99390FRZ-A    I15 @S9S_MB_2U_LIB.S9S_MB_2U(SCH_1):PAGE276
PR1803    1      A Q_RES_0402LF-3.3,1%,1/16W,CHIPA    I17 @S9S_MB_2U_LIB.S9S_MB_2U(SCH_1):PAGE276

SW_PVCCFA_EHV_FIVRA_CPU1_BOOT4_ @S9S_MB_2U_LIB.S9S_MB_2U(SCH_1):SW_PVCCFA_EHV_FIVRA_CPU1_BOOT4_R
PC1198    1      A Q_CAP_C0402-100NF,50V,10%,X7R,A    I45 @S9S_MB_2U_LIB.S9S_MB_2U(SCH_1):PAGE276
PR1803    2      B Q_RES_0402LF-3.3,1%,1/16W,CHIPA    I17 @S9S_MB_2U_LIB.S9S_MB_2U(SCH_1):PAGE276

SW_PVCCFA_EHV_FIVRA_CPU1_BOOTR1 @S9S_MB_2U_LIB.S9S_MB_2U(SCH_1):SW_PVCCFA_EHV_FIVRA_CPU1_BOOTR1
 PC401    2      B Q_CAP_C0402-100NF,50V,10%,X7R,A    I54 @S9S_MB_2U_LIB.S9S_MB_2U(SCH_1):PAGE275
PU75_P1_1   32  PHASE ISL99390FRZTR5935-ISL99390FRZ-A    I89 @S9S_MB_2U_LIB.S9S_MB_2U(SCH_1):PAGE275

SW_PVCCFA_EHV_FIVRA_CPU1_BOOTR2 @S9S_MB_2U_LIB.S9S_MB_2U(SCH_1):SW_PVCCFA_EHV_FIVRA_CPU1_BOOTR2
PU76_P1_2   32  PHASE ISL99390FRZTR5935-ISL99390FRZ-A     I9 @S9S_MB_2U_LIB.S9S_MB_2U(SCH_1):PAGE275
 PC402    2      B Q_CAP_C0402-100NF,50V,10%,X7R,A    I43 @S9S_MB_2U_LIB.S9S_MB_2U(SCH_1):PAGE275

SW_PVCCFA_EHV_FIVRA_CPU1_BOOTR3 @S9S_MB_2U_LIB.S9S_MB_2U(SCH_1):SW_PVCCFA_EHV_FIVRA_CPU1_BOOTR3
PU77_P1_3   32  PHASE ISL99390FRZTR5935-ISL99390FRZ-A    I24 @S9S_MB_2U_LIB.S9S_MB_2U(SCH_1):PAGE276
PC1197    2      B Q_CAP_C0402-100NF,50V,10%,X7R,A    I58 @S9S_MB_2U_LIB.S9S_MB_2U(SCH_1):PAGE276

SW_PVCCFA_EHV_FIVRA_CPU1_BOOTR4 @S9S_MB_2U_LIB.S9S_MB_2U(SCH_1):SW_PVCCFA_EHV_FIVRA_CPU1_BOOTR4
PC1198    2      B Q_CAP_C0402-100NF,50V,10%,X7R,A    I45 @S9S_MB_2U_LIB.S9S_MB_2U(SCH_1):PAGE276
PU78_P1_4   32  PHASE ISL99390FRZTR5935-ISL99390FRZ-A    I15 @S9S_MB_2U_LIB.S9S_MB_2U(SCH_1):PAGE276

SW_PVCCFA_EHV_FIVRA_CPU1_SW1 @S9S_MB_2U_LIB.S9S_MB_2U(SCH_1):SW_PVCCFA_EHV_FIVRA_CPU1_SW1
  PL18    1      1 Q_INDUCTOR_SMLF-130NH/106A,INDA    I55 @S9S_MB_2U_LIB.S9S_MB_2U(SCH_1):PAGE275
PU75_P1_1 10_19     SW ISL99390FRZTR5935-ISL99390FRZ-A    I89 @S9S_MB_2U_LIB.S9S_MB_2U(SCH_1):PAGE275

SW_PVCCFA_EHV_FIVRA_CPU1_SW2 @S9S_MB_2U_LIB.S9S_MB_2U(SCH_1):SW_PVCCFA_EHV_FIVRA_CPU1_SW2
PU76_P1_2 10_19     SW ISL99390FRZTR5935-ISL99390FRZ-A     I9 @S9S_MB_2U_LIB.S9S_MB_2U(SCH_1):PAGE275
  PL19    1      1 Q_INDUCTOR_SMLF-130NH/106A,INDA    I44 @S9S_MB_2U_LIB.S9S_MB_2U(SCH_1):PAGE275

SW_PVCCFA_EHV_FIVRA_CPU1_SW3 @S9S_MB_2U_LIB.S9S_MB_2U(SCH_1):SW_PVCCFA_EHV_FIVRA_CPU1_SW3
  PL12    1      1 Q_INDUCTOR_SMLF-130NH/106A,INDA    I57 @S9S_MB_2U_LIB.S9S_MB_2U(SCH_1):PAGE276
PU77_P1_3 10_19     SW ISL99390FRZTR5935-ISL99390FRZ-A    I24 @S9S_MB_2U_LIB.S9S_MB_2U(SCH_1):PAGE276

SW_PVCCFA_EHV_FIVRA_CPU1_SW4 @S9S_MB_2U_LIB.S9S_MB_2U(SCH_1):SW_PVCCFA_EHV_FIVRA_CPU1_SW4
 PL113    1      1 Q_INDUCTOR_SMLF-130NH/106A,INDA    I44 @S9S_MB_2U_LIB.S9S_MB_2U(SCH_1):PAGE276
PU78_P1_4 10_19     SW ISL99390FRZTR5935-ISL99390FRZ-A    I15 @S9S_MB_2U_LIB.S9S_MB_2U(SCH_1):PAGE276

SW_PVCCINFAON_CPU0_BOOT1 @S9S_MB_2U_LIB.S9S_MB_2U(SCH_1):SW_PVCCINFAON_CPU0_BOOT1
PR1774    1      A Q_RES_0402LF-3.3,1%,1/16W,CHIPA    I47 @S9S_MB_2U_LIB.S9S_MB_2U(SCH_1):PAGE261
PU43_P0_1   33   BOOT ISL99390FRZTR5935-ISL99390FRZ-A    I79 @S9S_MB_2U_LIB.S9S_MB_2U(SCH_1):PAGE261

SW_PVCCINFAON_CPU0_BOOT1_R @S9S_MB_2U_LIB.S9S_MB_2U(SCH_1):SW_PVCCINFAON_CPU0_BOOT1_R
PR1774    2      B Q_RES_0402LF-3.3,1%,1/16W,CHIPA    I47 @S9S_MB_2U_LIB.S9S_MB_2U(SCH_1):PAGE261
 PC193    1      A Q_CAP_C0402-100NF,50V,10%,X7R,A    I51 @S9S_MB_2U_LIB.S9S_MB_2U(SCH_1):PAGE261

SW_PVCCINFAON_CPU0_BOOT2 @S9S_MB_2U_LIB.S9S_MB_2U(SCH_1):SW_PVCCINFAON_CPU0_BOOT2
PU44_P0_2   33   BOOT ISL99390FRZTR5935-ISL99390FRZ-A    I12 @S9S_MB_2U_LIB.S9S_MB_2U(SCH_1):PAGE261
PR1775    1      A Q_RES_0402LF-3.3,1%,1/16W,CHIPA    I34 @S9S_MB_2U_LIB.S9S_MB_2U(SCH_1):PAGE261

SW_PVCCINFAON_CPU0_BOOT2_R @S9S_MB_2U_LIB.S9S_MB_2U(SCH_1):SW_PVCCINFAON_CPU0_BOOT2_R
PR1775    2      B Q_RES_0402LF-3.3,1%,1/16W,CHIPA    I34 @S9S_MB_2U_LIB.S9S_MB_2U(SCH_1):PAGE261
 PC194    1      A Q_CAP_C0402-100NF,50V,10%,X7R,A    I38 @S9S_MB_2U_LIB.S9S_MB_2U(SCH_1):PAGE261

SW_PVCCINFAON_CPU0_BOOTR1 @S9S_MB_2U_LIB.S9S_MB_2U(SCH_1):SW_PVCCINFAON_CPU0_BOOTR1
 PC193    2      B Q_CAP_C0402-100NF,50V,10%,X7R,A    I51 @S9S_MB_2U_LIB.S9S_MB_2U(SCH_1):PAGE261
PU43_P0_1   32  PHASE ISL99390FRZTR5935-ISL99390FRZ-A    I79 @S9S_MB_2U_LIB.S9S_MB_2U(SCH_1):PAGE261

SW_PVCCINFAON_CPU0_BOOTR2 @S9S_MB_2U_LIB.S9S_MB_2U(SCH_1):SW_PVCCINFAON_CPU0_BOOTR2
PU44_P0_2   32  PHASE ISL99390FRZTR5935-ISL99390FRZ-A    I12 @S9S_MB_2U_LIB.S9S_MB_2U(SCH_1):PAGE261
 PC194    2      B Q_CAP_C0402-100NF,50V,10%,X7R,A    I38 @S9S_MB_2U_LIB.S9S_MB_2U(SCH_1):PAGE261

SW_PVCCINFAON_CPU0_SW1 @S9S_MB_2U_LIB.S9S_MB_2U(SCH_1):SW_PVCCINFAON_CPU0_SW1
   PL4    1      1 Q_INDUCTOR_SMLF-120NH/69A,IND,A    I52 @S9S_MB_2U_LIB.S9S_MB_2U(SCH_1):PAGE261
PU43_P0_1 10_19     SW ISL99390FRZTR5935-ISL99390FRZ-A    I79 @S9S_MB_2U_LIB.S9S_MB_2U(SCH_1):PAGE261

SW_PVCCINFAON_CPU0_SW2 @S9S_MB_2U_LIB.S9S_MB_2U(SCH_1):SW_PVCCINFAON_CPU0_SW2
PU44_P0_2 10_19     SW ISL99390FRZTR5935-ISL99390FRZ-A    I12 @S9S_MB_2U_LIB.S9S_MB_2U(SCH_1):PAGE261
   PL5    1      1 Q_INDUCTOR_SMLF-120NH/69A,IND,A    I39 @S9S_MB_2U_LIB.S9S_MB_2U(SCH_1):PAGE261

SW_PVCCINFAON_CPU1_BOOT1 @S9S_MB_2U_LIB.S9S_MB_2U(SCH_1):SW_PVCCINFAON_CPU1_BOOT1
PU50_P1_1   33   BOOT ISL99390FRZTR5935-ISL99390FRZ-A    I38 @S9S_MB_2U_LIB.S9S_MB_2U(SCH_1):PAGE279
PR1794    1      A Q_RES_0402LF-3.3,1%,1/16W,CHIPA    I50 @S9S_MB_2U_LIB.S9S_MB_2U(SCH_1):PAGE279

SW_PVCCINFAON_CPU1_BOOT1_R @S9S_MB_2U_LIB.S9S_MB_2U(SCH_1):SW_PVCCINFAON_CPU1_BOOT1_R
 PC446    1      A Q_CAP_C0402-100NF,50V,10%,X7R,A    I52 @S9S_MB_2U_LIB.S9S_MB_2U(SCH_1):PAGE279
PR1794    2      B Q_RES_0402LF-3.3,1%,1/16W,CHIPA    I50 @S9S_MB_2U_LIB.S9S_MB_2U(SCH_1):PAGE279

SW_PVCCINFAON_CPU1_BOOT2 @S9S_MB_2U_LIB.S9S_MB_2U(SCH_1):SW_PVCCINFAON_CPU1_BOOT2
PU51_P1_2   33   BOOT ISL99390FRZTR5935-ISL99390FRZ-A    I29 @S9S_MB_2U_LIB.S9S_MB_2U(SCH_1):PAGE279
PR1795    1      A Q_RES_0402LF-3.3,1%,1/16W,CHIPA    I42 @S9S_MB_2U_LIB.S9S_MB_2U(SCH_1):PAGE279

SW_PVCCINFAON_CPU1_BOOT2_R @S9S_MB_2U_LIB.S9S_MB_2U(SCH_1):SW_PVCCINFAON_CPU1_BOOT2_R
PR1795    2      B Q_RES_0402LF-3.3,1%,1/16W,CHIPA    I42 @S9S_MB_2U_LIB.S9S_MB_2U(SCH_1):PAGE279
 PC447    1      A Q_CAP_C0402-100NF,50V,10%,X7R,A    I44 @S9S_MB_2U_LIB.S9S_MB_2U(SCH_1):PAGE279

SW_PVCCINFAON_CPU1_BOOTR1 @S9S_MB_2U_LIB.S9S_MB_2U(SCH_1):SW_PVCCINFAON_CPU1_BOOTR1
PU50_P1_1   32  PHASE ISL99390FRZTR5935-ISL99390FRZ-A    I38 @S9S_MB_2U_LIB.S9S_MB_2U(SCH_1):PAGE279
 PC446    2      B Q_CAP_C0402-100NF,50V,10%,X7R,A    I52 @S9S_MB_2U_LIB.S9S_MB_2U(SCH_1):PAGE279

SW_PVCCINFAON_CPU1_BOOTR2 @S9S_MB_2U_LIB.S9S_MB_2U(SCH_1):SW_PVCCINFAON_CPU1_BOOTR2
PU51_P1_2   32  PHASE ISL99390FRZTR5935-ISL99390FRZ-A    I29 @S9S_MB_2U_LIB.S9S_MB_2U(SCH_1):PAGE279
 PC447    2      B Q_CAP_C0402-100NF,50V,10%,X7R,A    I44 @S9S_MB_2U_LIB.S9S_MB_2U(SCH_1):PAGE279

SW_PVCCINFAON_CPU1_SW1 @S9S_MB_2U_LIB.S9S_MB_2U(SCH_1):SW_PVCCINFAON_CPU1_SW1
PU50_P1_1 10_19     SW ISL99390FRZTR5935-ISL99390FRZ-A    I38 @S9S_MB_2U_LIB.S9S_MB_2U(SCH_1):PAGE279
  PL21    1      1 Q_INDUCTOR_SMLF-120NH/69A,IND,A    I54 @S9S_MB_2U_LIB.S9S_MB_2U(SCH_1):PAGE279

SW_PVCCINFAON_CPU1_SW2 @S9S_MB_2U_LIB.S9S_MB_2U(SCH_1):SW_PVCCINFAON_CPU1_SW2
PU51_P1_2 10_19     SW ISL99390FRZTR5935-ISL99390FRZ-A    I29 @S9S_MB_2U_LIB.S9S_MB_2U(SCH_1):PAGE279
  PL22    1      1 Q_INDUCTOR_SMLF-120NH/69A,IND,A    I46 @S9S_MB_2U_LIB.S9S_MB_2U(SCH_1):PAGE279

SW_PVCCIN_CPU0_BOOT1 @S9S_MB_2U_LIB.S9S_MB_2U(SCH_1):SW_PVCCIN_CPU0_BOOT1
PU13_P0_1   33   BOOT ISL99390FRZTR5935-ISL99390FRZ-A    I40 @S9S_MB_2U_LIB.S9S_MB_2U(SCH_1):PAGE253
PR1787    1      A Q_RES_0402LF-3.3,1%,1/16W,CHIPA    I97 @S9S_MB_2U_LIB.S9S_MB_2U(SCH_1):PAGE253

SW_PVCCIN_CPU0_BOOT1_R @S9S_MB_2U_LIB.S9S_MB_2U(SCH_1):SW_PVCCIN_CPU0_BOOT1_R
 PC301    1      A Q_CAP_C0402-100NF,50V,10%,X7R,A    I48 @S9S_MB_2U_LIB.S9S_MB_2U(SCH_1):PAGE253
PR1787    2      B Q_RES_0402LF-3.3,1%,1/16W,CHIPA    I97 @S9S_MB_2U_LIB.S9S_MB_2U(SCH_1):PAGE253

SW_PVCCIN_CPU0_BOOT2 @S9S_MB_2U_LIB.S9S_MB_2U(SCH_1):SW_PVCCIN_CPU0_BOOT2
PU12_P0_2   33   BOOT ISL99390FRZTR5935-ISL99390FRZ-A     I6 @S9S_MB_2U_LIB.S9S_MB_2U(SCH_1):PAGE253
PR1786    1      A Q_RES_0402LF-3.3,1%,1/16W,CHIPA    I18 @S9S_MB_2U_LIB.S9S_MB_2U(SCH_1):PAGE253

SW_PVCCIN_CPU0_BOOT2_R @S9S_MB_2U_LIB.S9S_MB_2U(SCH_1):SW_PVCCIN_CPU0_BOOT2_R
PR1786    2      B Q_RES_0402LF-3.3,1%,1/16W,CHIPA    I18 @S9S_MB_2U_LIB.S9S_MB_2U(SCH_1):PAGE253
 PC300    1      A Q_CAP_C0402-100NF,50V,10%,X7R,A    I20 @S9S_MB_2U_LIB.S9S_MB_2U(SCH_1):PAGE253

SW_PVCCIN_CPU0_BOOT3 @S9S_MB_2U_LIB.S9S_MB_2U(SCH_1):SW_PVCCIN_CPU0_BOOT3
PR1769    1      A Q_RES_0402LF-3.3,1%,1/16W,CHIPA    I49 @S9S_MB_2U_LIB.S9S_MB_2U(SCH_1):PAGE254
PU11_P0_3   33   BOOT ISL99390FRZTR5935-ISL99390FRZ-A    I20 @S9S_MB_2U_LIB.S9S_MB_2U(SCH_1):PAGE254

SW_PVCCIN_CPU0_BOOT3_R @S9S_MB_2U_LIB.S9S_MB_2U(SCH_1):SW_PVCCIN_CPU0_BOOT3_R
PR1769    2      B Q_RES_0402LF-3.3,1%,1/16W,CHIPA    I49 @S9S_MB_2U_LIB.S9S_MB_2U(SCH_1):PAGE254
 PC279    1      A Q_CAP_C0402-100NF,50V,10%,X7R,A    I51 @S9S_MB_2U_LIB.S9S_MB_2U(SCH_1):PAGE254

SW_PVCCIN_CPU0_BOOT4 @S9S_MB_2U_LIB.S9S_MB_2U(SCH_1):SW_PVCCIN_CPU0_BOOT4
PU10_P0_4   33   BOOT ISL99390FRZTR5935-ISL99390FRZ-A    I13 @S9S_MB_2U_LIB.S9S_MB_2U(SCH_1):PAGE254
PR1768    1      A Q_RES_0402LF-3.3,1%,1/16W,CHIPA    I36 @S9S_MB_2U_LIB.S9S_MB_2U(SCH_1):PAGE254

SW_PVCCIN_CPU0_BOOT4_R @S9S_MB_2U_LIB.S9S_MB_2U(SCH_1):SW_PVCCIN_CPU0_BOOT4_R
PR1768    2      B Q_RES_0402LF-3.3,1%,1/16W,CHIPA    I36 @S9S_MB_2U_LIB.S9S_MB_2U(SCH_1):PAGE254
 PC278    1      A Q_CAP_C0402-100NF,50V,10%,X7R,A    I34 @S9S_MB_2U_LIB.S9S_MB_2U(SCH_1):PAGE254

SW_PVCCIN_CPU0_BOOT5 @S9S_MB_2U_LIB.S9S_MB_2U(SCH_1):SW_PVCCIN_CPU0_BOOT5
PR1771    1      A Q_RES_0402LF-3.3,1%,1/16W,CHIPA    I49 @S9S_MB_2U_LIB.S9S_MB_2U(SCH_1):PAGE255
PU9_P0_5   33   BOOT ISL99390FRZTR5935-ISL99390FRZ-A    I66 @S9S_MB_2U_LIB.S9S_MB_2U(SCH_1):PAGE255

SW_PVCCIN_CPU0_BOOT5_R @S9S_MB_2U_LIB.S9S_MB_2U(SCH_1):SW_PVCCIN_CPU0_BOOT5_R
PR1771    2      B Q_RES_0402LF-3.3,1%,1/16W,CHIPA    I49 @S9S_MB_2U_LIB.S9S_MB_2U(SCH_1):PAGE255
 PC257    1      A Q_CAP_C0402-100NF,50V,10%,X7R,A    I51 @S9S_MB_2U_LIB.S9S_MB_2U(SCH_1):PAGE255

SW_PVCCIN_CPU0_BOOT6 @S9S_MB_2U_LIB.S9S_MB_2U(SCH_1):SW_PVCCIN_CPU0_BOOT6
PU8_P0_6   33   BOOT ISL99390FRZTR5935-ISL99390FRZ-A    I12 @S9S_MB_2U_LIB.S9S_MB_2U(SCH_1):PAGE255
PR1770    1      A Q_RES_0402LF-3.3,1%,1/16W,CHIPA    I35 @S9S_MB_2U_LIB.S9S_MB_2U(SCH_1):PAGE255

SW_PVCCIN_CPU0_BOOT6_R @S9S_MB_2U_LIB.S9S_MB_2U(SCH_1):SW_PVCCIN_CPU0_BOOT6_R
 PC256    1      A Q_CAP_C0402-100NF,50V,10%,X7R,A    I33 @S9S_MB_2U_LIB.S9S_MB_2U(SCH_1):PAGE255
PR1770    2      B Q_RES_0402LF-3.3,1%,1/16W,CHIPA    I35 @S9S_MB_2U_LIB.S9S_MB_2U(SCH_1):PAGE255

SW_PVCCIN_CPU0_BOOT7 @S9S_MB_2U_LIB.S9S_MB_2U(SCH_1):SW_PVCCIN_CPU0_BOOT7
PR1773    1      A Q_RES_0402LF-3.3,1%,1/16W,CHIPA    I40 @S9S_MB_2U_LIB.S9S_MB_2U(SCH_1):PAGE256
PU7_P0_7   33   BOOT ISL99390FRZTR5935-ISL99390FRZ-A    I32 @S9S_MB_2U_LIB.S9S_MB_2U(SCH_1):PAGE256

SW_PVCCIN_CPU0_BOOT7_R @S9S_MB_2U_LIB.S9S_MB_2U(SCH_1):SW_PVCCIN_CPU0_BOOT7_R
PR1773    2      B Q_RES_0402LF-3.3,1%,1/16W,CHIPA    I40 @S9S_MB_2U_LIB.S9S_MB_2U(SCH_1):PAGE256
 PC235    1      A Q_CAP_C0402-100NF,50V,10%,X7R,A    I59 @S9S_MB_2U_LIB.S9S_MB_2U(SCH_1):PAGE256

SW_PVCCIN_CPU0_BOOT8 @S9S_MB_2U_LIB.S9S_MB_2U(SCH_1):SW_PVCCIN_CPU0_BOOT8
PU6_P0_8   33   BOOT ISL99390FRZTR5935-ISL99390FRZ-A     I2 @S9S_MB_2U_LIB.S9S_MB_2U(SCH_1):PAGE256
PR1772    1      A Q_RES_0402LF-3.3,1%,1/16W,CHIPA    I19 @S9S_MB_2U_LIB.S9S_MB_2U(SCH_1):PAGE256

SW_PVCCIN_CPU0_BOOT8_R @S9S_MB_2U_LIB.S9S_MB_2U(SCH_1):SW_PVCCIN_CPU0_BOOT8_R
PR1772    2      B Q_RES_0402LF-3.3,1%,1/16W,CHIPA    I19 @S9S_MB_2U_LIB.S9S_MB_2U(SCH_1):PAGE256
 PC234    1      A Q_CAP_C0402-100NF,50V,10%,X7R,A    I45 @S9S_MB_2U_LIB.S9S_MB_2U(SCH_1):PAGE256

SW_PVCCIN_CPU0_BOOTR1 @S9S_MB_2U_LIB.S9S_MB_2U(SCH_1):SW_PVCCIN_CPU0_BOOTR1
PU13_P0_1   32  PHASE ISL99390FRZTR5935-ISL99390FRZ-A    I40 @S9S_MB_2U_LIB.S9S_MB_2U(SCH_1):PAGE253
 PC301    2      B Q_CAP_C0402-100NF,50V,10%,X7R,A    I48 @S9S_MB_2U_LIB.S9S_MB_2U(SCH_1):PAGE253

SW_PVCCIN_CPU0_BOOTR2 @S9S_MB_2U_LIB.S9S_MB_2U(SCH_1):SW_PVCCIN_CPU0_BOOTR2
PU12_P0_2   32  PHASE ISL99390FRZTR5935-ISL99390FRZ-A     I6 @S9S_MB_2U_LIB.S9S_MB_2U(SCH_1):PAGE253
 PC300    2      B Q_CAP_C0402-100NF,50V,10%,X7R,A    I20 @S9S_MB_2U_LIB.S9S_MB_2U(SCH_1):PAGE253

SW_PVCCIN_CPU0_BOOTR3 @S9S_MB_2U_LIB.S9S_MB_2U(SCH_1):SW_PVCCIN_CPU0_BOOTR3
 PC279    2      B Q_CAP_C0402-100NF,50V,10%,X7R,A    I51 @S9S_MB_2U_LIB.S9S_MB_2U(SCH_1):PAGE254
PU11_P0_3   32  PHASE ISL99390FRZTR5935-ISL99390FRZ-A    I20 @S9S_MB_2U_LIB.S9S_MB_2U(SCH_1):PAGE254

SW_PVCCIN_CPU0_BOOTR4 @S9S_MB_2U_LIB.S9S_MB_2U(SCH_1):SW_PVCCIN_CPU0_BOOTR4
PU10_P0_4   32  PHASE ISL99390FRZTR5935-ISL99390FRZ-A    I13 @S9S_MB_2U_LIB.S9S_MB_2U(SCH_1):PAGE254
 PC278    2      B Q_CAP_C0402-100NF,50V,10%,X7R,A    I34 @S9S_MB_2U_LIB.S9S_MB_2U(SCH_1):PAGE254

SW_PVCCIN_CPU0_BOOTR5 @S9S_MB_2U_LIB.S9S_MB_2U(SCH_1):SW_PVCCIN_CPU0_BOOTR5
 PC257    2      B Q_CAP_C0402-100NF,50V,10%,X7R,A    I51 @S9S_MB_2U_LIB.S9S_MB_2U(SCH_1):PAGE255
PU9_P0_5   32  PHASE ISL99390FRZTR5935-ISL99390FRZ-A    I66 @S9S_MB_2U_LIB.S9S_MB_2U(SCH_1):PAGE255

SW_PVCCIN_CPU0_BOOTR6 @S9S_MB_2U_LIB.S9S_MB_2U(SCH_1):SW_PVCCIN_CPU0_BOOTR6
PU8_P0_6   32  PHASE ISL99390FRZTR5935-ISL99390FRZ-A    I12 @S9S_MB_2U_LIB.S9S_MB_2U(SCH_1):PAGE255
 PC256    2      B Q_CAP_C0402-100NF,50V,10%,X7R,A    I33 @S9S_MB_2U_LIB.S9S_MB_2U(SCH_1):PAGE255

SW_PVCCIN_CPU0_BOOTR7 @S9S_MB_2U_LIB.S9S_MB_2U(SCH_1):SW_PVCCIN_CPU0_BOOTR7
PU7_P0_7   32  PHASE ISL99390FRZTR5935-ISL99390FRZ-A    I32 @S9S_MB_2U_LIB.S9S_MB_2U(SCH_1):PAGE256
 PC235    2      B Q_CAP_C0402-100NF,50V,10%,X7R,A    I59 @S9S_MB_2U_LIB.S9S_MB_2U(SCH_1):PAGE256

SW_PVCCIN_CPU0_BOOTR8 @S9S_MB_2U_LIB.S9S_MB_2U(SCH_1):SW_PVCCIN_CPU0_BOOTR8
PU6_P0_8   32  PHASE ISL99390FRZTR5935-ISL99390FRZ-A     I2 @S9S_MB_2U_LIB.S9S_MB_2U(SCH_1):PAGE256
 PC234    2      B Q_CAP_C0402-100NF,50V,10%,X7R,A    I45 @S9S_MB_2U_LIB.S9S_MB_2U(SCH_1):PAGE256

SW_PVCCIN_CPU0_SW1 @S9S_MB_2U_LIB.S9S_MB_2U(SCH_1):SW_PVCCIN_CPU0_SW1
PU13_P0_1 10_19     SW ISL99390FRZTR5935-ISL99390FRZ-A    I40 @S9S_MB_2U_LIB.S9S_MB_2U(SCH_1):PAGE253
 PL114    1      1 Q_INDUCTOR4P_14-150NH,SMLF,INDA    I46 @S9S_MB_2U_LIB.S9S_MB_2U(SCH_1):PAGE253

SW_PVCCIN_CPU0_SW2 @S9S_MB_2U_LIB.S9S_MB_2U(SCH_1):SW_PVCCIN_CPU0_SW2
  PL13    1      1 Q_INDUCTOR4P_14-150NH,SMLF,INDA    I21 @S9S_MB_2U_LIB.S9S_MB_2U(SCH_1):PAGE253
PU12_P0_2 10_19     SW ISL99390FRZTR5935-ISL99390FRZ-A     I6 @S9S_MB_2U_LIB.S9S_MB_2U(SCH_1):PAGE253

SW_PVCCIN_CPU0_SW3 @S9S_MB_2U_LIB.S9S_MB_2U(SCH_1):SW_PVCCIN_CPU0_SW3
 PL112    1      1 Q_INDUCTOR4P_14-150NH,SMLF,INDA    I50 @S9S_MB_2U_LIB.S9S_MB_2U(SCH_1):PAGE254
PU11_P0_3 10_19     SW ISL99390FRZTR5935-ISL99390FRZ-A    I20 @S9S_MB_2U_LIB.S9S_MB_2U(SCH_1):PAGE254

SW_PVCCIN_CPU0_SW4 @S9S_MB_2U_LIB.S9S_MB_2U(SCH_1):SW_PVCCIN_CPU0_SW4
PU10_P0_4 10_19     SW ISL99390FRZTR5935-ISL99390FRZ-A    I13 @S9S_MB_2U_LIB.S9S_MB_2U(SCH_1):PAGE254
  PL11    1      1 Q_INDUCTOR4P_14-150NH,SMLF,INDA    I33 @S9S_MB_2U_LIB.S9S_MB_2U(SCH_1):PAGE254

SW_PVCCIN_CPU0_SW5 @S9S_MB_2U_LIB.S9S_MB_2U(SCH_1):SW_PVCCIN_CPU0_SW5
  PL10    1      1 Q_INDUCTOR4P_14-150NH,SMLF,INDA    I50 @S9S_MB_2U_LIB.S9S_MB_2U(SCH_1):PAGE255
PU9_P0_5 10_19     SW ISL99390FRZTR5935-ISL99390FRZ-A    I66 @S9S_MB_2U_LIB.S9S_MB_2U(SCH_1):PAGE255

SW_PVCCIN_CPU0_SW6 @S9S_MB_2U_LIB.S9S_MB_2U(SCH_1):SW_PVCCIN_CPU0_SW6
PU8_P0_6 10_19     SW ISL99390FRZTR5935-ISL99390FRZ-A    I12 @S9S_MB_2U_LIB.S9S_MB_2U(SCH_1):PAGE255
   PL9    1      1 Q_INDUCTOR4P_14-150NH,SMLF,INDA    I32 @S9S_MB_2U_LIB.S9S_MB_2U(SCH_1):PAGE255

SW_PVCCIN_CPU0_SW7 @S9S_MB_2U_LIB.S9S_MB_2U(SCH_1):SW_PVCCIN_CPU0_SW7
   PL8    1      1 Q_INDUCTOR4P_14-150NH,SMLF,INDA    I58 @S9S_MB_2U_LIB.S9S_MB_2U(SCH_1):PAGE256
PU7_P0_7 10_19     SW ISL99390FRZTR5935-ISL99390FRZ-A    I32 @S9S_MB_2U_LIB.S9S_MB_2U(SCH_1):PAGE256

SW_PVCCIN_CPU0_SW8 @S9S_MB_2U_LIB.S9S_MB_2U(SCH_1):SW_PVCCIN_CPU0_SW8
PU6_P0_8 10_19     SW ISL99390FRZTR5935-ISL99390FRZ-A     I2 @S9S_MB_2U_LIB.S9S_MB_2U(SCH_1):PAGE256
   PL7    1      1 Q_INDUCTOR4P_14-150NH,SMLF,INDA    I44 @S9S_MB_2U_LIB.S9S_MB_2U(SCH_1):PAGE256

SW_PVCCIN_CPU1_BOOT1 @S9S_MB_2U_LIB.S9S_MB_2U(SCH_1):SW_PVCCIN_CPU1_BOOT1
PR1767    1      A Q_RES_0402LF-3.3,1%,1/16W,CHIPA    I46 @S9S_MB_2U_LIB.S9S_MB_2U(SCH_1):PAGE271
PU31_P1_1   33   BOOT ISL99390FRZTR5935-ISL99390FRZ-A    I40 @S9S_MB_2U_LIB.S9S_MB_2U(SCH_1):PAGE271

SW_PVCCIN_CPU1_BOOT1_R @S9S_MB_2U_LIB.S9S_MB_2U(SCH_1):SW_PVCCIN_CPU1_BOOT1_R
PR1767    2      B Q_RES_0402LF-3.3,1%,1/16W,CHIPA    I46 @S9S_MB_2U_LIB.S9S_MB_2U(SCH_1):PAGE271
 PC565    1      A Q_CAP_C0402-100NF,50V,10%,X7R,A    I49 @S9S_MB_2U_LIB.S9S_MB_2U(SCH_1):PAGE271

SW_PVCCIN_CPU1_BOOT2 @S9S_MB_2U_LIB.S9S_MB_2U(SCH_1):SW_PVCCIN_CPU1_BOOT2
PR1766    1      A Q_RES_0402LF-3.3,1%,1/16W,CHIPA    I20 @S9S_MB_2U_LIB.S9S_MB_2U(SCH_1):PAGE271
PU30_P1_2   33   BOOT ISL99390FRZTR5935-ISL99390FRZ-A     I7 @S9S_MB_2U_LIB.S9S_MB_2U(SCH_1):PAGE271

SW_PVCCIN_CPU1_BOOT2_R @S9S_MB_2U_LIB.S9S_MB_2U(SCH_1):SW_PVCCIN_CPU1_BOOT2_R
 PC564    1      A Q_CAP_C0402-100NF,50V,10%,X7R,A    I23 @S9S_MB_2U_LIB.S9S_MB_2U(SCH_1):PAGE271
PR1766    2      B Q_RES_0402LF-3.3,1%,1/16W,CHIPA    I20 @S9S_MB_2U_LIB.S9S_MB_2U(SCH_1):PAGE271

SW_PVCCIN_CPU1_BOOT3 @S9S_MB_2U_LIB.S9S_MB_2U(SCH_1):SW_PVCCIN_CPU1_BOOT3
PR1789    1      A Q_RES_0402LF-3.3,1%,1/16W,CHIPA    I46 @S9S_MB_2U_LIB.S9S_MB_2U(SCH_1):PAGE272
PU28_P1_3   33   BOOT ISL99390FRZTR5935-ISL99390FRZ-A    I66 @S9S_MB_2U_LIB.S9S_MB_2U(SCH_1):PAGE272

SW_PVCCIN_CPU1_BOOT3_R @S9S_MB_2U_LIB.S9S_MB_2U(SCH_1):SW_PVCCIN_CPU1_BOOT3_R
PR1789    2      B Q_RES_0402LF-3.3,1%,1/16W,CHIPA    I46 @S9S_MB_2U_LIB.S9S_MB_2U(SCH_1):PAGE272
 PC532    1      A Q_CAP_C0402-100NF,50V,10%,X7R,A    I52 @S9S_MB_2U_LIB.S9S_MB_2U(SCH_1):PAGE272

SW_PVCCIN_CPU1_BOOT4 @S9S_MB_2U_LIB.S9S_MB_2U(SCH_1):SW_PVCCIN_CPU1_BOOT4
PR1788    1      A Q_RES_0402LF-3.3,1%,1/16W,CHIPA    I34 @S9S_MB_2U_LIB.S9S_MB_2U(SCH_1):PAGE272
PU27_P1_4   33   BOOT ISL99390FRZTR5935-ISL99390FRZ-A    I10 @S9S_MB_2U_LIB.S9S_MB_2U(SCH_1):PAGE272

SW_PVCCIN_CPU1_BOOT4_R @S9S_MB_2U_LIB.S9S_MB_2U(SCH_1):SW_PVCCIN_CPU1_BOOT4_R
PR1788    2      B Q_RES_0402LF-3.3,1%,1/16W,CHIPA    I34 @S9S_MB_2U_LIB.S9S_MB_2U(SCH_1):PAGE272
 PC531    1      A Q_CAP_C0402-100NF,50V,10%,X7R,A    I39 @S9S_MB_2U_LIB.S9S_MB_2U(SCH_1):PAGE272

SW_PVCCIN_CPU1_BOOT5 @S9S_MB_2U_LIB.S9S_MB_2U(SCH_1):SW_PVCCIN_CPU1_BOOT5
PU26_P1_5   33   BOOT ISL99390FRZTR5935-ISL99390FRZ-A    I23 @S9S_MB_2U_LIB.S9S_MB_2U(SCH_1):PAGE273
PR1791    1      A Q_RES_0402LF-3.3,1%,1/16W,CHIPA    I44 @S9S_MB_2U_LIB.S9S_MB_2U(SCH_1):PAGE273

SW_PVCCIN_CPU1_BOOT5_R @S9S_MB_2U_LIB.S9S_MB_2U(SCH_1):SW_PVCCIN_CPU1_BOOT5_R
PR1791    2      B Q_RES_0402LF-3.3,1%,1/16W,CHIPA    I44 @S9S_MB_2U_LIB.S9S_MB_2U(SCH_1):PAGE273
 PC510    1      A Q_CAP_C0402-100NF,50V,10%,X7R,A    I47 @S9S_MB_2U_LIB.S9S_MB_2U(SCH_1):PAGE273

SW_PVCCIN_CPU1_BOOT6 @S9S_MB_2U_LIB.S9S_MB_2U(SCH_1):SW_PVCCIN_CPU1_BOOT6
PU25_P1_6   33   BOOT ISL99390FRZTR5935-ISL99390FRZ-A    I16 @S9S_MB_2U_LIB.S9S_MB_2U(SCH_1):PAGE273
PR1790    1      A Q_RES_0402LF-3.3,1%,1/16W,CHIPA    I30 @S9S_MB_2U_LIB.S9S_MB_2U(SCH_1):PAGE273

SW_PVCCIN_CPU1_BOOT6_R @S9S_MB_2U_LIB.S9S_MB_2U(SCH_1):SW_PVCCIN_CPU1_BOOT6_R
 PC509    1      A Q_CAP_C0402-100NF,50V,10%,X7R,A    I26 @S9S_MB_2U_LIB.S9S_MB_2U(SCH_1):PAGE273
PR1790    2      B Q_RES_0402LF-3.3,1%,1/16W,CHIPA    I30 @S9S_MB_2U_LIB.S9S_MB_2U(SCH_1):PAGE273

SW_PVCCIN_CPU1_BOOT7 @S9S_MB_2U_LIB.S9S_MB_2U(SCH_1):SW_PVCCIN_CPU1_BOOT7
PR1793    1      A Q_RES_0402LF-3.3,1%,1/16W,CHIPA    I39 @S9S_MB_2U_LIB.S9S_MB_2U(SCH_1):PAGE274
PU24_P1_7   33   BOOT ISL99390FRZTR5935-ISL99390FRZ-A    I20 @S9S_MB_2U_LIB.S9S_MB_2U(SCH_1):PAGE274

SW_PVCCIN_CPU1_BOOT7_R @S9S_MB_2U_LIB.S9S_MB_2U(SCH_1):SW_PVCCIN_CPU1_BOOT7_R
PR1793    2      B Q_RES_0402LF-3.3,1%,1/16W,CHIPA    I39 @S9S_MB_2U_LIB.S9S_MB_2U(SCH_1):PAGE274
 PC488    1      A Q_CAP_C0402-100NF,50V,10%,X7R,A    I59 @S9S_MB_2U_LIB.S9S_MB_2U(SCH_1):PAGE274

SW_PVCCIN_CPU1_BOOT8 @S9S_MB_2U_LIB.S9S_MB_2U(SCH_1):SW_PVCCIN_CPU1_BOOT8
PR1792    1      A Q_RES_0402LF-3.3,1%,1/16W,CHIPA    I26 @S9S_MB_2U_LIB.S9S_MB_2U(SCH_1):PAGE274
PU23_P1_8   33   BOOT ISL99390FRZTR5935-ISL99390FRZ-A    I11 @S9S_MB_2U_LIB.S9S_MB_2U(SCH_1):PAGE274

SW_PVCCIN_CPU1_BOOT8_R @S9S_MB_2U_LIB.S9S_MB_2U(SCH_1):SW_PVCCIN_CPU1_BOOT8_R
PR1792    2      B Q_RES_0402LF-3.3,1%,1/16W,CHIPA    I26 @S9S_MB_2U_LIB.S9S_MB_2U(SCH_1):PAGE274
 PC487    1      A Q_CAP_C0402-100NF,50V,10%,X7R,A    I42 @S9S_MB_2U_LIB.S9S_MB_2U(SCH_1):PAGE274

SW_PVCCIN_CPU1_BOOTR1 @S9S_MB_2U_LIB.S9S_MB_2U(SCH_1):SW_PVCCIN_CPU1_BOOTR1
 PC565    2      B Q_CAP_C0402-100NF,50V,10%,X7R,A    I49 @S9S_MB_2U_LIB.S9S_MB_2U(SCH_1):PAGE271
PU31_P1_1   32  PHASE ISL99390FRZTR5935-ISL99390FRZ-A    I40 @S9S_MB_2U_LIB.S9S_MB_2U(SCH_1):PAGE271

SW_PVCCIN_CPU1_BOOTR2 @S9S_MB_2U_LIB.S9S_MB_2U(SCH_1):SW_PVCCIN_CPU1_BOOTR2
 PC564    2      B Q_CAP_C0402-100NF,50V,10%,X7R,A    I23 @S9S_MB_2U_LIB.S9S_MB_2U(SCH_1):PAGE271
PU30_P1_2   32  PHASE ISL99390FRZTR5935-ISL99390FRZ-A     I7 @S9S_MB_2U_LIB.S9S_MB_2U(SCH_1):PAGE271

SW_PVCCIN_CPU1_BOOTR3 @S9S_MB_2U_LIB.S9S_MB_2U(SCH_1):SW_PVCCIN_CPU1_BOOTR3
 PC532    2      B Q_CAP_C0402-100NF,50V,10%,X7R,A    I52 @S9S_MB_2U_LIB.S9S_MB_2U(SCH_1):PAGE272
PU28_P1_3   32  PHASE ISL99390FRZTR5935-ISL99390FRZ-A    I66 @S9S_MB_2U_LIB.S9S_MB_2U(SCH_1):PAGE272

SW_PVCCIN_CPU1_BOOTR4 @S9S_MB_2U_LIB.S9S_MB_2U(SCH_1):SW_PVCCIN_CPU1_BOOTR4
PU27_P1_4   32  PHASE ISL99390FRZTR5935-ISL99390FRZ-A    I10 @S9S_MB_2U_LIB.S9S_MB_2U(SCH_1):PAGE272
 PC531    2      B Q_CAP_C0402-100NF,50V,10%,X7R,A    I39 @S9S_MB_2U_LIB.S9S_MB_2U(SCH_1):PAGE272

SW_PVCCIN_CPU1_BOOTR5 @S9S_MB_2U_LIB.S9S_MB_2U(SCH_1):SW_PVCCIN_CPU1_BOOTR5
PU26_P1_5   32  PHASE ISL99390FRZTR5935-ISL99390FRZ-A    I23 @S9S_MB_2U_LIB.S9S_MB_2U(SCH_1):PAGE273
 PC510    2      B Q_CAP_C0402-100NF,50V,10%,X7R,A    I47 @S9S_MB_2U_LIB.S9S_MB_2U(SCH_1):PAGE273

SW_PVCCIN_CPU1_BOOTR6 @S9S_MB_2U_LIB.S9S_MB_2U(SCH_1):SW_PVCCIN_CPU1_BOOTR6
PU25_P1_6   32  PHASE ISL99390FRZTR5935-ISL99390FRZ-A    I16 @S9S_MB_2U_LIB.S9S_MB_2U(SCH_1):PAGE273
 PC509    2      B Q_CAP_C0402-100NF,50V,10%,X7R,A    I26 @S9S_MB_2U_LIB.S9S_MB_2U(SCH_1):PAGE273

SW_PVCCIN_CPU1_BOOTR7 @S9S_MB_2U_LIB.S9S_MB_2U(SCH_1):SW_PVCCIN_CPU1_BOOTR7
PU24_P1_7   32  PHASE ISL99390FRZTR5935-ISL99390FRZ-A    I20 @S9S_MB_2U_LIB.S9S_MB_2U(SCH_1):PAGE274
 PC488    2      B Q_CAP_C0402-100NF,50V,10%,X7R,A    I59 @S9S_MB_2U_LIB.S9S_MB_2U(SCH_1):PAGE274

SW_PVCCIN_CPU1_BOOTR8 @S9S_MB_2U_LIB.S9S_MB_2U(SCH_1):SW_PVCCIN_CPU1_BOOTR8
 PC487    2      B Q_CAP_C0402-100NF,50V,10%,X7R,A    I42 @S9S_MB_2U_LIB.S9S_MB_2U(SCH_1):PAGE274
PU23_P1_8   32  PHASE ISL99390FRZTR5935-ISL99390FRZ-A    I11 @S9S_MB_2U_LIB.S9S_MB_2U(SCH_1):PAGE274

SW_PVCCIN_CPU1_SW1 @S9S_MB_2U_LIB.S9S_MB_2U(SCH_1):SW_PVCCIN_CPU1_SW1
  PL31    1      1 Q_INDUCTOR4P_14-150NH,SMLF,INDA    I74 @S9S_MB_2U_LIB.S9S_MB_2U(SCH_1):PAGE271
PU31_P1_1 10_19     SW ISL99390FRZTR5935-ISL99390FRZ-A    I40 @S9S_MB_2U_LIB.S9S_MB_2U(SCH_1):PAGE271

SW_PVCCIN_CPU1_SW2 @S9S_MB_2U_LIB.S9S_MB_2U(SCH_1):SW_PVCCIN_CPU1_SW2
PU30_P1_2 10_19     SW ISL99390FRZTR5935-ISL99390FRZ-A     I7 @S9S_MB_2U_LIB.S9S_MB_2U(SCH_1):PAGE271
  PL30    1      1 Q_INDUCTOR4P_14-150NH,SMLF,INDA    I18 @S9S_MB_2U_LIB.S9S_MB_2U(SCH_1):PAGE271

SW_PVCCIN_CPU1_SW3 @S9S_MB_2U_LIB.S9S_MB_2U(SCH_1):SW_PVCCIN_CPU1_SW3
  PL29    1      1 Q_INDUCTOR4P_14-150NH,SMLF,INDA    I51 @S9S_MB_2U_LIB.S9S_MB_2U(SCH_1):PAGE272
PU28_P1_3 10_19     SW ISL99390FRZTR5935-ISL99390FRZ-A    I66 @S9S_MB_2U_LIB.S9S_MB_2U(SCH_1):PAGE272

SW_PVCCIN_CPU1_SW4 @S9S_MB_2U_LIB.S9S_MB_2U(SCH_1):SW_PVCCIN_CPU1_SW4
PU27_P1_4 10_19     SW ISL99390FRZTR5935-ISL99390FRZ-A    I10 @S9S_MB_2U_LIB.S9S_MB_2U(SCH_1):PAGE272
  PL28    1      1 Q_INDUCTOR4P_14-150NH,SMLF,INDA    I37 @S9S_MB_2U_LIB.S9S_MB_2U(SCH_1):PAGE272

SW_PVCCIN_CPU1_SW5 @S9S_MB_2U_LIB.S9S_MB_2U(SCH_1):SW_PVCCIN_CPU1_SW5
PU26_P1_5 10_19     SW ISL99390FRZTR5935-ISL99390FRZ-A    I23 @S9S_MB_2U_LIB.S9S_MB_2U(SCH_1):PAGE273
  PL27    1      1 Q_INDUCTOR4P_14-150NH,SMLF,INDA    I48 @S9S_MB_2U_LIB.S9S_MB_2U(SCH_1):PAGE273

SW_PVCCIN_CPU1_SW6 @S9S_MB_2U_LIB.S9S_MB_2U(SCH_1):SW_PVCCIN_CPU1_SW6
  PL26    1      1 Q_INDUCTOR4P_14-150NH,SMLF,INDA    I28 @S9S_MB_2U_LIB.S9S_MB_2U(SCH_1):PAGE273
PU25_P1_6 10_19     SW ISL99390FRZTR5935-ISL99390FRZ-A    I16 @S9S_MB_2U_LIB.S9S_MB_2U(SCH_1):PAGE273

SW_PVCCIN_CPU1_SW7 @S9S_MB_2U_LIB.S9S_MB_2U(SCH_1):SW_PVCCIN_CPU1_SW7
PU24_P1_7 10_19     SW ISL99390FRZTR5935-ISL99390FRZ-A    I20 @S9S_MB_2U_LIB.S9S_MB_2U(SCH_1):PAGE274
  PL25    1      1 Q_INDUCTOR4P_14-150NH,SMLF,INDA    I58 @S9S_MB_2U_LIB.S9S_MB_2U(SCH_1):PAGE274

SW_PVCCIN_CPU1_SW8 @S9S_MB_2U_LIB.S9S_MB_2U(SCH_1):SW_PVCCIN_CPU1_SW8
  PL24    1      1 Q_INDUCTOR4P_14-150NH,SMLF,INDA    I43 @S9S_MB_2U_LIB.S9S_MB_2U(SCH_1):PAGE274
PU23_P1_8 10_19     SW ISL99390FRZTR5935-ISL99390FRZ-A    I11 @S9S_MB_2U_LIB.S9S_MB_2U(SCH_1):PAGE274

SW_PVNN_MAIN_CPU0_BST @S9S_MB_2U_LIB.S9S_MB_2U(SCH_1):SW_PVNN_MAIN_CPU0_BST
PR4271    1      A Q_RES_0402LF-0,5%,1/16W,CHIP,CA    I27 @S9S_MB_2U_LIB.S9S_MB_2U(SCH_1):PAGE268
  PU81   10    BST RS53317LR-RS53317LR,SMLF,IC,ALA    I22 @S9S_MB_2U_LIB.S9S_MB_2U(SCH_1):PAGE268

SW_PVNN_MAIN_CPU0_BST_R @S9S_MB_2U_LIB.S9S_MB_2U(SCH_1):SW_PVNN_MAIN_CPU0_BST_R
PC1275    1      A Q_CAP_C0402-0.22UF,25V,10%,X7RA    I26 @S9S_MB_2U_LIB.S9S_MB_2U(SCH_1):PAGE268
PR4271    2      B Q_RES_0402LF-0,5%,1/16W,CHIP,CA    I27 @S9S_MB_2U_LIB.S9S_MB_2U(SCH_1):PAGE268

SW_PVNN_MAIN_CPU0_SW @S9S_MB_2U_LIB.S9S_MB_2U(SCH_1):SW_PVNN_MAIN_CPU0_SW
PC1275    2      B Q_CAP_C0402-0.22UF,25V,10%,X7RA    I26 @S9S_MB_2U_LIB.S9S_MB_2U(SCH_1):PAGE268
  PU81    2    SW1 RS53317LR-RS53317LR,SMLF,IC,ALA    I22 @S9S_MB_2U_LIB.S9S_MB_2U(SCH_1):PAGE268
  PU81   11    SW2 RS53317LR-RS53317LR,SMLF,IC,ALA    I22 @S9S_MB_2U_LIB.S9S_MB_2U(SCH_1):PAGE268
 PL120    1      1 Q_INDUCTOR_SMLF-4.7UH,IND,CV-4B    I29 @S9S_MB_2U_LIB.S9S_MB_2U(SCH_1):PAGE268

SW_PVNN_MAIN_CPU1_BST @S9S_MB_2U_LIB.S9S_MB_2U(SCH_1):SW_PVNN_MAIN_CPU1_BST
  PU82   10    BST RS53317LR-RS53317LR,SMLF,IC,ALA    I20 @S9S_MB_2U_LIB.S9S_MB_2U(SCH_1):PAGE286
PR4272    1      A Q_RES_0402LF-0,5%,1/16W,CHIP,CA    I25 @S9S_MB_2U_LIB.S9S_MB_2U(SCH_1):PAGE286

SW_PVNN_MAIN_CPU1_BST_R @S9S_MB_2U_LIB.S9S_MB_2U(SCH_1):SW_PVNN_MAIN_CPU1_BST_R
PR4272    2      B Q_RES_0402LF-0,5%,1/16W,CHIP,CA    I25 @S9S_MB_2U_LIB.S9S_MB_2U(SCH_1):PAGE286
PC1283    1      A Q_CAP_C0402-0.22UF,25V,10%,X7RA    I24 @S9S_MB_2U_LIB.S9S_MB_2U(SCH_1):PAGE286

SW_PVNN_MAIN_CPU1_SW @S9S_MB_2U_LIB.S9S_MB_2U(SCH_1):SW_PVNN_MAIN_CPU1_SW
 PL121    1      1 Q_INDUCTOR_SMLF-4.7UH,IND,CV-4B    I27 @S9S_MB_2U_LIB.S9S_MB_2U(SCH_1):PAGE286
  PU82    2    SW1 RS53317LR-RS53317LR,SMLF,IC,ALA    I20 @S9S_MB_2U_LIB.S9S_MB_2U(SCH_1):PAGE286
  PU82   11    SW2 RS53317LR-RS53317LR,SMLF,IC,ALA    I20 @S9S_MB_2U_LIB.S9S_MB_2U(SCH_1):PAGE286
PC1283    2      B Q_CAP_C0402-0.22UF,25V,10%,X7RA    I24 @S9S_MB_2U_LIB.S9S_MB_2U(SCH_1):PAGE286

SW_PVPP_HBM_CPU0_BST @S9S_MB_2U_LIB.S9S_MB_2U(SCH_1):SW_PVPP_HBM_CPU0_BST
PC1252    1      A Q_CAP_C0402-0.22UF,25V,10%,X7RA    I27 @S9S_MB_2U_LIB.S9S_MB_2U(SCH_1):PAGE267
  PU79    1    BST RS53318LR-RS53318LR,SMLF,IC,ALA    I19 @S9S_MB_2U_LIB.S9S_MB_2U(SCH_1):PAGE267

SW_PVPP_HBM_CPU0_SW @S9S_MB_2U_LIB.S9S_MB_2U(SCH_1):SW_PVPP_HBM_CPU0_SW
PC1252    2      B Q_CAP_C0402-0.22UF,25V,10%,X7RA    I27 @S9S_MB_2U_LIB.S9S_MB_2U(SCH_1):PAGE267
 PL118    1      1 Q_INDUCTOR_SMLF-0.68UH,IND,CV+A    I28 @S9S_MB_2U_LIB.S9S_MB_2U(SCH_1):PAGE267
  PU79   20     SW RS53318LR-RS53318LR,SMLF,IC,ALA    I19 @S9S_MB_2U_LIB.S9S_MB_2U(SCH_1):PAGE267

SW_PVPP_HBM_CPU1_BST @S9S_MB_2U_LIB.S9S_MB_2U(SCH_1):SW_PVPP_HBM_CPU1_BST
  PU80    1    BST RS53318LR-RS53318LR,SMLF,IC,ALA    I25 @S9S_MB_2U_LIB.S9S_MB_2U(SCH_1):PAGE285
PC1265    1      A Q_CAP_C0402-0.22UF,25V,10%,X7RA    I26 @S9S_MB_2U_LIB.S9S_MB_2U(SCH_1):PAGE285

SW_PVPP_HBM_CPU1_SW @S9S_MB_2U_LIB.S9S_MB_2U(SCH_1):SW_PVPP_HBM_CPU1_SW
 PL119    1      1 Q_INDUCTOR_SMLF-0.68UH,IND,CV+A    I33 @S9S_MB_2U_LIB.S9S_MB_2U(SCH_1):PAGE285
  PU80   20     SW RS53318LR-RS53318LR,SMLF,IC,ALA    I25 @S9S_MB_2U_LIB.S9S_MB_2U(SCH_1):PAGE285
PC1265    2      B Q_CAP_C0402-0.22UF,25V,10%,X7RA    I26 @S9S_MB_2U_LIB.S9S_MB_2U(SCH_1):PAGE285

T1_GND @S9S_MB_2U_LIB.S9S_MB_2U(SCH_1):T1_GND
   X19    2     P1 TP_TDR_4P_FTS_TH-TP_TDR_4P_DIPA     I3 @S9S_MB_2U_LIB.S9S_MB_2U(SCH_1):PAGE288
   X19    3     P2 TP_TDR_4P_FTS_TH-TP_TDR_4P_DIPA     I3 @S9S_MB_2U_LIB.S9S_MB_2U(SCH_1):PAGE288
   X20    2     P1 TP_TDR_4P_FTS_TH-TP_TDR_4P_DIPA     I4 @S9S_MB_2U_LIB.S9S_MB_2U(SCH_1):PAGE288
   X20    3     P2 TP_TDR_4P_FTS_TH-TP_TDR_4P_DIPA     I4 @S9S_MB_2U_LIB.S9S_MB_2U(SCH_1):PAGE288
   X22    2     P1 TP_TDR_4P_FTS_TH-TP_TDR_4P_DIPA     I8 @S9S_MB_2U_LIB.S9S_MB_2U(SCH_1):PAGE288
   X22    3     P2 TP_TDR_4P_FTS_TH-TP_TDR_4P_DIPA     I8 @S9S_MB_2U_LIB.S9S_MB_2U(SCH_1):PAGE288
   X21    2     P1 TP_TDR_4P_FTS_TH-TP_TDR_4P_DIPA     I9 @S9S_MB_2U_LIB.S9S_MB_2U(SCH_1):PAGE288
   X21    3     P2 TP_TDR_4P_FTS_TH-TP_TDR_4P_DIPA     I9 @S9S_MB_2U_LIB.S9S_MB_2U(SCH_1):PAGE288
   X23    2     P1 TP_TDR_4P_FTS_TH-TP_TDR_4P_DIPA    I10 @S9S_MB_2U_LIB.S9S_MB_2U(SCH_1):PAGE288
   X23    3     P2 TP_TDR_4P_FTS_TH-TP_TDR_4P_DIPA    I10 @S9S_MB_2U_LIB.S9S_MB_2U(SCH_1):PAGE288
   X13    2     P1 TP_TDR_4P_FTS_TH-TP_TDR_4P_DIPA    I11 @S9S_MB_2U_LIB.S9S_MB_2U(SCH_1):PAGE288
   X13    3     P2 TP_TDR_4P_FTS_TH-TP_TDR_4P_DIPA    I11 @S9S_MB_2U_LIB.S9S_MB_2U(SCH_1):PAGE288
   X14    2     P1 TP_TDR_4P_FTS_TH-TP_TDR_4P_DIPA    I12 @S9S_MB_2U_LIB.S9S_MB_2U(SCH_1):PAGE288
   X14    3     P2 TP_TDR_4P_FTS_TH-TP_TDR_4P_DIPA    I12 @S9S_MB_2U_LIB.S9S_MB_2U(SCH_1):PAGE288
   X15    2     P1 TP_TDR_4P_FTS_TH-TP_TDR_4P_DIPA    I17 @S9S_MB_2U_LIB.S9S_MB_2U(SCH_1):PAGE288
   X15    3     P2 TP_TDR_4P_FTS_TH-TP_TDR_4P_DIPA    I17 @S9S_MB_2U_LIB.S9S_MB_2U(SCH_1):PAGE288
   X16    2     P1 TP_TDR_4P_FTS_TH-TP_TDR_4P_DIPA    I18 @S9S_MB_2U_LIB.S9S_MB_2U(SCH_1):PAGE288
   X16    3     P2 TP_TDR_4P_FTS_TH-TP_TDR_4P_DIPA    I18 @S9S_MB_2U_LIB.S9S_MB_2U(SCH_1):PAGE288
   X17    2     P1 TP_TDR_4P_FTS_TH-TP_TDR_4P_DIPA    I19 @S9S_MB_2U_LIB.S9S_MB_2U(SCH_1):PAGE288
   X17    3     P2 TP_TDR_4P_FTS_TH-TP_TDR_4P_DIPA    I19 @S9S_MB_2U_LIB.S9S_MB_2U(SCH_1):PAGE288
    X7    2     P1 TP_TDR_4P_FTS_TH-TP_TDR_4P_DIPA    I26 @S9S_MB_2U_LIB.S9S_MB_2U(SCH_1):PAGE288
    X7    3     P2 TP_TDR_4P_FTS_TH-TP_TDR_4P_DIPA    I26 @S9S_MB_2U_LIB.S9S_MB_2U(SCH_1):PAGE288
    X8    2     P1 TP_TDR_4P_FTS_TH-TP_TDR_4P_DIPA    I27 @S9S_MB_2U_LIB.S9S_MB_2U(SCH_1):PAGE288
    X8    3     P2 TP_TDR_4P_FTS_TH-TP_TDR_4P_DIPA    I27 @S9S_MB_2U_LIB.S9S_MB_2U(SCH_1):PAGE288
    X1    2     P1 TP_TDR_4P_FTS_TH-TP_TDR_4P_DIPA    I28 @S9S_MB_2U_LIB.S9S_MB_2U(SCH_1):PAGE288
    X1    3     P2 TP_TDR_4P_FTS_TH-TP_TDR_4P_DIPA    I28 @S9S_MB_2U_LIB.S9S_MB_2U(SCH_1):PAGE288
    X2    2     P1 TP_TDR_4P_FTS_TH-TP_TDR_4P_DIPA    I30 @S9S_MB_2U_LIB.S9S_MB_2U(SCH_1):PAGE288
    X2    3     P2 TP_TDR_4P_FTS_TH-TP_TDR_4P_DIPA    I30 @S9S_MB_2U_LIB.S9S_MB_2U(SCH_1):PAGE288
    X9    2     P1 TP_TDR_4P_FTS_TH-TP_TDR_4P_DIPA    I32 @S9S_MB_2U_LIB.S9S_MB_2U(SCH_1):PAGE288
    X9    3     P2 TP_TDR_4P_FTS_TH-TP_TDR_4P_DIPA    I32 @S9S_MB_2U_LIB.S9S_MB_2U(SCH_1):PAGE288
   X10    2     P1 TP_TDR_4P_FTS_TH-TP_TDR_4P_DIPA    I33 @S9S_MB_2U_LIB.S9S_MB_2U(SCH_1):PAGE288
   X10    3     P2 TP_TDR_4P_FTS_TH-TP_TDR_4P_DIPA    I33 @S9S_MB_2U_LIB.S9S_MB_2U(SCH_1):PAGE288
   X11    2     P1 TP_TDR_4P_FTS_TH-TP_TDR_4P_DIPA    I34 @S9S_MB_2U_LIB.S9S_MB_2U(SCH_1):PAGE288
   X11    3     P2 TP_TDR_4P_FTS_TH-TP_TDR_4P_DIPA    I34 @S9S_MB_2U_LIB.S9S_MB_2U(SCH_1):PAGE288
    X3    2     P1 TP_TDR_4P_FTS_TH-TP_TDR_4P_DIPA    I35 @S9S_MB_2U_LIB.S9S_MB_2U(SCH_1):PAGE288
    X3    3     P2 TP_TDR_4P_FTS_TH-TP_TDR_4P_DIPA    I35 @S9S_MB_2U_LIB.S9S_MB_2U(SCH_1):PAGE288
    X4    2     P1 TP_TDR_4P_FTS_TH-TP_TDR_4P_DIPA    I37 @S9S_MB_2U_LIB.S9S_MB_2U(SCH_1):PAGE288
    X4    3     P2 TP_TDR_4P_FTS_TH-TP_TDR_4P_DIPA    I37 @S9S_MB_2U_LIB.S9S_MB_2U(SCH_1):PAGE288
    X5    2     P1 TP_TDR_4P_FTS_TH-TP_TDR_4P_DIPA    I39 @S9S_MB_2U_LIB.S9S_MB_2U(SCH_1):PAGE288
    X5    3     P2 TP_TDR_4P_FTS_TH-TP_TDR_4P_DIPA    I39 @S9S_MB_2U_LIB.S9S_MB_2U(SCH_1):PAGE288
   X24    2     P1 TP_TDR_4P_FTS_TH-TP_TDR_4P_DIPA    I42 @S9S_MB_2U_LIB.S9S_MB_2U(SCH_1):PAGE288
   X24    3     P2 TP_TDR_4P_FTS_TH-TP_TDR_4P_DIPA    I42 @S9S_MB_2U_LIB.S9S_MB_2U(SCH_1):PAGE288
   X18    2     P1 TP_TDR_4P_FTS_TH-TP_TDR_4P_DIPA    I43 @S9S_MB_2U_LIB.S9S_MB_2U(SCH_1):PAGE288
   X18    3     P2 TP_TDR_4P_FTS_TH-TP_TDR_4P_DIPA    I43 @S9S_MB_2U_LIB.S9S_MB_2U(SCH_1):PAGE288
   X12    2     P1 TP_TDR_4P_FTS_TH-TP_TDR_4P_DIPA    I46 @S9S_MB_2U_LIB.S9S_MB_2U(SCH_1):PAGE288
   X12    3     P2 TP_TDR_4P_FTS_TH-TP_TDR_4P_DIPA    I46 @S9S_MB_2U_LIB.S9S_MB_2U(SCH_1):PAGE288
    X6    2     P1 TP_TDR_4P_FTS_TH-TP_TDR_4P_DIPA    I47 @S9S_MB_2U_LIB.S9S_MB_2U(SCH_1):PAGE288
    X6    3     P2 TP_TDR_4P_FTS_TH-TP_TDR_4P_DIPA    I47 @S9S_MB_2U_LIB.S9S_MB_2U(SCH_1):PAGE288
   DB7    1    GND TDR_3P_TH2-EMPTY,N_A    I49 @S9S_MB_2U_LIB.S9S_MB_2U(SCH_1):PAGE288
   DB8    1    GND TDR_3P_TH2-EMPTY,N_A    I51 @S9S_MB_2U_LIB.S9S_MB_2U(SCH_1):PAGE288
   DB9    1    GND TDR_3P_TH2-EMPTY,N_A    I53 @S9S_MB_2U_LIB.S9S_MB_2U(SCH_1):PAGE288
  DB10    1    GND TDR_3P_TH2-EMPTY,N_A    I55 @S9S_MB_2U_LIB.S9S_MB_2U(SCH_1):PAGE288
  DB11    1    GND TDR_3P_TH2-EMPTY,N_A    I57 @S9S_MB_2U_LIB.S9S_MB_2U(SCH_1):PAGE288
  DB12    1    GND TDR_3P_TH2-EMPTY,N_A    I60 @S9S_MB_2U_LIB.S9S_MB_2U(SCH_1):PAGE288
   DB1    1    GND TDR_3P_TH2-EMPTY,N_A    I61 @S9S_MB_2U_LIB.S9S_MB_2U(SCH_1):PAGE288
   DB2    1    GND TDR_3P_TH2-EMPTY,N_A    I62 @S9S_MB_2U_LIB.S9S_MB_2U(SCH_1):PAGE288
   DB3    1    GND TDR_3P_TH2-EMPTY,N_A    I63 @S9S_MB_2U_LIB.S9S_MB_2U(SCH_1):PAGE288
   DB4    1    GND TDR_3P_TH2-EMPTY,N_A    I67 @S9S_MB_2U_LIB.S9S_MB_2U(SCH_1):PAGE288
   DB5    1    GND TDR_3P_TH2-EMPTY,N_A    I68 @S9S_MB_2U_LIB.S9S_MB_2U(SCH_1):PAGE288
   DB6    1    GND TDR_3P_TH2-EMPTY,N_A    I69 @S9S_MB_2U_LIB.S9S_MB_2U(SCH_1):PAGE288
  DB14    1    GND TDR_3P_TH2-EMPTY,N_A    I96 @S9S_MB_2U_LIB.S9S_MB_2U(SCH_1):PAGE288
  DB15    1    GND TDR_3P_TH2-EMPTY,N_A    I97 @S9S_MB_2U_LIB.S9S_MB_2U(SCH_1):PAGE288
  DB16    1    GND TDR_3P_TH2-EMPTY,N_A    I99 @S9S_MB_2U_LIB.S9S_MB_2U(SCH_1):PAGE288
  DB13    1    GND TDR_3P_TH2-EMPTY,N_A   I101 @S9S_MB_2U_LIB.S9S_MB_2U(SCH_1):PAGE288
   X27    2     P1 TP_TDR_4P_FTS_TH-TP_TDR_4P_DIPA   I106 @S9S_MB_2U_LIB.S9S_MB_2U(SCH_1):PAGE288
   X27    3     P2 TP_TDR_4P_FTS_TH-TP_TDR_4P_DIPA   I106 @S9S_MB_2U_LIB.S9S_MB_2U(SCH_1):PAGE288
   X28    2     P1 TP_TDR_4P_FTS_TH-TP_TDR_4P_DIPA   I107 @S9S_MB_2U_LIB.S9S_MB_2U(SCH_1):PAGE288
   X28    3     P2 TP_TDR_4P_FTS_TH-TP_TDR_4P_DIPA   I107 @S9S_MB_2U_LIB.S9S_MB_2U(SCH_1):PAGE288
   X25    2     P1 TP_TDR_4P_FTS_TH-TP_TDR_4P_DIPA   I108 @S9S_MB_2U_LIB.S9S_MB_2U(SCH_1):PAGE288
   X25    3     P2 TP_TDR_4P_FTS_TH-TP_TDR_4P_DIPA   I108 @S9S_MB_2U_LIB.S9S_MB_2U(SCH_1):PAGE288
   X26    2     P1 TP_TDR_4P_FTS_TH-TP_TDR_4P_DIPA   I110 @S9S_MB_2U_LIB.S9S_MB_2U(SCH_1):PAGE288
   X26    3     P2 TP_TDR_4P_FTS_TH-TP_TDR_4P_DIPA   I110 @S9S_MB_2U_LIB.S9S_MB_2U(SCH_1):PAGE288
   X31    2     P1 TP_TDR_4P_FTS_TH-TP_TDR_4P_DIPA   I112 @S9S_MB_2U_LIB.S9S_MB_2U(SCH_1):PAGE288
   X31    3     P2 TP_TDR_4P_FTS_TH-TP_TDR_4P_DIPA   I112 @S9S_MB_2U_LIB.S9S_MB_2U(SCH_1):PAGE288
   X32    2     P1 TP_TDR_4P_FTS_TH-TP_TDR_4P_DIPA   I115 @S9S_MB_2U_LIB.S9S_MB_2U(SCH_1):PAGE288
   X32    3     P2 TP_TDR_4P_FTS_TH-TP_TDR_4P_DIPA   I115 @S9S_MB_2U_LIB.S9S_MB_2U(SCH_1):PAGE288
   X29    2     P1 TP_TDR_4P_FTS_TH-TP_TDR_4P_DIPA   I116 @S9S_MB_2U_LIB.S9S_MB_2U(SCH_1):PAGE288
   X29    3     P2 TP_TDR_4P_FTS_TH-TP_TDR_4P_DIPA   I116 @S9S_MB_2U_LIB.S9S_MB_2U(SCH_1):PAGE288
   X30    2     P1 TP_TDR_4P_FTS_TH-TP_TDR_4P_DIPA   I117 @S9S_MB_2U_LIB.S9S_MB_2U(SCH_1):PAGE288
   X30    3     P2 TP_TDR_4P_FTS_TH-TP_TDR_4P_DIPA   I117 @S9S_MB_2U_LIB.S9S_MB_2U(SCH_1):PAGE288
   X38    2     P1 TP_TDR_4P_FTS_TH-TP_TDR_4P_DIPA     I5 @S9S_MB_2U_LIB.S9S_MB_2U(SCH_1):PAGE310
   X38    3     P2 TP_TDR_4P_FTS_TH-TP_TDR_4P_DIPA     I5 @S9S_MB_2U_LIB.S9S_MB_2U(SCH_1):PAGE310
   X44    2     P1 TP_TDR_4P_FTS_TH-TP_TDR_4P_DIPA     I6 @S9S_MB_2U_LIB.S9S_MB_2U(SCH_1):PAGE310
   X44    3     P2 TP_TDR_4P_FTS_TH-TP_TDR_4P_DIPA     I6 @S9S_MB_2U_LIB.S9S_MB_2U(SCH_1):PAGE310
   X37    2     P1 TP_TDR_4P_FTS_TH-TP_TDR_4P_DIPA     I7 @S9S_MB_2U_LIB.S9S_MB_2U(SCH_1):PAGE310
   X37    3     P2 TP_TDR_4P_FTS_TH-TP_TDR_4P_DIPA     I7 @S9S_MB_2U_LIB.S9S_MB_2U(SCH_1):PAGE310
   X36    2     P1 TP_TDR_4P_FTS_TH-TP_TDR_4P_DIPA     I8 @S9S_MB_2U_LIB.S9S_MB_2U(SCH_1):PAGE310
   X36    3     P2 TP_TDR_4P_FTS_TH-TP_TDR_4P_DIPA     I8 @S9S_MB_2U_LIB.S9S_MB_2U(SCH_1):PAGE310
   X43    2     P1 TP_TDR_4P_FTS_TH-TP_TDR_4P_DIPA     I9 @S9S_MB_2U_LIB.S9S_MB_2U(SCH_1):PAGE310
   X43    3     P2 TP_TDR_4P_FTS_TH-TP_TDR_4P_DIPA     I9 @S9S_MB_2U_LIB.S9S_MB_2U(SCH_1):PAGE310
   X42    2     P1 TP_TDR_4P_FTS_TH-TP_TDR_4P_DIPA    I10 @S9S_MB_2U_LIB.S9S_MB_2U(SCH_1):PAGE310
   X42    3     P2 TP_TDR_4P_FTS_TH-TP_TDR_4P_DIPA    I10 @S9S_MB_2U_LIB.S9S_MB_2U(SCH_1):PAGE310
   X41    2     P1 TP_TDR_4P_FTS_TH-TP_TDR_4P_DIPA    I15 @S9S_MB_2U_LIB.S9S_MB_2U(SCH_1):PAGE310
   X41    3     P2 TP_TDR_4P_FTS_TH-TP_TDR_4P_DIPA    I15 @S9S_MB_2U_LIB.S9S_MB_2U(SCH_1):PAGE310
   X35    2     P1 TP_TDR_4P_FTS_TH-TP_TDR_4P_DIPA    I16 @S9S_MB_2U_LIB.S9S_MB_2U(SCH_1):PAGE310
   X35    3     P2 TP_TDR_4P_FTS_TH-TP_TDR_4P_DIPA    I16 @S9S_MB_2U_LIB.S9S_MB_2U(SCH_1):PAGE310
   X34    2     P1 TP_TDR_4P_FTS_TH-TP_TDR_4P_DIPA    I19 @S9S_MB_2U_LIB.S9S_MB_2U(SCH_1):PAGE310
   X34    3     P2 TP_TDR_4P_FTS_TH-TP_TDR_4P_DIPA    I19 @S9S_MB_2U_LIB.S9S_MB_2U(SCH_1):PAGE310
   X33    2     P1 TP_TDR_4P_FTS_TH-TP_TDR_4P_DIPA    I20 @S9S_MB_2U_LIB.S9S_MB_2U(SCH_1):PAGE310
   X33    3     P2 TP_TDR_4P_FTS_TH-TP_TDR_4P_DIPA    I20 @S9S_MB_2U_LIB.S9S_MB_2U(SCH_1):PAGE310
   X40    2     P1 TP_TDR_4P_FTS_TH-TP_TDR_4P_DIPA    I21 @S9S_MB_2U_LIB.S9S_MB_2U(SCH_1):PAGE310
   X40    3     P2 TP_TDR_4P_FTS_TH-TP_TDR_4P_DIPA    I21 @S9S_MB_2U_LIB.S9S_MB_2U(SCH_1):PAGE310
   X39    2     P1 TP_TDR_4P_FTS_TH-TP_TDR_4P_DIPA    I22 @S9S_MB_2U_LIB.S9S_MB_2U(SCH_1):PAGE310
   X39    3     P2 TP_TDR_4P_FTS_TH-TP_TDR_4P_DIPA    I22 @S9S_MB_2U_LIB.S9S_MB_2U(SCH_1):PAGE310

TCA9539_0_ADD0 @S9S_MB_2U_LIB.S9S_MB_2U(SCH_1):TCA9539_0_ADD0
  U181   21     A0 PCA9539RPW-PCA9539RPW,SMLF,IC,A    I66 @S9S_MB_2U_LIB.S9S_MB_2U(SCH_1):PAGE214
 R2695    2      B Q_RES_0402LF-1K,1%,1/16W,EMPTYA    I74 @S9S_MB_2U_LIB.S9S_MB_2U(SCH_1):PAGE214
 R2696    1      A Q_RES_0402LF-1K,1%,1/16W,CHIP,A    I75 @S9S_MB_2U_LIB.S9S_MB_2U(SCH_1):PAGE214

TCA9539_0_ADD1 @S9S_MB_2U_LIB.S9S_MB_2U(SCH_1):TCA9539_0_ADD1
  U181    2     A1 PCA9539RPW-PCA9539RPW,SMLF,IC,A    I66 @S9S_MB_2U_LIB.S9S_MB_2U(SCH_1):PAGE214
 R2693    2      B Q_RES_0402LF-1K,1%,1/16W,EMPTYA    I76 @S9S_MB_2U_LIB.S9S_MB_2U(SCH_1):PAGE214
 R2694    1      A Q_RES_0402LF-1K,1%,1/16W,CHIP,A    I77 @S9S_MB_2U_LIB.S9S_MB_2U(SCH_1):PAGE214

TDR_DIFF_100_BOT_DN @S9S_MB_2U_LIB.S9S_MB_2U(SCH_1):TDR_DIFF_100_BOT_DN
   X24    1     S1 TP_TDR_4P_FTS_TH-TP_TDR_4P_DIPA    I42 @S9S_MB_2U_LIB.S9S_MB_2U(SCH_1):PAGE288
   X18    4     S2 TP_TDR_4P_FTS_TH-TP_TDR_4P_DIPA    I43 @S9S_MB_2U_LIB.S9S_MB_2U(SCH_1):PAGE288

TDR_DIFF_100_BOT_DP @S9S_MB_2U_LIB.S9S_MB_2U(SCH_1):TDR_DIFF_100_BOT_DP
   X24    4     S2 TP_TDR_4P_FTS_TH-TP_TDR_4P_DIPA    I42 @S9S_MB_2U_LIB.S9S_MB_2U(SCH_1):PAGE288
   X18    1     S1 TP_TDR_4P_FTS_TH-TP_TDR_4P_DIPA    I43 @S9S_MB_2U_LIB.S9S_MB_2U(SCH_1):PAGE288

TDR_DIFF_100_IN1_DN @S9S_MB_2U_LIB.S9S_MB_2U(SCH_1):TDR_DIFF_100_IN1_DN
   X20    1     S1 TP_TDR_4P_FTS_TH-TP_TDR_4P_DIPA     I4 @S9S_MB_2U_LIB.S9S_MB_2U(SCH_1):PAGE288
   X14    4     S2 TP_TDR_4P_FTS_TH-TP_TDR_4P_DIPA    I12 @S9S_MB_2U_LIB.S9S_MB_2U(SCH_1):PAGE288

TDR_DIFF_100_IN1_DP @S9S_MB_2U_LIB.S9S_MB_2U(SCH_1):TDR_DIFF_100_IN1_DP
   X20    4     S2 TP_TDR_4P_FTS_TH-TP_TDR_4P_DIPA     I4 @S9S_MB_2U_LIB.S9S_MB_2U(SCH_1):PAGE288
   X14    1     S1 TP_TDR_4P_FTS_TH-TP_TDR_4P_DIPA    I12 @S9S_MB_2U_LIB.S9S_MB_2U(SCH_1):PAGE288

TDR_DIFF_100_IN2_DN @S9S_MB_2U_LIB.S9S_MB_2U(SCH_1):TDR_DIFF_100_IN2_DN
   X21    1     S1 TP_TDR_4P_FTS_TH-TP_TDR_4P_DIPA     I9 @S9S_MB_2U_LIB.S9S_MB_2U(SCH_1):PAGE288
   X15    4     S2 TP_TDR_4P_FTS_TH-TP_TDR_4P_DIPA    I17 @S9S_MB_2U_LIB.S9S_MB_2U(SCH_1):PAGE288

TDR_DIFF_100_IN2_DP @S9S_MB_2U_LIB.S9S_MB_2U(SCH_1):TDR_DIFF_100_IN2_DP
   X21    4     S2 TP_TDR_4P_FTS_TH-TP_TDR_4P_DIPA     I9 @S9S_MB_2U_LIB.S9S_MB_2U(SCH_1):PAGE288
   X15    1     S1 TP_TDR_4P_FTS_TH-TP_TDR_4P_DIPA    I17 @S9S_MB_2U_LIB.S9S_MB_2U(SCH_1):PAGE288

TDR_DIFF_100_IN3_DN @S9S_MB_2U_LIB.S9S_MB_2U(SCH_1):TDR_DIFF_100_IN3_DN
   X22    1     S1 TP_TDR_4P_FTS_TH-TP_TDR_4P_DIPA     I8 @S9S_MB_2U_LIB.S9S_MB_2U(SCH_1):PAGE288
   X16    4     S2 TP_TDR_4P_FTS_TH-TP_TDR_4P_DIPA    I18 @S9S_MB_2U_LIB.S9S_MB_2U(SCH_1):PAGE288

TDR_DIFF_100_IN3_DP @S9S_MB_2U_LIB.S9S_MB_2U(SCH_1):TDR_DIFF_100_IN3_DP
   X22    4     S2 TP_TDR_4P_FTS_TH-TP_TDR_4P_DIPA     I8 @S9S_MB_2U_LIB.S9S_MB_2U(SCH_1):PAGE288
   X16    1     S1 TP_TDR_4P_FTS_TH-TP_TDR_4P_DIPA    I18 @S9S_MB_2U_LIB.S9S_MB_2U(SCH_1):PAGE288

TDR_DIFF_100_IN4_DN @S9S_MB_2U_LIB.S9S_MB_2U(SCH_1):TDR_DIFF_100_IN4_DN
   X23    1     S1 TP_TDR_4P_FTS_TH-TP_TDR_4P_DIPA    I10 @S9S_MB_2U_LIB.S9S_MB_2U(SCH_1):PAGE288
   X17    4     S2 TP_TDR_4P_FTS_TH-TP_TDR_4P_DIPA    I19 @S9S_MB_2U_LIB.S9S_MB_2U(SCH_1):PAGE288

TDR_DIFF_100_IN4_DP @S9S_MB_2U_LIB.S9S_MB_2U(SCH_1):TDR_DIFF_100_IN4_DP
   X23    4     S2 TP_TDR_4P_FTS_TH-TP_TDR_4P_DIPA    I10 @S9S_MB_2U_LIB.S9S_MB_2U(SCH_1):PAGE288
   X17    1     S1 TP_TDR_4P_FTS_TH-TP_TDR_4P_DIPA    I19 @S9S_MB_2U_LIB.S9S_MB_2U(SCH_1):PAGE288

TDR_DIFF_100_IN5_DN @S9S_MB_2U_LIB.S9S_MB_2U(SCH_1):TDR_DIFF_100_IN5_DN
   X31    1     S1 TP_TDR_4P_FTS_TH-TP_TDR_4P_DIPA   I112 @S9S_MB_2U_LIB.S9S_MB_2U(SCH_1):PAGE288
   X29    4     S2 TP_TDR_4P_FTS_TH-TP_TDR_4P_DIPA   I116 @S9S_MB_2U_LIB.S9S_MB_2U(SCH_1):PAGE288

TDR_DIFF_100_IN5_DP @S9S_MB_2U_LIB.S9S_MB_2U(SCH_1):TDR_DIFF_100_IN5_DP
   X31    4     S2 TP_TDR_4P_FTS_TH-TP_TDR_4P_DIPA   I112 @S9S_MB_2U_LIB.S9S_MB_2U(SCH_1):PAGE288
   X29    1     S1 TP_TDR_4P_FTS_TH-TP_TDR_4P_DIPA   I116 @S9S_MB_2U_LIB.S9S_MB_2U(SCH_1):PAGE288

TDR_DIFF_100_IN6_DN @S9S_MB_2U_LIB.S9S_MB_2U(SCH_1):TDR_DIFF_100_IN6_DN
   X32    1     S1 TP_TDR_4P_FTS_TH-TP_TDR_4P_DIPA   I115 @S9S_MB_2U_LIB.S9S_MB_2U(SCH_1):PAGE288
   X30    4     S2 TP_TDR_4P_FTS_TH-TP_TDR_4P_DIPA   I117 @S9S_MB_2U_LIB.S9S_MB_2U(SCH_1):PAGE288

TDR_DIFF_100_IN6_DP @S9S_MB_2U_LIB.S9S_MB_2U(SCH_1):TDR_DIFF_100_IN6_DP
   X32    4     S2 TP_TDR_4P_FTS_TH-TP_TDR_4P_DIPA   I115 @S9S_MB_2U_LIB.S9S_MB_2U(SCH_1):PAGE288
   X30    1     S1 TP_TDR_4P_FTS_TH-TP_TDR_4P_DIPA   I117 @S9S_MB_2U_LIB.S9S_MB_2U(SCH_1):PAGE288

TDR_DIFF_100_TOP_DN @S9S_MB_2U_LIB.S9S_MB_2U(SCH_1):TDR_DIFF_100_TOP_DN
   X19    1     S1 TP_TDR_4P_FTS_TH-TP_TDR_4P_DIPA     I3 @S9S_MB_2U_LIB.S9S_MB_2U(SCH_1):PAGE288
   X13    4     S2 TP_TDR_4P_FTS_TH-TP_TDR_4P_DIPA    I11 @S9S_MB_2U_LIB.S9S_MB_2U(SCH_1):PAGE288

TDR_DIFF_100_TOP_DP @S9S_MB_2U_LIB.S9S_MB_2U(SCH_1):TDR_DIFF_100_TOP_DP
   X19    4     S2 TP_TDR_4P_FTS_TH-TP_TDR_4P_DIPA     I3 @S9S_MB_2U_LIB.S9S_MB_2U(SCH_1):PAGE288
   X13    1     S1 TP_TDR_4P_FTS_TH-TP_TDR_4P_DIPA    I11 @S9S_MB_2U_LIB.S9S_MB_2U(SCH_1):PAGE288

TDR_DIFF_85_BOT_DN @S9S_MB_2U_LIB.S9S_MB_2U(SCH_1):TDR_DIFF_85_BOT_DN
   X12    1     S1 TP_TDR_4P_FTS_TH-TP_TDR_4P_DIPA    I46 @S9S_MB_2U_LIB.S9S_MB_2U(SCH_1):PAGE288
    X6    4     S2 TP_TDR_4P_FTS_TH-TP_TDR_4P_DIPA    I47 @S9S_MB_2U_LIB.S9S_MB_2U(SCH_1):PAGE288

TDR_DIFF_85_BOT_DP @S9S_MB_2U_LIB.S9S_MB_2U(SCH_1):TDR_DIFF_85_BOT_DP
   X12    4     S2 TP_TDR_4P_FTS_TH-TP_TDR_4P_DIPA    I46 @S9S_MB_2U_LIB.S9S_MB_2U(SCH_1):PAGE288
    X6    1     S1 TP_TDR_4P_FTS_TH-TP_TDR_4P_DIPA    I47 @S9S_MB_2U_LIB.S9S_MB_2U(SCH_1):PAGE288

TDR_DIFF_85_IN1_DN @S9S_MB_2U_LIB.S9S_MB_2U(SCH_1):TDR_DIFF_85_IN1_DN
    X8    1     S1 TP_TDR_4P_FTS_TH-TP_TDR_4P_DIPA    I27 @S9S_MB_2U_LIB.S9S_MB_2U(SCH_1):PAGE288
    X2    4     S2 TP_TDR_4P_FTS_TH-TP_TDR_4P_DIPA    I30 @S9S_MB_2U_LIB.S9S_MB_2U(SCH_1):PAGE288

TDR_DIFF_85_IN1_DP @S9S_MB_2U_LIB.S9S_MB_2U(SCH_1):TDR_DIFF_85_IN1_DP
    X8    4     S2 TP_TDR_4P_FTS_TH-TP_TDR_4P_DIPA    I27 @S9S_MB_2U_LIB.S9S_MB_2U(SCH_1):PAGE288
    X2    1     S1 TP_TDR_4P_FTS_TH-TP_TDR_4P_DIPA    I30 @S9S_MB_2U_LIB.S9S_MB_2U(SCH_1):PAGE288

TDR_DIFF_85_IN2_DN @S9S_MB_2U_LIB.S9S_MB_2U(SCH_1):TDR_DIFF_85_IN2_DN
    X9    1     S1 TP_TDR_4P_FTS_TH-TP_TDR_4P_DIPA    I32 @S9S_MB_2U_LIB.S9S_MB_2U(SCH_1):PAGE288
    X3    4     S2 TP_TDR_4P_FTS_TH-TP_TDR_4P_DIPA    I35 @S9S_MB_2U_LIB.S9S_MB_2U(SCH_1):PAGE288

TDR_DIFF_85_IN2_DP @S9S_MB_2U_LIB.S9S_MB_2U(SCH_1):TDR_DIFF_85_IN2_DP
    X9    4     S2 TP_TDR_4P_FTS_TH-TP_TDR_4P_DIPA    I32 @S9S_MB_2U_LIB.S9S_MB_2U(SCH_1):PAGE288
    X3    1     S1 TP_TDR_4P_FTS_TH-TP_TDR_4P_DIPA    I35 @S9S_MB_2U_LIB.S9S_MB_2U(SCH_1):PAGE288

TDR_DIFF_85_IN3_DN @S9S_MB_2U_LIB.S9S_MB_2U(SCH_1):TDR_DIFF_85_IN3_DN
   X10    1     S1 TP_TDR_4P_FTS_TH-TP_TDR_4P_DIPA    I33 @S9S_MB_2U_LIB.S9S_MB_2U(SCH_1):PAGE288
    X4    4     S2 TP_TDR_4P_FTS_TH-TP_TDR_4P_DIPA    I37 @S9S_MB_2U_LIB.S9S_MB_2U(SCH_1):PAGE288

TDR_DIFF_85_IN3_DP @S9S_MB_2U_LIB.S9S_MB_2U(SCH_1):TDR_DIFF_85_IN3_DP
   X10    4     S2 TP_TDR_4P_FTS_TH-TP_TDR_4P_DIPA    I33 @S9S_MB_2U_LIB.S9S_MB_2U(SCH_1):PAGE288
    X4    1     S1 TP_TDR_4P_FTS_TH-TP_TDR_4P_DIPA    I37 @S9S_MB_2U_LIB.S9S_MB_2U(SCH_1):PAGE288

TDR_DIFF_85_IN4_DN @S9S_MB_2U_LIB.S9S_MB_2U(SCH_1):TDR_DIFF_85_IN4_DN
   X11    1     S1 TP_TDR_4P_FTS_TH-TP_TDR_4P_DIPA    I34 @S9S_MB_2U_LIB.S9S_MB_2U(SCH_1):PAGE288
    X5    4     S2 TP_TDR_4P_FTS_TH-TP_TDR_4P_DIPA    I39 @S9S_MB_2U_LIB.S9S_MB_2U(SCH_1):PAGE288

TDR_DIFF_85_IN4_DP @S9S_MB_2U_LIB.S9S_MB_2U(SCH_1):TDR_DIFF_85_IN4_DP
   X11    4     S2 TP_TDR_4P_FTS_TH-TP_TDR_4P_DIPA    I34 @S9S_MB_2U_LIB.S9S_MB_2U(SCH_1):PAGE288
    X5    1     S1 TP_TDR_4P_FTS_TH-TP_TDR_4P_DIPA    I39 @S9S_MB_2U_LIB.S9S_MB_2U(SCH_1):PAGE288

TDR_DIFF_85_IN5_DN @S9S_MB_2U_LIB.S9S_MB_2U(SCH_1):TDR_DIFF_85_IN5_DN
   X27    1     S1 TP_TDR_4P_FTS_TH-TP_TDR_4P_DIPA   I106 @S9S_MB_2U_LIB.S9S_MB_2U(SCH_1):PAGE288
   X25    4     S2 TP_TDR_4P_FTS_TH-TP_TDR_4P_DIPA   I108 @S9S_MB_2U_LIB.S9S_MB_2U(SCH_1):PAGE288

TDR_DIFF_85_IN5_DP @S9S_MB_2U_LIB.S9S_MB_2U(SCH_1):TDR_DIFF_85_IN5_DP
   X27    4     S2 TP_TDR_4P_FTS_TH-TP_TDR_4P_DIPA   I106 @S9S_MB_2U_LIB.S9S_MB_2U(SCH_1):PAGE288
   X25    1     S1 TP_TDR_4P_FTS_TH-TP_TDR_4P_DIPA   I108 @S9S_MB_2U_LIB.S9S_MB_2U(SCH_1):PAGE288

TDR_DIFF_85_IN6_DN @S9S_MB_2U_LIB.S9S_MB_2U(SCH_1):TDR_DIFF_85_IN6_DN
   X28    1     S1 TP_TDR_4P_FTS_TH-TP_TDR_4P_DIPA   I107 @S9S_MB_2U_LIB.S9S_MB_2U(SCH_1):PAGE288
   X26    4     S2 TP_TDR_4P_FTS_TH-TP_TDR_4P_DIPA   I110 @S9S_MB_2U_LIB.S9S_MB_2U(SCH_1):PAGE288

TDR_DIFF_85_IN6_DP @S9S_MB_2U_LIB.S9S_MB_2U(SCH_1):TDR_DIFF_85_IN6_DP
   X28    4     S2 TP_TDR_4P_FTS_TH-TP_TDR_4P_DIPA   I107 @S9S_MB_2U_LIB.S9S_MB_2U(SCH_1):PAGE288
   X26    1     S1 TP_TDR_4P_FTS_TH-TP_TDR_4P_DIPA   I110 @S9S_MB_2U_LIB.S9S_MB_2U(SCH_1):PAGE288

TDR_DIFF_85_TOP_DN @S9S_MB_2U_LIB.S9S_MB_2U(SCH_1):TDR_DIFF_85_TOP_DN
    X7    1     S1 TP_TDR_4P_FTS_TH-TP_TDR_4P_DIPA    I26 @S9S_MB_2U_LIB.S9S_MB_2U(SCH_1):PAGE288
    X1    4     S2 TP_TDR_4P_FTS_TH-TP_TDR_4P_DIPA    I28 @S9S_MB_2U_LIB.S9S_MB_2U(SCH_1):PAGE288

TDR_DIFF_85_TOP_DP @S9S_MB_2U_LIB.S9S_MB_2U(SCH_1):TDR_DIFF_85_TOP_DP
    X7    4     S2 TP_TDR_4P_FTS_TH-TP_TDR_4P_DIPA    I26 @S9S_MB_2U_LIB.S9S_MB_2U(SCH_1):PAGE288
    X1    1     S1 TP_TDR_4P_FTS_TH-TP_TDR_4P_DIPA    I28 @S9S_MB_2U_LIB.S9S_MB_2U(SCH_1):PAGE288

TDR_SE_40_OHM_BOT @S9S_MB_2U_LIB.S9S_MB_2U(SCH_1):TDR_SE_40_OHM_BOT
   DB6    2    IO1 TDR_3P_TH2-EMPTY,N_A    I69 @S9S_MB_2U_LIB.S9S_MB_2U(SCH_1):PAGE288
   DB6    3    IO2 TDR_3P_TH2-EMPTY,N_A    I69 @S9S_MB_2U_LIB.S9S_MB_2U(SCH_1):PAGE288

TDR_SE_40_OHM_IN1 @S9S_MB_2U_LIB.S9S_MB_2U(SCH_1):TDR_SE_40_OHM_IN1
   DB2    2    IO1 TDR_3P_TH2-EMPTY,N_A    I62 @S9S_MB_2U_LIB.S9S_MB_2U(SCH_1):PAGE288
   DB2    3    IO2 TDR_3P_TH2-EMPTY,N_A    I62 @S9S_MB_2U_LIB.S9S_MB_2U(SCH_1):PAGE288

TDR_SE_40_OHM_IN2 @S9S_MB_2U_LIB.S9S_MB_2U(SCH_1):TDR_SE_40_OHM_IN2
   DB3    2    IO1 TDR_3P_TH2-EMPTY,N_A    I63 @S9S_MB_2U_LIB.S9S_MB_2U(SCH_1):PAGE288
   DB3    3    IO2 TDR_3P_TH2-EMPTY,N_A    I63 @S9S_MB_2U_LIB.S9S_MB_2U(SCH_1):PAGE288

TDR_SE_40_OHM_IN3 @S9S_MB_2U_LIB.S9S_MB_2U(SCH_1):TDR_SE_40_OHM_IN3
   DB4    2    IO1 TDR_3P_TH2-EMPTY,N_A    I67 @S9S_MB_2U_LIB.S9S_MB_2U(SCH_1):PAGE288
   DB4    3    IO2 TDR_3P_TH2-EMPTY,N_A    I67 @S9S_MB_2U_LIB.S9S_MB_2U(SCH_1):PAGE288

TDR_SE_40_OHM_IN4 @S9S_MB_2U_LIB.S9S_MB_2U(SCH_1):TDR_SE_40_OHM_IN4
   DB5    2    IO1 TDR_3P_TH2-EMPTY,N_A    I68 @S9S_MB_2U_LIB.S9S_MB_2U(SCH_1):PAGE288
   DB5    3    IO2 TDR_3P_TH2-EMPTY,N_A    I68 @S9S_MB_2U_LIB.S9S_MB_2U(SCH_1):PAGE288

TDR_SE_40_OHM_IN5 @S9S_MB_2U_LIB.S9S_MB_2U(SCH_1):TDR_SE_40_OHM_IN5
  DB13    2    IO1 TDR_3P_TH2-EMPTY,N_A   I101 @S9S_MB_2U_LIB.S9S_MB_2U(SCH_1):PAGE288
  DB13    3    IO2 TDR_3P_TH2-EMPTY,N_A   I101 @S9S_MB_2U_LIB.S9S_MB_2U(SCH_1):PAGE288

TDR_SE_40_OHM_IN6 @S9S_MB_2U_LIB.S9S_MB_2U(SCH_1):TDR_SE_40_OHM_IN6
  DB14    2    IO1 TDR_3P_TH2-EMPTY,N_A    I96 @S9S_MB_2U_LIB.S9S_MB_2U(SCH_1):PAGE288
  DB14    3    IO2 TDR_3P_TH2-EMPTY,N_A    I96 @S9S_MB_2U_LIB.S9S_MB_2U(SCH_1):PAGE288

TDR_SE_40_OHM_TOP @S9S_MB_2U_LIB.S9S_MB_2U(SCH_1):TDR_SE_40_OHM_TOP
   DB1    2    IO1 TDR_3P_TH2-EMPTY,N_A    I61 @S9S_MB_2U_LIB.S9S_MB_2U(SCH_1):PAGE288
   DB1    3    IO2 TDR_3P_TH2-EMPTY,N_A    I61 @S9S_MB_2U_LIB.S9S_MB_2U(SCH_1):PAGE288

TDR_SE_50_OHM_BOT @S9S_MB_2U_LIB.S9S_MB_2U(SCH_1):TDR_SE_50_OHM_BOT
  DB12    2    IO1 TDR_3P_TH2-EMPTY,N_A    I60 @S9S_MB_2U_LIB.S9S_MB_2U(SCH_1):PAGE288
  DB12    3    IO2 TDR_3P_TH2-EMPTY,N_A    I60 @S9S_MB_2U_LIB.S9S_MB_2U(SCH_1):PAGE288

TDR_SE_50_OHM_IN1 @S9S_MB_2U_LIB.S9S_MB_2U(SCH_1):TDR_SE_50_OHM_IN1
   DB8    2    IO1 TDR_3P_TH2-EMPTY,N_A    I51 @S9S_MB_2U_LIB.S9S_MB_2U(SCH_1):PAGE288
   DB8    3    IO2 TDR_3P_TH2-EMPTY,N_A    I51 @S9S_MB_2U_LIB.S9S_MB_2U(SCH_1):PAGE288

TDR_SE_50_OHM_IN2 @S9S_MB_2U_LIB.S9S_MB_2U(SCH_1):TDR_SE_50_OHM_IN2
   DB9    2    IO1 TDR_3P_TH2-EMPTY,N_A    I53 @S9S_MB_2U_LIB.S9S_MB_2U(SCH_1):PAGE288
   DB9    3    IO2 TDR_3P_TH2-EMPTY,N_A    I53 @S9S_MB_2U_LIB.S9S_MB_2U(SCH_1):PAGE288

TDR_SE_50_OHM_IN3 @S9S_MB_2U_LIB.S9S_MB_2U(SCH_1):TDR_SE_50_OHM_IN3
  DB10    2    IO1 TDR_3P_TH2-EMPTY,N_A    I55 @S9S_MB_2U_LIB.S9S_MB_2U(SCH_1):PAGE288
  DB10    3    IO2 TDR_3P_TH2-EMPTY,N_A    I55 @S9S_MB_2U_LIB.S9S_MB_2U(SCH_1):PAGE288

TDR_SE_50_OHM_IN4 @S9S_MB_2U_LIB.S9S_MB_2U(SCH_1):TDR_SE_50_OHM_IN4
  DB11    2    IO1 TDR_3P_TH2-EMPTY,N_A    I57 @S9S_MB_2U_LIB.S9S_MB_2U(SCH_1):PAGE288
  DB11    3    IO2 TDR_3P_TH2-EMPTY,N_A    I57 @S9S_MB_2U_LIB.S9S_MB_2U(SCH_1):PAGE288

TDR_SE_50_OHM_IN5 @S9S_MB_2U_LIB.S9S_MB_2U(SCH_1):TDR_SE_50_OHM_IN5
  DB15    2    IO1 TDR_3P_TH2-EMPTY,N_A    I97 @S9S_MB_2U_LIB.S9S_MB_2U(SCH_1):PAGE288
  DB15    3    IO2 TDR_3P_TH2-EMPTY,N_A    I97 @S9S_MB_2U_LIB.S9S_MB_2U(SCH_1):PAGE288

TDR_SE_50_OHM_IN6 @S9S_MB_2U_LIB.S9S_MB_2U(SCH_1):TDR_SE_50_OHM_IN6
  DB16    2    IO1 TDR_3P_TH2-EMPTY,N_A    I99 @S9S_MB_2U_LIB.S9S_MB_2U(SCH_1):PAGE288
  DB16    3    IO2 TDR_3P_TH2-EMPTY,N_A    I99 @S9S_MB_2U_LIB.S9S_MB_2U(SCH_1):PAGE288

TDR_SE_50_OHM_TOP @S9S_MB_2U_LIB.S9S_MB_2U(SCH_1):TDR_SE_50_OHM_TOP
   DB7    2    IO1 TDR_3P_TH2-EMPTY,N_A    I49 @S9S_MB_2U_LIB.S9S_MB_2U(SCH_1):PAGE288
   DB7    3    IO2 TDR_3P_TH2-EMPTY,N_A    I49 @S9S_MB_2U_LIB.S9S_MB_2U(SCH_1):PAGE288

TP_74CB_B8 @S9S_MB_2U_LIB.S9S_MB_2U(SCH_1):TP_74CB_B8
   U17    8     3B 74CBTLV3126PW-74CBTLV3126PW,SMA    I80 @S9S_MB_2U_LIB.S9S_MB_2U(SCH_1):PAGE134

TP_ADC128_INT @S9S_MB_2U_LIB.S9S_MB_2U(SCH_1):TP_ADC128_INT
  U269    6   INT# ADC128D818CIMTXNOPB-ADC128D818A   I103 @S9S_MB_2U_LIB.S9S_MB_2U(SCH_1):PAGE239

TP_CHA_CPU0_DIMM1_FRU_0 @S9S_MB_2U_LIB.S9S_MB_2U(SCH_1):TP_CHA_CPU0_DIMM1_FRU_0
    J1    2   RFU0 SCONN288_ADR50017P130CC-SCONN2A   I198 @S9S_MB_2U_LIB.S9S_MB_2U(SCH_1):PAGE82

TP_CHA_CPU0_DIMM1_FRU_1 @S9S_MB_2U_LIB.S9S_MB_2U(SCH_1):TP_CHA_CPU0_DIMM1_FRU_1
    J1  144   RFU1 SCONN288_ADR50017P130CC-SCONN2A   I198 @S9S_MB_2U_LIB.S9S_MB_2U(SCH_1):PAGE82

TP_CHA_CPU0_DIMM1_FRU_2 @S9S_MB_2U_LIB.S9S_MB_2U(SCH_1):TP_CHA_CPU0_DIMM1_FRU_2
    J1  149   RFU2 SCONN288_ADR50017P130CC-SCONN2A   I198 @S9S_MB_2U_LIB.S9S_MB_2U(SCH_1):PAGE82

TP_CHA_CPU0_DIMM1_FRU_3 @S9S_MB_2U_LIB.S9S_MB_2U(SCH_1):TP_CHA_CPU0_DIMM1_FRU_3
    J1  150   RFU3 SCONN288_ADR50017P130CC-SCONN2A   I198 @S9S_MB_2U_LIB.S9S_MB_2U(SCH_1):PAGE82

TP_CHA_CPU0_DIMM1_FRU_4 @S9S_MB_2U_LIB.S9S_MB_2U(SCH_1):TP_CHA_CPU0_DIMM1_FRU_4
    J1  220   RFU4 SCONN288_ADR50017P130CC-SCONN2A   I198 @S9S_MB_2U_LIB.S9S_MB_2U(SCH_1):PAGE82

TP_CHA_CPU0_DIMM1_FRU_5 @S9S_MB_2U_LIB.S9S_MB_2U(SCH_1):TP_CHA_CPU0_DIMM1_FRU_5
    J1  231   RFU5 SCONN288_ADR50017P130CC-SCONN2A   I198 @S9S_MB_2U_LIB.S9S_MB_2U(SCH_1):PAGE82

TP_CHA_CPU0_DIMM1_FRU_6 @S9S_MB_2U_LIB.S9S_MB_2U(SCH_1):TP_CHA_CPU0_DIMM1_FRU_6
    J1  232   RFU6 SCONN288_ADR50017P130CC-SCONN2A   I198 @S9S_MB_2U_LIB.S9S_MB_2U(SCH_1):PAGE82

TP_CHA_CPU0_DIMM2_FRU_0 @S9S_MB_2U_LIB.S9S_MB_2U(SCH_1):TP_CHA_CPU0_DIMM2_FRU_0
    J2    2   RFU0 SCONN288_ADR50017P087CC-SCONN2A   I177 @S9S_MB_2U_LIB.S9S_MB_2U(SCH_1):PAGE83

TP_CHA_CPU0_DIMM2_FRU_1 @S9S_MB_2U_LIB.S9S_MB_2U(SCH_1):TP_CHA_CPU0_DIMM2_FRU_1
    J2  144   RFU1 SCONN288_ADR50017P087CC-SCONN2A   I177 @S9S_MB_2U_LIB.S9S_MB_2U(SCH_1):PAGE83

TP_CHA_CPU0_DIMM2_FRU_2 @S9S_MB_2U_LIB.S9S_MB_2U(SCH_1):TP_CHA_CPU0_DIMM2_FRU_2
    J2  149   RFU2 SCONN288_ADR50017P087CC-SCONN2A   I177 @S9S_MB_2U_LIB.S9S_MB_2U(SCH_1):PAGE83

TP_CHA_CPU0_DIMM2_FRU_3 @S9S_MB_2U_LIB.S9S_MB_2U(SCH_1):TP_CHA_CPU0_DIMM2_FRU_3
    J2  150   RFU3 SCONN288_ADR50017P087CC-SCONN2A   I177 @S9S_MB_2U_LIB.S9S_MB_2U(SCH_1):PAGE83

TP_CHA_CPU0_DIMM2_FRU_4 @S9S_MB_2U_LIB.S9S_MB_2U(SCH_1):TP_CHA_CPU0_DIMM2_FRU_4
    J2  220   RFU4 SCONN288_ADR50017P087CC-SCONN2A   I177 @S9S_MB_2U_LIB.S9S_MB_2U(SCH_1):PAGE83

TP_CHA_CPU0_DIMM2_FRU_5 @S9S_MB_2U_LIB.S9S_MB_2U(SCH_1):TP_CHA_CPU0_DIMM2_FRU_5
    J2  231   RFU5 SCONN288_ADR50017P087CC-SCONN2A   I177 @S9S_MB_2U_LIB.S9S_MB_2U(SCH_1):PAGE83

TP_CHA_CPU0_DIMM2_FRU_6 @S9S_MB_2U_LIB.S9S_MB_2U(SCH_1):TP_CHA_CPU0_DIMM2_FRU_6
    J2  232   RFU6 SCONN288_ADR50017P087CC-SCONN2A   I177 @S9S_MB_2U_LIB.S9S_MB_2U(SCH_1):PAGE83

TP_CHA_CPU1_DIMM1_FRU_0 @S9S_MB_2U_LIB.S9S_MB_2U(SCH_1):TP_CHA_CPU1_DIMM1_FRU_0
   J17    2   RFU0 SCONN288_ADR50017P130CC-SCONN2A    I12 @S9S_MB_2U_LIB.S9S_MB_2U(SCH_1):PAGE98

TP_CHA_CPU1_DIMM1_FRU_1 @S9S_MB_2U_LIB.S9S_MB_2U(SCH_1):TP_CHA_CPU1_DIMM1_FRU_1
   J17  144   RFU1 SCONN288_ADR50017P130CC-SCONN2A    I12 @S9S_MB_2U_LIB.S9S_MB_2U(SCH_1):PAGE98

TP_CHA_CPU1_DIMM1_FRU_2 @S9S_MB_2U_LIB.S9S_MB_2U(SCH_1):TP_CHA_CPU1_DIMM1_FRU_2
   J17  149   RFU2 SCONN288_ADR50017P130CC-SCONN2A    I12 @S9S_MB_2U_LIB.S9S_MB_2U(SCH_1):PAGE98

TP_CHA_CPU1_DIMM1_FRU_3 @S9S_MB_2U_LIB.S9S_MB_2U(SCH_1):TP_CHA_CPU1_DIMM1_FRU_3
   J17  150   RFU3 SCONN288_ADR50017P130CC-SCONN2A    I12 @S9S_MB_2U_LIB.S9S_MB_2U(SCH_1):PAGE98

TP_CHA_CPU1_DIMM1_FRU_4 @S9S_MB_2U_LIB.S9S_MB_2U(SCH_1):TP_CHA_CPU1_DIMM1_FRU_4
   J17  220   RFU4 SCONN288_ADR50017P130CC-SCONN2A    I12 @S9S_MB_2U_LIB.S9S_MB_2U(SCH_1):PAGE98

TP_CHA_CPU1_DIMM1_FRU_5 @S9S_MB_2U_LIB.S9S_MB_2U(SCH_1):TP_CHA_CPU1_DIMM1_FRU_5
   J17  231   RFU5 SCONN288_ADR50017P130CC-SCONN2A    I12 @S9S_MB_2U_LIB.S9S_MB_2U(SCH_1):PAGE98

TP_CHA_CPU1_DIMM1_FRU_6 @S9S_MB_2U_LIB.S9S_MB_2U(SCH_1):TP_CHA_CPU1_DIMM1_FRU_6
   J17  232   RFU6 SCONN288_ADR50017P130CC-SCONN2A    I12 @S9S_MB_2U_LIB.S9S_MB_2U(SCH_1):PAGE98

TP_CHA_CPU1_DIMM2_FRU_0 @S9S_MB_2U_LIB.S9S_MB_2U(SCH_1):TP_CHA_CPU1_DIMM2_FRU_0
   J18    2   RFU0 SCONN288_ADR50017P087CC-SCONN2A    I24 @S9S_MB_2U_LIB.S9S_MB_2U(SCH_1):PAGE99

TP_CHA_CPU1_DIMM2_FRU_1 @S9S_MB_2U_LIB.S9S_MB_2U(SCH_1):TP_CHA_CPU1_DIMM2_FRU_1
   J18  144   RFU1 SCONN288_ADR50017P087CC-SCONN2A    I24 @S9S_MB_2U_LIB.S9S_MB_2U(SCH_1):PAGE99

TP_CHA_CPU1_DIMM2_FRU_2 @S9S_MB_2U_LIB.S9S_MB_2U(SCH_1):TP_CHA_CPU1_DIMM2_FRU_2
   J18  149   RFU2 SCONN288_ADR50017P087CC-SCONN2A    I24 @S9S_MB_2U_LIB.S9S_MB_2U(SCH_1):PAGE99

TP_CHA_CPU1_DIMM2_FRU_3 @S9S_MB_2U_LIB.S9S_MB_2U(SCH_1):TP_CHA_CPU1_DIMM2_FRU_3
   J18  150   RFU3 SCONN288_ADR50017P087CC-SCONN2A    I24 @S9S_MB_2U_LIB.S9S_MB_2U(SCH_1):PAGE99

TP_CHA_CPU1_DIMM2_FRU_4 @S9S_MB_2U_LIB.S9S_MB_2U(SCH_1):TP_CHA_CPU1_DIMM2_FRU_4
   J18  220   RFU4 SCONN288_ADR50017P087CC-SCONN2A    I24 @S9S_MB_2U_LIB.S9S_MB_2U(SCH_1):PAGE99

TP_CHA_CPU1_DIMM2_FRU_5 @S9S_MB_2U_LIB.S9S_MB_2U(SCH_1):TP_CHA_CPU1_DIMM2_FRU_5
   J18  231   RFU5 SCONN288_ADR50017P087CC-SCONN2A    I24 @S9S_MB_2U_LIB.S9S_MB_2U(SCH_1):PAGE99

TP_CHA_CPU1_DIMM2_FRU_6 @S9S_MB_2U_LIB.S9S_MB_2U(SCH_1):TP_CHA_CPU1_DIMM2_FRU_6
   J18  232   RFU6 SCONN288_ADR50017P087CC-SCONN2A    I24 @S9S_MB_2U_LIB.S9S_MB_2U(SCH_1):PAGE99

TP_CHB_CPU0_DIMM1_FRU_0 @S9S_MB_2U_LIB.S9S_MB_2U(SCH_1):TP_CHB_CPU0_DIMM1_FRU_0
    J3    2   RFU0 SCONN288_ADR50017P130CC-SCONN2A   I180 @S9S_MB_2U_LIB.S9S_MB_2U(SCH_1):PAGE84

TP_CHB_CPU0_DIMM1_FRU_1 @S9S_MB_2U_LIB.S9S_MB_2U(SCH_1):TP_CHB_CPU0_DIMM1_FRU_1
    J3  144   RFU1 SCONN288_ADR50017P130CC-SCONN2A   I180 @S9S_MB_2U_LIB.S9S_MB_2U(SCH_1):PAGE84

TP_CHB_CPU0_DIMM1_FRU_2 @S9S_MB_2U_LIB.S9S_MB_2U(SCH_1):TP_CHB_CPU0_DIMM1_FRU_2
    J3  149   RFU2 SCONN288_ADR50017P130CC-SCONN2A   I180 @S9S_MB_2U_LIB.S9S_MB_2U(SCH_1):PAGE84

TP_CHB_CPU0_DIMM1_FRU_3 @S9S_MB_2U_LIB.S9S_MB_2U(SCH_1):TP_CHB_CPU0_DIMM1_FRU_3
    J3  150   RFU3 SCONN288_ADR50017P130CC-SCONN2A   I180 @S9S_MB_2U_LIB.S9S_MB_2U(SCH_1):PAGE84

TP_CHB_CPU0_DIMM1_FRU_4 @S9S_MB_2U_LIB.S9S_MB_2U(SCH_1):TP_CHB_CPU0_DIMM1_FRU_4
    J3  220   RFU4 SCONN288_ADR50017P130CC-SCONN2A   I180 @S9S_MB_2U_LIB.S9S_MB_2U(SCH_1):PAGE84

TP_CHB_CPU0_DIMM1_FRU_5 @S9S_MB_2U_LIB.S9S_MB_2U(SCH_1):TP_CHB_CPU0_DIMM1_FRU_5
    J3  231   RFU5 SCONN288_ADR50017P130CC-SCONN2A   I180 @S9S_MB_2U_LIB.S9S_MB_2U(SCH_1):PAGE84

TP_CHB_CPU0_DIMM1_FRU_6 @S9S_MB_2U_LIB.S9S_MB_2U(SCH_1):TP_CHB_CPU0_DIMM1_FRU_6
    J3  232   RFU6 SCONN288_ADR50017P130CC-SCONN2A   I180 @S9S_MB_2U_LIB.S9S_MB_2U(SCH_1):PAGE84

TP_CHB_CPU0_DIMM2_FRU_0 @S9S_MB_2U_LIB.S9S_MB_2U(SCH_1):TP_CHB_CPU0_DIMM2_FRU_0
    J4    2   RFU0 SCONN288_ADR50017P087CC-SCONN2A    I23 @S9S_MB_2U_LIB.S9S_MB_2U(SCH_1):PAGE85

TP_CHB_CPU0_DIMM2_FRU_1 @S9S_MB_2U_LIB.S9S_MB_2U(SCH_1):TP_CHB_CPU0_DIMM2_FRU_1
    J4  144   RFU1 SCONN288_ADR50017P087CC-SCONN2A    I23 @S9S_MB_2U_LIB.S9S_MB_2U(SCH_1):PAGE85

TP_CHB_CPU0_DIMM2_FRU_2 @S9S_MB_2U_LIB.S9S_MB_2U(SCH_1):TP_CHB_CPU0_DIMM2_FRU_2
    J4  149   RFU2 SCONN288_ADR50017P087CC-SCONN2A    I23 @S9S_MB_2U_LIB.S9S_MB_2U(SCH_1):PAGE85

TP_CHB_CPU0_DIMM2_FRU_3 @S9S_MB_2U_LIB.S9S_MB_2U(SCH_1):TP_CHB_CPU0_DIMM2_FRU_3
    J4  150   RFU3 SCONN288_ADR50017P087CC-SCONN2A    I23 @S9S_MB_2U_LIB.S9S_MB_2U(SCH_1):PAGE85

TP_CHB_CPU0_DIMM2_FRU_4 @S9S_MB_2U_LIB.S9S_MB_2U(SCH_1):TP_CHB_CPU0_DIMM2_FRU_4
    J4  220   RFU4 SCONN288_ADR50017P087CC-SCONN2A    I23 @S9S_MB_2U_LIB.S9S_MB_2U(SCH_1):PAGE85

TP_CHB_CPU0_DIMM2_FRU_5 @S9S_MB_2U_LIB.S9S_MB_2U(SCH_1):TP_CHB_CPU0_DIMM2_FRU_5
    J4  231   RFU5 SCONN288_ADR50017P087CC-SCONN2A    I23 @S9S_MB_2U_LIB.S9S_MB_2U(SCH_1):PAGE85

TP_CHB_CPU0_DIMM2_FRU_6 @S9S_MB_2U_LIB.S9S_MB_2U(SCH_1):TP_CHB_CPU0_DIMM2_FRU_6
    J4  232   RFU6 SCONN288_ADR50017P087CC-SCONN2A    I23 @S9S_MB_2U_LIB.S9S_MB_2U(SCH_1):PAGE85

TP_CHB_CPU1_DIMM1_FRU_0 @S9S_MB_2U_LIB.S9S_MB_2U(SCH_1):TP_CHB_CPU1_DIMM1_FRU_0
   J19    2   RFU0 SCONN288_ADR50017P130CC-SCONN2A    I25 @S9S_MB_2U_LIB.S9S_MB_2U(SCH_1):PAGE100

TP_CHB_CPU1_DIMM1_FRU_1 @S9S_MB_2U_LIB.S9S_MB_2U(SCH_1):TP_CHB_CPU1_DIMM1_FRU_1
   J19  144   RFU1 SCONN288_ADR50017P130CC-SCONN2A    I25 @S9S_MB_2U_LIB.S9S_MB_2U(SCH_1):PAGE100

TP_CHB_CPU1_DIMM1_FRU_2 @S9S_MB_2U_LIB.S9S_MB_2U(SCH_1):TP_CHB_CPU1_DIMM1_FRU_2
   J19  149   RFU2 SCONN288_ADR50017P130CC-SCONN2A    I25 @S9S_MB_2U_LIB.S9S_MB_2U(SCH_1):PAGE100

TP_CHB_CPU1_DIMM1_FRU_3 @S9S_MB_2U_LIB.S9S_MB_2U(SCH_1):TP_CHB_CPU1_DIMM1_FRU_3
   J19  150   RFU3 SCONN288_ADR50017P130CC-SCONN2A    I25 @S9S_MB_2U_LIB.S9S_MB_2U(SCH_1):PAGE100

TP_CHB_CPU1_DIMM1_FRU_4 @S9S_MB_2U_LIB.S9S_MB_2U(SCH_1):TP_CHB_CPU1_DIMM1_FRU_4
   J19  220   RFU4 SCONN288_ADR50017P130CC-SCONN2A    I25 @S9S_MB_2U_LIB.S9S_MB_2U(SCH_1):PAGE100

TP_CHB_CPU1_DIMM1_FRU_5 @S9S_MB_2U_LIB.S9S_MB_2U(SCH_1):TP_CHB_CPU1_DIMM1_FRU_5
   J19  231   RFU5 SCONN288_ADR50017P130CC-SCONN2A    I25 @S9S_MB_2U_LIB.S9S_MB_2U(SCH_1):PAGE100

TP_CHB_CPU1_DIMM1_FRU_6 @S9S_MB_2U_LIB.S9S_MB_2U(SCH_1):TP_CHB_CPU1_DIMM1_FRU_6
   J19  232   RFU6 SCONN288_ADR50017P130CC-SCONN2A    I25 @S9S_MB_2U_LIB.S9S_MB_2U(SCH_1):PAGE100

TP_CHB_CPU1_DIMM2_FRU_0 @S9S_MB_2U_LIB.S9S_MB_2U(SCH_1):TP_CHB_CPU1_DIMM2_FRU_0
   J20    2   RFU0 SCONN288_ADR50017P087CC-SCONN2A    I47 @S9S_MB_2U_LIB.S9S_MB_2U(SCH_1):PAGE101

TP_CHB_CPU1_DIMM2_FRU_1 @S9S_MB_2U_LIB.S9S_MB_2U(SCH_1):TP_CHB_CPU1_DIMM2_FRU_1
   J20  144   RFU1 SCONN288_ADR50017P087CC-SCONN2A    I47 @S9S_MB_2U_LIB.S9S_MB_2U(SCH_1):PAGE101

TP_CHB_CPU1_DIMM2_FRU_2 @S9S_MB_2U_LIB.S9S_MB_2U(SCH_1):TP_CHB_CPU1_DIMM2_FRU_2
   J20  149   RFU2 SCONN288_ADR50017P087CC-SCONN2A    I47 @S9S_MB_2U_LIB.S9S_MB_2U(SCH_1):PAGE101

TP_CHB_CPU1_DIMM2_FRU_3 @S9S_MB_2U_LIB.S9S_MB_2U(SCH_1):TP_CHB_CPU1_DIMM2_FRU_3
   J20  150   RFU3 SCONN288_ADR50017P087CC-SCONN2A    I47 @S9S_MB_2U_LIB.S9S_MB_2U(SCH_1):PAGE101

TP_CHB_CPU1_DIMM2_FRU_4 @S9S_MB_2U_LIB.S9S_MB_2U(SCH_1):TP_CHB_CPU1_DIMM2_FRU_4
   J20  220   RFU4 SCONN288_ADR50017P087CC-SCONN2A    I47 @S9S_MB_2U_LIB.S9S_MB_2U(SCH_1):PAGE101

TP_CHB_CPU1_DIMM2_FRU_5 @S9S_MB_2U_LIB.S9S_MB_2U(SCH_1):TP_CHB_CPU1_DIMM2_FRU_5
   J20  231   RFU5 SCONN288_ADR50017P087CC-SCONN2A    I47 @S9S_MB_2U_LIB.S9S_MB_2U(SCH_1):PAGE101

TP_CHB_CPU1_DIMM2_FRU_6 @S9S_MB_2U_LIB.S9S_MB_2U(SCH_1):TP_CHB_CPU1_DIMM2_FRU_6
   J20  232   RFU6 SCONN288_ADR50017P087CC-SCONN2A    I47 @S9S_MB_2U_LIB.S9S_MB_2U(SCH_1):PAGE101

TP_CHC_CPU0_DIMM1_FRU_0 @S9S_MB_2U_LIB.S9S_MB_2U(SCH_1):TP_CHC_CPU0_DIMM1_FRU_0
    J5    2   RFU0 SCONN288_ADR50017P130CC-SCONN2A    I24 @S9S_MB_2U_LIB.S9S_MB_2U(SCH_1):PAGE86

TP_CHC_CPU0_DIMM1_FRU_1 @S9S_MB_2U_LIB.S9S_MB_2U(SCH_1):TP_CHC_CPU0_DIMM1_FRU_1
    J5  144   RFU1 SCONN288_ADR50017P130CC-SCONN2A    I24 @S9S_MB_2U_LIB.S9S_MB_2U(SCH_1):PAGE86

TP_CHC_CPU0_DIMM1_FRU_2 @S9S_MB_2U_LIB.S9S_MB_2U(SCH_1):TP_CHC_CPU0_DIMM1_FRU_2
    J5  149   RFU2 SCONN288_ADR50017P130CC-SCONN2A    I24 @S9S_MB_2U_LIB.S9S_MB_2U(SCH_1):PAGE86

TP_CHC_CPU0_DIMM1_FRU_3 @S9S_MB_2U_LIB.S9S_MB_2U(SCH_1):TP_CHC_CPU0_DIMM1_FRU_3
    J5  150   RFU3 SCONN288_ADR50017P130CC-SCONN2A    I24 @S9S_MB_2U_LIB.S9S_MB_2U(SCH_1):PAGE86

TP_CHC_CPU0_DIMM1_FRU_4 @S9S_MB_2U_LIB.S9S_MB_2U(SCH_1):TP_CHC_CPU0_DIMM1_FRU_4
    J5  220   RFU4 SCONN288_ADR50017P130CC-SCONN2A    I24 @S9S_MB_2U_LIB.S9S_MB_2U(SCH_1):PAGE86

TP_CHC_CPU0_DIMM1_FRU_5 @S9S_MB_2U_LIB.S9S_MB_2U(SCH_1):TP_CHC_CPU0_DIMM1_FRU_5
    J5  231   RFU5 SCONN288_ADR50017P130CC-SCONN2A    I24 @S9S_MB_2U_LIB.S9S_MB_2U(SCH_1):PAGE86

TP_CHC_CPU0_DIMM1_FRU_6 @S9S_MB_2U_LIB.S9S_MB_2U(SCH_1):TP_CHC_CPU0_DIMM1_FRU_6
    J5  232   RFU6 SCONN288_ADR50017P130CC-SCONN2A    I24 @S9S_MB_2U_LIB.S9S_MB_2U(SCH_1):PAGE86

TP_CHC_CPU0_DIMM2_FRU_0 @S9S_MB_2U_LIB.S9S_MB_2U(SCH_1):TP_CHC_CPU0_DIMM2_FRU_0
    J6    2   RFU0 SCONN288_ADR50017P087CC-SCONN2A    I46 @S9S_MB_2U_LIB.S9S_MB_2U(SCH_1):PAGE87

TP_CHC_CPU0_DIMM2_FRU_1 @S9S_MB_2U_LIB.S9S_MB_2U(SCH_1):TP_CHC_CPU0_DIMM2_FRU_1
    J6  144   RFU1 SCONN288_ADR50017P087CC-SCONN2A    I46 @S9S_MB_2U_LIB.S9S_MB_2U(SCH_1):PAGE87

TP_CHC_CPU0_DIMM2_FRU_2 @S9S_MB_2U_LIB.S9S_MB_2U(SCH_1):TP_CHC_CPU0_DIMM2_FRU_2
    J6  149   RFU2 SCONN288_ADR50017P087CC-SCONN2A    I46 @S9S_MB_2U_LIB.S9S_MB_2U(SCH_1):PAGE87

TP_CHC_CPU0_DIMM2_FRU_3 @S9S_MB_2U_LIB.S9S_MB_2U(SCH_1):TP_CHC_CPU0_DIMM2_FRU_3
    J6  150   RFU3 SCONN288_ADR50017P087CC-SCONN2A    I46 @S9S_MB_2U_LIB.S9S_MB_2U(SCH_1):PAGE87

TP_CHC_CPU0_DIMM2_FRU_4 @S9S_MB_2U_LIB.S9S_MB_2U(SCH_1):TP_CHC_CPU0_DIMM2_FRU_4
    J6  220   RFU4 SCONN288_ADR50017P087CC-SCONN2A    I46 @S9S_MB_2U_LIB.S9S_MB_2U(SCH_1):PAGE87

TP_CHC_CPU0_DIMM2_FRU_5 @S9S_MB_2U_LIB.S9S_MB_2U(SCH_1):TP_CHC_CPU0_DIMM2_FRU_5
    J6  231   RFU5 SCONN288_ADR50017P087CC-SCONN2A    I46 @S9S_MB_2U_LIB.S9S_MB_2U(SCH_1):PAGE87

TP_CHC_CPU0_DIMM2_FRU_6 @S9S_MB_2U_LIB.S9S_MB_2U(SCH_1):TP_CHC_CPU0_DIMM2_FRU_6
    J6  232   RFU6 SCONN288_ADR50017P087CC-SCONN2A    I46 @S9S_MB_2U_LIB.S9S_MB_2U(SCH_1):PAGE87

TP_CHC_CPU1_DIMM1_FRU_0 @S9S_MB_2U_LIB.S9S_MB_2U(SCH_1):TP_CHC_CPU1_DIMM1_FRU_0
   J21    2   RFU0 SCONN288_ADR50017P130CC-SCONN2A    I13 @S9S_MB_2U_LIB.S9S_MB_2U(SCH_1):PAGE102

TP_CHC_CPU1_DIMM1_FRU_1 @S9S_MB_2U_LIB.S9S_MB_2U(SCH_1):TP_CHC_CPU1_DIMM1_FRU_1
   J21  144   RFU1 SCONN288_ADR50017P130CC-SCONN2A    I13 @S9S_MB_2U_LIB.S9S_MB_2U(SCH_1):PAGE102

TP_CHC_CPU1_DIMM1_FRU_2 @S9S_MB_2U_LIB.S9S_MB_2U(SCH_1):TP_CHC_CPU1_DIMM1_FRU_2
   J21  149   RFU2 SCONN288_ADR50017P130CC-SCONN2A    I13 @S9S_MB_2U_LIB.S9S_MB_2U(SCH_1):PAGE102

TP_CHC_CPU1_DIMM1_FRU_3 @S9S_MB_2U_LIB.S9S_MB_2U(SCH_1):TP_CHC_CPU1_DIMM1_FRU_3
   J21  150   RFU3 SCONN288_ADR50017P130CC-SCONN2A    I13 @S9S_MB_2U_LIB.S9S_MB_2U(SCH_1):PAGE102

TP_CHC_CPU1_DIMM1_FRU_4 @S9S_MB_2U_LIB.S9S_MB_2U(SCH_1):TP_CHC_CPU1_DIMM1_FRU_4
   J21  220   RFU4 SCONN288_ADR50017P130CC-SCONN2A    I13 @S9S_MB_2U_LIB.S9S_MB_2U(SCH_1):PAGE102

TP_CHC_CPU1_DIMM1_FRU_5 @S9S_MB_2U_LIB.S9S_MB_2U(SCH_1):TP_CHC_CPU1_DIMM1_FRU_5
   J21  231   RFU5 SCONN288_ADR50017P130CC-SCONN2A    I13 @S9S_MB_2U_LIB.S9S_MB_2U(SCH_1):PAGE102

TP_CHC_CPU1_DIMM1_FRU_6 @S9S_MB_2U_LIB.S9S_MB_2U(SCH_1):TP_CHC_CPU1_DIMM1_FRU_6
   J21  232   RFU6 SCONN288_ADR50017P130CC-SCONN2A    I13 @S9S_MB_2U_LIB.S9S_MB_2U(SCH_1):PAGE102

TP_CHC_CPU1_DIMM2_FRU_0 @S9S_MB_2U_LIB.S9S_MB_2U(SCH_1):TP_CHC_CPU1_DIMM2_FRU_0
   J22    2   RFU0 SCONN288_ADR50017P087CC-SCONN2A    I51 @S9S_MB_2U_LIB.S9S_MB_2U(SCH_1):PAGE103

TP_CHC_CPU1_DIMM2_FRU_1 @S9S_MB_2U_LIB.S9S_MB_2U(SCH_1):TP_CHC_CPU1_DIMM2_FRU_1
   J22  144   RFU1 SCONN288_ADR50017P087CC-SCONN2A    I51 @S9S_MB_2U_LIB.S9S_MB_2U(SCH_1):PAGE103

TP_CHC_CPU1_DIMM2_FRU_2 @S9S_MB_2U_LIB.S9S_MB_2U(SCH_1):TP_CHC_CPU1_DIMM2_FRU_2
   J22  149   RFU2 SCONN288_ADR50017P087CC-SCONN2A    I51 @S9S_MB_2U_LIB.S9S_MB_2U(SCH_1):PAGE103

TP_CHC_CPU1_DIMM2_FRU_3 @S9S_MB_2U_LIB.S9S_MB_2U(SCH_1):TP_CHC_CPU1_DIMM2_FRU_3
   J22  150   RFU3 SCONN288_ADR50017P087CC-SCONN2A    I51 @S9S_MB_2U_LIB.S9S_MB_2U(SCH_1):PAGE103

TP_CHC_CPU1_DIMM2_FRU_4 @S9S_MB_2U_LIB.S9S_MB_2U(SCH_1):TP_CHC_CPU1_DIMM2_FRU_4
   J22  220   RFU4 SCONN288_ADR50017P087CC-SCONN2A    I51 @S9S_MB_2U_LIB.S9S_MB_2U(SCH_1):PAGE103

TP_CHC_CPU1_DIMM2_FRU_5 @S9S_MB_2U_LIB.S9S_MB_2U(SCH_1):TP_CHC_CPU1_DIMM2_FRU_5
   J22  231   RFU5 SCONN288_ADR50017P087CC-SCONN2A    I51 @S9S_MB_2U_LIB.S9S_MB_2U(SCH_1):PAGE103

TP_CHC_CPU1_DIMM2_FRU_6 @S9S_MB_2U_LIB.S9S_MB_2U(SCH_1):TP_CHC_CPU1_DIMM2_FRU_6
   J22  232   RFU6 SCONN288_ADR50017P087CC-SCONN2A    I51 @S9S_MB_2U_LIB.S9S_MB_2U(SCH_1):PAGE103

TP_CHD_CPU0_DIMM1_FRU_0 @S9S_MB_2U_LIB.S9S_MB_2U(SCH_1):TP_CHD_CPU0_DIMM1_FRU_0
    J7    2   RFU0 SCONN288_ADR50017P130CC-SCONN2A    I12 @S9S_MB_2U_LIB.S9S_MB_2U(SCH_1):PAGE88

TP_CHD_CPU0_DIMM1_FRU_1 @S9S_MB_2U_LIB.S9S_MB_2U(SCH_1):TP_CHD_CPU0_DIMM1_FRU_1
    J7  144   RFU1 SCONN288_ADR50017P130CC-SCONN2A    I12 @S9S_MB_2U_LIB.S9S_MB_2U(SCH_1):PAGE88

TP_CHD_CPU0_DIMM1_FRU_2 @S9S_MB_2U_LIB.S9S_MB_2U(SCH_1):TP_CHD_CPU0_DIMM1_FRU_2
    J7  149   RFU2 SCONN288_ADR50017P130CC-SCONN2A    I12 @S9S_MB_2U_LIB.S9S_MB_2U(SCH_1):PAGE88

TP_CHD_CPU0_DIMM1_FRU_3 @S9S_MB_2U_LIB.S9S_MB_2U(SCH_1):TP_CHD_CPU0_DIMM1_FRU_3
    J7  150   RFU3 SCONN288_ADR50017P130CC-SCONN2A    I12 @S9S_MB_2U_LIB.S9S_MB_2U(SCH_1):PAGE88

TP_CHD_CPU0_DIMM1_FRU_4 @S9S_MB_2U_LIB.S9S_MB_2U(SCH_1):TP_CHD_CPU0_DIMM1_FRU_4
    J7  220   RFU4 SCONN288_ADR50017P130CC-SCONN2A    I12 @S9S_MB_2U_LIB.S9S_MB_2U(SCH_1):PAGE88

TP_CHD_CPU0_DIMM1_FRU_5 @S9S_MB_2U_LIB.S9S_MB_2U(SCH_1):TP_CHD_CPU0_DIMM1_FRU_5
    J7  231   RFU5 SCONN288_ADR50017P130CC-SCONN2A    I12 @S9S_MB_2U_LIB.S9S_MB_2U(SCH_1):PAGE88

TP_CHD_CPU0_DIMM1_FRU_6 @S9S_MB_2U_LIB.S9S_MB_2U(SCH_1):TP_CHD_CPU0_DIMM1_FRU_6
    J7  232   RFU6 SCONN288_ADR50017P130CC-SCONN2A    I12 @S9S_MB_2U_LIB.S9S_MB_2U(SCH_1):PAGE88

TP_CHD_CPU0_DIMM2_FRU_0 @S9S_MB_2U_LIB.S9S_MB_2U(SCH_1):TP_CHD_CPU0_DIMM2_FRU_0
    J8    2   RFU0 SCONN288_ADR50017P087CC-SCONN2A    I50 @S9S_MB_2U_LIB.S9S_MB_2U(SCH_1):PAGE89

TP_CHD_CPU0_DIMM2_FRU_1 @S9S_MB_2U_LIB.S9S_MB_2U(SCH_1):TP_CHD_CPU0_DIMM2_FRU_1
    J8  144   RFU1 SCONN288_ADR50017P087CC-SCONN2A    I50 @S9S_MB_2U_LIB.S9S_MB_2U(SCH_1):PAGE89

TP_CHD_CPU0_DIMM2_FRU_2 @S9S_MB_2U_LIB.S9S_MB_2U(SCH_1):TP_CHD_CPU0_DIMM2_FRU_2
    J8  149   RFU2 SCONN288_ADR50017P087CC-SCONN2A    I50 @S9S_MB_2U_LIB.S9S_MB_2U(SCH_1):PAGE89

TP_CHD_CPU0_DIMM2_FRU_3 @S9S_MB_2U_LIB.S9S_MB_2U(SCH_1):TP_CHD_CPU0_DIMM2_FRU_3
    J8  150   RFU3 SCONN288_ADR50017P087CC-SCONN2A    I50 @S9S_MB_2U_LIB.S9S_MB_2U(SCH_1):PAGE89

TP_CHD_CPU0_DIMM2_FRU_4 @S9S_MB_2U_LIB.S9S_MB_2U(SCH_1):TP_CHD_CPU0_DIMM2_FRU_4
    J8  220   RFU4 SCONN288_ADR50017P087CC-SCONN2A    I50 @S9S_MB_2U_LIB.S9S_MB_2U(SCH_1):PAGE89

TP_CHD_CPU0_DIMM2_FRU_5 @S9S_MB_2U_LIB.S9S_MB_2U(SCH_1):TP_CHD_CPU0_DIMM2_FRU_5
    J8  231   RFU5 SCONN288_ADR50017P087CC-SCONN2A    I50 @S9S_MB_2U_LIB.S9S_MB_2U(SCH_1):PAGE89

TP_CHD_CPU0_DIMM2_FRU_6 @S9S_MB_2U_LIB.S9S_MB_2U(SCH_1):TP_CHD_CPU0_DIMM2_FRU_6
    J8  232   RFU6 SCONN288_ADR50017P087CC-SCONN2A    I50 @S9S_MB_2U_LIB.S9S_MB_2U(SCH_1):PAGE89

TP_CHD_CPU1_DIMM1_FRU_0 @S9S_MB_2U_LIB.S9S_MB_2U(SCH_1):TP_CHD_CPU1_DIMM1_FRU_0
   J23    2   RFU0 SCONN288_ADR50017P130CC-SCONN2A    I25 @S9S_MB_2U_LIB.S9S_MB_2U(SCH_1):PAGE104

TP_CHD_CPU1_DIMM1_FRU_1 @S9S_MB_2U_LIB.S9S_MB_2U(SCH_1):TP_CHD_CPU1_DIMM1_FRU_1
   J23  144   RFU1 SCONN288_ADR50017P130CC-SCONN2A    I25 @S9S_MB_2U_LIB.S9S_MB_2U(SCH_1):PAGE104

TP_CHD_CPU1_DIMM1_FRU_2 @S9S_MB_2U_LIB.S9S_MB_2U(SCH_1):TP_CHD_CPU1_DIMM1_FRU_2
   J23  149   RFU2 SCONN288_ADR50017P130CC-SCONN2A    I25 @S9S_MB_2U_LIB.S9S_MB_2U(SCH_1):PAGE104

TP_CHD_CPU1_DIMM1_FRU_3 @S9S_MB_2U_LIB.S9S_MB_2U(SCH_1):TP_CHD_CPU1_DIMM1_FRU_3
   J23  150   RFU3 SCONN288_ADR50017P130CC-SCONN2A    I25 @S9S_MB_2U_LIB.S9S_MB_2U(SCH_1):PAGE104

TP_CHD_CPU1_DIMM1_FRU_4 @S9S_MB_2U_LIB.S9S_MB_2U(SCH_1):TP_CHD_CPU1_DIMM1_FRU_4
   J23  220   RFU4 SCONN288_ADR50017P130CC-SCONN2A    I25 @S9S_MB_2U_LIB.S9S_MB_2U(SCH_1):PAGE104

TP_CHD_CPU1_DIMM1_FRU_5 @S9S_MB_2U_LIB.S9S_MB_2U(SCH_1):TP_CHD_CPU1_DIMM1_FRU_5
   J23  231   RFU5 SCONN288_ADR50017P130CC-SCONN2A    I25 @S9S_MB_2U_LIB.S9S_MB_2U(SCH_1):PAGE104

TP_CHD_CPU1_DIMM1_FRU_6 @S9S_MB_2U_LIB.S9S_MB_2U(SCH_1):TP_CHD_CPU1_DIMM1_FRU_6
   J23  232   RFU6 SCONN288_ADR50017P130CC-SCONN2A    I25 @S9S_MB_2U_LIB.S9S_MB_2U(SCH_1):PAGE104

TP_CHD_CPU1_DIMM2_FRU_0 @S9S_MB_2U_LIB.S9S_MB_2U(SCH_1):TP_CHD_CPU1_DIMM2_FRU_0
   J24    2   RFU0 SCONN288_ADR50017P087CC-SCONN2A   I178 @S9S_MB_2U_LIB.S9S_MB_2U(SCH_1):PAGE105

TP_CHD_CPU1_DIMM2_FRU_1 @S9S_MB_2U_LIB.S9S_MB_2U(SCH_1):TP_CHD_CPU1_DIMM2_FRU_1
   J24  144   RFU1 SCONN288_ADR50017P087CC-SCONN2A   I178 @S9S_MB_2U_LIB.S9S_MB_2U(SCH_1):PAGE105

TP_CHD_CPU1_DIMM2_FRU_2 @S9S_MB_2U_LIB.S9S_MB_2U(SCH_1):TP_CHD_CPU1_DIMM2_FRU_2
   J24  149   RFU2 SCONN288_ADR50017P087CC-SCONN2A   I178 @S9S_MB_2U_LIB.S9S_MB_2U(SCH_1):PAGE105

TP_CHD_CPU1_DIMM2_FRU_3 @S9S_MB_2U_LIB.S9S_MB_2U(SCH_1):TP_CHD_CPU1_DIMM2_FRU_3
   J24  150   RFU3 SCONN288_ADR50017P087CC-SCONN2A   I178 @S9S_MB_2U_LIB.S9S_MB_2U(SCH_1):PAGE105

TP_CHD_CPU1_DIMM2_FRU_4 @S9S_MB_2U_LIB.S9S_MB_2U(SCH_1):TP_CHD_CPU1_DIMM2_FRU_4
   J24  220   RFU4 SCONN288_ADR50017P087CC-SCONN2A   I178 @S9S_MB_2U_LIB.S9S_MB_2U(SCH_1):PAGE105

TP_CHD_CPU1_DIMM2_FRU_5 @S9S_MB_2U_LIB.S9S_MB_2U(SCH_1):TP_CHD_CPU1_DIMM2_FRU_5
   J24  231   RFU5 SCONN288_ADR50017P087CC-SCONN2A   I178 @S9S_MB_2U_LIB.S9S_MB_2U(SCH_1):PAGE105

TP_CHD_CPU1_DIMM2_FRU_6 @S9S_MB_2U_LIB.S9S_MB_2U(SCH_1):TP_CHD_CPU1_DIMM2_FRU_6
   J24  232   RFU6 SCONN288_ADR50017P087CC-SCONN2A   I178 @S9S_MB_2U_LIB.S9S_MB_2U(SCH_1):PAGE105

TP_CHE_CPU0_DIMM1_FRU_0 @S9S_MB_2U_LIB.S9S_MB_2U(SCH_1):TP_CHE_CPU0_DIMM1_FRU_0
    J9    2   RFU0 SCONN288_ADR50017P130CC-SCONN2A    I12 @S9S_MB_2U_LIB.S9S_MB_2U(SCH_1):PAGE90

TP_CHE_CPU0_DIMM1_FRU_1 @S9S_MB_2U_LIB.S9S_MB_2U(SCH_1):TP_CHE_CPU0_DIMM1_FRU_1
    J9  144   RFU1 SCONN288_ADR50017P130CC-SCONN2A    I12 @S9S_MB_2U_LIB.S9S_MB_2U(SCH_1):PAGE90

TP_CHE_CPU0_DIMM1_FRU_2 @S9S_MB_2U_LIB.S9S_MB_2U(SCH_1):TP_CHE_CPU0_DIMM1_FRU_2
    J9  149   RFU2 SCONN288_ADR50017P130CC-SCONN2A    I12 @S9S_MB_2U_LIB.S9S_MB_2U(SCH_1):PAGE90

TP_CHE_CPU0_DIMM1_FRU_3 @S9S_MB_2U_LIB.S9S_MB_2U(SCH_1):TP_CHE_CPU0_DIMM1_FRU_3
    J9  150   RFU3 SCONN288_ADR50017P130CC-SCONN2A    I12 @S9S_MB_2U_LIB.S9S_MB_2U(SCH_1):PAGE90

TP_CHE_CPU0_DIMM1_FRU_4 @S9S_MB_2U_LIB.S9S_MB_2U(SCH_1):TP_CHE_CPU0_DIMM1_FRU_4
    J9  220   RFU4 SCONN288_ADR50017P130CC-SCONN2A    I12 @S9S_MB_2U_LIB.S9S_MB_2U(SCH_1):PAGE90

TP_CHE_CPU0_DIMM1_FRU_5 @S9S_MB_2U_LIB.S9S_MB_2U(SCH_1):TP_CHE_CPU0_DIMM1_FRU_5
    J9  231   RFU5 SCONN288_ADR50017P130CC-SCONN2A    I12 @S9S_MB_2U_LIB.S9S_MB_2U(SCH_1):PAGE90

TP_CHE_CPU0_DIMM1_FRU_6 @S9S_MB_2U_LIB.S9S_MB_2U(SCH_1):TP_CHE_CPU0_DIMM1_FRU_6
    J9  232   RFU6 SCONN288_ADR50017P130CC-SCONN2A    I12 @S9S_MB_2U_LIB.S9S_MB_2U(SCH_1):PAGE90

TP_CHE_CPU0_DIMM2_FRU_0 @S9S_MB_2U_LIB.S9S_MB_2U(SCH_1):TP_CHE_CPU0_DIMM2_FRU_0
   J10    2   RFU0 SCONN288_ADR50017P087CC-SCONN2A    I13 @S9S_MB_2U_LIB.S9S_MB_2U(SCH_1):PAGE91

TP_CHE_CPU0_DIMM2_FRU_1 @S9S_MB_2U_LIB.S9S_MB_2U(SCH_1):TP_CHE_CPU0_DIMM2_FRU_1
   J10  144   RFU1 SCONN288_ADR50017P087CC-SCONN2A    I13 @S9S_MB_2U_LIB.S9S_MB_2U(SCH_1):PAGE91

TP_CHE_CPU0_DIMM2_FRU_2 @S9S_MB_2U_LIB.S9S_MB_2U(SCH_1):TP_CHE_CPU0_DIMM2_FRU_2
   J10  149   RFU2 SCONN288_ADR50017P087CC-SCONN2A    I13 @S9S_MB_2U_LIB.S9S_MB_2U(SCH_1):PAGE91

TP_CHE_CPU0_DIMM2_FRU_3 @S9S_MB_2U_LIB.S9S_MB_2U(SCH_1):TP_CHE_CPU0_DIMM2_FRU_3
   J10  150   RFU3 SCONN288_ADR50017P087CC-SCONN2A    I13 @S9S_MB_2U_LIB.S9S_MB_2U(SCH_1):PAGE91

TP_CHE_CPU0_DIMM2_FRU_4 @S9S_MB_2U_LIB.S9S_MB_2U(SCH_1):TP_CHE_CPU0_DIMM2_FRU_4
   J10  220   RFU4 SCONN288_ADR50017P087CC-SCONN2A    I13 @S9S_MB_2U_LIB.S9S_MB_2U(SCH_1):PAGE91

TP_CHE_CPU0_DIMM2_FRU_5 @S9S_MB_2U_LIB.S9S_MB_2U(SCH_1):TP_CHE_CPU0_DIMM2_FRU_5
   J10  231   RFU5 SCONN288_ADR50017P087CC-SCONN2A    I13 @S9S_MB_2U_LIB.S9S_MB_2U(SCH_1):PAGE91

TP_CHE_CPU0_DIMM2_FRU_6 @S9S_MB_2U_LIB.S9S_MB_2U(SCH_1):TP_CHE_CPU0_DIMM2_FRU_6
   J10  232   RFU6 SCONN288_ADR50017P087CC-SCONN2A    I13 @S9S_MB_2U_LIB.S9S_MB_2U(SCH_1):PAGE91

TP_CHE_CPU1_DIMM1_FRU_0 @S9S_MB_2U_LIB.S9S_MB_2U(SCH_1):TP_CHE_CPU1_DIMM1_FRU_0
   J25    2   RFU0 SCONN288_ADR50017P130CC-SCONN2A   I180 @S9S_MB_2U_LIB.S9S_MB_2U(SCH_1):PAGE106

TP_CHE_CPU1_DIMM1_FRU_1 @S9S_MB_2U_LIB.S9S_MB_2U(SCH_1):TP_CHE_CPU1_DIMM1_FRU_1
   J25  144   RFU1 SCONN288_ADR50017P130CC-SCONN2A   I180 @S9S_MB_2U_LIB.S9S_MB_2U(SCH_1):PAGE106

TP_CHE_CPU1_DIMM1_FRU_2 @S9S_MB_2U_LIB.S9S_MB_2U(SCH_1):TP_CHE_CPU1_DIMM1_FRU_2
   J25  149   RFU2 SCONN288_ADR50017P130CC-SCONN2A   I180 @S9S_MB_2U_LIB.S9S_MB_2U(SCH_1):PAGE106

TP_CHE_CPU1_DIMM1_FRU_3 @S9S_MB_2U_LIB.S9S_MB_2U(SCH_1):TP_CHE_CPU1_DIMM1_FRU_3
   J25  150   RFU3 SCONN288_ADR50017P130CC-SCONN2A   I180 @S9S_MB_2U_LIB.S9S_MB_2U(SCH_1):PAGE106

TP_CHE_CPU1_DIMM1_FRU_4 @S9S_MB_2U_LIB.S9S_MB_2U(SCH_1):TP_CHE_CPU1_DIMM1_FRU_4
   J25  220   RFU4 SCONN288_ADR50017P130CC-SCONN2A   I180 @S9S_MB_2U_LIB.S9S_MB_2U(SCH_1):PAGE106

TP_CHE_CPU1_DIMM1_FRU_5 @S9S_MB_2U_LIB.S9S_MB_2U(SCH_1):TP_CHE_CPU1_DIMM1_FRU_5
   J25  231   RFU5 SCONN288_ADR50017P130CC-SCONN2A   I180 @S9S_MB_2U_LIB.S9S_MB_2U(SCH_1):PAGE106

TP_CHE_CPU1_DIMM1_FRU_6 @S9S_MB_2U_LIB.S9S_MB_2U(SCH_1):TP_CHE_CPU1_DIMM1_FRU_6
   J25  232   RFU6 SCONN288_ADR50017P130CC-SCONN2A   I180 @S9S_MB_2U_LIB.S9S_MB_2U(SCH_1):PAGE106

TP_CHE_CPU1_DIMM2_FRU_0 @S9S_MB_2U_LIB.S9S_MB_2U(SCH_1):TP_CHE_CPU1_DIMM2_FRU_0
   J26    2   RFU0 SCONN288_ADR50017P087CC-SCONN2A   I180 @S9S_MB_2U_LIB.S9S_MB_2U(SCH_1):PAGE107

TP_CHE_CPU1_DIMM2_FRU_1 @S9S_MB_2U_LIB.S9S_MB_2U(SCH_1):TP_CHE_CPU1_DIMM2_FRU_1
   J26  144   RFU1 SCONN288_ADR50017P087CC-SCONN2A   I180 @S9S_MB_2U_LIB.S9S_MB_2U(SCH_1):PAGE107

TP_CHE_CPU1_DIMM2_FRU_2 @S9S_MB_2U_LIB.S9S_MB_2U(SCH_1):TP_CHE_CPU1_DIMM2_FRU_2
   J26  149   RFU2 SCONN288_ADR50017P087CC-SCONN2A   I180 @S9S_MB_2U_LIB.S9S_MB_2U(SCH_1):PAGE107

TP_CHE_CPU1_DIMM2_FRU_3 @S9S_MB_2U_LIB.S9S_MB_2U(SCH_1):TP_CHE_CPU1_DIMM2_FRU_3
   J26  150   RFU3 SCONN288_ADR50017P087CC-SCONN2A   I180 @S9S_MB_2U_LIB.S9S_MB_2U(SCH_1):PAGE107

TP_CHE_CPU1_DIMM2_FRU_4 @S9S_MB_2U_LIB.S9S_MB_2U(SCH_1):TP_CHE_CPU1_DIMM2_FRU_4
   J26  220   RFU4 SCONN288_ADR50017P087CC-SCONN2A   I180 @S9S_MB_2U_LIB.S9S_MB_2U(SCH_1):PAGE107

TP_CHE_CPU1_DIMM2_FRU_5 @S9S_MB_2U_LIB.S9S_MB_2U(SCH_1):TP_CHE_CPU1_DIMM2_FRU_5
   J26  231   RFU5 SCONN288_ADR50017P087CC-SCONN2A   I180 @S9S_MB_2U_LIB.S9S_MB_2U(SCH_1):PAGE107

TP_CHE_CPU1_DIMM2_FRU_6 @S9S_MB_2U_LIB.S9S_MB_2U(SCH_1):TP_CHE_CPU1_DIMM2_FRU_6
   J26  232   RFU6 SCONN288_ADR50017P087CC-SCONN2A   I180 @S9S_MB_2U_LIB.S9S_MB_2U(SCH_1):PAGE107

TP_CHF_CPU0_DIMM1_FRU_0 @S9S_MB_2U_LIB.S9S_MB_2U(SCH_1):TP_CHF_CPU0_DIMM1_FRU_0
   J11    2   RFU0 SCONN288_ADR50017P130CC-SCONN2A    I25 @S9S_MB_2U_LIB.S9S_MB_2U(SCH_1):PAGE92

TP_CHF_CPU0_DIMM1_FRU_1 @S9S_MB_2U_LIB.S9S_MB_2U(SCH_1):TP_CHF_CPU0_DIMM1_FRU_1
   J11  144   RFU1 SCONN288_ADR50017P130CC-SCONN2A    I25 @S9S_MB_2U_LIB.S9S_MB_2U(SCH_1):PAGE92

TP_CHF_CPU0_DIMM1_FRU_2 @S9S_MB_2U_LIB.S9S_MB_2U(SCH_1):TP_CHF_CPU0_DIMM1_FRU_2
   J11  149   RFU2 SCONN288_ADR50017P130CC-SCONN2A    I25 @S9S_MB_2U_LIB.S9S_MB_2U(SCH_1):PAGE92

TP_CHF_CPU0_DIMM1_FRU_3 @S9S_MB_2U_LIB.S9S_MB_2U(SCH_1):TP_CHF_CPU0_DIMM1_FRU_3
   J11  150   RFU3 SCONN288_ADR50017P130CC-SCONN2A    I25 @S9S_MB_2U_LIB.S9S_MB_2U(SCH_1):PAGE92

TP_CHF_CPU0_DIMM1_FRU_4 @S9S_MB_2U_LIB.S9S_MB_2U(SCH_1):TP_CHF_CPU0_DIMM1_FRU_4
   J11  220   RFU4 SCONN288_ADR50017P130CC-SCONN2A    I25 @S9S_MB_2U_LIB.S9S_MB_2U(SCH_1):PAGE92

TP_CHF_CPU0_DIMM1_FRU_5 @S9S_MB_2U_LIB.S9S_MB_2U(SCH_1):TP_CHF_CPU0_DIMM1_FRU_5
   J11  231   RFU5 SCONN288_ADR50017P130CC-SCONN2A    I25 @S9S_MB_2U_LIB.S9S_MB_2U(SCH_1):PAGE92

TP_CHF_CPU0_DIMM1_FRU_6 @S9S_MB_2U_LIB.S9S_MB_2U(SCH_1):TP_CHF_CPU0_DIMM1_FRU_6
   J11  232   RFU6 SCONN288_ADR50017P130CC-SCONN2A    I25 @S9S_MB_2U_LIB.S9S_MB_2U(SCH_1):PAGE92

TP_CHF_CPU0_DIMM2_FRU_0 @S9S_MB_2U_LIB.S9S_MB_2U(SCH_1):TP_CHF_CPU0_DIMM2_FRU_0
   J12    2   RFU0 SCONN288_ADR50017P087CC-SCONN2A    I24 @S9S_MB_2U_LIB.S9S_MB_2U(SCH_1):PAGE93

TP_CHF_CPU0_DIMM2_FRU_1 @S9S_MB_2U_LIB.S9S_MB_2U(SCH_1):TP_CHF_CPU0_DIMM2_FRU_1
   J12  144   RFU1 SCONN288_ADR50017P087CC-SCONN2A    I24 @S9S_MB_2U_LIB.S9S_MB_2U(SCH_1):PAGE93

TP_CHF_CPU0_DIMM2_FRU_2 @S9S_MB_2U_LIB.S9S_MB_2U(SCH_1):TP_CHF_CPU0_DIMM2_FRU_2
   J12  149   RFU2 SCONN288_ADR50017P087CC-SCONN2A    I24 @S9S_MB_2U_LIB.S9S_MB_2U(SCH_1):PAGE93

TP_CHF_CPU0_DIMM2_FRU_3 @S9S_MB_2U_LIB.S9S_MB_2U(SCH_1):TP_CHF_CPU0_DIMM2_FRU_3
   J12  150   RFU3 SCONN288_ADR50017P087CC-SCONN2A    I24 @S9S_MB_2U_LIB.S9S_MB_2U(SCH_1):PAGE93

TP_CHF_CPU0_DIMM2_FRU_4 @S9S_MB_2U_LIB.S9S_MB_2U(SCH_1):TP_CHF_CPU0_DIMM2_FRU_4
   J12  220   RFU4 SCONN288_ADR50017P087CC-SCONN2A    I24 @S9S_MB_2U_LIB.S9S_MB_2U(SCH_1):PAGE93

TP_CHF_CPU0_DIMM2_FRU_5 @S9S_MB_2U_LIB.S9S_MB_2U(SCH_1):TP_CHF_CPU0_DIMM2_FRU_5
   J12  231   RFU5 SCONN288_ADR50017P087CC-SCONN2A    I24 @S9S_MB_2U_LIB.S9S_MB_2U(SCH_1):PAGE93

TP_CHF_CPU0_DIMM2_FRU_6 @S9S_MB_2U_LIB.S9S_MB_2U(SCH_1):TP_CHF_CPU0_DIMM2_FRU_6
   J12  232   RFU6 SCONN288_ADR50017P087CC-SCONN2A    I24 @S9S_MB_2U_LIB.S9S_MB_2U(SCH_1):PAGE93

TP_CHF_CPU1_DIMM1_FRU_0 @S9S_MB_2U_LIB.S9S_MB_2U(SCH_1):TP_CHF_CPU1_DIMM1_FRU_0
   J27    2   RFU0 SCONN288_ADR50017P130CC-SCONN2A   I179 @S9S_MB_2U_LIB.S9S_MB_2U(SCH_1):PAGE108

TP_CHF_CPU1_DIMM1_FRU_1 @S9S_MB_2U_LIB.S9S_MB_2U(SCH_1):TP_CHF_CPU1_DIMM1_FRU_1
   J27  144   RFU1 SCONN288_ADR50017P130CC-SCONN2A   I179 @S9S_MB_2U_LIB.S9S_MB_2U(SCH_1):PAGE108

TP_CHF_CPU1_DIMM1_FRU_2 @S9S_MB_2U_LIB.S9S_MB_2U(SCH_1):TP_CHF_CPU1_DIMM1_FRU_2
   J27  149   RFU2 SCONN288_ADR50017P130CC-SCONN2A   I179 @S9S_MB_2U_LIB.S9S_MB_2U(SCH_1):PAGE108

TP_CHF_CPU1_DIMM1_FRU_3 @S9S_MB_2U_LIB.S9S_MB_2U(SCH_1):TP_CHF_CPU1_DIMM1_FRU_3
   J27  150   RFU3 SCONN288_ADR50017P130CC-SCONN2A   I179 @S9S_MB_2U_LIB.S9S_MB_2U(SCH_1):PAGE108

TP_CHF_CPU1_DIMM1_FRU_4 @S9S_MB_2U_LIB.S9S_MB_2U(SCH_1):TP_CHF_CPU1_DIMM1_FRU_4
   J27  220   RFU4 SCONN288_ADR50017P130CC-SCONN2A   I179 @S9S_MB_2U_LIB.S9S_MB_2U(SCH_1):PAGE108

TP_CHF_CPU1_DIMM1_FRU_5 @S9S_MB_2U_LIB.S9S_MB_2U(SCH_1):TP_CHF_CPU1_DIMM1_FRU_5
   J27  231   RFU5 SCONN288_ADR50017P130CC-SCONN2A   I179 @S9S_MB_2U_LIB.S9S_MB_2U(SCH_1):PAGE108

TP_CHF_CPU1_DIMM1_FRU_6 @S9S_MB_2U_LIB.S9S_MB_2U(SCH_1):TP_CHF_CPU1_DIMM1_FRU_6
   J27  232   RFU6 SCONN288_ADR50017P130CC-SCONN2A   I179 @S9S_MB_2U_LIB.S9S_MB_2U(SCH_1):PAGE108

TP_CHF_CPU1_DIMM2_FRU_0 @S9S_MB_2U_LIB.S9S_MB_2U(SCH_1):TP_CHF_CPU1_DIMM2_FRU_0
   J28    2   RFU0 SCONN288_ADR50017P087CC-SCONN2A    I47 @S9S_MB_2U_LIB.S9S_MB_2U(SCH_1):PAGE109

TP_CHF_CPU1_DIMM2_FRU_1 @S9S_MB_2U_LIB.S9S_MB_2U(SCH_1):TP_CHF_CPU1_DIMM2_FRU_1
   J28  144   RFU1 SCONN288_ADR50017P087CC-SCONN2A    I47 @S9S_MB_2U_LIB.S9S_MB_2U(SCH_1):PAGE109

TP_CHF_CPU1_DIMM2_FRU_2 @S9S_MB_2U_LIB.S9S_MB_2U(SCH_1):TP_CHF_CPU1_DIMM2_FRU_2
   J28  149   RFU2 SCONN288_ADR50017P087CC-SCONN2A    I47 @S9S_MB_2U_LIB.S9S_MB_2U(SCH_1):PAGE109

TP_CHF_CPU1_DIMM2_FRU_3 @S9S_MB_2U_LIB.S9S_MB_2U(SCH_1):TP_CHF_CPU1_DIMM2_FRU_3
   J28  150   RFU3 SCONN288_ADR50017P087CC-SCONN2A    I47 @S9S_MB_2U_LIB.S9S_MB_2U(SCH_1):PAGE109

TP_CHF_CPU1_DIMM2_FRU_4 @S9S_MB_2U_LIB.S9S_MB_2U(SCH_1):TP_CHF_CPU1_DIMM2_FRU_4
   J28  220   RFU4 SCONN288_ADR50017P087CC-SCONN2A    I47 @S9S_MB_2U_LIB.S9S_MB_2U(SCH_1):PAGE109

TP_CHF_CPU1_DIMM2_FRU_5 @S9S_MB_2U_LIB.S9S_MB_2U(SCH_1):TP_CHF_CPU1_DIMM2_FRU_5
   J28  231   RFU5 SCONN288_ADR50017P087CC-SCONN2A    I47 @S9S_MB_2U_LIB.S9S_MB_2U(SCH_1):PAGE109

TP_CHF_CPU1_DIMM2_FRU_6 @S9S_MB_2U_LIB.S9S_MB_2U(SCH_1):TP_CHF_CPU1_DIMM2_FRU_6
   J28  232   RFU6 SCONN288_ADR50017P087CC-SCONN2A    I47 @S9S_MB_2U_LIB.S9S_MB_2U(SCH_1):PAGE109

TP_CHG_CPU0_DIMM1_FRU_0 @S9S_MB_2U_LIB.S9S_MB_2U(SCH_1):TP_CHG_CPU0_DIMM1_FRU_0
   J13    2   RFU0 SCONN288_ADR50017P130CC-SCONN2A    I11 @S9S_MB_2U_LIB.S9S_MB_2U(SCH_1):PAGE94

TP_CHG_CPU0_DIMM1_FRU_1 @S9S_MB_2U_LIB.S9S_MB_2U(SCH_1):TP_CHG_CPU0_DIMM1_FRU_1
   J13  144   RFU1 SCONN288_ADR50017P130CC-SCONN2A    I11 @S9S_MB_2U_LIB.S9S_MB_2U(SCH_1):PAGE94

TP_CHG_CPU0_DIMM1_FRU_2 @S9S_MB_2U_LIB.S9S_MB_2U(SCH_1):TP_CHG_CPU0_DIMM1_FRU_2
   J13  149   RFU2 SCONN288_ADR50017P130CC-SCONN2A    I11 @S9S_MB_2U_LIB.S9S_MB_2U(SCH_1):PAGE94

TP_CHG_CPU0_DIMM1_FRU_3 @S9S_MB_2U_LIB.S9S_MB_2U(SCH_1):TP_CHG_CPU0_DIMM1_FRU_3
   J13  150   RFU3 SCONN288_ADR50017P130CC-SCONN2A    I11 @S9S_MB_2U_LIB.S9S_MB_2U(SCH_1):PAGE94

TP_CHG_CPU0_DIMM1_FRU_4 @S9S_MB_2U_LIB.S9S_MB_2U(SCH_1):TP_CHG_CPU0_DIMM1_FRU_4
   J13  220   RFU4 SCONN288_ADR50017P130CC-SCONN2A    I11 @S9S_MB_2U_LIB.S9S_MB_2U(SCH_1):PAGE94

TP_CHG_CPU0_DIMM1_FRU_5 @S9S_MB_2U_LIB.S9S_MB_2U(SCH_1):TP_CHG_CPU0_DIMM1_FRU_5
   J13  231   RFU5 SCONN288_ADR50017P130CC-SCONN2A    I11 @S9S_MB_2U_LIB.S9S_MB_2U(SCH_1):PAGE94

TP_CHG_CPU0_DIMM1_FRU_6 @S9S_MB_2U_LIB.S9S_MB_2U(SCH_1):TP_CHG_CPU0_DIMM1_FRU_6
   J13  232   RFU6 SCONN288_ADR50017P130CC-SCONN2A    I11 @S9S_MB_2U_LIB.S9S_MB_2U(SCH_1):PAGE94

TP_CHG_CPU0_DIMM2_FRU_0 @S9S_MB_2U_LIB.S9S_MB_2U(SCH_1):TP_CHG_CPU0_DIMM2_FRU_0
   J14    2   RFU0 SCONN288_ADR50017P087CC-SCONN2A    I47 @S9S_MB_2U_LIB.S9S_MB_2U(SCH_1):PAGE95

TP_CHG_CPU0_DIMM2_FRU_1 @S9S_MB_2U_LIB.S9S_MB_2U(SCH_1):TP_CHG_CPU0_DIMM2_FRU_1
   J14  144   RFU1 SCONN288_ADR50017P087CC-SCONN2A    I47 @S9S_MB_2U_LIB.S9S_MB_2U(SCH_1):PAGE95

TP_CHG_CPU0_DIMM2_FRU_2 @S9S_MB_2U_LIB.S9S_MB_2U(SCH_1):TP_CHG_CPU0_DIMM2_FRU_2
   J14  149   RFU2 SCONN288_ADR50017P087CC-SCONN2A    I47 @S9S_MB_2U_LIB.S9S_MB_2U(SCH_1):PAGE95

TP_CHG_CPU0_DIMM2_FRU_3 @S9S_MB_2U_LIB.S9S_MB_2U(SCH_1):TP_CHG_CPU0_DIMM2_FRU_3
   J14  150   RFU3 SCONN288_ADR50017P087CC-SCONN2A    I47 @S9S_MB_2U_LIB.S9S_MB_2U(SCH_1):PAGE95

TP_CHG_CPU0_DIMM2_FRU_4 @S9S_MB_2U_LIB.S9S_MB_2U(SCH_1):TP_CHG_CPU0_DIMM2_FRU_4
   J14  220   RFU4 SCONN288_ADR50017P087CC-SCONN2A    I47 @S9S_MB_2U_LIB.S9S_MB_2U(SCH_1):PAGE95

TP_CHG_CPU0_DIMM2_FRU_5 @S9S_MB_2U_LIB.S9S_MB_2U(SCH_1):TP_CHG_CPU0_DIMM2_FRU_5
   J14  231   RFU5 SCONN288_ADR50017P087CC-SCONN2A    I47 @S9S_MB_2U_LIB.S9S_MB_2U(SCH_1):PAGE95

TP_CHG_CPU0_DIMM2_FRU_6 @S9S_MB_2U_LIB.S9S_MB_2U(SCH_1):TP_CHG_CPU0_DIMM2_FRU_6
   J14  232   RFU6 SCONN288_ADR50017P087CC-SCONN2A    I47 @S9S_MB_2U_LIB.S9S_MB_2U(SCH_1):PAGE95

TP_CHG_CPU1_DIMM1_FRU_0 @S9S_MB_2U_LIB.S9S_MB_2U(SCH_1):TP_CHG_CPU1_DIMM1_FRU_0
   J29    2   RFU0 SCONN288_ADR50017P130CC-SCONN2A   I179 @S9S_MB_2U_LIB.S9S_MB_2U(SCH_1):PAGE110

TP_CHG_CPU1_DIMM1_FRU_1 @S9S_MB_2U_LIB.S9S_MB_2U(SCH_1):TP_CHG_CPU1_DIMM1_FRU_1
   J29  144   RFU1 SCONN288_ADR50017P130CC-SCONN2A   I179 @S9S_MB_2U_LIB.S9S_MB_2U(SCH_1):PAGE110

TP_CHG_CPU1_DIMM1_FRU_2 @S9S_MB_2U_LIB.S9S_MB_2U(SCH_1):TP_CHG_CPU1_DIMM1_FRU_2
   J29  149   RFU2 SCONN288_ADR50017P130CC-SCONN2A   I179 @S9S_MB_2U_LIB.S9S_MB_2U(SCH_1):PAGE110

TP_CHG_CPU1_DIMM1_FRU_3 @S9S_MB_2U_LIB.S9S_MB_2U(SCH_1):TP_CHG_CPU1_DIMM1_FRU_3
   J29  150   RFU3 SCONN288_ADR50017P130CC-SCONN2A   I179 @S9S_MB_2U_LIB.S9S_MB_2U(SCH_1):PAGE110

TP_CHG_CPU1_DIMM1_FRU_4 @S9S_MB_2U_LIB.S9S_MB_2U(SCH_1):TP_CHG_CPU1_DIMM1_FRU_4
   J29  220   RFU4 SCONN288_ADR50017P130CC-SCONN2A   I179 @S9S_MB_2U_LIB.S9S_MB_2U(SCH_1):PAGE110

TP_CHG_CPU1_DIMM1_FRU_5 @S9S_MB_2U_LIB.S9S_MB_2U(SCH_1):TP_CHG_CPU1_DIMM1_FRU_5
   J29  231   RFU5 SCONN288_ADR50017P130CC-SCONN2A   I179 @S9S_MB_2U_LIB.S9S_MB_2U(SCH_1):PAGE110

TP_CHG_CPU1_DIMM1_FRU_6 @S9S_MB_2U_LIB.S9S_MB_2U(SCH_1):TP_CHG_CPU1_DIMM1_FRU_6
   J29  232   RFU6 SCONN288_ADR50017P130CC-SCONN2A   I179 @S9S_MB_2U_LIB.S9S_MB_2U(SCH_1):PAGE110

TP_CHG_CPU1_DIMM2_FRU_0 @S9S_MB_2U_LIB.S9S_MB_2U(SCH_1):TP_CHG_CPU1_DIMM2_FRU_0
   J30    2   RFU0 SCONN288_ADR50017P087CC-SCONN2A   I179 @S9S_MB_2U_LIB.S9S_MB_2U(SCH_1):PAGE111

TP_CHG_CPU1_DIMM2_FRU_1 @S9S_MB_2U_LIB.S9S_MB_2U(SCH_1):TP_CHG_CPU1_DIMM2_FRU_1
   J30  144   RFU1 SCONN288_ADR50017P087CC-SCONN2A   I179 @S9S_MB_2U_LIB.S9S_MB_2U(SCH_1):PAGE111

TP_CHG_CPU1_DIMM2_FRU_2 @S9S_MB_2U_LIB.S9S_MB_2U(SCH_1):TP_CHG_CPU1_DIMM2_FRU_2
   J30  149   RFU2 SCONN288_ADR50017P087CC-SCONN2A   I179 @S9S_MB_2U_LIB.S9S_MB_2U(SCH_1):PAGE111

TP_CHG_CPU1_DIMM2_FRU_3 @S9S_MB_2U_LIB.S9S_MB_2U(SCH_1):TP_CHG_CPU1_DIMM2_FRU_3
   J30  150   RFU3 SCONN288_ADR50017P087CC-SCONN2A   I179 @S9S_MB_2U_LIB.S9S_MB_2U(SCH_1):PAGE111

TP_CHG_CPU1_DIMM2_FRU_4 @S9S_MB_2U_LIB.S9S_MB_2U(SCH_1):TP_CHG_CPU1_DIMM2_FRU_4
   J30  220   RFU4 SCONN288_ADR50017P087CC-SCONN2A   I179 @S9S_MB_2U_LIB.S9S_MB_2U(SCH_1):PAGE111

TP_CHG_CPU1_DIMM2_FRU_5 @S9S_MB_2U_LIB.S9S_MB_2U(SCH_1):TP_CHG_CPU1_DIMM2_FRU_5
   J30  231   RFU5 SCONN288_ADR50017P087CC-SCONN2A   I179 @S9S_MB_2U_LIB.S9S_MB_2U(SCH_1):PAGE111

TP_CHG_CPU1_DIMM2_FRU_6 @S9S_MB_2U_LIB.S9S_MB_2U(SCH_1):TP_CHG_CPU1_DIMM2_FRU_6
   J30  232   RFU6 SCONN288_ADR50017P087CC-SCONN2A   I179 @S9S_MB_2U_LIB.S9S_MB_2U(SCH_1):PAGE111

TP_CHH_CPU0_DIMM1_FRU_0 @S9S_MB_2U_LIB.S9S_MB_2U(SCH_1):TP_CHH_CPU0_DIMM1_FRU_0
   J15    2   RFU0 SCONN288_ADR50017P130CC-SCONN2A    I48 @S9S_MB_2U_LIB.S9S_MB_2U(SCH_1):PAGE96

TP_CHH_CPU0_DIMM1_FRU_1 @S9S_MB_2U_LIB.S9S_MB_2U(SCH_1):TP_CHH_CPU0_DIMM1_FRU_1
   J15  144   RFU1 SCONN288_ADR50017P130CC-SCONN2A    I48 @S9S_MB_2U_LIB.S9S_MB_2U(SCH_1):PAGE96

TP_CHH_CPU0_DIMM1_FRU_2 @S9S_MB_2U_LIB.S9S_MB_2U(SCH_1):TP_CHH_CPU0_DIMM1_FRU_2
   J15  149   RFU2 SCONN288_ADR50017P130CC-SCONN2A    I48 @S9S_MB_2U_LIB.S9S_MB_2U(SCH_1):PAGE96

TP_CHH_CPU0_DIMM1_FRU_3 @S9S_MB_2U_LIB.S9S_MB_2U(SCH_1):TP_CHH_CPU0_DIMM1_FRU_3
   J15  150   RFU3 SCONN288_ADR50017P130CC-SCONN2A    I48 @S9S_MB_2U_LIB.S9S_MB_2U(SCH_1):PAGE96

TP_CHH_CPU0_DIMM1_FRU_4 @S9S_MB_2U_LIB.S9S_MB_2U(SCH_1):TP_CHH_CPU0_DIMM1_FRU_4
   J15  220   RFU4 SCONN288_ADR50017P130CC-SCONN2A    I48 @S9S_MB_2U_LIB.S9S_MB_2U(SCH_1):PAGE96

TP_CHH_CPU0_DIMM1_FRU_5 @S9S_MB_2U_LIB.S9S_MB_2U(SCH_1):TP_CHH_CPU0_DIMM1_FRU_5
   J15  231   RFU5 SCONN288_ADR50017P130CC-SCONN2A    I48 @S9S_MB_2U_LIB.S9S_MB_2U(SCH_1):PAGE96

TP_CHH_CPU0_DIMM1_FRU_6 @S9S_MB_2U_LIB.S9S_MB_2U(SCH_1):TP_CHH_CPU0_DIMM1_FRU_6
   J15  232   RFU6 SCONN288_ADR50017P130CC-SCONN2A    I48 @S9S_MB_2U_LIB.S9S_MB_2U(SCH_1):PAGE96

TP_CHH_CPU0_DIMM2_FRU_0 @S9S_MB_2U_LIB.S9S_MB_2U(SCH_1):TP_CHH_CPU0_DIMM2_FRU_0
   J16    2   RFU0 SCONN288_ADR50017P087CC-SCONN2A     I6 @S9S_MB_2U_LIB.S9S_MB_2U(SCH_1):PAGE97

TP_CHH_CPU0_DIMM2_FRU_1 @S9S_MB_2U_LIB.S9S_MB_2U(SCH_1):TP_CHH_CPU0_DIMM2_FRU_1
   J16  144   RFU1 SCONN288_ADR50017P087CC-SCONN2A     I6 @S9S_MB_2U_LIB.S9S_MB_2U(SCH_1):PAGE97

TP_CHH_CPU0_DIMM2_FRU_2 @S9S_MB_2U_LIB.S9S_MB_2U(SCH_1):TP_CHH_CPU0_DIMM2_FRU_2
   J16  149   RFU2 SCONN288_ADR50017P087CC-SCONN2A     I6 @S9S_MB_2U_LIB.S9S_MB_2U(SCH_1):PAGE97

TP_CHH_CPU0_DIMM2_FRU_3 @S9S_MB_2U_LIB.S9S_MB_2U(SCH_1):TP_CHH_CPU0_DIMM2_FRU_3
   J16  150   RFU3 SCONN288_ADR50017P087CC-SCONN2A     I6 @S9S_MB_2U_LIB.S9S_MB_2U(SCH_1):PAGE97

TP_CHH_CPU0_DIMM2_FRU_4 @S9S_MB_2U_LIB.S9S_MB_2U(SCH_1):TP_CHH_CPU0_DIMM2_FRU_4
   J16  220   RFU4 SCONN288_ADR50017P087CC-SCONN2A     I6 @S9S_MB_2U_LIB.S9S_MB_2U(SCH_1):PAGE97

TP_CHH_CPU0_DIMM2_FRU_5 @S9S_MB_2U_LIB.S9S_MB_2U(SCH_1):TP_CHH_CPU0_DIMM2_FRU_5
   J16  231   RFU5 SCONN288_ADR50017P087CC-SCONN2A     I6 @S9S_MB_2U_LIB.S9S_MB_2U(SCH_1):PAGE97

TP_CHH_CPU0_DIMM2_FRU_6 @S9S_MB_2U_LIB.S9S_MB_2U(SCH_1):TP_CHH_CPU0_DIMM2_FRU_6
   J16  232   RFU6 SCONN288_ADR50017P087CC-SCONN2A     I6 @S9S_MB_2U_LIB.S9S_MB_2U(SCH_1):PAGE97

TP_CHH_CPU1_DIMM1_FRU_0 @S9S_MB_2U_LIB.S9S_MB_2U(SCH_1):TP_CHH_CPU1_DIMM1_FRU_0
   J31    2   RFU0 SCONN288_ADR50017P130CC-SCONN2A   I180 @S9S_MB_2U_LIB.S9S_MB_2U(SCH_1):PAGE112

TP_CHH_CPU1_DIMM1_FRU_1 @S9S_MB_2U_LIB.S9S_MB_2U(SCH_1):TP_CHH_CPU1_DIMM1_FRU_1
   J31  144   RFU1 SCONN288_ADR50017P130CC-SCONN2A   I180 @S9S_MB_2U_LIB.S9S_MB_2U(SCH_1):PAGE112

TP_CHH_CPU1_DIMM1_FRU_2 @S9S_MB_2U_LIB.S9S_MB_2U(SCH_1):TP_CHH_CPU1_DIMM1_FRU_2
   J31  149   RFU2 SCONN288_ADR50017P130CC-SCONN2A   I180 @S9S_MB_2U_LIB.S9S_MB_2U(SCH_1):PAGE112

TP_CHH_CPU1_DIMM1_FRU_3 @S9S_MB_2U_LIB.S9S_MB_2U(SCH_1):TP_CHH_CPU1_DIMM1_FRU_3
   J31  150   RFU3 SCONN288_ADR50017P130CC-SCONN2A   I180 @S9S_MB_2U_LIB.S9S_MB_2U(SCH_1):PAGE112

TP_CHH_CPU1_DIMM1_FRU_4 @S9S_MB_2U_LIB.S9S_MB_2U(SCH_1):TP_CHH_CPU1_DIMM1_FRU_4
   J31  220   RFU4 SCONN288_ADR50017P130CC-SCONN2A   I180 @S9S_MB_2U_LIB.S9S_MB_2U(SCH_1):PAGE112

TP_CHH_CPU1_DIMM1_FRU_5 @S9S_MB_2U_LIB.S9S_MB_2U(SCH_1):TP_CHH_CPU1_DIMM1_FRU_5
   J31  231   RFU5 SCONN288_ADR50017P130CC-SCONN2A   I180 @S9S_MB_2U_LIB.S9S_MB_2U(SCH_1):PAGE112

TP_CHH_CPU1_DIMM1_FRU_6 @S9S_MB_2U_LIB.S9S_MB_2U(SCH_1):TP_CHH_CPU1_DIMM1_FRU_6
   J31  232   RFU6 SCONN288_ADR50017P130CC-SCONN2A   I180 @S9S_MB_2U_LIB.S9S_MB_2U(SCH_1):PAGE112

TP_CHH_CPU1_DIMM2_FRU_0 @S9S_MB_2U_LIB.S9S_MB_2U(SCH_1):TP_CHH_CPU1_DIMM2_FRU_0
   J32    2   RFU0 SCONN288_ADR50017P087CC-SCONN2A   I179 @S9S_MB_2U_LIB.S9S_MB_2U(SCH_1):PAGE113

TP_CHH_CPU1_DIMM2_FRU_1 @S9S_MB_2U_LIB.S9S_MB_2U(SCH_1):TP_CHH_CPU1_DIMM2_FRU_1
   J32  144   RFU1 SCONN288_ADR50017P087CC-SCONN2A   I179 @S9S_MB_2U_LIB.S9S_MB_2U(SCH_1):PAGE113

TP_CHH_CPU1_DIMM2_FRU_2 @S9S_MB_2U_LIB.S9S_MB_2U(SCH_1):TP_CHH_CPU1_DIMM2_FRU_2
   J32  149   RFU2 SCONN288_ADR50017P087CC-SCONN2A   I179 @S9S_MB_2U_LIB.S9S_MB_2U(SCH_1):PAGE113

TP_CHH_CPU1_DIMM2_FRU_3 @S9S_MB_2U_LIB.S9S_MB_2U(SCH_1):TP_CHH_CPU1_DIMM2_FRU_3
   J32  150   RFU3 SCONN288_ADR50017P087CC-SCONN2A   I179 @S9S_MB_2U_LIB.S9S_MB_2U(SCH_1):PAGE113

TP_CHH_CPU1_DIMM2_FRU_4 @S9S_MB_2U_LIB.S9S_MB_2U(SCH_1):TP_CHH_CPU1_DIMM2_FRU_4
   J32  220   RFU4 SCONN288_ADR50017P087CC-SCONN2A   I179 @S9S_MB_2U_LIB.S9S_MB_2U(SCH_1):PAGE113

TP_CHH_CPU1_DIMM2_FRU_5 @S9S_MB_2U_LIB.S9S_MB_2U(SCH_1):TP_CHH_CPU1_DIMM2_FRU_5
   J32  231   RFU5 SCONN288_ADR50017P087CC-SCONN2A   I179 @S9S_MB_2U_LIB.S9S_MB_2U(SCH_1):PAGE113

TP_CHH_CPU1_DIMM2_FRU_6 @S9S_MB_2U_LIB.S9S_MB_2U(SCH_1):TP_CHH_CPU1_DIMM2_FRU_6
   J32  232   RFU6 SCONN288_ADR50017P087CC-SCONN2A   I179 @S9S_MB_2U_LIB.S9S_MB_2U(SCH_1):PAGE113

TP_CK440_SBI_DATA_OUT @S9S_MB_2U_LIB.S9S_MB_2U(SCH_1):TP_CK440_SBI_DATA_OUT
   U13  A53 SBI_OUT 9SQ440NQQI8-9SQ440NQQI8,SMLF,IA   I180 @S9S_MB_2U_LIB.S9S_MB_2U(SCH_1):PAGE197

TP_CLK_100M_BUF_DIF3_DN @S9S_MB_2U_LIB.S9S_MB_2U(SCH_1):TP_CLK_100M_BUF_DIF3_DN
  U314   28  DIF3# 9ZXL0451EKILFT-9ZXL0451EKILFT,A     I1 @S9S_MB_2U_LIB.S9S_MB_2U(SCH_1):PAGE200

TP_CLK_100M_BUF_DIF3_DP @S9S_MB_2U_LIB.S9S_MB_2U(SCH_1):TP_CLK_100M_BUF_DIF3_DP
  U314   27   DIF3 9ZXL0451EKILFT-9ZXL0451EKILFT,A     I1 @S9S_MB_2U_LIB.S9S_MB_2U(SCH_1):PAGE200

TP_CLK_100M_DIF13_DN @S9S_MB_2U_LIB.S9S_MB_2U(SCH_1):TP_CLK_100M_DIF13_DN
   U38   A8 DIF13# 9QXL2001BNHGI8-9QXL2001BNHGI8,A   I119 @S9S_MB_2U_LIB.S9S_MB_2U(SCH_1):PAGE195

TP_CLK_100M_DIF13_DP @S9S_MB_2U_LIB.S9S_MB_2U(SCH_1):TP_CLK_100M_DIF13_DP
   U38   A9  DIF13 9QXL2001BNHGI8-9QXL2001BNHGI8,A   I119 @S9S_MB_2U_LIB.S9S_MB_2U(SCH_1):PAGE195

TP_CLK_100M_DIF18_DN @S9S_MB_2U_LIB.S9S_MB_2U(SCH_1):TP_CLK_100M_DIF18_DN
   U38   D1 DIF18# 9QXL2001BNHGI8-9QXL2001BNHGI8,A   I119 @S9S_MB_2U_LIB.S9S_MB_2U(SCH_1):PAGE195

TP_CLK_100M_DIF18_DP @S9S_MB_2U_LIB.S9S_MB_2U(SCH_1):TP_CLK_100M_DIF18_DP
   U38   C1  DIF18 9QXL2001BNHGI8-9QXL2001BNHGI8,A   I119 @S9S_MB_2U_LIB.S9S_MB_2U(SCH_1):PAGE195

TP_CLK_100M_DIF19_DN @S9S_MB_2U_LIB.S9S_MB_2U(SCH_1):TP_CLK_100M_DIF19_DN
   U38   F1 DIF19# 9QXL2001BNHGI8-9QXL2001BNHGI8,A   I119 @S9S_MB_2U_LIB.S9S_MB_2U(SCH_1):PAGE195

TP_CLK_100M_DIF19_DP @S9S_MB_2U_LIB.S9S_MB_2U(SCH_1):TP_CLK_100M_DIF19_DP
   U38   E1  DIF19 9QXL2001BNHGI8-9QXL2001BNHGI8,A   I119 @S9S_MB_2U_LIB.S9S_MB_2U(SCH_1):PAGE195

TP_CLK_100M_E1S_0_DN @S9S_MB_2U_LIB.S9S_MB_2U(SCH_1):TP_CLK_100M_E1S_0_DN
   J90  A14 REFCLK_N1 SCONN56_123276793-SCONN56_1-23A   I318 @S9S_MB_2U_LIB.S9S_MB_2U(SCH_1):PAGE297

TP_CLK_100M_E1S_0_DP @S9S_MB_2U_LIB.S9S_MB_2U(SCH_1):TP_CLK_100M_E1S_0_DP
   J90  A15 REFCLK_P1 SCONN56_123276793-SCONN56_1-23A   I318 @S9S_MB_2U_LIB.S9S_MB_2U(SCH_1):PAGE297

TP_CLK_100M_PCH_0_DN @S9S_MB_2U_LIB.S9S_MB_2U(SCH_1):TP_CLK_100M_PCH_0_DN
    U4  A16 CLKOUT_SRC_N_0 EMMITSBURG_REV0P9-GFNOCPU04302A    I78 @S9S_MB_2U_LIB.S9S_MB_2U(SCH_1):PAGE171

TP_CLK_100M_PCH_0_DP @S9S_MB_2U_LIB.S9S_MB_2U(SCH_1):TP_CLK_100M_PCH_0_DP
    U4  C16 CLKOUT_SRC_P_0 EMMITSBURG_REV0P9-GFNOCPU04302A    I78 @S9S_MB_2U_LIB.S9S_MB_2U(SCH_1):PAGE171

TP_CLK_100M_PCH_10_DN @S9S_MB_2U_LIB.S9S_MB_2U(SCH_1):TP_CLK_100M_PCH_10_DN
    U4  J16 CLKOUT_SRC_N_10 EMMITSBURG_REV0P9-GFNOCPU04302A    I78 @S9S_MB_2U_LIB.S9S_MB_2U(SCH_1):PAGE171

TP_CLK_100M_PCH_10_DP @S9S_MB_2U_LIB.S9S_MB_2U(SCH_1):TP_CLK_100M_PCH_10_DP
    U4  K18 CLKOUT_SRC_P_10 EMMITSBURG_REV0P9-GFNOCPU04302A    I78 @S9S_MB_2U_LIB.S9S_MB_2U(SCH_1):PAGE171

TP_CLK_100M_PCH_11_DN @S9S_MB_2U_LIB.S9S_MB_2U(SCH_1):TP_CLK_100M_PCH_11_DN
    U4  G16 CLKOUT_SRC_N_11 EMMITSBURG_REV0P9-GFNOCPU04302A    I78 @S9S_MB_2U_LIB.S9S_MB_2U(SCH_1):PAGE171

TP_CLK_100M_PCH_11_DP @S9S_MB_2U_LIB.S9S_MB_2U(SCH_1):TP_CLK_100M_PCH_11_DP
    U4  H15 CLKOUT_SRC_P_11 EMMITSBURG_REV0P9-GFNOCPU04302A    I78 @S9S_MB_2U_LIB.S9S_MB_2U(SCH_1):PAGE171

TP_CLK_100M_PCH_12_DN @S9S_MB_2U_LIB.S9S_MB_2U(SCH_1):TP_CLK_100M_PCH_12_DN
    U4  A10 CLKOUT_SRC_N_12 EMMITSBURG_REV0P9-GFNOCPU04302A    I78 @S9S_MB_2U_LIB.S9S_MB_2U(SCH_1):PAGE171

TP_CLK_100M_PCH_12_DP @S9S_MB_2U_LIB.S9S_MB_2U(SCH_1):TP_CLK_100M_PCH_12_DP
    U4  C10 CLKOUT_SRC_P_12 EMMITSBURG_REV0P9-GFNOCPU04302A    I78 @S9S_MB_2U_LIB.S9S_MB_2U(SCH_1):PAGE171

TP_CLK_100M_PCH_13_DN @S9S_MB_2U_LIB.S9S_MB_2U(SCH_1):TP_CLK_100M_PCH_13_DN
    U4   A8 CLKOUT_SRC_N_13 EMMITSBURG_REV0P9-GFNOCPU04302A    I78 @S9S_MB_2U_LIB.S9S_MB_2U(SCH_1):PAGE171

TP_CLK_100M_PCH_13_DP @S9S_MB_2U_LIB.S9S_MB_2U(SCH_1):TP_CLK_100M_PCH_13_DP
    U4   C8 CLKOUT_SRC_P_13 EMMITSBURG_REV0P9-GFNOCPU04302A    I78 @S9S_MB_2U_LIB.S9S_MB_2U(SCH_1):PAGE171

TP_CLK_100M_PCH_14_DN @S9S_MB_2U_LIB.S9S_MB_2U(SCH_1):TP_CLK_100M_PCH_14_DN
    U4   B7 CLKOUT_SRC_N_14 EMMITSBURG_REV0P9-GFNOCPU04302A    I78 @S9S_MB_2U_LIB.S9S_MB_2U(SCH_1):PAGE171

TP_CLK_100M_PCH_14_DP @S9S_MB_2U_LIB.S9S_MB_2U(SCH_1):TP_CLK_100M_PCH_14_DP
    U4   D7 CLKOUT_SRC_P_14 EMMITSBURG_REV0P9-GFNOCPU04302A    I78 @S9S_MB_2U_LIB.S9S_MB_2U(SCH_1):PAGE171

TP_CLK_100M_PCH_15_DN @S9S_MB_2U_LIB.S9S_MB_2U(SCH_1):TP_CLK_100M_PCH_15_DN
    U4   B5 CLKOUT_SRC_N_15 EMMITSBURG_REV0P9-GFNOCPU04302A    I78 @S9S_MB_2U_LIB.S9S_MB_2U(SCH_1):PAGE171

TP_CLK_100M_PCH_15_DP @S9S_MB_2U_LIB.S9S_MB_2U(SCH_1):TP_CLK_100M_PCH_15_DP
    U4   C6 CLKOUT_SRC_P_15 EMMITSBURG_REV0P9-GFNOCPU04302A    I78 @S9S_MB_2U_LIB.S9S_MB_2U(SCH_1):PAGE171

TP_CLK_100M_PCH_16_DN @S9S_MB_2U_LIB.S9S_MB_2U(SCH_1):TP_CLK_100M_PCH_16_DN
    U4  A18 CLKOUT_SRC_N_16 EMMITSBURG_REV0P9-GFNOCPU04302A    I78 @S9S_MB_2U_LIB.S9S_MB_2U(SCH_1):PAGE171

TP_CLK_100M_PCH_16_DP @S9S_MB_2U_LIB.S9S_MB_2U(SCH_1):TP_CLK_100M_PCH_16_DP
    U4  C18 CLKOUT_SRC_P_16 EMMITSBURG_REV0P9-GFNOCPU04302A    I78 @S9S_MB_2U_LIB.S9S_MB_2U(SCH_1):PAGE171

TP_CLK_100M_PCH_1_DN @S9S_MB_2U_LIB.S9S_MB_2U(SCH_1):TP_CLK_100M_PCH_1_DN
    U4  G23 CLKOUT_SRC_N_1 EMMITSBURG_REV0P9-GFNOCPU04302A    I78 @S9S_MB_2U_LIB.S9S_MB_2U(SCH_1):PAGE171

TP_CLK_100M_PCH_1_DP @S9S_MB_2U_LIB.S9S_MB_2U(SCH_1):TP_CLK_100M_PCH_1_DP
    U4  F21 CLKOUT_SRC_P_1 EMMITSBURG_REV0P9-GFNOCPU04302A    I78 @S9S_MB_2U_LIB.S9S_MB_2U(SCH_1):PAGE171

TP_CLK_100M_PCH_4_DN @S9S_MB_2U_LIB.S9S_MB_2U(SCH_1):TP_CLK_100M_PCH_4_DN
    U4  B19 CLKOUT_SRC_N_4 EMMITSBURG_REV0P9-GFNOCPU04302A    I78 @S9S_MB_2U_LIB.S9S_MB_2U(SCH_1):PAGE171

TP_CLK_100M_PCH_4_DP @S9S_MB_2U_LIB.S9S_MB_2U(SCH_1):TP_CLK_100M_PCH_4_DP
    U4  D19 CLKOUT_SRC_P_4 EMMITSBURG_REV0P9-GFNOCPU04302A    I78 @S9S_MB_2U_LIB.S9S_MB_2U(SCH_1):PAGE171

TP_CLK_100M_PCH_5_DN @S9S_MB_2U_LIB.S9S_MB_2U(SCH_1):TP_CLK_100M_PCH_5_DN
    U4  A12 CLKOUT_SRC_N_5 EMMITSBURG_REV0P9-GFNOCPU04302A    I78 @S9S_MB_2U_LIB.S9S_MB_2U(SCH_1):PAGE171

TP_CLK_100M_PCH_5_DP @S9S_MB_2U_LIB.S9S_MB_2U(SCH_1):TP_CLK_100M_PCH_5_DP
    U4  C12 CLKOUT_SRC_P_5 EMMITSBURG_REV0P9-GFNOCPU04302A    I78 @S9S_MB_2U_LIB.S9S_MB_2U(SCH_1):PAGE171

TP_CLK_100M_PCH_7_DN @S9S_MB_2U_LIB.S9S_MB_2U(SCH_1):TP_CLK_100M_PCH_7_DN
    U4  A14 CLKOUT_SRC_N_7 EMMITSBURG_REV0P9-GFNOCPU04302A    I78 @S9S_MB_2U_LIB.S9S_MB_2U(SCH_1):PAGE171

TP_CLK_100M_PCH_7_DP @S9S_MB_2U_LIB.S9S_MB_2U(SCH_1):TP_CLK_100M_PCH_7_DP
    U4  C14 CLKOUT_SRC_P_7 EMMITSBURG_REV0P9-GFNOCPU04302A    I78 @S9S_MB_2U_LIB.S9S_MB_2U(SCH_1):PAGE171

TP_CLK_100M_PCH_8_DN @S9S_MB_2U_LIB.S9S_MB_2U(SCH_1):TP_CLK_100M_PCH_8_DN
    U4  F18 CLKOUT_SRC_N_8 EMMITSBURG_REV0P9-GFNOCPU04302A    I78 @S9S_MB_2U_LIB.S9S_MB_2U(SCH_1):PAGE171

TP_CLK_100M_PCH_8_DP @S9S_MB_2U_LIB.S9S_MB_2U(SCH_1):TP_CLK_100M_PCH_8_DP
    U4  H18 CLKOUT_SRC_P_8 EMMITSBURG_REV0P9-GFNOCPU04302A    I78 @S9S_MB_2U_LIB.S9S_MB_2U(SCH_1):PAGE171

TP_CLK_100M_PCH_9_DN @S9S_MB_2U_LIB.S9S_MB_2U(SCH_1):TP_CLK_100M_PCH_9_DN
    U4  B15 CLKOUT_SRC_N_9 EMMITSBURG_REV0P9-GFNOCPU04302A    I78 @S9S_MB_2U_LIB.S9S_MB_2U(SCH_1):PAGE171

TP_CLK_100M_PCH_9_DP @S9S_MB_2U_LIB.S9S_MB_2U(SCH_1):TP_CLK_100M_PCH_9_DP
    U4  D15 CLKOUT_SRC_P_9 EMMITSBURG_REV0P9-GFNOCPU04302A    I78 @S9S_MB_2U_LIB.S9S_MB_2U(SCH_1):PAGE171

TP_CLK_50M_PCH_LOM @S9S_MB_2U_LIB.S9S_MB_2U(SCH_1):TP_CLK_50M_PCH_LOM
   U90    8     Y3 PI6CV304LE-PI6CV304LE,SMLF,IC,A    I46 @S9S_MB_2U_LIB.S9S_MB_2U(SCH_1):PAGE152

TP_CLK_66M_ESPI_IBL_CPU0_LVC1 @S9S_MB_2U_LIB.S9S_MB_2U(SCH_1):TP_CLK_66M_ESPI_IBL_CPU0_LVC1
    U2 BG62 RSVD52 SOCKET4677_AZIF0045P001C01CS-SA     I1 @S9S_MB_2U_LIB.S9S_MB_2U(SCH_1):PAGE15

TP_CLK_CK440_PFT_OUT_DN @S9S_MB_2U_LIB.S9S_MB_2U(SCH_1):TP_CLK_CK440_PFT_OUT_DN
   U13   A7 PFT_OUT# 9SQ440NQQI8-9SQ440NQQI8,SMLF,IA   I180 @S9S_MB_2U_LIB.S9S_MB_2U(SCH_1):PAGE197

TP_CLK_CK440_PFT_OUT_DP @S9S_MB_2U_LIB.S9S_MB_2U(SCH_1):TP_CLK_CK440_PFT_OUT_DP
   U13   A6 PFT_OUT 9SQ440NQQI8-9SQ440NQQI8,SMLF,IA   I180 @S9S_MB_2U_LIB.S9S_MB_2U(SCH_1):PAGE197

TP_CLK_PFT_IN_DN @S9S_MB_2U_LIB.S9S_MB_2U(SCH_1):TP_CLK_PFT_IN_DN
   U13   A9 PFT_IN# 9SQ440NQQI8-9SQ440NQQI8,SMLF,IA   I180 @S9S_MB_2U_LIB.S9S_MB_2U(SCH_1):PAGE197

TP_CLK_PFT_IN_DP @S9S_MB_2U_LIB.S9S_MB_2U(SCH_1):TP_CLK_PFT_IN_DP
   U13   A8 PFT_IN 9SQ440NQQI8-9SQ440NQQI8,SMLF,IA   I180 @S9S_MB_2U_LIB.S9S_MB_2U(SCH_1):PAGE197

TP_CPU0_A0_DEBUG_EN @S9S_MB_2U_LIB.S9S_MB_2U(SCH_1):TP_CPU0_A0_DEBUG_EN
    U2  H12 RSVD162 SOCKET4677_AZIF0045P001C01CS-SA     I1 @S9S_MB_2U_LIB.S9S_MB_2U(SCH_1):PAGE16

TP_CPU0_BR23 @S9S_MB_2U_LIB.S9S_MB_2U(SCH_1):TP_CPU0_BR23
    U2 BR23 RSVD72 SOCKET4677_AZIF0045P001C01CS-SA    I57 @S9S_MB_2U_LIB.S9S_MB_2U(SCH_1):PAGE13

TP_CPU0_DIE_HVM_EN_LVC1 @S9S_MB_2U_LIB.S9S_MB_2U(SCH_1):TP_CPU0_DIE_HVM_EN_LVC1
    U2 BE21 RSVD45 SOCKET4677_AZIF0045P001C01CS-SA     I1 @S9S_MB_2U_LIB.S9S_MB_2U(SCH_1):PAGE17

TP_CPU0_IFST_DONE_LVC1_R @S9S_MB_2U_LIB.S9S_MB_2U(SCH_1):TP_CPU0_IFST_DONE_LVC1_R
    U2 BC23 RSVD37 SOCKET4677_AZIF0045P001C01CS-SA     I1 @S9S_MB_2U_LIB.S9S_MB_2U(SCH_1):PAGE16

TP_CPU0_IFST_KOT_LVC1_R @S9S_MB_2U_LIB.S9S_MB_2U(SCH_1):TP_CPU0_IFST_KOT_LVC1_R
    U2 BE23 RSVD46 SOCKET4677_AZIF0045P001C01CS-SA     I1 @S9S_MB_2U_LIB.S9S_MB_2U(SCH_1):PAGE16

TP_CPU0_IFST_TRIG_LVC1_R @S9S_MB_2U_LIB.S9S_MB_2U(SCH_1):TP_CPU0_IFST_TRIG_LVC1_R
    U2 BF24 RSVD49 SOCKET4677_AZIF0045P001C01CS-SA     I1 @S9S_MB_2U_LIB.S9S_MB_2U(SCH_1):PAGE16

TP_CPU0_PPD @S9S_MB_2U_LIB.S9S_MB_2U(SCH_1):TP_CPU0_PPD
    U2  J13 RSVD163 SOCKET4677_AZIF0045P001C01CS-SA     I1 @S9S_MB_2U_LIB.S9S_MB_2U(SCH_1):PAGE18

TP_CPU0_PROCDIS_COD_GTL_N @S9S_MB_2U_LIB.S9S_MB_2U(SCH_1):TP_CPU0_PROCDIS_COD_GTL_N
    U2 DA52 PROCDIS_N SOCKET4677_AZIF0045P001C01CS-SA    I57 @S9S_MB_2U_LIB.S9S_MB_2U(SCH_1):PAGE13

TP_CPU0_PWRBTN_N @S9S_MB_2U_LIB.S9S_MB_2U(SCH_1):TP_CPU0_PWRBTN_N
    U2 CK24 RSVD110 SOCKET4677_AZIF0045P001C01CS-SA     I1 @S9S_MB_2U_LIB.S9S_MB_2U(SCH_1):PAGE15

TP_CPU0_SPARE10 @S9S_MB_2U_LIB.S9S_MB_2U(SCH_1):TP_CPU0_SPARE10
    U2 CG60 RSVD95 SOCKET4677_AZIF0045P001C01CS-SA     I1 @S9S_MB_2U_LIB.S9S_MB_2U(SCH_1):PAGE18

TP_CPU0_SPARE11 @S9S_MB_2U_LIB.S9S_MB_2U(SCH_1):TP_CPU0_SPARE11
    U2 CD69 RSVD87 SOCKET4677_AZIF0045P001C01CS-SA     I1 @S9S_MB_2U_LIB.S9S_MB_2U(SCH_1):PAGE18

TP_CPU0_SPARE12 @S9S_MB_2U_LIB.S9S_MB_2U(SCH_1):TP_CPU0_SPARE12
    U2 CL70 RSVD119 SOCKET4677_AZIF0045P001C01CS-SA     I1 @S9S_MB_2U_LIB.S9S_MB_2U(SCH_1):PAGE18

TP_CPU0_SPARE13 @S9S_MB_2U_LIB.S9S_MB_2U(SCH_1):TP_CPU0_SPARE13
    U2 BD77 RSVD44 SOCKET4677_AZIF0045P001C01CS-SA     I1 @S9S_MB_2U_LIB.S9S_MB_2U(SCH_1):PAGE18

TP_CPU0_SPARE4 @S9S_MB_2U_LIB.S9S_MB_2U(SCH_1):TP_CPU0_SPARE4
    U2 DA70 RSVD159 SOCKET4677_AZIF0045P001C01CS-SA     I1 @S9S_MB_2U_LIB.S9S_MB_2U(SCH_1):PAGE18

TP_CPU0_SPARE5 @S9S_MB_2U_LIB.S9S_MB_2U(SCH_1):TP_CPU0_SPARE5
    U2 AU52  RSVD8 SOCKET4677_AZIF0045P001C01CS-SA     I1 @S9S_MB_2U_LIB.S9S_MB_2U(SCH_1):PAGE18

TP_CPU0_SPARE6 @S9S_MB_2U_LIB.S9S_MB_2U(SCH_1):TP_CPU0_SPARE6
    U2 CW43 RSVD148 SOCKET4677_AZIF0045P001C01CS-SA     I1 @S9S_MB_2U_LIB.S9S_MB_2U(SCH_1):PAGE18

TP_CPU0_SPARE7 @S9S_MB_2U_LIB.S9S_MB_2U(SCH_1):TP_CPU0_SPARE7
    U2 CL60 RSVD115 SOCKET4677_AZIF0045P001C01CS-SA     I1 @S9S_MB_2U_LIB.S9S_MB_2U(SCH_1):PAGE18

TP_CPU0_SPARE8 @S9S_MB_2U_LIB.S9S_MB_2U(SCH_1):TP_CPU0_SPARE8
    U2 CK61 RSVD111 SOCKET4677_AZIF0045P001C01CS-SA     I1 @S9S_MB_2U_LIB.S9S_MB_2U(SCH_1):PAGE18

TP_CPU0_SPARE9 @S9S_MB_2U_LIB.S9S_MB_2U(SCH_1):TP_CPU0_SPARE9
    U2 CH61 RSVD97 SOCKET4677_AZIF0045P001C01CS-SA     I1 @S9S_MB_2U_LIB.S9S_MB_2U(SCH_1):PAGE18

TP_CPU0_SSC_SYNC @S9S_MB_2U_LIB.S9S_MB_2U(SCH_1):TP_CPU0_SSC_SYNC
    U2 CL66 RSVD117 SOCKET4677_AZIF0045P001C01CS-SA     I1 @S9S_MB_2U_LIB.S9S_MB_2U(SCH_1):PAGE15

TP_CPU1_A0_DEBUG_EN @S9S_MB_2U_LIB.S9S_MB_2U(SCH_1):TP_CPU1_A0_DEBUG_EN
    U1  H12 RSVD162 SOCKET4677_AZIF0045P001C01CS-SA    I16 @S9S_MB_2U_LIB.S9S_MB_2U(SCH_1):PAGE47

TP_CPU1_BR23 @S9S_MB_2U_LIB.S9S_MB_2U(SCH_1):TP_CPU1_BR23
    U1 BR23 RSVD72 SOCKET4677_AZIF0045P001C01CS-SA    I51 @S9S_MB_2U_LIB.S9S_MB_2U(SCH_1):PAGE44

TP_CPU1_DIE_HVM_EN_LVC1 @S9S_MB_2U_LIB.S9S_MB_2U(SCH_1):TP_CPU1_DIE_HVM_EN_LVC1
    U1 BE21 RSVD45 SOCKET4677_AZIF0045P001C01CS-SA     I1 @S9S_MB_2U_LIB.S9S_MB_2U(SCH_1):PAGE48

TP_CPU1_IBL_GRST_WARN_CPU1_N @S9S_MB_2U_LIB.S9S_MB_2U(SCH_1):TP_CPU1_IBL_GRST_WARN_CPU1_N
    U1 CJ21 RSVD101 SOCKET4677_AZIF0045P001C01CS-SA     I5 @S9S_MB_2U_LIB.S9S_MB_2U(SCH_1):PAGE46

TP_CPU1_IFST_DONE_LVC1_R @S9S_MB_2U_LIB.S9S_MB_2U(SCH_1):TP_CPU1_IFST_DONE_LVC1_R
    U1 BC23 RSVD37 SOCKET4677_AZIF0045P001C01CS-SA    I16 @S9S_MB_2U_LIB.S9S_MB_2U(SCH_1):PAGE47

TP_CPU1_IFST_KOT_LVC1_R @S9S_MB_2U_LIB.S9S_MB_2U(SCH_1):TP_CPU1_IFST_KOT_LVC1_R
    U1 BE23 RSVD46 SOCKET4677_AZIF0045P001C01CS-SA    I16 @S9S_MB_2U_LIB.S9S_MB_2U(SCH_1):PAGE47

TP_CPU1_IFST_TRIG_LVC1_R @S9S_MB_2U_LIB.S9S_MB_2U(SCH_1):TP_CPU1_IFST_TRIG_LVC1_R
    U1 BF24 RSVD49 SOCKET4677_AZIF0045P001C01CS-SA    I16 @S9S_MB_2U_LIB.S9S_MB_2U(SCH_1):PAGE47

TP_CPU1_PPD @S9S_MB_2U_LIB.S9S_MB_2U(SCH_1):TP_CPU1_PPD
    U1  J13 RSVD163 SOCKET4677_AZIF0045P001C01CS-SA     I2 @S9S_MB_2U_LIB.S9S_MB_2U(SCH_1):PAGE49

TP_CPU1_SPARE10 @S9S_MB_2U_LIB.S9S_MB_2U(SCH_1):TP_CPU1_SPARE10
    U1 CG60 RSVD95 SOCKET4677_AZIF0045P001C01CS-SA     I2 @S9S_MB_2U_LIB.S9S_MB_2U(SCH_1):PAGE49

TP_CPU1_SPARE11 @S9S_MB_2U_LIB.S9S_MB_2U(SCH_1):TP_CPU1_SPARE11
    U1 CD69 RSVD87 SOCKET4677_AZIF0045P001C01CS-SA     I2 @S9S_MB_2U_LIB.S9S_MB_2U(SCH_1):PAGE49

TP_CPU1_SPARE12 @S9S_MB_2U_LIB.S9S_MB_2U(SCH_1):TP_CPU1_SPARE12
    U1 CL70 RSVD119 SOCKET4677_AZIF0045P001C01CS-SA     I2 @S9S_MB_2U_LIB.S9S_MB_2U(SCH_1):PAGE49

TP_CPU1_SPARE13 @S9S_MB_2U_LIB.S9S_MB_2U(SCH_1):TP_CPU1_SPARE13
    U1 BD77 RSVD44 SOCKET4677_AZIF0045P001C01CS-SA     I2 @S9S_MB_2U_LIB.S9S_MB_2U(SCH_1):PAGE49

TP_CPU1_SPARE4 @S9S_MB_2U_LIB.S9S_MB_2U(SCH_1):TP_CPU1_SPARE4
    U1 DA70 RSVD159 SOCKET4677_AZIF0045P001C01CS-SA     I2 @S9S_MB_2U_LIB.S9S_MB_2U(SCH_1):PAGE49

TP_CPU1_SPARE5 @S9S_MB_2U_LIB.S9S_MB_2U(SCH_1):TP_CPU1_SPARE5
    U1 AU52  RSVD8 SOCKET4677_AZIF0045P001C01CS-SA     I2 @S9S_MB_2U_LIB.S9S_MB_2U(SCH_1):PAGE49

TP_CPU1_SPARE6 @S9S_MB_2U_LIB.S9S_MB_2U(SCH_1):TP_CPU1_SPARE6
    U1 CW43 RSVD148 SOCKET4677_AZIF0045P001C01CS-SA     I2 @S9S_MB_2U_LIB.S9S_MB_2U(SCH_1):PAGE49

TP_CPU1_SPARE7 @S9S_MB_2U_LIB.S9S_MB_2U(SCH_1):TP_CPU1_SPARE7
    U1 CL60 RSVD115 SOCKET4677_AZIF0045P001C01CS-SA     I2 @S9S_MB_2U_LIB.S9S_MB_2U(SCH_1):PAGE49

TP_CPU1_SPARE8 @S9S_MB_2U_LIB.S9S_MB_2U(SCH_1):TP_CPU1_SPARE8
    U1 CK61 RSVD111 SOCKET4677_AZIF0045P001C01CS-SA     I2 @S9S_MB_2U_LIB.S9S_MB_2U(SCH_1):PAGE49

TP_CPU1_SPARE9 @S9S_MB_2U_LIB.S9S_MB_2U(SCH_1):TP_CPU1_SPARE9
    U1 CH61 RSVD97 SOCKET4677_AZIF0045P001C01CS-SA     I2 @S9S_MB_2U_LIB.S9S_MB_2U(SCH_1):PAGE49

TP_CPU1_SSC_SYNC @S9S_MB_2U_LIB.S9S_MB_2U(SCH_1):TP_CPU1_SSC_SYNC
    U1 CL66 RSVD117 SOCKET4677_AZIF0045P001C01CS-SA     I5 @S9S_MB_2U_LIB.S9S_MB_2U(SCH_1):PAGE46

TP_DMI_CPU1_PCH_RX_C_DN<0> @S9S_MB_2U_LIB.S9S_MB_2U(SCH_1):TP_DMI_CPU1_PCH_RX_C_DN(0)
    U1 BB18 DMI_RX_DN0 SOCKET4677_AZIF0045P001C01CS-SA    I20 @S9S_MB_2U_LIB.S9S_MB_2U(SCH_1):PAGE59

TP_DMI_CPU1_PCH_RX_C_DN<1> @S9S_MB_2U_LIB.S9S_MB_2U(SCH_1):TP_DMI_CPU1_PCH_RX_C_DN(1)
    U1 BE17 DMI_RX_DN1 SOCKET4677_AZIF0045P001C01CS-SA    I20 @S9S_MB_2U_LIB.S9S_MB_2U(SCH_1):PAGE59

TP_DMI_CPU1_PCH_RX_C_DN<2> @S9S_MB_2U_LIB.S9S_MB_2U(SCH_1):TP_DMI_CPU1_PCH_RX_C_DN(2)
    U1 BF18 DMI_RX_DN2 SOCKET4677_AZIF0045P001C01CS-SA    I20 @S9S_MB_2U_LIB.S9S_MB_2U(SCH_1):PAGE59

TP_DMI_CPU1_PCH_RX_C_DN<3> @S9S_MB_2U_LIB.S9S_MB_2U(SCH_1):TP_DMI_CPU1_PCH_RX_C_DN(3)
    U1 BJ17 DMI_RX_DN3 SOCKET4677_AZIF0045P001C01CS-SA    I20 @S9S_MB_2U_LIB.S9S_MB_2U(SCH_1):PAGE59

TP_DMI_CPU1_PCH_RX_C_DN<4> @S9S_MB_2U_LIB.S9S_MB_2U(SCH_1):TP_DMI_CPU1_PCH_RX_C_DN(4)
    U1 BK18 DMI_RX_DN4 SOCKET4677_AZIF0045P001C01CS-SA    I20 @S9S_MB_2U_LIB.S9S_MB_2U(SCH_1):PAGE59

TP_DMI_CPU1_PCH_RX_C_DN<5> @S9S_MB_2U_LIB.S9S_MB_2U(SCH_1):TP_DMI_CPU1_PCH_RX_C_DN(5)
    U1 BN17 DMI_RX_DN5 SOCKET4677_AZIF0045P001C01CS-SA    I20 @S9S_MB_2U_LIB.S9S_MB_2U(SCH_1):PAGE59

TP_DMI_CPU1_PCH_RX_C_DN<6> @S9S_MB_2U_LIB.S9S_MB_2U(SCH_1):TP_DMI_CPU1_PCH_RX_C_DN(6)
    U1 BP18 DMI_RX_DN6 SOCKET4677_AZIF0045P001C01CS-SA    I20 @S9S_MB_2U_LIB.S9S_MB_2U(SCH_1):PAGE59

TP_DMI_CPU1_PCH_RX_C_DN<7> @S9S_MB_2U_LIB.S9S_MB_2U(SCH_1):TP_DMI_CPU1_PCH_RX_C_DN(7)
    U1 BU17 DMI_RX_DN7 SOCKET4677_AZIF0045P001C01CS-SA    I20 @S9S_MB_2U_LIB.S9S_MB_2U(SCH_1):PAGE59

TP_DMI_CPU1_PCH_RX_C_DP<0> @S9S_MB_2U_LIB.S9S_MB_2U(SCH_1):TP_DMI_CPU1_PCH_RX_C_DP(0)
    U1 BC19 DMI_RX_DP0 SOCKET4677_AZIF0045P001C01CS-SA    I20 @S9S_MB_2U_LIB.S9S_MB_2U(SCH_1):PAGE59

TP_DMI_CPU1_PCH_RX_C_DP<1> @S9S_MB_2U_LIB.S9S_MB_2U(SCH_1):TP_DMI_CPU1_PCH_RX_C_DP(1)
    U1 BD18 DMI_RX_DP1 SOCKET4677_AZIF0045P001C01CS-SA    I20 @S9S_MB_2U_LIB.S9S_MB_2U(SCH_1):PAGE59

TP_DMI_CPU1_PCH_RX_C_DP<2> @S9S_MB_2U_LIB.S9S_MB_2U(SCH_1):TP_DMI_CPU1_PCH_RX_C_DP(2)
    U1 BG19 DMI_RX_DP2 SOCKET4677_AZIF0045P001C01CS-SA    I20 @S9S_MB_2U_LIB.S9S_MB_2U(SCH_1):PAGE59

TP_DMI_CPU1_PCH_RX_C_DP<3> @S9S_MB_2U_LIB.S9S_MB_2U(SCH_1):TP_DMI_CPU1_PCH_RX_C_DP(3)
    U1 BH18 DMI_RX_DP3 SOCKET4677_AZIF0045P001C01CS-SA    I20 @S9S_MB_2U_LIB.S9S_MB_2U(SCH_1):PAGE59

TP_DMI_CPU1_PCH_RX_C_DP<4> @S9S_MB_2U_LIB.S9S_MB_2U(SCH_1):TP_DMI_CPU1_PCH_RX_C_DP(4)
    U1 BL19 DMI_RX_DP4 SOCKET4677_AZIF0045P001C01CS-SA    I20 @S9S_MB_2U_LIB.S9S_MB_2U(SCH_1):PAGE59

TP_DMI_CPU1_PCH_RX_C_DP<5> @S9S_MB_2U_LIB.S9S_MB_2U(SCH_1):TP_DMI_CPU1_PCH_RX_C_DP(5)
    U1 BM18 DMI_RX_DP5 SOCKET4677_AZIF0045P001C01CS-SA    I20 @S9S_MB_2U_LIB.S9S_MB_2U(SCH_1):PAGE59

TP_DMI_CPU1_PCH_RX_C_DP<6> @S9S_MB_2U_LIB.S9S_MB_2U(SCH_1):TP_DMI_CPU1_PCH_RX_C_DP(6)
    U1 BR19 DMI_RX_DP6 SOCKET4677_AZIF0045P001C01CS-SA    I20 @S9S_MB_2U_LIB.S9S_MB_2U(SCH_1):PAGE59

TP_DMI_CPU1_PCH_RX_C_DP<7> @S9S_MB_2U_LIB.S9S_MB_2U(SCH_1):TP_DMI_CPU1_PCH_RX_C_DP(7)
    U1 BT18 DMI_RX_DP7 SOCKET4677_AZIF0045P001C01CS-SA    I20 @S9S_MB_2U_LIB.S9S_MB_2U(SCH_1):PAGE59

TP_DMI_CPU1_PCH_TX_DN<0> @S9S_MB_2U_LIB.S9S_MB_2U(SCH_1):TP_DMI_CPU1_PCH_TX_DN(0)
    U1 BW19 DMI_TX_DN0 SOCKET4677_AZIF0045P001C01CS-SA    I20 @S9S_MB_2U_LIB.S9S_MB_2U(SCH_1):PAGE59

TP_DMI_CPU1_PCH_TX_DN<1> @S9S_MB_2U_LIB.S9S_MB_2U(SCH_1):TP_DMI_CPU1_PCH_TX_DN(1)
    U1 CA17 DMI_TX_DN1 SOCKET4677_AZIF0045P001C01CS-SA    I20 @S9S_MB_2U_LIB.S9S_MB_2U(SCH_1):PAGE59

TP_DMI_CPU1_PCH_TX_DN<2> @S9S_MB_2U_LIB.S9S_MB_2U(SCH_1):TP_DMI_CPU1_PCH_TX_DN(2)
    U1 CB18 DMI_TX_DN2 SOCKET4677_AZIF0045P001C01CS-SA    I20 @S9S_MB_2U_LIB.S9S_MB_2U(SCH_1):PAGE59

TP_DMI_CPU1_PCH_TX_DN<3> @S9S_MB_2U_LIB.S9S_MB_2U(SCH_1):TP_DMI_CPU1_PCH_TX_DN(3)
    U1 CE17 DMI_TX_DN3 SOCKET4677_AZIF0045P001C01CS-SA    I20 @S9S_MB_2U_LIB.S9S_MB_2U(SCH_1):PAGE59

TP_DMI_CPU1_PCH_TX_DN<4> @S9S_MB_2U_LIB.S9S_MB_2U(SCH_1):TP_DMI_CPU1_PCH_TX_DN(4)
    U1 CF18 DMI_TX_DN4 SOCKET4677_AZIF0045P001C01CS-SA    I20 @S9S_MB_2U_LIB.S9S_MB_2U(SCH_1):PAGE59

TP_DMI_CPU1_PCH_TX_DN<5> @S9S_MB_2U_LIB.S9S_MB_2U(SCH_1):TP_DMI_CPU1_PCH_TX_DN(5)
    U1 CJ17 DMI_TX_DN5 SOCKET4677_AZIF0045P001C01CS-SA    I20 @S9S_MB_2U_LIB.S9S_MB_2U(SCH_1):PAGE59

TP_DMI_CPU1_PCH_TX_DN<6> @S9S_MB_2U_LIB.S9S_MB_2U(SCH_1):TP_DMI_CPU1_PCH_TX_DN(6)
    U1 CK18 DMI_TX_DN6 SOCKET4677_AZIF0045P001C01CS-SA    I20 @S9S_MB_2U_LIB.S9S_MB_2U(SCH_1):PAGE59

TP_DMI_CPU1_PCH_TX_DN<7> @S9S_MB_2U_LIB.S9S_MB_2U(SCH_1):TP_DMI_CPU1_PCH_TX_DN(7)
    U1 CN17 DMI_TX_DN7 SOCKET4677_AZIF0045P001C01CS-SA    I20 @S9S_MB_2U_LIB.S9S_MB_2U(SCH_1):PAGE59

TP_DMI_CPU1_PCH_TX_DP<0> @S9S_MB_2U_LIB.S9S_MB_2U(SCH_1):TP_DMI_CPU1_PCH_TX_DP(0)
    U1 CA19 DMI_TX_DP0 SOCKET4677_AZIF0045P001C01CS-SA    I20 @S9S_MB_2U_LIB.S9S_MB_2U(SCH_1):PAGE59

TP_DMI_CPU1_PCH_TX_DP<1> @S9S_MB_2U_LIB.S9S_MB_2U(SCH_1):TP_DMI_CPU1_PCH_TX_DP(1)
    U1 BY18 DMI_TX_DP1 SOCKET4677_AZIF0045P001C01CS-SA    I20 @S9S_MB_2U_LIB.S9S_MB_2U(SCH_1):PAGE59

TP_DMI_CPU1_PCH_TX_DP<2> @S9S_MB_2U_LIB.S9S_MB_2U(SCH_1):TP_DMI_CPU1_PCH_TX_DP(2)
    U1 CC19 DMI_TX_DP2 SOCKET4677_AZIF0045P001C01CS-SA    I20 @S9S_MB_2U_LIB.S9S_MB_2U(SCH_1):PAGE59

TP_DMI_CPU1_PCH_TX_DP<3> @S9S_MB_2U_LIB.S9S_MB_2U(SCH_1):TP_DMI_CPU1_PCH_TX_DP(3)
    U1 CD18 DMI_TX_DP3 SOCKET4677_AZIF0045P001C01CS-SA    I20 @S9S_MB_2U_LIB.S9S_MB_2U(SCH_1):PAGE59

TP_DMI_CPU1_PCH_TX_DP<4> @S9S_MB_2U_LIB.S9S_MB_2U(SCH_1):TP_DMI_CPU1_PCH_TX_DP(4)
    U1 CG19 DMI_TX_DP4 SOCKET4677_AZIF0045P001C01CS-SA    I20 @S9S_MB_2U_LIB.S9S_MB_2U(SCH_1):PAGE59

TP_DMI_CPU1_PCH_TX_DP<5> @S9S_MB_2U_LIB.S9S_MB_2U(SCH_1):TP_DMI_CPU1_PCH_TX_DP(5)
    U1 CH18 DMI_TX_DP5 SOCKET4677_AZIF0045P001C01CS-SA    I20 @S9S_MB_2U_LIB.S9S_MB_2U(SCH_1):PAGE59

TP_DMI_CPU1_PCH_TX_DP<6> @S9S_MB_2U_LIB.S9S_MB_2U(SCH_1):TP_DMI_CPU1_PCH_TX_DP(6)
    U1 CL19 DMI_TX_DP6 SOCKET4677_AZIF0045P001C01CS-SA    I20 @S9S_MB_2U_LIB.S9S_MB_2U(SCH_1):PAGE59

TP_DMI_CPU1_PCH_TX_DP<7> @S9S_MB_2U_LIB.S9S_MB_2U(SCH_1):TP_DMI_CPU1_PCH_TX_DP(7)
    U1 CM18 DMI_TX_DP7 SOCKET4677_AZIF0045P001C01CS-SA    I20 @S9S_MB_2U_LIB.S9S_MB_2U(SCH_1):PAGE59

TP_E1S_0_MFG @S9S_MB_2U_LIB.S9S_MB_2U(SCH_1):TP_E1S_0_MFG
   J90   B7    MFG SCONN56_123276793-SCONN56_1-23A   I318 @S9S_MB_2U_LIB.S9S_MB_2U(SCH_1):PAGE297

TP_E1S_0_RFU @S9S_MB_2U_LIB.S9S_MB_2U(SCH_1):TP_E1S_0_RFU
   J90   B8    RFU SCONN56_123276793-SCONN56_1-23A   I318 @S9S_MB_2U_LIB.S9S_MB_2U(SCH_1):PAGE297

TP_EDSFF1A_TYPE_ID @S9S_MB_2U_LIB.S9S_MB_2U(SCH_1):TP_EDSFF1A_TYPE_ID
    U4 AV24 GPP_E_4_SATA0_XPCIE_2 EMMITSBURG_REV0P9-GFNOCPU04302A    I22 @S9S_MB_2U_LIB.S9S_MB_2U(SCH_1):PAGE176

TP_EDSFF1B_TYPE_ID @S9S_MB_2U_LIB.S9S_MB_2U(SCH_1):TP_EDSFF1B_TYPE_ID
    U4 AV28 GPP_E_5_SATA0_XPCIE_3 EMMITSBURG_REV0P9-GFNOCPU04302A    I22 @S9S_MB_2U_LIB.S9S_MB_2U(SCH_1):PAGE176

TP_ESPI_IBL_CPU0_ALERT0_LVC1_N @S9S_MB_2U_LIB.S9S_MB_2U(SCH_1):TP_ESPI_IBL_CPU0_ALERT0_LVC1_N
    U2 BE62 RSVD48 SOCKET4677_AZIF0045P001C01CS-SA     I1 @S9S_MB_2U_LIB.S9S_MB_2U(SCH_1):PAGE15

TP_ESPI_IBL_CPU0_ALERT1_N @S9S_MB_2U_LIB.S9S_MB_2U(SCH_1):TP_ESPI_IBL_CPU0_ALERT1_N
    U2 BD63 RSVD41 SOCKET4677_AZIF0045P001C01CS-SA     I1 @S9S_MB_2U_LIB.S9S_MB_2U(SCH_1):PAGE15

TP_ESPI_IBL_CPU0_CS0_LVC1_N @S9S_MB_2U_LIB.S9S_MB_2U(SCH_1):TP_ESPI_IBL_CPU0_CS0_LVC1_N
    U2 BF65 RSVD50 SOCKET4677_AZIF0045P001C01CS-SA     I1 @S9S_MB_2U_LIB.S9S_MB_2U(SCH_1):PAGE15

TP_ESPI_IBL_CPU0_CS1_N @S9S_MB_2U_LIB.S9S_MB_2U(SCH_1):TP_ESPI_IBL_CPU0_CS1_N
    U2 BH65 RSVD56 SOCKET4677_AZIF0045P001C01CS-SA     I1 @S9S_MB_2U_LIB.S9S_MB_2U(SCH_1):PAGE15

TP_ESPI_IBL_CPU0_IO0_LVC1 @S9S_MB_2U_LIB.S9S_MB_2U(SCH_1):TP_ESPI_IBL_CPU0_IO0_LVC1
    U2 BK63 RSVD61 SOCKET4677_AZIF0045P001C01CS-SA     I1 @S9S_MB_2U_LIB.S9S_MB_2U(SCH_1):PAGE15

TP_ESPI_IBL_CPU0_IO1_LVC1 @S9S_MB_2U_LIB.S9S_MB_2U(SCH_1):TP_ESPI_IBL_CPU0_IO1_LVC1
    U2 BJ64 RSVD58 SOCKET4677_AZIF0045P001C01CS-SA     I1 @S9S_MB_2U_LIB.S9S_MB_2U(SCH_1):PAGE15

TP_ESPI_IBL_CPU0_IO2_LVC1 @S9S_MB_2U_LIB.S9S_MB_2U(SCH_1):TP_ESPI_IBL_CPU0_IO2_LVC1
    U2 AU64 RSVD12 SOCKET4677_AZIF0045P001C01CS-SA     I1 @S9S_MB_2U_LIB.S9S_MB_2U(SCH_1):PAGE15

TP_ESPI_IBL_CPU0_IO3_LVC1 @S9S_MB_2U_LIB.S9S_MB_2U(SCH_1):TP_ESPI_IBL_CPU0_IO3_LVC1
    U2 BM63 RSVD64 SOCKET4677_AZIF0045P001C01CS-SA     I1 @S9S_MB_2U_LIB.S9S_MB_2U(SCH_1):PAGE15

TP_ESPI_IBL_CPU0_OE_LVC1_N @S9S_MB_2U_LIB.S9S_MB_2U(SCH_1):TP_ESPI_IBL_CPU0_OE_LVC1_N
    U2 BH63 RSVD55 SOCKET4677_AZIF0045P001C01CS-SA     I1 @S9S_MB_2U_LIB.S9S_MB_2U(SCH_1):PAGE15

TP_EV_CPU0_EXT_BGREF @S9S_MB_2U_LIB.S9S_MB_2U(SCH_1):TP_EV_CPU0_EXT_BGREF
    U2 AV59 RSVD19 SOCKET4677_AZIF0045P001C01CS-SA     I1 @S9S_MB_2U_LIB.S9S_MB_2U(SCH_1):PAGE14

TP_EV_CPU1_EXT_BGREF @S9S_MB_2U_LIB.S9S_MB_2U(SCH_1):TP_EV_CPU1_EXT_BGREF
    U1 AV59 RSVD19 SOCKET4677_AZIF0045P001C01CS-SA    I29 @S9S_MB_2U_LIB.S9S_MB_2U(SCH_1):PAGE45

TP_FM_IBL_ADR_ACK_CPU0 @S9S_MB_2U_LIB.S9S_MB_2U(SCH_1):TP_FM_IBL_ADR_ACK_CPU0
    U2 CN23 RSVD124 SOCKET4677_AZIF0045P001C01CS-SA     I1 @S9S_MB_2U_LIB.S9S_MB_2U(SCH_1):PAGE15

TP_FM_IBL_ADR_COMPLETE_CPU0_R @S9S_MB_2U_LIB.S9S_MB_2U(SCH_1):TP_FM_IBL_ADR_COMPLETE_CPU0_R
    U2 CP24 RSVD128 SOCKET4677_AZIF0045P001C01CS-SA     I1 @S9S_MB_2U_LIB.S9S_MB_2U(SCH_1):PAGE15

TP_FM_IBL_ADR_TRIGGER_CPU0_R @S9S_MB_2U_LIB.S9S_MB_2U(SCH_1):TP_FM_IBL_ADR_TRIGGER_CPU0_R
    U2 CT24 RSVD137 SOCKET4677_AZIF0045P001C01CS-SA     I1 @S9S_MB_2U_LIB.S9S_MB_2U(SCH_1):PAGE15

TP_FM_IBL_PWRBTN_CPU1_N @S9S_MB_2U_LIB.S9S_MB_2U(SCH_1):TP_FM_IBL_PWRBTN_CPU1_N
    U1 CK24 RSVD110 SOCKET4677_AZIF0045P001C01CS-SA     I5 @S9S_MB_2U_LIB.S9S_MB_2U(SCH_1):PAGE46

TP_FM_IBL_SLPS3_CPU1_R_N @S9S_MB_2U_LIB.S9S_MB_2U(SCH_1):TP_FM_IBL_SLPS3_CPU1_R_N
    U1 CR21 RSVD131 SOCKET4677_AZIF0045P001C01CS-SA     I5 @S9S_MB_2U_LIB.S9S_MB_2U(SCH_1):PAGE46

TP_FM_IBL_SLPS4_CPU1_R_N @S9S_MB_2U_LIB.S9S_MB_2U(SCH_1):TP_FM_IBL_SLPS4_CPU1_R_N
    U1 CN21 RSVD123 SOCKET4677_AZIF0045P001C01CS-SA     I5 @S9S_MB_2U_LIB.S9S_MB_2U(SCH_1):PAGE46

TP_FM_IBL_SLPS5_CPU1_R_N @S9S_MB_2U_LIB.S9S_MB_2U(SCH_1):TP_FM_IBL_SLPS5_CPU1_R_N
    U1 CW21 RSVD144 SOCKET4677_AZIF0045P001C01CS-SA     I5 @S9S_MB_2U_LIB.S9S_MB_2U(SCH_1):PAGE46

TP_FM_IBL_SYS_RST_CPU0_N @S9S_MB_2U_LIB.S9S_MB_2U(SCH_1):TP_FM_IBL_SYS_RST_CPU0_N
    U2 CK22 RSVD109 SOCKET4677_AZIF0045P001C01CS-SA     I1 @S9S_MB_2U_LIB.S9S_MB_2U(SCH_1):PAGE15

TP_FM_IBL_WAKE_CPU0_N @S9S_MB_2U_LIB.S9S_MB_2U(SCH_1):TP_FM_IBL_WAKE_CPU0_N
    U2 AW19 RSVD23 SOCKET4677_AZIF0045P001C01CS-SA     I1 @S9S_MB_2U_LIB.S9S_MB_2U(SCH_1):PAGE15

TP_FM_SYS_RST_CPU1_N @S9S_MB_2U_LIB.S9S_MB_2U(SCH_1):TP_FM_SYS_RST_CPU1_N
    U1 CK22 RSVD109 SOCKET4677_AZIF0045P001C01CS-SA     I5 @S9S_MB_2U_LIB.S9S_MB_2U(SCH_1):PAGE46

TP_FM_WAKE_CPU1_N @S9S_MB_2U_LIB.S9S_MB_2U(SCH_1):TP_FM_WAKE_CPU1_N
    U1 AW19 RSVD23 SOCKET4677_AZIF0045P001C01CS-SA     I5 @S9S_MB_2U_LIB.S9S_MB_2U(SCH_1):PAGE46

TP_GPP_L_2 @S9S_MB_2U_LIB.S9S_MB_2U(SCH_1):TP_GPP_L_2
    U4 AC10 GPP_L_2 EMMITSBURG_REV0P9-GFNOCPU04302A    I22 @S9S_MB_2U_LIB.S9S_MB_2U(SCH_1):PAGE176

TP_GPP_L_7 @S9S_MB_2U_LIB.S9S_MB_2U(SCH_1):TP_GPP_L_7
    U4  AC7 GPP_L_7 EMMITSBURG_REV0P9-GFNOCPU04302A    I22 @S9S_MB_2U_LIB.S9S_MB_2U(SCH_1):PAGE176

TP_GPP_L_8 @S9S_MB_2U_LIB.S9S_MB_2U(SCH_1):TP_GPP_L_8
    U4 AE10 GPP_L_8 EMMITSBURG_REV0P9-GFNOCPU04302A    I22 @S9S_MB_2U_LIB.S9S_MB_2U(SCH_1):PAGE176

TP_GPP_M_12 @S9S_MB_2U_LIB.S9S_MB_2U(SCH_1):TP_GPP_M_12
    U4   U7 GPP_M_12 EMMITSBURG_REV0P9-GFNOCPU04302A    I22 @S9S_MB_2U_LIB.S9S_MB_2U(SCH_1):PAGE176

TP_HPM_STBY_EN @S9S_MB_2U_LIB.S9S_MB_2U(SCH_1):TP_HPM_STBY_EN
   J41  A45  PERP8 SCONN168_ME1016810202011-SCONNA   I173 @S9S_MB_2U_LIB.S9S_MB_2U(SCH_1):PAGE227

TP_HSC_TYPE_ADC_ALERT @S9S_MB_2U_LIB.S9S_MB_2U(SCH_1):TP_HSC_TYPE_ADC_ALERT
 R4692    2      B Q_RES_0402LF-4.7K,1%,1/16W,EMPA    I35 @S9S_MB_2U_LIB.S9S_MB_2U(SCH_1):PAGE240
  U331    3  ALERT INA230AIRGTR-INA230AIRGTR,SMLFA    I39 @S9S_MB_2U_LIB.S9S_MB_2U(SCH_1):PAGE240

TP_H_CPU1_PMDOWN_PCH_R @S9S_MB_2U_LIB.S9S_MB_2U(SCH_1):TP_H_CPU1_PMDOWN_PCH_R
    U1 CY40 PMDOWN_PCH SOCKET4677_AZIF0045P001C01CS-SA    I29 @S9S_MB_2U_LIB.S9S_MB_2U(SCH_1):PAGE45

TP_H_CPU1_PMSYNC_PCH_INTRP_R @S9S_MB_2U_LIB.S9S_MB_2U(SCH_1):TP_H_CPU1_PMSYNC_PCH_INTRP_R
    U1 DA39 PMSYNC_PCH SOCKET4677_AZIF0045P001C01CS-SA    I29 @S9S_MB_2U_LIB.S9S_MB_2U(SCH_1):PAGE45

TP_H_SBLINK2_CPU0_PMDOWN @S9S_MB_2U_LIB.S9S_MB_2U(SCH_1):TP_H_SBLINK2_CPU0_PMDOWN
    U2 CP26 PMDOWN1 SOCKET4677_AZIF0045P001C01CS-SA     I1 @S9S_MB_2U_LIB.S9S_MB_2U(SCH_1):PAGE14

TP_H_SBLINK2_CPU0_PMSYNC @S9S_MB_2U_LIB.S9S_MB_2U(SCH_1):TP_H_SBLINK2_CPU0_PMSYNC
    U2 CL25 PMSYNC1 SOCKET4677_AZIF0045P001C01CS-SA     I1 @S9S_MB_2U_LIB.S9S_MB_2U(SCH_1):PAGE14

TP_H_SBLINK2_CPU1_PMDOWN @S9S_MB_2U_LIB.S9S_MB_2U(SCH_1):TP_H_SBLINK2_CPU1_PMDOWN
    U1 CP26 PMDOWN1 SOCKET4677_AZIF0045P001C01CS-SA    I29 @S9S_MB_2U_LIB.S9S_MB_2U(SCH_1):PAGE45

TP_H_SBLINK2_CPU1_PMSYNC @S9S_MB_2U_LIB.S9S_MB_2U(SCH_1):TP_H_SBLINK2_CPU1_PMSYNC
    U1 CL25 PMSYNC1 SOCKET4677_AZIF0045P001C01CS-SA    I29 @S9S_MB_2U_LIB.S9S_MB_2U(SCH_1):PAGE45

TP_H_SBLINK3_CPU0_PMDOWN @S9S_MB_2U_LIB.S9S_MB_2U(SCH_1):TP_H_SBLINK3_CPU0_PMDOWN
    U2 CM26 PMDOWN2 SOCKET4677_AZIF0045P001C01CS-SA     I1 @S9S_MB_2U_LIB.S9S_MB_2U(SCH_1):PAGE14

TP_H_SBLINK3_CPU0_PMSYNC @S9S_MB_2U_LIB.S9S_MB_2U(SCH_1):TP_H_SBLINK3_CPU0_PMSYNC
    U2 CH26 PMSYNC2 SOCKET4677_AZIF0045P001C01CS-SA     I1 @S9S_MB_2U_LIB.S9S_MB_2U(SCH_1):PAGE14

TP_H_SBLINK3_CPU1_PMDOWN @S9S_MB_2U_LIB.S9S_MB_2U(SCH_1):TP_H_SBLINK3_CPU1_PMDOWN
    U1 CM26 PMDOWN2 SOCKET4677_AZIF0045P001C01CS-SA    I29 @S9S_MB_2U_LIB.S9S_MB_2U(SCH_1):PAGE45

TP_H_SBLINK3_CPU1_PMSYNC @S9S_MB_2U_LIB.S9S_MB_2U(SCH_1):TP_H_SBLINK3_CPU1_PMSYNC
    U1 CH26 PMSYNC2 SOCKET4677_AZIF0045P001C01CS-SA    I29 @S9S_MB_2U_LIB.S9S_MB_2U(SCH_1):PAGE45

TP_H_SBLINK4_CPU0_PMDOWN @S9S_MB_2U_LIB.S9S_MB_2U(SCH_1):TP_H_SBLINK4_CPU0_PMDOWN
    U2 CD24 PMDOWN3 SOCKET4677_AZIF0045P001C01CS-SA     I1 @S9S_MB_2U_LIB.S9S_MB_2U(SCH_1):PAGE14

TP_H_SBLINK4_CPU0_PMSYNC @S9S_MB_2U_LIB.S9S_MB_2U(SCH_1):TP_H_SBLINK4_CPU0_PMSYNC
    U2 CE25 PMSYNC3 SOCKET4677_AZIF0045P001C01CS-SA     I1 @S9S_MB_2U_LIB.S9S_MB_2U(SCH_1):PAGE14

TP_H_SBLINK4_CPU1_PMDOWN @S9S_MB_2U_LIB.S9S_MB_2U(SCH_1):TP_H_SBLINK4_CPU1_PMDOWN
    U1 CD24 PMDOWN3 SOCKET4677_AZIF0045P001C01CS-SA    I29 @S9S_MB_2U_LIB.S9S_MB_2U(SCH_1):PAGE45

TP_H_SBLINK4_CPU1_PMSYNC @S9S_MB_2U_LIB.S9S_MB_2U(SCH_1):TP_H_SBLINK4_CPU1_PMSYNC
    U1 CE25 PMSYNC3 SOCKET4677_AZIF0045P001C01CS-SA    I29 @S9S_MB_2U_LIB.S9S_MB_2U(SCH_1):PAGE45

TP_H_SBLINK5_CPU0_PMDOWN @S9S_MB_2U_LIB.S9S_MB_2U(SCH_1):TP_H_SBLINK5_CPU0_PMDOWN
    U2 CV18 PMDOWN4 SOCKET4677_AZIF0045P001C01CS-SA     I1 @S9S_MB_2U_LIB.S9S_MB_2U(SCH_1):PAGE14

TP_H_SBLINK5_CPU0_PMSYNC @S9S_MB_2U_LIB.S9S_MB_2U(SCH_1):TP_H_SBLINK5_CPU0_PMSYNC
    U2 CR19 PMSYNC4 SOCKET4677_AZIF0045P001C01CS-SA     I1 @S9S_MB_2U_LIB.S9S_MB_2U(SCH_1):PAGE14

TP_H_SBLINK5_CPU1_PMDOWN @S9S_MB_2U_LIB.S9S_MB_2U(SCH_1):TP_H_SBLINK5_CPU1_PMDOWN
    U1 CV18 PMDOWN4 SOCKET4677_AZIF0045P001C01CS-SA    I29 @S9S_MB_2U_LIB.S9S_MB_2U(SCH_1):PAGE45

TP_H_SBLINK5_CPU1_PMSYNC @S9S_MB_2U_LIB.S9S_MB_2U(SCH_1):TP_H_SBLINK5_CPU1_PMSYNC
    U1 CR19 PMSYNC4 SOCKET4677_AZIF0045P001C01CS-SA    I29 @S9S_MB_2U_LIB.S9S_MB_2U(SCH_1):PAGE45

TP_H_SBLINK6_CPU0_PMDOWN @S9S_MB_2U_LIB.S9S_MB_2U(SCH_1):TP_H_SBLINK6_CPU0_PMDOWN
    U2 CE23 PMDOWN5 SOCKET4677_AZIF0045P001C01CS-SA     I1 @S9S_MB_2U_LIB.S9S_MB_2U(SCH_1):PAGE14

TP_H_SBLINK6_CPU0_PMSYNC @S9S_MB_2U_LIB.S9S_MB_2U(SCH_1):TP_H_SBLINK6_CPU0_PMSYNC
    U2 CH24 PMSYNC5 SOCKET4677_AZIF0045P001C01CS-SA     I1 @S9S_MB_2U_LIB.S9S_MB_2U(SCH_1):PAGE14

TP_H_SBLINK6_CPU1_PMDOWN @S9S_MB_2U_LIB.S9S_MB_2U(SCH_1):TP_H_SBLINK6_CPU1_PMDOWN
    U1 CE23 PMDOWN5 SOCKET4677_AZIF0045P001C01CS-SA    I29 @S9S_MB_2U_LIB.S9S_MB_2U(SCH_1):PAGE45

TP_H_SBLINK6_CPU1_PMSYNC @S9S_MB_2U_LIB.S9S_MB_2U(SCH_1):TP_H_SBLINK6_CPU1_PMSYNC
    U1 CH24 PMSYNC5 SOCKET4677_AZIF0045P001C01CS-SA    I29 @S9S_MB_2U_LIB.S9S_MB_2U(SCH_1):PAGE45

TP_H_SBLINK7_CPU0_PMDOWN @S9S_MB_2U_LIB.S9S_MB_2U(SCH_1):TP_H_SBLINK7_CPU0_PMDOWN
    U2 CC25 PMDOWN6 SOCKET4677_AZIF0045P001C01CS-SA     I1 @S9S_MB_2U_LIB.S9S_MB_2U(SCH_1):PAGE14

TP_H_SBLINK7_CPU0_PMSYNC @S9S_MB_2U_LIB.S9S_MB_2U(SCH_1):TP_H_SBLINK7_CPU0_PMSYNC
    U2 CF24 PMSYNC6 SOCKET4677_AZIF0045P001C01CS-SA     I1 @S9S_MB_2U_LIB.S9S_MB_2U(SCH_1):PAGE14

TP_H_SBLINK7_CPU1_PMDOWN @S9S_MB_2U_LIB.S9S_MB_2U(SCH_1):TP_H_SBLINK7_CPU1_PMDOWN
    U1 CC25 PMDOWN6 SOCKET4677_AZIF0045P001C01CS-SA    I29 @S9S_MB_2U_LIB.S9S_MB_2U(SCH_1):PAGE45

TP_H_SBLINK7_CPU1_PMSYNC @S9S_MB_2U_LIB.S9S_MB_2U(SCH_1):TP_H_SBLINK7_CPU1_PMSYNC
    U1 CF24 PMSYNC6 SOCKET4677_AZIF0045P001C01CS-SA    I29 @S9S_MB_2U_LIB.S9S_MB_2U(SCH_1):PAGE45

TP_I2C_S3M_RTC_CPU0_ALERT_N @S9S_MB_2U_LIB.S9S_MB_2U(SCH_1):TP_I2C_S3M_RTC_CPU0_ALERT_N
    U2 CJ25 RSVD103 SOCKET4677_AZIF0045P001C01CS-SA     I1 @S9S_MB_2U_LIB.S9S_MB_2U(SCH_1):PAGE15

TP_I2C_S3M_RTC_CPU0_SCL @S9S_MB_2U_LIB.S9S_MB_2U(SCH_1):TP_I2C_S3M_RTC_CPU0_SCL
    U2 CL23 RSVD114 SOCKET4677_AZIF0045P001C01CS-SA     I1 @S9S_MB_2U_LIB.S9S_MB_2U(SCH_1):PAGE15

TP_I2C_S3M_RTC_CPU0_SDA @S9S_MB_2U_LIB.S9S_MB_2U(SCH_1):TP_I2C_S3M_RTC_CPU0_SDA
    U2 CJ23 RSVD102 SOCKET4677_AZIF0045P001C01CS-SA     I1 @S9S_MB_2U_LIB.S9S_MB_2U(SCH_1):PAGE15

TP_I2C_S3M_RTC_CPU1_RST_N @S9S_MB_2U_LIB.S9S_MB_2U(SCH_1):TP_I2C_S3M_RTC_CPU1_RST_N
    U1 CJ25 RSVD103 SOCKET4677_AZIF0045P001C01CS-SA     I5 @S9S_MB_2U_LIB.S9S_MB_2U(SCH_1):PAGE46

TP_I2C_S3M_RTC_CPU1_SCL @S9S_MB_2U_LIB.S9S_MB_2U(SCH_1):TP_I2C_S3M_RTC_CPU1_SCL
    U1 CL23 RSVD114 SOCKET4677_AZIF0045P001C01CS-SA     I5 @S9S_MB_2U_LIB.S9S_MB_2U(SCH_1):PAGE46

TP_I2C_S3M_RTC_CPU1_SDA @S9S_MB_2U_LIB.S9S_MB_2U(SCH_1):TP_I2C_S3M_RTC_CPU1_SDA
    U1 CJ23 RSVD102 SOCKET4677_AZIF0045P001C01CS-SA     I5 @S9S_MB_2U_LIB.S9S_MB_2U(SCH_1):PAGE46

TP_I3C_MNG2_BMC_SW_SCL @S9S_MB_2U_LIB.S9S_MB_2U(SCH_1):TP_I3C_MNG2_BMC_SW_SCL
    U2 BE25 RSVD47 SOCKET4677_AZIF0045P001C01CS-SA     I1 @S9S_MB_2U_LIB.S9S_MB_2U(SCH_1):PAGE15

TP_I3C_MNG2_BMC_SW_SDA @S9S_MB_2U_LIB.S9S_MB_2U(SCH_1):TP_I3C_MNG2_BMC_SW_SDA
    U2 BC25 RSVD38 SOCKET4677_AZIF0045P001C01CS-SA     I1 @S9S_MB_2U_LIB.S9S_MB_2U(SCH_1):PAGE15

TP_I3C_MNG3_BMC_SW_SCL @S9S_MB_2U_LIB.S9S_MB_2U(SCH_1):TP_I3C_MNG3_BMC_SW_SCL
    U1 BE25 RSVD47 SOCKET4677_AZIF0045P001C01CS-SA     I5 @S9S_MB_2U_LIB.S9S_MB_2U(SCH_1):PAGE46

TP_I3C_MNG3_BMC_SW_SDA @S9S_MB_2U_LIB.S9S_MB_2U(SCH_1):TP_I3C_MNG3_BMC_SW_SDA
    U1 BC25 RSVD38 SOCKET4677_AZIF0045P001C01CS-SA     I5 @S9S_MB_2U_LIB.S9S_MB_2U(SCH_1):PAGE46

TP_IBL_GRST_WARN_PLD_R_N @S9S_MB_2U_LIB.S9S_MB_2U(SCH_1):TP_IBL_GRST_WARN_PLD_R_N
    U2 CJ21 RSVD101 SOCKET4677_AZIF0045P001C01CS-SA     I1 @S9S_MB_2U_LIB.S9S_MB_2U(SCH_1):PAGE15

TP_IBL_PLT_RST_SYNC_N @S9S_MB_2U_LIB.S9S_MB_2U(SCH_1):TP_IBL_PLT_RST_SYNC_N
    U2 CL21 RSVD113 SOCKET4677_AZIF0045P001C01CS-SA     I1 @S9S_MB_2U_LIB.S9S_MB_2U(SCH_1):PAGE14

TP_IBL_SLPS3_CPU0_R_N @S9S_MB_2U_LIB.S9S_MB_2U(SCH_1):TP_IBL_SLPS3_CPU0_R_N
    U2 CR21 RSVD131 SOCKET4677_AZIF0045P001C01CS-SA     I1 @S9S_MB_2U_LIB.S9S_MB_2U(SCH_1):PAGE15

TP_IBL_SLPS4_CPU0_R_N @S9S_MB_2U_LIB.S9S_MB_2U(SCH_1):TP_IBL_SLPS4_CPU0_R_N
    U2 CN21 RSVD123 SOCKET4677_AZIF0045P001C01CS-SA     I1 @S9S_MB_2U_LIB.S9S_MB_2U(SCH_1):PAGE15

TP_IBL_SLPS5_CPU0_R_N @S9S_MB_2U_LIB.S9S_MB_2U(SCH_1):TP_IBL_SLPS5_CPU0_R_N
    U2 CW21 RSVD144 SOCKET4677_AZIF0045P001C01CS-SA     I1 @S9S_MB_2U_LIB.S9S_MB_2U(SCH_1):PAGE15

TP_J45_A1 @S9S_MB_2U_LIB.S9S_MB_2U(SCH_1):TP_J45_A1
   J45   A1     A1 CONN60_101062636003K02LF-CONN6A    I12 @S9S_MB_2U_LIB.S9S_MB_2U(SCH_1):PAGE233

TP_JTAG_BMC_1B @S9S_MB_2U_LIB.S9S_MB_2U(SCH_1):TP_JTAG_BMC_1B
   U86    3     1B 74CBTLV3126PW-74CBTLV3126PW,SMA    I84 @S9S_MB_2U_LIB.S9S_MB_2U(SCH_1):PAGE137

TP_JTAG_BMC_4B @S9S_MB_2U_LIB.S9S_MB_2U(SCH_1):TP_JTAG_BMC_4B
   U86   11     4B 74CBTLV3126PW-74CBTLV3126PW,SMA    I84 @S9S_MB_2U_LIB.S9S_MB_2U(SCH_1):PAGE137

TP_JTAG_BMC_A0 @S9S_MB_2U_LIB.S9S_MB_2U(SCH_1):TP_JTAG_BMC_A0
   U83   13     A0 GTL2014PW-GTL2014PW,SMLF,IC,ALA    I45 @S9S_MB_2U_LIB.S9S_MB_2U(SCH_1):PAGE226

TP_JTAG_BMC_A2 @S9S_MB_2U_LIB.S9S_MB_2U(SCH_1):TP_JTAG_BMC_A2
   U83   10     A2 GTL2014PW-GTL2014PW,SMLF,IC,ALA    I45 @S9S_MB_2U_LIB.S9S_MB_2U(SCH_1):PAGE226

TP_JTAG_CPU0_PLD_TDI @S9S_MB_2U_LIB.S9S_MB_2U(SCH_1):TP_JTAG_CPU0_PLD_TDI
    U2 CT22 RSVD136 SOCKET4677_AZIF0045P001C01CS-SA     I1 @S9S_MB_2U_LIB.S9S_MB_2U(SCH_1):PAGE15

TP_JTAG_CPU0_PLD_TDO @S9S_MB_2U_LIB.S9S_MB_2U(SCH_1):TP_JTAG_CPU0_PLD_TDO
    U2 CP22 RSVD127 SOCKET4677_AZIF0045P001C01CS-SA     I1 @S9S_MB_2U_LIB.S9S_MB_2U(SCH_1):PAGE15

TP_JTAG_CPU0_PLD_TMS @S9S_MB_2U_LIB.S9S_MB_2U(SCH_1):TP_JTAG_CPU0_PLD_TMS
    U2 CV22 RSVD140 SOCKET4677_AZIF0045P001C01CS-SA     I1 @S9S_MB_2U_LIB.S9S_MB_2U(SCH_1):PAGE15

TP_JTAG_CPU1_PLD_TDI @S9S_MB_2U_LIB.S9S_MB_2U(SCH_1):TP_JTAG_CPU1_PLD_TDI
    U1 CT22 RSVD136 SOCKET4677_AZIF0045P001C01CS-SA     I5 @S9S_MB_2U_LIB.S9S_MB_2U(SCH_1):PAGE46

TP_JTAG_CPU1_PLD_TDO_R @S9S_MB_2U_LIB.S9S_MB_2U(SCH_1):TP_JTAG_CPU1_PLD_TDO_R
    U1 CP22 RSVD127 SOCKET4677_AZIF0045P001C01CS-SA     I5 @S9S_MB_2U_LIB.S9S_MB_2U(SCH_1):PAGE46

TP_JTAG_CPU1_PLD_TMS @S9S_MB_2U_LIB.S9S_MB_2U(SCH_1):TP_JTAG_CPU1_PLD_TMS
    U1 CV22 RSVD140 SOCKET4677_AZIF0045P001C01CS-SA     I5 @S9S_MB_2U_LIB.S9S_MB_2U(SCH_1):PAGE46

TP_OCP_SFF_B68 @S9S_MB_2U_LIB.S9S_MB_2U(SCH_1):TP_OCP_SFF_B68
   J37  B68 RFU1_NC_B68 SCONN168_ME1016810202011-SCONNA   I199 @S9S_MB_2U_LIB.S9S_MB_2U(SCH_1):PAGE150

TP_OCP_SFF_B69 @S9S_MB_2U_LIB.S9S_MB_2U(SCH_1):TP_OCP_SFF_B69
   J37  B69 RFU1_NC_B69 SCONN168_ME1016810202011-SCONNA   I199 @S9S_MB_2U_LIB.S9S_MB_2U(SCH_1):PAGE150

TP_OCP_V3_2_B68 @S9S_MB_2U_LIB.S9S_MB_2U(SCH_1):TP_OCP_V3_2_B68
   J35  B68 RFU1_NC_B68 SCONN168_ME1016810202011-SCONNA   I303 @S9S_MB_2U_LIB.S9S_MB_2U(SCH_1):PAGE146

TP_OCP_V3_2_B69 @S9S_MB_2U_LIB.S9S_MB_2U(SCH_1):TP_OCP_V3_2_B69
   J35  B69 RFU1_NC_B69 SCONN168_ME1016810202011-SCONNA   I303 @S9S_MB_2U_LIB.S9S_MB_2U(SCH_1):PAGE146

TP_P3E_PCH_12_RX_DN @S9S_MB_2U_LIB.S9S_MB_2U(SCH_1):TP_P3E_PCH_12_RX_DN
    U4  K41 SATA_12_PCIE3_12_GBE_1_RXN EMMITSBURG_REV0P9-GFNOCPU04302A   I110 @S9S_MB_2U_LIB.S9S_MB_2U(SCH_1):PAGE173

TP_P3E_PCH_12_RX_DP @S9S_MB_2U_LIB.S9S_MB_2U(SCH_1):TP_P3E_PCH_12_RX_DP
    U4  K43 SATA_12_PCIE3_12_GBE_1_RXP EMMITSBURG_REV0P9-GFNOCPU04302A   I110 @S9S_MB_2U_LIB.S9S_MB_2U(SCH_1):PAGE173

TP_P3E_PCH_12_TX_DN @S9S_MB_2U_LIB.S9S_MB_2U(SCH_1):TP_P3E_PCH_12_TX_DN
    U4  V34 SATA_12_PCIE3_12_GBE_1_TXN EMMITSBURG_REV0P9-GFNOCPU04302A   I110 @S9S_MB_2U_LIB.S9S_MB_2U(SCH_1):PAGE173

TP_P3E_PCH_12_TX_DP @S9S_MB_2U_LIB.S9S_MB_2U(SCH_1):TP_P3E_PCH_12_TX_DP
    U4  U36 SATA_12_PCIE3_12_GBE_1_TXP EMMITSBURG_REV0P9-GFNOCPU04302A   I110 @S9S_MB_2U_LIB.S9S_MB_2U(SCH_1):PAGE173

TP_P3E_PCH_13_RX_DN @S9S_MB_2U_LIB.S9S_MB_2U(SCH_1):TP_P3E_PCH_13_RX_DN
    U4  J40 SATA_13_PCIE3_13_RXN EMMITSBURG_REV0P9-GFNOCPU04302A   I110 @S9S_MB_2U_LIB.S9S_MB_2U(SCH_1):PAGE173

TP_P3E_PCH_13_RX_DP @S9S_MB_2U_LIB.S9S_MB_2U(SCH_1):TP_P3E_PCH_13_RX_DP
    U4  J42 SATA_13_PCIE3_13_RXP EMMITSBURG_REV0P9-GFNOCPU04302A   I110 @S9S_MB_2U_LIB.S9S_MB_2U(SCH_1):PAGE173

TP_P3E_PCH_13_TX_DN @S9S_MB_2U_LIB.S9S_MB_2U(SCH_1):TP_P3E_PCH_13_TX_DN
    U4  U32 SATA_13_PCIE3_13_TXN EMMITSBURG_REV0P9-GFNOCPU04302A   I110 @S9S_MB_2U_LIB.S9S_MB_2U(SCH_1):PAGE173

TP_P3E_PCH_13_TX_DP @S9S_MB_2U_LIB.S9S_MB_2U(SCH_1):TP_P3E_PCH_13_TX_DP
    U4  W32 SATA_13_PCIE3_13_TXP EMMITSBURG_REV0P9-GFNOCPU04302A   I110 @S9S_MB_2U_LIB.S9S_MB_2U(SCH_1):PAGE173

TP_P3E_PCH_14_RX_DN @S9S_MB_2U_LIB.S9S_MB_2U(SCH_1):TP_P3E_PCH_14_RX_DN
    U4  H41 SATA_14_PCIE3_14_GBE_2_RXN EMMITSBURG_REV0P9-GFNOCPU04302A   I110 @S9S_MB_2U_LIB.S9S_MB_2U(SCH_1):PAGE173

TP_P3E_PCH_14_RX_DP @S9S_MB_2U_LIB.S9S_MB_2U(SCH_1):TP_P3E_PCH_14_RX_DP
    U4  H43 SATA_14_PCIE3_14_GBE_2_RXP EMMITSBURG_REV0P9-GFNOCPU04302A   I110 @S9S_MB_2U_LIB.S9S_MB_2U(SCH_1):PAGE173

TP_P3E_PCH_14_TX_DN @S9S_MB_2U_LIB.S9S_MB_2U(SCH_1):TP_P3E_PCH_14_TX_DN
    U4  R32 SATA_14_PCIE3_14_GBE_2_TXN EMMITSBURG_REV0P9-GFNOCPU04302A   I110 @S9S_MB_2U_LIB.S9S_MB_2U(SCH_1):PAGE173

TP_P3E_PCH_14_TX_DP @S9S_MB_2U_LIB.S9S_MB_2U(SCH_1):TP_P3E_PCH_14_TX_DP
    U4  T34 SATA_14_PCIE3_14_GBE_2_TXP EMMITSBURG_REV0P9-GFNOCPU04302A   I110 @S9S_MB_2U_LIB.S9S_MB_2U(SCH_1):PAGE173

TP_P3E_PCH_15_RX_DN @S9S_MB_2U_LIB.S9S_MB_2U(SCH_1):TP_P3E_PCH_15_RX_DN
    U4  G40 SATA_15_PCIE3_15_RXN EMMITSBURG_REV0P9-GFNOCPU04302A   I110 @S9S_MB_2U_LIB.S9S_MB_2U(SCH_1):PAGE173

TP_P3E_PCH_15_RX_DP @S9S_MB_2U_LIB.S9S_MB_2U(SCH_1):TP_P3E_PCH_15_RX_DP
    U4  G42 SATA_15_PCIE3_15_RXP EMMITSBURG_REV0P9-GFNOCPU04302A   I110 @S9S_MB_2U_LIB.S9S_MB_2U(SCH_1):PAGE173

TP_P3E_PCH_15_TX_DN @S9S_MB_2U_LIB.S9S_MB_2U(SCH_1):TP_P3E_PCH_15_TX_DN
    U4  P34 SATA_15_PCIE3_15_TXN EMMITSBURG_REV0P9-GFNOCPU04302A   I110 @S9S_MB_2U_LIB.S9S_MB_2U(SCH_1):PAGE173

TP_P3E_PCH_15_TX_DP @S9S_MB_2U_LIB.S9S_MB_2U(SCH_1):TP_P3E_PCH_15_TX_DP
    U4  N36 SATA_15_PCIE3_15_TXP EMMITSBURG_REV0P9-GFNOCPU04302A   I110 @S9S_MB_2U_LIB.S9S_MB_2U(SCH_1):PAGE173

TP_P3V3_E1S_PWRGD_0 @S9S_MB_2U_LIB.S9S_MB_2U(SCH_1):TP_P3V3_E1S_PWRGD_0
 R3973    2      B Q_RES_0402LF-0,5%,1/16W,CHIP,CA    I44 @S9S_MB_2U_LIB.S9S_MB_2U(SCH_1):PAGE324
 R3979    2      B Q_RES_0402LF-100K,1%,1/16W,CHIA    I50 @S9S_MB_2U_LIB.S9S_MB_2U(SCH_1):PAGE324

TP_PCA9555_0_P00 @S9S_MB_2U_LIB.S9S_MB_2U(SCH_1):TP_PCA9555_0_P00
  U209    4   P0_0 PCA9555APW-PCA9555APW,SMLF,IC,A   I206 @S9S_MB_2U_LIB.S9S_MB_2U(SCH_1):PAGE154

TP_PCA9555_0_P01 @S9S_MB_2U_LIB.S9S_MB_2U(SCH_1):TP_PCA9555_0_P01
  U209    5   P0_1 PCA9555APW-PCA9555APW,SMLF,IC,A   I206 @S9S_MB_2U_LIB.S9S_MB_2U(SCH_1):PAGE154

TP_PCA9555_0_P10 @S9S_MB_2U_LIB.S9S_MB_2U(SCH_1):TP_PCA9555_0_P10
  U209   13   P1_0 PCA9555APW-PCA9555APW,SMLF,IC,A   I206 @S9S_MB_2U_LIB.S9S_MB_2U(SCH_1):PAGE154

TP_PCA9555_0_P11 @S9S_MB_2U_LIB.S9S_MB_2U(SCH_1):TP_PCA9555_0_P11
  U209   14   P1_1 PCA9555APW-PCA9555APW,SMLF,IC,A   I206 @S9S_MB_2U_LIB.S9S_MB_2U(SCH_1):PAGE154

TP_PCA9555_0_P12 @S9S_MB_2U_LIB.S9S_MB_2U(SCH_1):TP_PCA9555_0_P12
  U209   15   P1_2 PCA9555APW-PCA9555APW,SMLF,IC,A   I206 @S9S_MB_2U_LIB.S9S_MB_2U(SCH_1):PAGE154

TP_PCA9555_0_P13 @S9S_MB_2U_LIB.S9S_MB_2U(SCH_1):TP_PCA9555_0_P13
  U209   16   P1_3 PCA9555APW-PCA9555APW,SMLF,IC,A   I206 @S9S_MB_2U_LIB.S9S_MB_2U(SCH_1):PAGE154

TP_PCA9555_0_P14 @S9S_MB_2U_LIB.S9S_MB_2U(SCH_1):TP_PCA9555_0_P14
  U209   17   P1_4 PCA9555APW-PCA9555APW,SMLF,IC,A   I206 @S9S_MB_2U_LIB.S9S_MB_2U(SCH_1):PAGE154

TP_PCA9555_0_P15 @S9S_MB_2U_LIB.S9S_MB_2U(SCH_1):TP_PCA9555_0_P15
  U209   18   P1_5 PCA9555APW-PCA9555APW,SMLF,IC,A   I206 @S9S_MB_2U_LIB.S9S_MB_2U(SCH_1):PAGE154

TP_PCA9555_0_P16 @S9S_MB_2U_LIB.S9S_MB_2U(SCH_1):TP_PCA9555_0_P16
  U209   19   P1_6 PCA9555APW-PCA9555APW,SMLF,IC,A   I206 @S9S_MB_2U_LIB.S9S_MB_2U(SCH_1):PAGE154

TP_PCA9555_0_P17 @S9S_MB_2U_LIB.S9S_MB_2U(SCH_1):TP_PCA9555_0_P17
  U209   20   P1_7 PCA9555APW-PCA9555APW,SMLF,IC,A   I206 @S9S_MB_2U_LIB.S9S_MB_2U(SCH_1):PAGE154

TP_PCA9555_0_P5 @S9S_MB_2U_LIB.S9S_MB_2U(SCH_1):TP_PCA9555_0_P5
  U209    9   P0_5 PCA9555APW-PCA9555APW,SMLF,IC,A   I206 @S9S_MB_2U_LIB.S9S_MB_2U(SCH_1):PAGE154

TP_PCA9555_0_P6 @S9S_MB_2U_LIB.S9S_MB_2U(SCH_1):TP_PCA9555_0_P6
  U209   10   P0_6 PCA9555APW-PCA9555APW,SMLF,IC,A   I206 @S9S_MB_2U_LIB.S9S_MB_2U(SCH_1):PAGE154

TP_PCA9555_0_P7 @S9S_MB_2U_LIB.S9S_MB_2U(SCH_1):TP_PCA9555_0_P7
  U209   11   P0_7 PCA9555APW-PCA9555APW,SMLF,IC,A   I206 @S9S_MB_2U_LIB.S9S_MB_2U(SCH_1):PAGE154

TP_PCA9555_U51_P00 @S9S_MB_2U_LIB.S9S_MB_2U(SCH_1):TP_PCA9555_U51_P00
   U51    4   P0_0 PCA9555APW-PCA9555APW,SMLF,IC,A    I66 @S9S_MB_2U_LIB.S9S_MB_2U(SCH_1):PAGE132

TP_PCA9555_U51_P01 @S9S_MB_2U_LIB.S9S_MB_2U(SCH_1):TP_PCA9555_U51_P01
   U51    5   P0_1 PCA9555APW-PCA9555APW,SMLF,IC,A    I66 @S9S_MB_2U_LIB.S9S_MB_2U(SCH_1):PAGE132

TP_PCA9555_U51_P05 @S9S_MB_2U_LIB.S9S_MB_2U(SCH_1):TP_PCA9555_U51_P05
   U51    9   P0_5 PCA9555APW-PCA9555APW,SMLF,IC,A    I66 @S9S_MB_2U_LIB.S9S_MB_2U(SCH_1):PAGE132

TP_PCA9555_U51_P06 @S9S_MB_2U_LIB.S9S_MB_2U(SCH_1):TP_PCA9555_U51_P06
   U51   10   P0_6 PCA9555APW-PCA9555APW,SMLF,IC,A    I66 @S9S_MB_2U_LIB.S9S_MB_2U(SCH_1):PAGE132

TP_PCA9555_U51_P07 @S9S_MB_2U_LIB.S9S_MB_2U(SCH_1):TP_PCA9555_U51_P07
   U51   11   P0_7 PCA9555APW-PCA9555APW,SMLF,IC,A    I66 @S9S_MB_2U_LIB.S9S_MB_2U(SCH_1):PAGE132

TP_PCA9555_U51_P10 @S9S_MB_2U_LIB.S9S_MB_2U(SCH_1):TP_PCA9555_U51_P10
   U51   13   P1_0 PCA9555APW-PCA9555APW,SMLF,IC,A    I66 @S9S_MB_2U_LIB.S9S_MB_2U(SCH_1):PAGE132

TP_PCA9555_U51_P11 @S9S_MB_2U_LIB.S9S_MB_2U(SCH_1):TP_PCA9555_U51_P11
   U51   14   P1_1 PCA9555APW-PCA9555APW,SMLF,IC,A    I66 @S9S_MB_2U_LIB.S9S_MB_2U(SCH_1):PAGE132

TP_PCA9555_U51_P12 @S9S_MB_2U_LIB.S9S_MB_2U(SCH_1):TP_PCA9555_U51_P12
   U51   15   P1_2 PCA9555APW-PCA9555APW,SMLF,IC,A    I66 @S9S_MB_2U_LIB.S9S_MB_2U(SCH_1):PAGE132

TP_PCA9555_U51_P13 @S9S_MB_2U_LIB.S9S_MB_2U(SCH_1):TP_PCA9555_U51_P13
   U51   16   P1_3 PCA9555APW-PCA9555APW,SMLF,IC,A    I66 @S9S_MB_2U_LIB.S9S_MB_2U(SCH_1):PAGE132

TP_PCA9555_U51_P14 @S9S_MB_2U_LIB.S9S_MB_2U(SCH_1):TP_PCA9555_U51_P14
   U51   17   P1_4 PCA9555APW-PCA9555APW,SMLF,IC,A    I66 @S9S_MB_2U_LIB.S9S_MB_2U(SCH_1):PAGE132

TP_PCA9555_U51_P15 @S9S_MB_2U_LIB.S9S_MB_2U(SCH_1):TP_PCA9555_U51_P15
   U51   18   P1_5 PCA9555APW-PCA9555APW,SMLF,IC,A    I66 @S9S_MB_2U_LIB.S9S_MB_2U(SCH_1):PAGE132

TP_PCA9555_U51_P16 @S9S_MB_2U_LIB.S9S_MB_2U(SCH_1):TP_PCA9555_U51_P16
   U51   19   P1_6 PCA9555APW-PCA9555APW,SMLF,IC,A    I66 @S9S_MB_2U_LIB.S9S_MB_2U(SCH_1):PAGE132

TP_PCA9555_U51_P17 @S9S_MB_2U_LIB.S9S_MB_2U(SCH_1):TP_PCA9555_U51_P17
   U51   20   P1_7 PCA9555APW-PCA9555APW,SMLF,IC,A    I66 @S9S_MB_2U_LIB.S9S_MB_2U(SCH_1):PAGE132

TP_PCH_CGC_DUT_DETECTED @S9S_MB_2U_LIB.S9S_MB_2U(SCH_1):TP_PCH_CGC_DUT_DETECTED
    U4  BG3 NC_CGC_DUT_DETECT_N EMMITSBURG_REV0P9-GFNOCPU04302A    I27 @S9S_MB_2U_LIB.S9S_MB_2U(SCH_1):PAGE177

TP_PCH_CPU_MEMTRIP_N @S9S_MB_2U_LIB.S9S_MB_2U(SCH_1):TP_PCH_CPU_MEMTRIP_N
    U4   E4 CPU_MEMTRIP_N EMMITSBURG_REV0P9-GFNOCPU04302A    I36 @S9S_MB_2U_LIB.S9S_MB_2U(SCH_1):PAGE174

TP_PCH_CPU_MSMI_N @S9S_MB_2U_LIB.S9S_MB_2U(SCH_1):TP_PCH_CPU_MSMI_N
    U4  F11 CPU_MSMI_N EMMITSBURG_REV0P9-GFNOCPU04302A    I36 @S9S_MB_2U_LIB.S9S_MB_2U(SCH_1):PAGE174

TP_PCH_GPP_D_2 @S9S_MB_2U_LIB.S9S_MB_2U(SCH_1):TP_PCH_GPP_D_2
    U4  AD2 GPP_D_2_HS_SMBALERT_N_DMA_SMBALERT_N EMMITSBURG_REV0P9-GFNOCPU04302A    I93 @S9S_MB_2U_LIB.S9S_MB_2U(SCH_1):PAGE175

TP_PCH_GPP_D_20 @S9S_MB_2U_LIB.S9S_MB_2U(SCH_1):TP_PCH_GPP_D_20
    U4  AG3 GPP_D_20_CATERR_N EMMITSBURG_REV0P9-GFNOCPU04302A    I93 @S9S_MB_2U_LIB.S9S_MB_2U(SCH_1):PAGE175

TP_PCH_GPP_E_0 @S9S_MB_2U_LIB.S9S_MB_2U(SCH_1):TP_PCH_GPP_E_0
    U4 BA26 GPP_E_0_SATA1_XPCIE_0 EMMITSBURG_REV0P9-GFNOCPU04302A    I22 @S9S_MB_2U_LIB.S9S_MB_2U(SCH_1):PAGE176

TP_PCH_GPP_E_1 @S9S_MB_2U_LIB.S9S_MB_2U(SCH_1):TP_PCH_GPP_E_1
    U4 BA23 GPP_E_1_SATA1_XPCIE_1 EMMITSBURG_REV0P9-GFNOCPU04302A    I22 @S9S_MB_2U_LIB.S9S_MB_2U(SCH_1):PAGE176

TP_PCH_GPP_E_2 @S9S_MB_2U_LIB.S9S_MB_2U(SCH_1):TP_PCH_GPP_E_2
    U4 AW23 GPP_E_2_SATA1_XPCIE_2 EMMITSBURG_REV0P9-GFNOCPU04302A    I22 @S9S_MB_2U_LIB.S9S_MB_2U(SCH_1):PAGE176

TP_PCH_GPP_N_1 @S9S_MB_2U_LIB.S9S_MB_2U(SCH_1):TP_PCH_GPP_N_1
    U4  T11 GPP_N_1 EMMITSBURG_REV0P9-GFNOCPU04302A    I27 @S9S_MB_2U_LIB.S9S_MB_2U(SCH_1):PAGE177

TP_PCH_GPP_N_4 @S9S_MB_2U_LIB.S9S_MB_2U(SCH_1):TP_PCH_GPP_N_4
    U4  V11 GPP_N_4 EMMITSBURG_REV0P9-GFNOCPU04302A    I27 @S9S_MB_2U_LIB.S9S_MB_2U(SCH_1):PAGE177

TP_PCH_GPP_O_11 @S9S_MB_2U_LIB.S9S_MB_2U(SCH_1):TP_PCH_GPP_O_11
    U4  AJ7 LANPHYPC EMMITSBURG_REV0P9-GFNOCPU04302A    I36 @S9S_MB_2U_LIB.S9S_MB_2U(SCH_1):PAGE174

TP_PCH_MGPIO_TEST1 @S9S_MB_2U_LIB.S9S_MB_2U(SCH_1):TP_PCH_MGPIO_TEST1
    U4   J2 GPPC_H_15_FLEX_CLK_OUT_0 EMMITSBURG_REV0P9-GFNOCPU04302A    I22 @S9S_MB_2U_LIB.S9S_MB_2U(SCH_1):PAGE176

TP_PCH_RSVD<0> @S9S_MB_2U_LIB.S9S_MB_2U(SCH_1):TP_PCH_RSVD(0)
    U4   H1 RSVD_H1 EMMITSBURG_REV0P9-GFNOCPU04302A     I4 @S9S_MB_2U_LIB.S9S_MB_2U(SCH_1):PAGE179

TP_PCH_RSVD<12> @S9S_MB_2U_LIB.S9S_MB_2U(SCH_1):TP_PCH_RSVD(12)
    U4  N13 RSVD_N13 EMMITSBURG_REV0P9-GFNOCPU04302A     I4 @S9S_MB_2U_LIB.S9S_MB_2U(SCH_1):PAGE179

TP_PCH_RSVD<13> @S9S_MB_2U_LIB.S9S_MB_2U(SCH_1):TP_PCH_RSVD(13)
    U4  L13 RSVD_L13 EMMITSBURG_REV0P9-GFNOCPU04302A     I4 @S9S_MB_2U_LIB.S9S_MB_2U(SCH_1):PAGE179

TP_PCH_RSVD<15> @S9S_MB_2U_LIB.S9S_MB_2U(SCH_1):TP_PCH_RSVD(15)
    U4 AN26 RSVD_AN26 EMMITSBURG_REV0P9-GFNOCPU04302A    I11 @S9S_MB_2U_LIB.S9S_MB_2U(SCH_1):PAGE178

TP_PCH_RSVD<16> @S9S_MB_2U_LIB.S9S_MB_2U(SCH_1):TP_PCH_RSVD(16)
    U4 AF15 RSVD_AF15 EMMITSBURG_REV0P9-GFNOCPU04302A    I11 @S9S_MB_2U_LIB.S9S_MB_2U(SCH_1):PAGE178

TP_PCH_RSVD<18> @S9S_MB_2U_LIB.S9S_MB_2U(SCH_1):TP_PCH_RSVD(18)
    U4  H24 RSVD_H24 EMMITSBURG_REV0P9-GFNOCPU04302A    I78 @S9S_MB_2U_LIB.S9S_MB_2U(SCH_1):PAGE171

TP_PCH_RSVD<19> @S9S_MB_2U_LIB.S9S_MB_2U(SCH_1):TP_PCH_RSVD(19)
    U4  J23 RSVD_J23 EMMITSBURG_REV0P9-GFNOCPU04302A    I78 @S9S_MB_2U_LIB.S9S_MB_2U(SCH_1):PAGE171

TP_PCH_RSVD<1> @S9S_MB_2U_LIB.S9S_MB_2U(SCH_1):TP_PCH_RSVD(1)
    U4   F1 RSVD_F1 EMMITSBURG_REV0P9-GFNOCPU04302A     I4 @S9S_MB_2U_LIB.S9S_MB_2U(SCH_1):PAGE179

TP_PCH_RSVD<2> @S9S_MB_2U_LIB.S9S_MB_2U(SCH_1):TP_PCH_RSVD(2)
    U4   A4 RSVD_A4 EMMITSBURG_REV0P9-GFNOCPU04302A     I4 @S9S_MB_2U_LIB.S9S_MB_2U(SCH_1):PAGE179

TP_PCH_RSVD<6> @S9S_MB_2U_LIB.S9S_MB_2U(SCH_1):TP_PCH_RSVD(6)
    U4  P18 RSVD_P18 EMMITSBURG_REV0P9-GFNOCPU04302A     I4 @S9S_MB_2U_LIB.S9S_MB_2U(SCH_1):PAGE179

TP_PCH_RSVD<7> @S9S_MB_2U_LIB.S9S_MB_2U(SCH_1):TP_PCH_RSVD(7)
    U4 BB43 RSVD_BB43 EMMITSBURG_REV0P9-GFNOCPU04302A     I4 @S9S_MB_2U_LIB.S9S_MB_2U(SCH_1):PAGE179

TP_PCH_SLP_A_N @S9S_MB_2U_LIB.S9S_MB_2U(SCH_1):TP_PCH_SLP_A_N
    U4 AM11 SLP_A_N EMMITSBURG_REV0P9-GFNOCPU04302A    I36 @S9S_MB_2U_LIB.S9S_MB_2U(SCH_1):PAGE174

TP_PCH_SLP_S5_N @S9S_MB_2U_LIB.S9S_MB_2U(SCH_1):TP_PCH_SLP_S5_N
    U4 AJ13 SLP_S5_N EMMITSBURG_REV0P9-GFNOCPU04302A    I36 @S9S_MB_2U_LIB.S9S_MB_2U(SCH_1):PAGE174

TP_PCIE_HPM_RXN<1> @S9S_MB_2U_LIB.S9S_MB_2U(SCH_1):TP_PCIE_HPM_RXN(1)
   J41  A63 PERP14 SCONN168_ME1016810202011-SCONNA   I173 @S9S_MB_2U_LIB.S9S_MB_2U(SCH_1):PAGE227

TP_PCIE_HPM_RXP<1> @S9S_MB_2U_LIB.S9S_MB_2U(SCH_1):TP_PCIE_HPM_RXP(1)
   J41  A62 PERN14 SCONN168_ME1016810202011-SCONNA   I173 @S9S_MB_2U_LIB.S9S_MB_2U(SCH_1):PAGE227

TP_PCIE_HPM_TXN<1> @S9S_MB_2U_LIB.S9S_MB_2U(SCH_1):TP_PCIE_HPM_TXN(1)
   J41  B63 PETP14 SCONN168_ME1016810202011-SCONNA   I173 @S9S_MB_2U_LIB.S9S_MB_2U(SCH_1):PAGE227

TP_PCIE_HPM_TXN<3> @S9S_MB_2U_LIB.S9S_MB_2U(SCH_1):TP_PCIE_HPM_TXN(3)
 R3302    1      A Q_RES_0402LF-0,5%,1/16W,EMPTY,A    I48 @S9S_MB_2U_LIB.S9S_MB_2U(SCH_1):PAGE227
   J41  B69 RFU1_NC_B69 SCONN168_ME1016810202011-SCONNA   I173 @S9S_MB_2U_LIB.S9S_MB_2U(SCH_1):PAGE227

TP_PCIE_HPM_TXP<1> @S9S_MB_2U_LIB.S9S_MB_2U(SCH_1):TP_PCIE_HPM_TXP(1)
   J41  B62 PETN14 SCONN168_ME1016810202011-SCONNA   I173 @S9S_MB_2U_LIB.S9S_MB_2U(SCH_1):PAGE227

TP_PCIE_HPM_TXP<3> @S9S_MB_2U_LIB.S9S_MB_2U(SCH_1):TP_PCIE_HPM_TXP(3)
 R3254    1      A Q_RES_0402LF-0,5%,1/16W,EMPTY,A    I49 @S9S_MB_2U_LIB.S9S_MB_2U(SCH_1):PAGE227
   J41  B68 RFU1_NC_B68 SCONN168_ME1016810202011-SCONNA   I173 @S9S_MB_2U_LIB.S9S_MB_2U(SCH_1):PAGE227

TP_PLD_CONN_P4 @S9S_MB_2U_LIB.S9S_MB_2U(SCH_1):TP_PLD_CONN_P4
   J43    4      4 CONN8_210HP1080BR1-CONN8_210-HA    I79 @S9S_MB_2U_LIB.S9S_MB_2U(SCH_1):PAGE210

TP_PLD_CONN_P5 @S9S_MB_2U_LIB.S9S_MB_2U(SCH_1):TP_PLD_CONN_P5
   J43    5      5 CONN8_210HP1080BR1-CONN8_210-HA    I79 @S9S_MB_2U_LIB.S9S_MB_2U(SCH_1):PAGE210

TP_PLTRST_N @S9S_MB_2U_LIB.S9S_MB_2U(SCH_1):TP_PLTRST_N
    U4   M8 PLTRST_CPU_N EMMITSBURG_REV0P9-GFNOCPU04302A    I36 @S9S_MB_2U_LIB.S9S_MB_2U(SCH_1):PAGE174

TP_PWRGD_S0_PWROK_CPU0_LVC1 @S9S_MB_2U_LIB.S9S_MB_2U(SCH_1):TP_PWRGD_S0_PWROK_CPU0_LVC1
    U2 CH71 RSVD100 SOCKET4677_AZIF0045P001C01CS-SA     I1 @S9S_MB_2U_LIB.S9S_MB_2U(SCH_1):PAGE15

TP_PWRGD_S0_PWROK_CPU1_LVC1 @S9S_MB_2U_LIB.S9S_MB_2U(SCH_1):TP_PWRGD_S0_PWROK_CPU1_LVC1
    U1 CH71 RSVD100 SOCKET4677_AZIF0045P001C01CS-SA     I5 @S9S_MB_2U_LIB.S9S_MB_2U(SCH_1):PAGE46

TP_RST_ESPI_IBL_CPU0_LVC1_N @S9S_MB_2U_LIB.S9S_MB_2U(SCH_1):TP_RST_ESPI_IBL_CPU0_LVC1_N
    U2 BG64 RSVD53 SOCKET4677_AZIF0045P001C01CS-SA     I1 @S9S_MB_2U_LIB.S9S_MB_2U(SCH_1):PAGE15

TP_SGPIO_S3M_CPU0_GSXCLK_R @S9S_MB_2U_LIB.S9S_MB_2U(SCH_1):TP_SGPIO_S3M_CPU0_GSXCLK_R
    U2 CF63 RSVD93 SOCKET4677_AZIF0045P001C01CS-SA     I1 @S9S_MB_2U_LIB.S9S_MB_2U(SCH_1):PAGE15

TP_SGPIO_S3M_CPU0_GSXDIN @S9S_MB_2U_LIB.S9S_MB_2U(SCH_1):TP_SGPIO_S3M_CPU0_GSXDIN
    U2 CH63 RSVD98 SOCKET4677_AZIF0045P001C01CS-SA     I1 @S9S_MB_2U_LIB.S9S_MB_2U(SCH_1):PAGE15

TP_SGPIO_S3M_CPU0_GSXDLOAD_R @S9S_MB_2U_LIB.S9S_MB_2U(SCH_1):TP_SGPIO_S3M_CPU0_GSXDLOAD_R
    U2 CJ66 RSVD105 SOCKET4677_AZIF0045P001C01CS-SA     I1 @S9S_MB_2U_LIB.S9S_MB_2U(SCH_1):PAGE15

TP_SGPIO_S3M_CPU0_GSXDOUT_R @S9S_MB_2U_LIB.S9S_MB_2U(SCH_1):TP_SGPIO_S3M_CPU0_GSXDOUT_R
    U2 CF65 RSVD94 SOCKET4677_AZIF0045P001C01CS-SA     I1 @S9S_MB_2U_LIB.S9S_MB_2U(SCH_1):PAGE15

TP_SGPIO_S3M_CPU0_RST_R_N @S9S_MB_2U_LIB.S9S_MB_2U(SCH_1):TP_SGPIO_S3M_CPU0_RST_R_N
    U2 CD65 RSVD86 SOCKET4677_AZIF0045P001C01CS-SA     I1 @S9S_MB_2U_LIB.S9S_MB_2U(SCH_1):PAGE15

TP_SGPIO_S3M_CPU1_GSXCLK @S9S_MB_2U_LIB.S9S_MB_2U(SCH_1):TP_SGPIO_S3M_CPU1_GSXCLK
    U1 CF63 RSVD93 SOCKET4677_AZIF0045P001C01CS-SA     I5 @S9S_MB_2U_LIB.S9S_MB_2U(SCH_1):PAGE46

TP_SGPIO_S3M_CPU1_GSXDIN @S9S_MB_2U_LIB.S9S_MB_2U(SCH_1):TP_SGPIO_S3M_CPU1_GSXDIN
    U1 CH63 RSVD98 SOCKET4677_AZIF0045P001C01CS-SA     I5 @S9S_MB_2U_LIB.S9S_MB_2U(SCH_1):PAGE46

TP_SGPIO_S3M_CPU1_GSXDLOAD @S9S_MB_2U_LIB.S9S_MB_2U(SCH_1):TP_SGPIO_S3M_CPU1_GSXDLOAD
    U1 CJ66 RSVD105 SOCKET4677_AZIF0045P001C01CS-SA     I5 @S9S_MB_2U_LIB.S9S_MB_2U(SCH_1):PAGE46

TP_SGPIO_S3M_CPU1_GSXDOUT @S9S_MB_2U_LIB.S9S_MB_2U(SCH_1):TP_SGPIO_S3M_CPU1_GSXDOUT
    U1 CF65 RSVD94 SOCKET4677_AZIF0045P001C01CS-SA     I5 @S9S_MB_2U_LIB.S9S_MB_2U(SCH_1):PAGE46

TP_SGPIO_S3M_CPU1_GSXRST_N @S9S_MB_2U_LIB.S9S_MB_2U(SCH_1):TP_SGPIO_S3M_CPU1_GSXRST_N
    U1 CD65 RSVD86 SOCKET4677_AZIF0045P001C01CS-SA     I5 @S9S_MB_2U_LIB.S9S_MB_2U(SCH_1):PAGE46

TP_SLP_LAN_N @S9S_MB_2U_LIB.S9S_MB_2U(SCH_1):TP_SLP_LAN_N
    U4  AK8 SLP_LAN_N EMMITSBURG_REV0P9-GFNOCPU04302A    I36 @S9S_MB_2U_LIB.S9S_MB_2U(SCH_1):PAGE174

TP_SMB_PEHPCPU0_EN @S9S_MB_2U_LIB.S9S_MB_2U(SCH_1):TP_SMB_PEHPCPU0_EN
   U28    5     EN PCA9617ADP-PCA9617ADP,SMLF,IC,A    I39 @S9S_MB_2U_LIB.S9S_MB_2U(SCH_1):PAGE223

TP_SMB_PEHPCPU1_EN @S9S_MB_2U_LIB.S9S_MB_2U(SCH_1):TP_SMB_PEHPCPU1_EN
   U29    5     EN PCA9617ADP-PCA9617ADP,SMLF,IC,A    I43 @S9S_MB_2U_LIB.S9S_MB_2U(SCH_1):PAGE223

TP_SMB_S3M_CPU0_EN @S9S_MB_2U_LIB.S9S_MB_2U(SCH_1):TP_SMB_S3M_CPU0_EN
   U30    5 ENABLE PCA9517AD-PCA9517AD,SMLF,IC,ALA    I28 @S9S_MB_2U_LIB.S9S_MB_2U(SCH_1):PAGE224

TP_SMB_S3M_CPU1_EN @S9S_MB_2U_LIB.S9S_MB_2U(SCH_1):TP_SMB_S3M_CPU1_EN
   U31    5 ENABLE PCA9517AD-PCA9517AD,SMLF,IC,ALA    I37 @S9S_MB_2U_LIB.S9S_MB_2U(SCH_1):PAGE224

TP_SPI_2_PLD_CLK @S9S_MB_2U_LIB.S9S_MB_2U(SCH_1):TP_SPI_2_PLD_CLK
   J41  B43 GND_B43 SCONN168_ME1016810202011-SCONNA   I173 @S9S_MB_2U_LIB.S9S_MB_2U(SCH_1):PAGE227

TP_SPI_2_PLD_CS_N @S9S_MB_2U_LIB.S9S_MB_2U(SCH_1):TP_SPI_2_PLD_CS_N
   J41  B44  PETN8 SCONN168_ME1016810202011-SCONNA   I173 @S9S_MB_2U_LIB.S9S_MB_2U(SCH_1):PAGE227

TP_SPI_2_PLD_IO0 @S9S_MB_2U_LIB.S9S_MB_2U(SCH_1):TP_SPI_2_PLD_IO0
   J41  B45  PETP8 SCONN168_ME1016810202011-SCONNA   I173 @S9S_MB_2U_LIB.S9S_MB_2U(SCH_1):PAGE227

TP_SPI_2_PLD_IO1 @S9S_MB_2U_LIB.S9S_MB_2U(SCH_1):TP_SPI_2_PLD_IO1
   J41  B46 GND_B46 SCONN168_ME1016810202011-SCONNA   I173 @S9S_MB_2U_LIB.S9S_MB_2U(SCH_1):PAGE227

TP_SPI_2_PLD_IO2 @S9S_MB_2U_LIB.S9S_MB_2U(SCH_1):TP_SPI_2_PLD_IO2
   J41  B47  PETN9 SCONN168_ME1016810202011-SCONNA   I173 @S9S_MB_2U_LIB.S9S_MB_2U(SCH_1):PAGE227

TP_SPI_2_PLD_IO3 @S9S_MB_2U_LIB.S9S_MB_2U(SCH_1):TP_SPI_2_PLD_IO3
   J41  B48  PETP9 SCONN168_ME1016810202011-SCONNA   I173 @S9S_MB_2U_LIB.S9S_MB_2U(SCH_1):PAGE227

TP_SPI_IBL_CPU0_TPM_CLK @S9S_MB_2U_LIB.S9S_MB_2U(SCH_1):TP_SPI_IBL_CPU0_TPM_CLK
    U2 AU62 RSVD11 SOCKET4677_AZIF0045P001C01CS-SA     I1 @S9S_MB_2U_LIB.S9S_MB_2U(SCH_1):PAGE15

TP_SPI_IBL_CPU0_TPM_CS0_N @S9S_MB_2U_LIB.S9S_MB_2U(SCH_1):TP_SPI_IBL_CPU0_TPM_CS0_N
    U2 AY67 RSVD30 SOCKET4677_AZIF0045P001C01CS-SA     I1 @S9S_MB_2U_LIB.S9S_MB_2U(SCH_1):PAGE15

TP_SPI_IBL_CPU0_TPM_IO0 @S9S_MB_2U_LIB.S9S_MB_2U(SCH_1):TP_SPI_IBL_CPU0_TPM_IO0
    U2 BA66 RSVD33 SOCKET4677_AZIF0045P001C01CS-SA     I1 @S9S_MB_2U_LIB.S9S_MB_2U(SCH_1):PAGE15

TP_SPI_IBL_CPU0_TPM_IO1 @S9S_MB_2U_LIB.S9S_MB_2U(SCH_1):TP_SPI_IBL_CPU0_TPM_IO1
    U2 AY61 RSVD28 SOCKET4677_AZIF0045P001C01CS-SA     I1 @S9S_MB_2U_LIB.S9S_MB_2U(SCH_1):PAGE15

TP_SPI_IBL_CPU0_TPM_OE_N @S9S_MB_2U_LIB.S9S_MB_2U(SCH_1):TP_SPI_IBL_CPU0_TPM_OE_N
    U2 BB67 RSVD36 SOCKET4677_AZIF0045P001C01CS-SA     I1 @S9S_MB_2U_LIB.S9S_MB_2U(SCH_1):PAGE15

TP_SPI_PCH_CS1_R_N @S9S_MB_2U_LIB.S9S_MB_2U(SCH_1):TP_SPI_PCH_CS1_R_N
    U4 BA10 SPI0_FLASH_1_CS_N EMMITSBURG_REV0P9-GFNOCPU04302A    I27 @S9S_MB_2U_LIB.S9S_MB_2U(SCH_1):PAGE177

TP_SPI_S3M_CPU0_CLK_LVC1_R @S9S_MB_2U_LIB.S9S_MB_2U(SCH_1):TP_SPI_S3M_CPU0_CLK_LVC1_R
    U2 BC64 RSVD39 SOCKET4677_AZIF0045P001C01CS-SA     I1 @S9S_MB_2U_LIB.S9S_MB_2U(SCH_1):PAGE15

TP_SPI_S3M_CPU0_CS0_LVC1_R_N @S9S_MB_2U_LIB.S9S_MB_2U(SCH_1):TP_SPI_S3M_CPU0_CS0_LVC1_R_N
    U2 BB61 RSVD35 SOCKET4677_AZIF0045P001C01CS-SA     I1 @S9S_MB_2U_LIB.S9S_MB_2U(SCH_1):PAGE15

TP_SPI_S3M_CPU0_CS1_LVC1_R_N @S9S_MB_2U_LIB.S9S_MB_2U(SCH_1):TP_SPI_S3M_CPU0_CS1_LVC1_R_N
    U2 AV63 RSVD20 SOCKET4677_AZIF0045P001C01CS-SA     I1 @S9S_MB_2U_LIB.S9S_MB_2U(SCH_1):PAGE15

TP_SPI_S3M_CPU0_IO0_LVC1_R @S9S_MB_2U_LIB.S9S_MB_2U(SCH_1):TP_SPI_S3M_CPU0_IO0_LVC1_R
    U2 BA62 RSVD32 SOCKET4677_AZIF0045P001C01CS-SA     I1 @S9S_MB_2U_LIB.S9S_MB_2U(SCH_1):PAGE15

TP_SPI_S3M_CPU0_IO1_LVC1_R @S9S_MB_2U_LIB.S9S_MB_2U(SCH_1):TP_SPI_S3M_CPU0_IO1_LVC1_R
    U2 AW64 RSVD24 SOCKET4677_AZIF0045P001C01CS-SA     I1 @S9S_MB_2U_LIB.S9S_MB_2U(SCH_1):PAGE15

TP_SPI_S3M_CPU0_IO2_LVC1_R @S9S_MB_2U_LIB.S9S_MB_2U(SCH_1):TP_SPI_S3M_CPU0_IO2_LVC1_R
    U2 BD65 RSVD42 SOCKET4677_AZIF0045P001C01CS-SA     I1 @S9S_MB_2U_LIB.S9S_MB_2U(SCH_1):PAGE15

TP_SPI_S3M_CPU0_IO3_LVC1_R @S9S_MB_2U_LIB.S9S_MB_2U(SCH_1):TP_SPI_S3M_CPU0_IO3_LVC1_R
    U2 BD61 RSVD40 SOCKET4677_AZIF0045P001C01CS-SA     I1 @S9S_MB_2U_LIB.S9S_MB_2U(SCH_1):PAGE15

TP_SPI_S3M_CPU0_OE_LVC1_R_N @S9S_MB_2U_LIB.S9S_MB_2U(SCH_1):TP_SPI_S3M_CPU0_OE_LVC1_R_N
    U2 BA68 RSVD34 SOCKET4677_AZIF0045P001C01CS-SA     I1 @S9S_MB_2U_LIB.S9S_MB_2U(SCH_1):PAGE15

TP_TCA9539_0_P0_2 @S9S_MB_2U_LIB.S9S_MB_2U(SCH_1):TP_TCA9539_0_P0_2
  U181    6  IO0_2 PCA9539RPW-PCA9539RPW,SMLF,IC,A    I66 @S9S_MB_2U_LIB.S9S_MB_2U(SCH_1):PAGE214

TP_TCA9539_0_P0_3 @S9S_MB_2U_LIB.S9S_MB_2U(SCH_1):TP_TCA9539_0_P0_3
  U181    7  IO0_3 PCA9539RPW-PCA9539RPW,SMLF,IC,A    I66 @S9S_MB_2U_LIB.S9S_MB_2U(SCH_1):PAGE214

TP_TP_TRC_CPU0_PTI_MON<0> @S9S_MB_2U_LIB.S9S_MB_2U(SCH_1):TP_TP_TRC_CPU0_PTI_MON(0)
    U2 CC29 PTI_DIE000 SOCKET4677_AZIF0045P001C01CS-SA     I1 @S9S_MB_2U_LIB.S9S_MB_2U(SCH_1):PAGE19

TP_TRC_CPU0_PTI0_CLK @S9S_MB_2U_LIB.S9S_MB_2U(SCH_1):TP_TRC_CPU0_PTI0_CLK
    U2 CB30 PTI_DIE00_STB_0 SOCKET4677_AZIF0045P001C01CS-SA     I1 @S9S_MB_2U_LIB.S9S_MB_2U(SCH_1):PAGE19

TP_TRC_CPU0_PTI1_CLK @S9S_MB_2U_LIB.S9S_MB_2U(SCH_1):TP_TRC_CPU0_PTI1_CLK
    U2 BY28 PTI_DIE00_STB_1 SOCKET4677_AZIF0045P001C01CS-SA     I1 @S9S_MB_2U_LIB.S9S_MB_2U(SCH_1):PAGE19

TP_TRC_CPU0_PTI2_CLK @S9S_MB_2U_LIB.S9S_MB_2U(SCH_1):TP_TRC_CPU0_PTI2_CLK
    U2 BF67 PTI_DIE01_STB_0 SOCKET4677_AZIF0045P001C01CS-SA     I1 @S9S_MB_2U_LIB.S9S_MB_2U(SCH_1):PAGE19

TP_TRC_CPU0_PTI3_CLK @S9S_MB_2U_LIB.S9S_MB_2U(SCH_1):TP_TRC_CPU0_PTI3_CLK
    U2 BK67 PTI_DIE01_STB_1 SOCKET4677_AZIF0045P001C01CS-SA     I1 @S9S_MB_2U_LIB.S9S_MB_2U(SCH_1):PAGE19

TP_TRC_CPU0_PTI<10> @S9S_MB_2U_LIB.S9S_MB_2U(SCH_1):TP_TRC_CPU0_PTI(10)
    U2 BU29 PTI_DIE0010 SOCKET4677_AZIF0045P001C01CS-SA     I1 @S9S_MB_2U_LIB.S9S_MB_2U(SCH_1):PAGE19

TP_TRC_CPU0_PTI<11> @S9S_MB_2U_LIB.S9S_MB_2U(SCH_1):TP_TRC_CPU0_PTI(11)
    U2 BT30 PTI_DIE0011 SOCKET4677_AZIF0045P001C01CS-SA     I1 @S9S_MB_2U_LIB.S9S_MB_2U(SCH_1):PAGE19

TP_TRC_CPU0_PTI<12> @S9S_MB_2U_LIB.S9S_MB_2U(SCH_1):TP_TRC_CPU0_PTI(12)
    U2 BN27 PTI_DIE0012 SOCKET4677_AZIF0045P001C01CS-SA     I1 @S9S_MB_2U_LIB.S9S_MB_2U(SCH_1):PAGE19

TP_TRC_CPU0_PTI<13> @S9S_MB_2U_LIB.S9S_MB_2U(SCH_1):TP_TRC_CPU0_PTI(13)
    U2 BP28 PTI_DIE0013 SOCKET4677_AZIF0045P001C01CS-SA     I1 @S9S_MB_2U_LIB.S9S_MB_2U(SCH_1):PAGE19

TP_TRC_CPU0_PTI<14> @S9S_MB_2U_LIB.S9S_MB_2U(SCH_1):TP_TRC_CPU0_PTI(14)
    U2 BN29 PTI_DIE0014 SOCKET4677_AZIF0045P001C01CS-SA     I1 @S9S_MB_2U_LIB.S9S_MB_2U(SCH_1):PAGE19

TP_TRC_CPU0_PTI<15> @S9S_MB_2U_LIB.S9S_MB_2U(SCH_1):TP_TRC_CPU0_PTI(15)
    U2 BP30 PTI_DIE0015 SOCKET4677_AZIF0045P001C01CS-SA     I1 @S9S_MB_2U_LIB.S9S_MB_2U(SCH_1):PAGE19

TP_TRC_CPU0_PTI<16> @S9S_MB_2U_LIB.S9S_MB_2U(SCH_1):TP_TRC_CPU0_PTI(16)
    U2 BC70 PTI_DIE010 SOCKET4677_AZIF0045P001C01CS-SA     I1 @S9S_MB_2U_LIB.S9S_MB_2U(SCH_1):PAGE19

TP_TRC_CPU0_PTI<17> @S9S_MB_2U_LIB.S9S_MB_2U(SCH_1):TP_TRC_CPU0_PTI(17)
    U2 BE70 PTI_DIE011 SOCKET4677_AZIF0045P001C01CS-SA     I1 @S9S_MB_2U_LIB.S9S_MB_2U(SCH_1):PAGE19

TP_TRC_CPU0_PTI<18> @S9S_MB_2U_LIB.S9S_MB_2U(SCH_1):TP_TRC_CPU0_PTI(18)
    U2 BD69 PTI_DIE012 SOCKET4677_AZIF0045P001C01CS-SA     I1 @S9S_MB_2U_LIB.S9S_MB_2U(SCH_1):PAGE19

TP_TRC_CPU0_PTI<19> @S9S_MB_2U_LIB.S9S_MB_2U(SCH_1):TP_TRC_CPU0_PTI(19)
    U2 BF69 PTI_DIE013 SOCKET4677_AZIF0045P001C01CS-SA     I1 @S9S_MB_2U_LIB.S9S_MB_2U(SCH_1):PAGE19

TP_TRC_CPU0_PTI<20> @S9S_MB_2U_LIB.S9S_MB_2U(SCH_1):TP_TRC_CPU0_PTI(20)
    U2 BH69 PTI_DIE014 SOCKET4677_AZIF0045P001C01CS-SA     I1 @S9S_MB_2U_LIB.S9S_MB_2U(SCH_1):PAGE19

TP_TRC_CPU0_PTI<21> @S9S_MB_2U_LIB.S9S_MB_2U(SCH_1):TP_TRC_CPU0_PTI(21)
    U2 BC68 PTI_DIE015 SOCKET4677_AZIF0045P001C01CS-SA     I1 @S9S_MB_2U_LIB.S9S_MB_2U(SCH_1):PAGE19

TP_TRC_CPU0_PTI<22> @S9S_MB_2U_LIB.S9S_MB_2U(SCH_1):TP_TRC_CPU0_PTI(22)
    U2 BG68 PTI_DIE016 SOCKET4677_AZIF0045P001C01CS-SA     I1 @S9S_MB_2U_LIB.S9S_MB_2U(SCH_1):PAGE19

TP_TRC_CPU0_PTI<23> @S9S_MB_2U_LIB.S9S_MB_2U(SCH_1):TP_TRC_CPU0_PTI(23)
    U2 BD67 PTI_DIE017 SOCKET4677_AZIF0045P001C01CS-SA     I1 @S9S_MB_2U_LIB.S9S_MB_2U(SCH_1):PAGE19

TP_TRC_CPU0_PTI<24> @S9S_MB_2U_LIB.S9S_MB_2U(SCH_1):TP_TRC_CPU0_PTI(24)
    U2 BK69 PTI_DIE018 SOCKET4677_AZIF0045P001C01CS-SA     I1 @S9S_MB_2U_LIB.S9S_MB_2U(SCH_1):PAGE19

TP_TRC_CPU0_PTI<25> @S9S_MB_2U_LIB.S9S_MB_2U(SCH_1):TP_TRC_CPU0_PTI(25)
    U2 BM69 PTI_DIE019 SOCKET4677_AZIF0045P001C01CS-SA     I1 @S9S_MB_2U_LIB.S9S_MB_2U(SCH_1):PAGE19

TP_TRC_CPU0_PTI<26> @S9S_MB_2U_LIB.S9S_MB_2U(SCH_1):TP_TRC_CPU0_PTI(26)
    U2 BN68 PTI_DIE0110 SOCKET4677_AZIF0045P001C01CS-SA     I1 @S9S_MB_2U_LIB.S9S_MB_2U(SCH_1):PAGE19

TP_TRC_CPU0_PTI<27> @S9S_MB_2U_LIB.S9S_MB_2U(SCH_1):TP_TRC_CPU0_PTI(27)
    U2 BG66 PTI_DIE0111 SOCKET4677_AZIF0045P001C01CS-SA     I1 @S9S_MB_2U_LIB.S9S_MB_2U(SCH_1):PAGE19

TP_TRC_CPU0_PTI<28> @S9S_MB_2U_LIB.S9S_MB_2U(SCH_1):TP_TRC_CPU0_PTI(28)
    U2 BJ66 PTI_DIE0112 SOCKET4677_AZIF0045P001C01CS-SA     I1 @S9S_MB_2U_LIB.S9S_MB_2U(SCH_1):PAGE19

TP_TRC_CPU0_PTI<29> @S9S_MB_2U_LIB.S9S_MB_2U(SCH_1):TP_TRC_CPU0_PTI(29)
    U2 BL66 PTI_DIE0113 SOCKET4677_AZIF0045P001C01CS-SA     I1 @S9S_MB_2U_LIB.S9S_MB_2U(SCH_1):PAGE19

TP_TRC_CPU0_PTI<2> @S9S_MB_2U_LIB.S9S_MB_2U(SCH_1):TP_TRC_CPU0_PTI(2)
    U2 CC27 PTI_DIE002 SOCKET4677_AZIF0045P001C01CS-SA     I1 @S9S_MB_2U_LIB.S9S_MB_2U(SCH_1):PAGE19

TP_TRC_CPU0_PTI<30> @S9S_MB_2U_LIB.S9S_MB_2U(SCH_1):TP_TRC_CPU0_PTI(30)
    U2 BM67 PTI_DIE0114 SOCKET4677_AZIF0045P001C01CS-SA     I1 @S9S_MB_2U_LIB.S9S_MB_2U(SCH_1):PAGE19

TP_TRC_CPU0_PTI<31> @S9S_MB_2U_LIB.S9S_MB_2U(SCH_1):TP_TRC_CPU0_PTI(31)
    U2 BN66 PTI_DIE0115 SOCKET4677_AZIF0045P001C01CS-SA     I1 @S9S_MB_2U_LIB.S9S_MB_2U(SCH_1):PAGE19

TP_TRC_CPU0_PTI<3> @S9S_MB_2U_LIB.S9S_MB_2U(SCH_1):TP_TRC_CPU0_PTI(3)
    U2 BY30 PTI_DIE003 SOCKET4677_AZIF0045P001C01CS-SA     I1 @S9S_MB_2U_LIB.S9S_MB_2U(SCH_1):PAGE19

TP_TRC_CPU0_PTI<4> @S9S_MB_2U_LIB.S9S_MB_2U(SCH_1):TP_TRC_CPU0_PTI(4)
    U2 CA29 PTI_DIE004 SOCKET4677_AZIF0045P001C01CS-SA     I1 @S9S_MB_2U_LIB.S9S_MB_2U(SCH_1):PAGE19

TP_TRC_CPU0_PTI<5> @S9S_MB_2U_LIB.S9S_MB_2U(SCH_1):TP_TRC_CPU0_PTI(5)
    U2 BV30 PTI_DIE005 SOCKET4677_AZIF0045P001C01CS-SA     I1 @S9S_MB_2U_LIB.S9S_MB_2U(SCH_1):PAGE19

TP_TRC_CPU0_PTI<6> @S9S_MB_2U_LIB.S9S_MB_2U(SCH_1):TP_TRC_CPU0_PTI(6)
    U2 CA27 PTI_DIE006 SOCKET4677_AZIF0045P001C01CS-SA     I1 @S9S_MB_2U_LIB.S9S_MB_2U(SCH_1):PAGE19

TP_TRC_CPU0_PTI<7> @S9S_MB_2U_LIB.S9S_MB_2U(SCH_1):TP_TRC_CPU0_PTI(7)
    U2 BV28 PTI_DIE007 SOCKET4677_AZIF0045P001C01CS-SA     I1 @S9S_MB_2U_LIB.S9S_MB_2U(SCH_1):PAGE19

TP_TRC_CPU0_PTI<8> @S9S_MB_2U_LIB.S9S_MB_2U(SCH_1):TP_TRC_CPU0_PTI(8)
    U2 BU27 PTI_DIE008 SOCKET4677_AZIF0045P001C01CS-SA     I1 @S9S_MB_2U_LIB.S9S_MB_2U(SCH_1):PAGE19

TP_TRC_CPU0_PTI<9> @S9S_MB_2U_LIB.S9S_MB_2U(SCH_1):TP_TRC_CPU0_PTI(9)
    U2 BT28 PTI_DIE009 SOCKET4677_AZIF0045P001C01CS-SA     I1 @S9S_MB_2U_LIB.S9S_MB_2U(SCH_1):PAGE19

TP_TRC_CPU0_PTI_MON<1> @S9S_MB_2U_LIB.S9S_MB_2U(SCH_1):TP_TRC_CPU0_PTI_MON(1)
    U2 CD28 PTI_DIE001 SOCKET4677_AZIF0045P001C01CS-SA     I1 @S9S_MB_2U_LIB.S9S_MB_2U(SCH_1):PAGE19

TP_TRC_CPU1_PTI0_CLK @S9S_MB_2U_LIB.S9S_MB_2U(SCH_1):TP_TRC_CPU1_PTI0_CLK
    U1 CB30 PTI_DIE00_STB_0 SOCKET4677_AZIF0045P001C01CS-SA    I23 @S9S_MB_2U_LIB.S9S_MB_2U(SCH_1):PAGE50

TP_TRC_CPU1_PTI1_CLK @S9S_MB_2U_LIB.S9S_MB_2U(SCH_1):TP_TRC_CPU1_PTI1_CLK
    U1 BY28 PTI_DIE00_STB_1 SOCKET4677_AZIF0045P001C01CS-SA    I23 @S9S_MB_2U_LIB.S9S_MB_2U(SCH_1):PAGE50

TP_TRC_CPU1_PTI2_CLK @S9S_MB_2U_LIB.S9S_MB_2U(SCH_1):TP_TRC_CPU1_PTI2_CLK
    U1 BF67 PTI_DIE01_STB_0 SOCKET4677_AZIF0045P001C01CS-SA    I23 @S9S_MB_2U_LIB.S9S_MB_2U(SCH_1):PAGE50

TP_TRC_CPU1_PTI3_CLK @S9S_MB_2U_LIB.S9S_MB_2U(SCH_1):TP_TRC_CPU1_PTI3_CLK
    U1 BK67 PTI_DIE01_STB_1 SOCKET4677_AZIF0045P001C01CS-SA    I23 @S9S_MB_2U_LIB.S9S_MB_2U(SCH_1):PAGE50

TP_TRC_CPU1_PTI<0> @S9S_MB_2U_LIB.S9S_MB_2U(SCH_1):TP_TRC_CPU1_PTI(0)
    U1 CC29 PTI_DIE000 SOCKET4677_AZIF0045P001C01CS-SA    I23 @S9S_MB_2U_LIB.S9S_MB_2U(SCH_1):PAGE50

TP_TRC_CPU1_PTI<10> @S9S_MB_2U_LIB.S9S_MB_2U(SCH_1):TP_TRC_CPU1_PTI(10)
    U1 BU29 PTI_DIE0010 SOCKET4677_AZIF0045P001C01CS-SA    I23 @S9S_MB_2U_LIB.S9S_MB_2U(SCH_1):PAGE50

TP_TRC_CPU1_PTI<11> @S9S_MB_2U_LIB.S9S_MB_2U(SCH_1):TP_TRC_CPU1_PTI(11)
    U1 BT30 PTI_DIE0011 SOCKET4677_AZIF0045P001C01CS-SA    I23 @S9S_MB_2U_LIB.S9S_MB_2U(SCH_1):PAGE50

TP_TRC_CPU1_PTI<12> @S9S_MB_2U_LIB.S9S_MB_2U(SCH_1):TP_TRC_CPU1_PTI(12)
    U1 BN27 PTI_DIE0012 SOCKET4677_AZIF0045P001C01CS-SA    I23 @S9S_MB_2U_LIB.S9S_MB_2U(SCH_1):PAGE50

TP_TRC_CPU1_PTI<13> @S9S_MB_2U_LIB.S9S_MB_2U(SCH_1):TP_TRC_CPU1_PTI(13)
    U1 BP28 PTI_DIE0013 SOCKET4677_AZIF0045P001C01CS-SA    I23 @S9S_MB_2U_LIB.S9S_MB_2U(SCH_1):PAGE50

TP_TRC_CPU1_PTI<14> @S9S_MB_2U_LIB.S9S_MB_2U(SCH_1):TP_TRC_CPU1_PTI(14)
    U1 BN29 PTI_DIE0014 SOCKET4677_AZIF0045P001C01CS-SA    I23 @S9S_MB_2U_LIB.S9S_MB_2U(SCH_1):PAGE50

TP_TRC_CPU1_PTI<15> @S9S_MB_2U_LIB.S9S_MB_2U(SCH_1):TP_TRC_CPU1_PTI(15)
    U1 BP30 PTI_DIE0015 SOCKET4677_AZIF0045P001C01CS-SA    I23 @S9S_MB_2U_LIB.S9S_MB_2U(SCH_1):PAGE50

TP_TRC_CPU1_PTI<16> @S9S_MB_2U_LIB.S9S_MB_2U(SCH_1):TP_TRC_CPU1_PTI(16)
    U1 BC70 PTI_DIE010 SOCKET4677_AZIF0045P001C01CS-SA    I23 @S9S_MB_2U_LIB.S9S_MB_2U(SCH_1):PAGE50

TP_TRC_CPU1_PTI<17> @S9S_MB_2U_LIB.S9S_MB_2U(SCH_1):TP_TRC_CPU1_PTI(17)
    U1 BE70 PTI_DIE011 SOCKET4677_AZIF0045P001C01CS-SA    I23 @S9S_MB_2U_LIB.S9S_MB_2U(SCH_1):PAGE50

TP_TRC_CPU1_PTI<18> @S9S_MB_2U_LIB.S9S_MB_2U(SCH_1):TP_TRC_CPU1_PTI(18)
    U1 BD69 PTI_DIE012 SOCKET4677_AZIF0045P001C01CS-SA    I23 @S9S_MB_2U_LIB.S9S_MB_2U(SCH_1):PAGE50

TP_TRC_CPU1_PTI<19> @S9S_MB_2U_LIB.S9S_MB_2U(SCH_1):TP_TRC_CPU1_PTI(19)
    U1 BF69 PTI_DIE013 SOCKET4677_AZIF0045P001C01CS-SA    I23 @S9S_MB_2U_LIB.S9S_MB_2U(SCH_1):PAGE50

TP_TRC_CPU1_PTI<1> @S9S_MB_2U_LIB.S9S_MB_2U(SCH_1):TP_TRC_CPU1_PTI(1)
    U1 CD28 PTI_DIE001 SOCKET4677_AZIF0045P001C01CS-SA    I23 @S9S_MB_2U_LIB.S9S_MB_2U(SCH_1):PAGE50

TP_TRC_CPU1_PTI<20> @S9S_MB_2U_LIB.S9S_MB_2U(SCH_1):TP_TRC_CPU1_PTI(20)
    U1 BH69 PTI_DIE014 SOCKET4677_AZIF0045P001C01CS-SA    I23 @S9S_MB_2U_LIB.S9S_MB_2U(SCH_1):PAGE50

TP_TRC_CPU1_PTI<21> @S9S_MB_2U_LIB.S9S_MB_2U(SCH_1):TP_TRC_CPU1_PTI(21)
    U1 BC68 PTI_DIE015 SOCKET4677_AZIF0045P001C01CS-SA    I23 @S9S_MB_2U_LIB.S9S_MB_2U(SCH_1):PAGE50

TP_TRC_CPU1_PTI<22> @S9S_MB_2U_LIB.S9S_MB_2U(SCH_1):TP_TRC_CPU1_PTI(22)
    U1 BG68 PTI_DIE016 SOCKET4677_AZIF0045P001C01CS-SA    I23 @S9S_MB_2U_LIB.S9S_MB_2U(SCH_1):PAGE50

TP_TRC_CPU1_PTI<23> @S9S_MB_2U_LIB.S9S_MB_2U(SCH_1):TP_TRC_CPU1_PTI(23)
    U1 BD67 PTI_DIE017 SOCKET4677_AZIF0045P001C01CS-SA    I23 @S9S_MB_2U_LIB.S9S_MB_2U(SCH_1):PAGE50

TP_TRC_CPU1_PTI<24> @S9S_MB_2U_LIB.S9S_MB_2U(SCH_1):TP_TRC_CPU1_PTI(24)
    U1 BK69 PTI_DIE018 SOCKET4677_AZIF0045P001C01CS-SA    I23 @S9S_MB_2U_LIB.S9S_MB_2U(SCH_1):PAGE50

TP_TRC_CPU1_PTI<25> @S9S_MB_2U_LIB.S9S_MB_2U(SCH_1):TP_TRC_CPU1_PTI(25)
    U1 BM69 PTI_DIE019 SOCKET4677_AZIF0045P001C01CS-SA    I23 @S9S_MB_2U_LIB.S9S_MB_2U(SCH_1):PAGE50

TP_TRC_CPU1_PTI<26> @S9S_MB_2U_LIB.S9S_MB_2U(SCH_1):TP_TRC_CPU1_PTI(26)
    U1 BN68 PTI_DIE0110 SOCKET4677_AZIF0045P001C01CS-SA    I23 @S9S_MB_2U_LIB.S9S_MB_2U(SCH_1):PAGE50

TP_TRC_CPU1_PTI<27> @S9S_MB_2U_LIB.S9S_MB_2U(SCH_1):TP_TRC_CPU1_PTI(27)
    U1 BG66 PTI_DIE0111 SOCKET4677_AZIF0045P001C01CS-SA    I23 @S9S_MB_2U_LIB.S9S_MB_2U(SCH_1):PAGE50

TP_TRC_CPU1_PTI<28> @S9S_MB_2U_LIB.S9S_MB_2U(SCH_1):TP_TRC_CPU1_PTI(28)
    U1 BJ66 PTI_DIE0112 SOCKET4677_AZIF0045P001C01CS-SA    I23 @S9S_MB_2U_LIB.S9S_MB_2U(SCH_1):PAGE50

TP_TRC_CPU1_PTI<29> @S9S_MB_2U_LIB.S9S_MB_2U(SCH_1):TP_TRC_CPU1_PTI(29)
    U1 BL66 PTI_DIE0113 SOCKET4677_AZIF0045P001C01CS-SA    I23 @S9S_MB_2U_LIB.S9S_MB_2U(SCH_1):PAGE50

TP_TRC_CPU1_PTI<2> @S9S_MB_2U_LIB.S9S_MB_2U(SCH_1):TP_TRC_CPU1_PTI(2)
    U1 CC27 PTI_DIE002 SOCKET4677_AZIF0045P001C01CS-SA    I23 @S9S_MB_2U_LIB.S9S_MB_2U(SCH_1):PAGE50

TP_TRC_CPU1_PTI<30> @S9S_MB_2U_LIB.S9S_MB_2U(SCH_1):TP_TRC_CPU1_PTI(30)
    U1 BM67 PTI_DIE0114 SOCKET4677_AZIF0045P001C01CS-SA    I23 @S9S_MB_2U_LIB.S9S_MB_2U(SCH_1):PAGE50

TP_TRC_CPU1_PTI<31> @S9S_MB_2U_LIB.S9S_MB_2U(SCH_1):TP_TRC_CPU1_PTI(31)
    U1 BN66 PTI_DIE0115 SOCKET4677_AZIF0045P001C01CS-SA    I23 @S9S_MB_2U_LIB.S9S_MB_2U(SCH_1):PAGE50

TP_TRC_CPU1_PTI<3> @S9S_MB_2U_LIB.S9S_MB_2U(SCH_1):TP_TRC_CPU1_PTI(3)
    U1 BY30 PTI_DIE003 SOCKET4677_AZIF0045P001C01CS-SA    I23 @S9S_MB_2U_LIB.S9S_MB_2U(SCH_1):PAGE50

TP_TRC_CPU1_PTI<4> @S9S_MB_2U_LIB.S9S_MB_2U(SCH_1):TP_TRC_CPU1_PTI(4)
    U1 CA29 PTI_DIE004 SOCKET4677_AZIF0045P001C01CS-SA    I23 @S9S_MB_2U_LIB.S9S_MB_2U(SCH_1):PAGE50

TP_TRC_CPU1_PTI<5> @S9S_MB_2U_LIB.S9S_MB_2U(SCH_1):TP_TRC_CPU1_PTI(5)
    U1 BV30 PTI_DIE005 SOCKET4677_AZIF0045P001C01CS-SA    I23 @S9S_MB_2U_LIB.S9S_MB_2U(SCH_1):PAGE50

TP_TRC_CPU1_PTI<6> @S9S_MB_2U_LIB.S9S_MB_2U(SCH_1):TP_TRC_CPU1_PTI(6)
    U1 CA27 PTI_DIE006 SOCKET4677_AZIF0045P001C01CS-SA    I23 @S9S_MB_2U_LIB.S9S_MB_2U(SCH_1):PAGE50

TP_TRC_CPU1_PTI<7> @S9S_MB_2U_LIB.S9S_MB_2U(SCH_1):TP_TRC_CPU1_PTI(7)
    U1 BV28 PTI_DIE007 SOCKET4677_AZIF0045P001C01CS-SA    I23 @S9S_MB_2U_LIB.S9S_MB_2U(SCH_1):PAGE50

TP_TRC_CPU1_PTI<8> @S9S_MB_2U_LIB.S9S_MB_2U(SCH_1):TP_TRC_CPU1_PTI(8)
    U1 BU27 PTI_DIE008 SOCKET4677_AZIF0045P001C01CS-SA    I23 @S9S_MB_2U_LIB.S9S_MB_2U(SCH_1):PAGE50

TP_TRC_CPU1_PTI<9> @S9S_MB_2U_LIB.S9S_MB_2U(SCH_1):TP_TRC_CPU1_PTI(9)
    U1 BT28 PTI_DIE009 SOCKET4677_AZIF0045P001C01CS-SA    I23 @S9S_MB_2U_LIB.S9S_MB_2U(SCH_1):PAGE50

TP_USB2_10_DN @S9S_MB_2U_LIB.S9S_MB_2U(SCH_1):TP_USB2_10_DN
    U4 AY43 USB2N_10 EMMITSBURG_REV0P9-GFNOCPU04302A    I11 @S9S_MB_2U_LIB.S9S_MB_2U(SCH_1):PAGE172

TP_USB2_10_DP @S9S_MB_2U_LIB.S9S_MB_2U(SCH_1):TP_USB2_10_DP
    U4 AY41 USB2P_10 EMMITSBURG_REV0P9-GFNOCPU04302A    I11 @S9S_MB_2U_LIB.S9S_MB_2U(SCH_1):PAGE172

TP_USB2_11_DN @S9S_MB_2U_LIB.S9S_MB_2U(SCH_1):TP_USB2_11_DN
    U4 AH42 USB2N_11 EMMITSBURG_REV0P9-GFNOCPU04302A    I11 @S9S_MB_2U_LIB.S9S_MB_2U(SCH_1):PAGE172

TP_USB2_11_DP @S9S_MB_2U_LIB.S9S_MB_2U(SCH_1):TP_USB2_11_DP
    U4 AH40 USB2P_11 EMMITSBURG_REV0P9-GFNOCPU04302A    I11 @S9S_MB_2U_LIB.S9S_MB_2U(SCH_1):PAGE172

TP_USB2_12_DN @S9S_MB_2U_LIB.S9S_MB_2U(SCH_1):TP_USB2_12_DN
    U4 BA42 USB2N_12 EMMITSBURG_REV0P9-GFNOCPU04302A    I11 @S9S_MB_2U_LIB.S9S_MB_2U(SCH_1):PAGE172

TP_USB2_12_DP @S9S_MB_2U_LIB.S9S_MB_2U(SCH_1):TP_USB2_12_DP
    U4 BA40 USB2P_12 EMMITSBURG_REV0P9-GFNOCPU04302A    I11 @S9S_MB_2U_LIB.S9S_MB_2U(SCH_1):PAGE172

TP_USB2_13_DN @S9S_MB_2U_LIB.S9S_MB_2U(SCH_1):TP_USB2_13_DN
    U4 AG43 USB2N_13 EMMITSBURG_REV0P9-GFNOCPU04302A    I11 @S9S_MB_2U_LIB.S9S_MB_2U(SCH_1):PAGE172

TP_USB2_13_DP @S9S_MB_2U_LIB.S9S_MB_2U(SCH_1):TP_USB2_13_DP
    U4 AG41 USB2P_13 EMMITSBURG_REV0P9-GFNOCPU04302A    I11 @S9S_MB_2U_LIB.S9S_MB_2U(SCH_1):PAGE172

TP_USB2_1_DN @S9S_MB_2U_LIB.S9S_MB_2U(SCH_1):TP_USB2_1_DN
    U4 AP43 USB2N_1 EMMITSBURG_REV0P9-GFNOCPU04302A    I11 @S9S_MB_2U_LIB.S9S_MB_2U(SCH_1):PAGE172

TP_USB2_1_DP @S9S_MB_2U_LIB.S9S_MB_2U(SCH_1):TP_USB2_1_DP
    U4 AP41 USB2P_1 EMMITSBURG_REV0P9-GFNOCPU04302A    I11 @S9S_MB_2U_LIB.S9S_MB_2U(SCH_1):PAGE172

TP_USB2_2_DN @S9S_MB_2U_LIB.S9S_MB_2U(SCH_1):TP_USB2_2_DN
    U4 AT43 USB2N_2 EMMITSBURG_REV0P9-GFNOCPU04302A    I11 @S9S_MB_2U_LIB.S9S_MB_2U(SCH_1):PAGE172

TP_USB2_2_DP @S9S_MB_2U_LIB.S9S_MB_2U(SCH_1):TP_USB2_2_DP
    U4 AT41 USB2P_2 EMMITSBURG_REV0P9-GFNOCPU04302A    I11 @S9S_MB_2U_LIB.S9S_MB_2U(SCH_1):PAGE172

TP_USB2_4_DN @S9S_MB_2U_LIB.S9S_MB_2U(SCH_1):TP_USB2_4_DN
    U4 AU42 USB2N_4 EMMITSBURG_REV0P9-GFNOCPU04302A    I11 @S9S_MB_2U_LIB.S9S_MB_2U(SCH_1):PAGE172

TP_USB2_4_DP @S9S_MB_2U_LIB.S9S_MB_2U(SCH_1):TP_USB2_4_DP
    U4 AU40 USB2P_4 EMMITSBURG_REV0P9-GFNOCPU04302A    I11 @S9S_MB_2U_LIB.S9S_MB_2U(SCH_1):PAGE172

TP_USB2_6_DN @S9S_MB_2U_LIB.S9S_MB_2U(SCH_1):TP_USB2_6_DN
    U4 AV43 USB2N_6 EMMITSBURG_REV0P9-GFNOCPU04302A    I11 @S9S_MB_2U_LIB.S9S_MB_2U(SCH_1):PAGE172

TP_USB2_6_DP @S9S_MB_2U_LIB.S9S_MB_2U(SCH_1):TP_USB2_6_DP
    U4 AV41 USB2P_6 EMMITSBURG_REV0P9-GFNOCPU04302A    I11 @S9S_MB_2U_LIB.S9S_MB_2U(SCH_1):PAGE172

TP_USB2_9_DN @S9S_MB_2U_LIB.S9S_MB_2U(SCH_1):TP_USB2_9_DN
    U4 AJ43 USB2N_9 EMMITSBURG_REV0P9-GFNOCPU04302A    I11 @S9S_MB_2U_LIB.S9S_MB_2U(SCH_1):PAGE172

TP_USB2_9_DP @S9S_MB_2U_LIB.S9S_MB_2U(SCH_1):TP_USB2_9_DP
    U4 AJ41 USB2P_9 EMMITSBURG_REV0P9-GFNOCPU04302A    I11 @S9S_MB_2U_LIB.S9S_MB_2U(SCH_1):PAGE172

TP_USB2_CD @S9S_MB_2U_LIB.S9S_MB_2U(SCH_1):TP_USB2_CD
 U5201    4     CD TUSB211IRWBR-TUSB211IRWBR,SMLFA    I84 @S9S_MB_2U_LIB.S9S_MB_2U(SCH_1):PAGE155

TP_USB2_ENA_HS @S9S_MB_2U_LIB.S9S_MB_2U(SCH_1):TP_USB2_ENA_HS
 U5201    9 ENA_HS TUSB211IRWBR-TUSB211IRWBR,SMLFA    I84 @S9S_MB_2U_LIB.S9S_MB_2U(SCH_1):PAGE155

TP_USB2_TEST @S9S_MB_2U_LIB.S9S_MB_2U(SCH_1):TP_USB2_TEST
 U5201    3   TEST TUSB211IRWBR-TUSB211IRWBR,SMLFA    I84 @S9S_MB_2U_LIB.S9S_MB_2U(SCH_1):PAGE155

TP_USB_HUB_2_CD @S9S_MB_2U_LIB.S9S_MB_2U(SCH_1):TP_USB_HUB_2_CD
  U312    4     CD TUSB211IRWBR-TUSB211IRWBR,SMLFA    I20 @S9S_MB_2U_LIB.S9S_MB_2U(SCH_1):PAGE194

TP_USB_HUB_2_ENA_HS @S9S_MB_2U_LIB.S9S_MB_2U(SCH_1):TP_USB_HUB_2_ENA_HS
  U312    9 ENA_HS TUSB211IRWBR-TUSB211IRWBR,SMLFA    I20 @S9S_MB_2U_LIB.S9S_MB_2U(SCH_1):PAGE194

TP_USB_HUB_2_TEST @S9S_MB_2U_LIB.S9S_MB_2U(SCH_1):TP_USB_HUB_2_TEST
  U312    3   TEST TUSB211IRWBR-TUSB211IRWBR,SMLFA    I20 @S9S_MB_2U_LIB.S9S_MB_2U(SCH_1):PAGE194

U205_VDD @S9S_MB_2U_LIB.S9S_MB_2U(SCH_1):U205_VDD
  U205    5    VDD TPS3700DDCR-TPS3700DDCR,SMLF,EA     I5 @S9S_MB_2U_LIB.S9S_MB_2U(SCH_1):PAGE326
 C1562    1      A Q_CAP_C0402-1UF,25V,10%,EMPTY,A    I89 @S9S_MB_2U_LIB.S9S_MB_2U(SCH_1):PAGE326
 C2392    1      A Q_CAP_0402-0.1UF,25V,10%,EMPTYA    I95 @S9S_MB_2U_LIB.S9S_MB_2U(SCH_1):PAGE326
 R4804    2      B Q_RES_0402LF-1K,1%,1/16W,EMPTYA    I97 @S9S_MB_2U_LIB.S9S_MB_2U(SCH_1):PAGE326

U206_VDD @S9S_MB_2U_LIB.S9S_MB_2U(SCH_1):U206_VDD
 C1561    1      A Q_CAP_C0402-1UF,25V,10%,X6S,CHA    I90 @S9S_MB_2U_LIB.S9S_MB_2U(SCH_1):PAGE326
 C2394    1      A Q_CAP_0402-0.1UF,25V,10%,X7R,CA    I93 @S9S_MB_2U_LIB.S9S_MB_2U(SCH_1):PAGE326
 R4806    2      B Q_RES_0402LF-1K,1%,1/16W,CHIP,A    I98 @S9S_MB_2U_LIB.S9S_MB_2U(SCH_1):PAGE326
  U206    5     VS LT6700CS61TRPBF-LT6700CS6-1#TRA   I102 @S9S_MB_2U_LIB.S9S_MB_2U(SCH_1):PAGE326

U270_0_ADD0 @S9S_MB_2U_LIB.S9S_MB_2U(SCH_1):U270_0_ADD0
 R4207    1      A Q_RES_0402LF-1K,1%,1/16W,CHIP,A    I85 @S9S_MB_2U_LIB.S9S_MB_2U(SCH_1):PAGE161
 R4206    2      B Q_RES_0402LF-1K,1%,1/16W,EMPTYA    I86 @S9S_MB_2U_LIB.S9S_MB_2U(SCH_1):PAGE161
  U270    7     A0 LM75BD-LM75BD,SMLF,IC,AL0075BDA   I164 @S9S_MB_2U_LIB.S9S_MB_2U(SCH_1):PAGE161

U270_0_ADD1 @S9S_MB_2U_LIB.S9S_MB_2U(SCH_1):U270_0_ADD1
 R4199    1      A Q_RES_0402LF-1K,1%,1/16W,CHIP,A    I81 @S9S_MB_2U_LIB.S9S_MB_2U(SCH_1):PAGE161
 R4198    2      B Q_RES_0402LF-1K,1%,1/16W,EMPTYA    I82 @S9S_MB_2U_LIB.S9S_MB_2U(SCH_1):PAGE161
  U270    6     A1 LM75BD-LM75BD,SMLF,IC,AL0075BDA   I164 @S9S_MB_2U_LIB.S9S_MB_2U(SCH_1):PAGE161

U270_0_ADD2 @S9S_MB_2U_LIB.S9S_MB_2U(SCH_1):U270_0_ADD2
 R4191    1      A Q_RES_0402LF-1K,1%,1/16W,CHIP,A    I89 @S9S_MB_2U_LIB.S9S_MB_2U(SCH_1):PAGE161
 R4190    2      B Q_RES_0402LF-1K,1%,1/16W,EMPTYA    I91 @S9S_MB_2U_LIB.S9S_MB_2U(SCH_1):PAGE161
  U270    5     A2 LM75BD-LM75BD,SMLF,IC,AL0075BDA   I164 @S9S_MB_2U_LIB.S9S_MB_2U(SCH_1):PAGE161

U271_1_ADD0 @S9S_MB_2U_LIB.S9S_MB_2U(SCH_1):U271_1_ADD0
 R4204    2      B Q_RES_0402LF-1K,1%,1/16W,EMPTYA    I94 @S9S_MB_2U_LIB.S9S_MB_2U(SCH_1):PAGE161
 R4205    1      A Q_RES_0402LF-1K,1%,1/16W,CHIP,A    I96 @S9S_MB_2U_LIB.S9S_MB_2U(SCH_1):PAGE161
  U271    7     A0 LM75BD-LM75BD,SMLF,IC,AL0075BDA   I165 @S9S_MB_2U_LIB.S9S_MB_2U(SCH_1):PAGE161

U271_1_ADD1 @S9S_MB_2U_LIB.S9S_MB_2U(SCH_1):U271_1_ADD1
 R4196    2      B Q_RES_0402LF-1K,1%,1/16W,EMPTYA    I95 @S9S_MB_2U_LIB.S9S_MB_2U(SCH_1):PAGE161
 R4197    1      A Q_RES_0402LF-1K,1%,1/16W,CHIP,A    I98 @S9S_MB_2U_LIB.S9S_MB_2U(SCH_1):PAGE161
  U271    6     A1 LM75BD-LM75BD,SMLF,IC,AL0075BDA   I165 @S9S_MB_2U_LIB.S9S_MB_2U(SCH_1):PAGE161

U271_1_ADD2 @S9S_MB_2U_LIB.S9S_MB_2U(SCH_1):U271_1_ADD2
 R4188    2      B Q_RES_0402LF-1K,1%,1/16W,EMPTYA   I101 @S9S_MB_2U_LIB.S9S_MB_2U(SCH_1):PAGE161
 R4189    1      A Q_RES_0402LF-1K,1%,1/16W,CHIP,A   I102 @S9S_MB_2U_LIB.S9S_MB_2U(SCH_1):PAGE161
  U271    5     A2 LM75BD-LM75BD,SMLF,IC,AL0075BDA   I165 @S9S_MB_2U_LIB.S9S_MB_2U(SCH_1):PAGE161

U272_2_ADD0 @S9S_MB_2U_LIB.S9S_MB_2U(SCH_1):U272_2_ADD0
 R4203    1      A Q_RES_0402LF-1K,1%,1/16W,CHIP,A   I127 @S9S_MB_2U_LIB.S9S_MB_2U(SCH_1):PAGE161
 R4202    2      B Q_RES_0402LF-1K,1%,1/16W,EMPTYA   I129 @S9S_MB_2U_LIB.S9S_MB_2U(SCH_1):PAGE161
  U272    7     A0 LM75BD-LM75BD,SMLF,IC,AL0075BDA   I166 @S9S_MB_2U_LIB.S9S_MB_2U(SCH_1):PAGE161

U272_2_ADD1 @S9S_MB_2U_LIB.S9S_MB_2U(SCH_1):U272_2_ADD1
 R4195    1      A Q_RES_0402LF-1K,1%,1/16W,CHIP,A   I125 @S9S_MB_2U_LIB.S9S_MB_2U(SCH_1):PAGE161
 R4194    2      B Q_RES_0402LF-1K,1%,1/16W,EMPTYA   I128 @S9S_MB_2U_LIB.S9S_MB_2U(SCH_1):PAGE161
  U272    6     A1 LM75BD-LM75BD,SMLF,IC,AL0075BDA   I166 @S9S_MB_2U_LIB.S9S_MB_2U(SCH_1):PAGE161

U272_2_ADD2 @S9S_MB_2U_LIB.S9S_MB_2U(SCH_1):U272_2_ADD2
 R4187    1      A Q_RES_0402LF-1K,1%,1/16W,CHIP,A   I121 @S9S_MB_2U_LIB.S9S_MB_2U(SCH_1):PAGE161
 R4186    2      B Q_RES_0402LF-1K,1%,1/16W,EMPTYA   I122 @S9S_MB_2U_LIB.S9S_MB_2U(SCH_1):PAGE161
  U272    5     A2 LM75BD-LM75BD,SMLF,IC,AL0075BDA   I166 @S9S_MB_2U_LIB.S9S_MB_2U(SCH_1):PAGE161

U273_3_ADD0 @S9S_MB_2U_LIB.S9S_MB_2U(SCH_1):U273_3_ADD0
 R4201    1      A Q_RES_0402LF-1K,1%,1/16W,CHIP,A   I147 @S9S_MB_2U_LIB.S9S_MB_2U(SCH_1):PAGE161
 R4200    2      B Q_RES_0402LF-1K,1%,1/16W,EMPTYA   I149 @S9S_MB_2U_LIB.S9S_MB_2U(SCH_1):PAGE161
  U273    7     A0 LM75BD-LM75BD,SMLF,IC,AL0075BDA   I167 @S9S_MB_2U_LIB.S9S_MB_2U(SCH_1):PAGE161

U273_3_ADD1 @S9S_MB_2U_LIB.S9S_MB_2U(SCH_1):U273_3_ADD1
 R4193    1      A Q_RES_0402LF-1K,1%,1/16W,CHIP,A   I145 @S9S_MB_2U_LIB.S9S_MB_2U(SCH_1):PAGE161
 R4192    2      B Q_RES_0402LF-1K,1%,1/16W,EMPTYA   I148 @S9S_MB_2U_LIB.S9S_MB_2U(SCH_1):PAGE161
  U273    6     A1 LM75BD-LM75BD,SMLF,IC,AL0075BDA   I167 @S9S_MB_2U_LIB.S9S_MB_2U(SCH_1):PAGE161

U273_3_ADD2 @S9S_MB_2U_LIB.S9S_MB_2U(SCH_1):U273_3_ADD2
 R4185    1      A Q_RES_0402LF-1K,1%,1/16W,CHIP,A   I141 @S9S_MB_2U_LIB.S9S_MB_2U(SCH_1):PAGE161
 R4184    2      B Q_RES_0402LF-1K,1%,1/16W,EMPTYA   I142 @S9S_MB_2U_LIB.S9S_MB_2U(SCH_1):PAGE161
  U273    5     A2 LM75BD-LM75BD,SMLF,IC,AL0075BDA   I167 @S9S_MB_2U_LIB.S9S_MB_2U(SCH_1):PAGE161

U369_VDD @S9S_MB_2U_LIB.S9S_MB_2U(SCH_1):U369_VDD
  U369    5    VDD TPS3700DDCR-TPS3700DDCR,SMLF,EA    I30 @S9S_MB_2U_LIB.S9S_MB_2U(SCH_1):PAGE326
 C4562    1      A Q_CAP_C0402-1UF,25V,10%,EMPTY,A    I91 @S9S_MB_2U_LIB.S9S_MB_2U(SCH_1):PAGE326
 C2393    1      A Q_CAP_0402-0.1UF,25V,10%,EMPTYA    I92 @S9S_MB_2U_LIB.S9S_MB_2U(SCH_1):PAGE326
 R4805    2      B Q_RES_0402LF-1K,1%,1/16W,EMPTYA    I99 @S9S_MB_2U_LIB.S9S_MB_2U(SCH_1):PAGE326

UART_BMC_BIC_BUF_RX @S9S_MB_2U_LIB.S9S_MB_2U(SCH_1):UART_BMC_BIC_BUF_RX
 R3036    2      B Q_RES_0402LF-33.2,1%,1/16W,CHIA   I197 @S9S_MB_2U_LIB.S9S_MB_2U(SCH_1):PAGE140
   J41  OB6    CLK SCONN168_ME1016810202011-SCONNA   I173 @S9S_MB_2U_LIB.S9S_MB_2U(SCH_1):PAGE227

UART_BMC_BIC_RX @S9S_MB_2U_LIB.S9S_MB_2U(SCH_1):UART_BMC_BIC_RX
  J106   N6     N6 CONN112_10137002101LF-CONN112_A    I68 @S9S_MB_2U_LIB.S9S_MB_2U(SCH_1):PAGE144
 R3033    1      A Q_RES_0402LF-0,5%,1/16W,CHIP,CA   I170 @S9S_MB_2U_LIB.S9S_MB_2U(SCH_1):PAGE140
 R4515    2      B Q_RES_0402LF-100K,1%,1/16W,CHIA   I200 @S9S_MB_2U_LIB.S9S_MB_2U(SCH_1):PAGE140

UART_BMC_BIC_R_BUF_RX @S9S_MB_2U_LIB.S9S_MB_2U(SCH_1):UART_BMC_BIC_R_BUF_RX
  U204    4      Y 74LVC1G126SE7-74LVC1G126SE-7,SA   I195 @S9S_MB_2U_LIB.S9S_MB_2U(SCH_1):PAGE140
 R3036    1      A Q_RES_0402LF-33.2,1%,1/16W,CHIA   I197 @S9S_MB_2U_LIB.S9S_MB_2U(SCH_1):PAGE140
 R4173    2      B Q_RES_0402LF-100K,1%,1/16W,EMPA   I202 @S9S_MB_2U_LIB.S9S_MB_2U(SCH_1):PAGE140

UART_BMC_BIC_R_RX @S9S_MB_2U_LIB.S9S_MB_2U(SCH_1):UART_BMC_BIC_R_RX
 R3033    2      B Q_RES_0402LF-0,5%,1/16W,CHIP,CA   I170 @S9S_MB_2U_LIB.S9S_MB_2U(SCH_1):PAGE140
  U204    2      A 74LVC1G126SE7-74LVC1G126SE-7,SA   I195 @S9S_MB_2U_LIB.S9S_MB_2U(SCH_1):PAGE140

UART_BMC_BIC_TX @S9S_MB_2U_LIB.S9S_MB_2U(SCH_1):UART_BMC_BIC_TX
  J106   N8     N8 CONN112_10137002101LF-CONN112_A    I68 @S9S_MB_2U_LIB.S9S_MB_2U(SCH_1):PAGE144
   J41  OB5 DATA_OUT SCONN168_ME1016810202011-SCONNA   I173 @S9S_MB_2U_LIB.S9S_MB_2U(SCH_1):PAGE227

UNNAMED_310_TPTDR4PFTS_I10_S1 @S9S_MB_2U_LIB.S9S_MB_2U(SCH_1):UNNAMED_310_TPTDR4PFTS_I10_S1
   X36    4     S2 TP_TDR_4P_FTS_TH-TP_TDR_4P_DIPA     I8 @S9S_MB_2U_LIB.S9S_MB_2U(SCH_1):PAGE310
   X42    1     S1 TP_TDR_4P_FTS_TH-TP_TDR_4P_DIPA    I10 @S9S_MB_2U_LIB.S9S_MB_2U(SCH_1):PAGE310

UNNAMED_310_TPTDR4PFTS_I10_S2 @S9S_MB_2U_LIB.S9S_MB_2U(SCH_1):UNNAMED_310_TPTDR4PFTS_I10_S2
   X36    1     S1 TP_TDR_4P_FTS_TH-TP_TDR_4P_DIPA     I8 @S9S_MB_2U_LIB.S9S_MB_2U(SCH_1):PAGE310
   X42    4     S2 TP_TDR_4P_FTS_TH-TP_TDR_4P_DIPA    I10 @S9S_MB_2U_LIB.S9S_MB_2U(SCH_1):PAGE310

UNNAMED_310_TPTDR4PFTS_I15_S1 @S9S_MB_2U_LIB.S9S_MB_2U(SCH_1):UNNAMED_310_TPTDR4PFTS_I15_S1
   X41    1     S1 TP_TDR_4P_FTS_TH-TP_TDR_4P_DIPA    I15 @S9S_MB_2U_LIB.S9S_MB_2U(SCH_1):PAGE310
   X35    4     S2 TP_TDR_4P_FTS_TH-TP_TDR_4P_DIPA    I16 @S9S_MB_2U_LIB.S9S_MB_2U(SCH_1):PAGE310

UNNAMED_310_TPTDR4PFTS_I15_S2 @S9S_MB_2U_LIB.S9S_MB_2U(SCH_1):UNNAMED_310_TPTDR4PFTS_I15_S2
   X41    4     S2 TP_TDR_4P_FTS_TH-TP_TDR_4P_DIPA    I15 @S9S_MB_2U_LIB.S9S_MB_2U(SCH_1):PAGE310
   X35    1     S1 TP_TDR_4P_FTS_TH-TP_TDR_4P_DIPA    I16 @S9S_MB_2U_LIB.S9S_MB_2U(SCH_1):PAGE310

UNNAMED_310_TPTDR4PFTS_I19_S1 @S9S_MB_2U_LIB.S9S_MB_2U(SCH_1):UNNAMED_310_TPTDR4PFTS_I19_S1
   X34    1     S1 TP_TDR_4P_FTS_TH-TP_TDR_4P_DIPA    I19 @S9S_MB_2U_LIB.S9S_MB_2U(SCH_1):PAGE310
   X40    4     S2 TP_TDR_4P_FTS_TH-TP_TDR_4P_DIPA    I21 @S9S_MB_2U_LIB.S9S_MB_2U(SCH_1):PAGE310

UNNAMED_310_TPTDR4PFTS_I19_S2 @S9S_MB_2U_LIB.S9S_MB_2U(SCH_1):UNNAMED_310_TPTDR4PFTS_I19_S2
   X34    4     S2 TP_TDR_4P_FTS_TH-TP_TDR_4P_DIPA    I19 @S9S_MB_2U_LIB.S9S_MB_2U(SCH_1):PAGE310
   X40    1     S1 TP_TDR_4P_FTS_TH-TP_TDR_4P_DIPA    I21 @S9S_MB_2U_LIB.S9S_MB_2U(SCH_1):PAGE310

UNNAMED_310_TPTDR4PFTS_I20_S1 @S9S_MB_2U_LIB.S9S_MB_2U(SCH_1):UNNAMED_310_TPTDR4PFTS_I20_S1
   X33    1     S1 TP_TDR_4P_FTS_TH-TP_TDR_4P_DIPA    I20 @S9S_MB_2U_LIB.S9S_MB_2U(SCH_1):PAGE310
   X39    4     S2 TP_TDR_4P_FTS_TH-TP_TDR_4P_DIPA    I22 @S9S_MB_2U_LIB.S9S_MB_2U(SCH_1):PAGE310

UNNAMED_310_TPTDR4PFTS_I20_S2 @S9S_MB_2U_LIB.S9S_MB_2U(SCH_1):UNNAMED_310_TPTDR4PFTS_I20_S2
   X33    4     S2 TP_TDR_4P_FTS_TH-TP_TDR_4P_DIPA    I20 @S9S_MB_2U_LIB.S9S_MB_2U(SCH_1):PAGE310
   X39    1     S1 TP_TDR_4P_FTS_TH-TP_TDR_4P_DIPA    I22 @S9S_MB_2U_LIB.S9S_MB_2U(SCH_1):PAGE310

UNNAMED_310_TPTDR4PFTS_I5_S1 @S9S_MB_2U_LIB.S9S_MB_2U(SCH_1):UNNAMED_310_TPTDR4PFTS_I5_S1
   X38    1     S1 TP_TDR_4P_FTS_TH-TP_TDR_4P_DIPA     I5 @S9S_MB_2U_LIB.S9S_MB_2U(SCH_1):PAGE310
   X44    4     S2 TP_TDR_4P_FTS_TH-TP_TDR_4P_DIPA     I6 @S9S_MB_2U_LIB.S9S_MB_2U(SCH_1):PAGE310

UNNAMED_310_TPTDR4PFTS_I5_S2 @S9S_MB_2U_LIB.S9S_MB_2U(SCH_1):UNNAMED_310_TPTDR4PFTS_I5_S2
   X38    4     S2 TP_TDR_4P_FTS_TH-TP_TDR_4P_DIPA     I5 @S9S_MB_2U_LIB.S9S_MB_2U(SCH_1):PAGE310
   X44    1     S1 TP_TDR_4P_FTS_TH-TP_TDR_4P_DIPA     I6 @S9S_MB_2U_LIB.S9S_MB_2U(SCH_1):PAGE310

UNNAMED_310_TPTDR4PFTS_I7_S1 @S9S_MB_2U_LIB.S9S_MB_2U(SCH_1):UNNAMED_310_TPTDR4PFTS_I7_S1
   X37    1     S1 TP_TDR_4P_FTS_TH-TP_TDR_4P_DIPA     I7 @S9S_MB_2U_LIB.S9S_MB_2U(SCH_1):PAGE310
   X43    4     S2 TP_TDR_4P_FTS_TH-TP_TDR_4P_DIPA     I9 @S9S_MB_2U_LIB.S9S_MB_2U(SCH_1):PAGE310

UNNAMED_310_TPTDR4PFTS_I7_S2 @S9S_MB_2U_LIB.S9S_MB_2U(SCH_1):UNNAMED_310_TPTDR4PFTS_I7_S2
   X37    4     S2 TP_TDR_4P_FTS_TH-TP_TDR_4P_DIPA     I7 @S9S_MB_2U_LIB.S9S_MB_2U(SCH_1):PAGE310
   X43    1     S1 TP_TDR_4P_FTS_TH-TP_TDR_4P_DIPA     I9 @S9S_MB_2U_LIB.S9S_MB_2U(SCH_1):PAGE310

UPI_CPU0_CPU1_P0P1_DN<0> @S9S_MB_2U_LIB.S9S_MB_2U(SCH_1):UPI_CPU0_CPU1_P0P1_DN(0)
    U2   K4 UPI0_TX_DN0 SOCKET4677_AZIF0045P001C01CS-SA    I70 @S9S_MB_2U_LIB.S9S_MB_2U(SCH_1):PAGE32
    U1  EH2 UPI1_RX_DN0 SOCKET4677_AZIF0045P001C01CS-SA    I21 @S9S_MB_2U_LIB.S9S_MB_2U(SCH_1):PAGE64

UPI_CPU0_CPU1_P0P1_DN<10> @S9S_MB_2U_LIB.S9S_MB_2U(SCH_1):UPI_CPU0_CPU1_P0P1_DN(10)
    U2  AK2 UPI0_TX_DN10 SOCKET4677_AZIF0045P001C01CS-SA    I70 @S9S_MB_2U_LIB.S9S_MB_2U(SCH_1):PAGE32
    U1  DG3 UPI1_RX_DN10 SOCKET4677_AZIF0045P001C01CS-SA    I21 @S9S_MB_2U_LIB.S9S_MB_2U(SCH_1):PAGE64

UPI_CPU0_CPU1_P0P1_DN<11> @S9S_MB_2U_LIB.S9S_MB_2U(SCH_1):UPI_CPU0_CPU1_P0P1_DN(11)
    U2  AM2 UPI0_TX_DN11 SOCKET4677_AZIF0045P001C01CS-SA    I70 @S9S_MB_2U_LIB.S9S_MB_2U(SCH_1):PAGE32
    U1  DE1 UPI1_RX_DN11 SOCKET4677_AZIF0045P001C01CS-SA    I21 @S9S_MB_2U_LIB.S9S_MB_2U(SCH_1):PAGE64

UPI_CPU0_CPU1_P0P1_DN<12> @S9S_MB_2U_LIB.S9S_MB_2U(SCH_1):UPI_CPU0_CPU1_P0P1_DN(12)
    U2  AN1 UPI0_TX_DP12 SOCKET4677_AZIF0045P001C01CS-SA    I70 @S9S_MB_2U_LIB.S9S_MB_2U(SCH_1):PAGE32
    U1  DD2 UPI1_RX_DN12 SOCKET4677_AZIF0045P001C01CS-SA    I21 @S9S_MB_2U_LIB.S9S_MB_2U(SCH_1):PAGE64

UPI_CPU0_CPU1_P0P1_DN<13> @S9S_MB_2U_LIB.S9S_MB_2U(SCH_1):UPI_CPU0_CPU1_P0P1_DN(13)
    U2  AR3 UPI0_TX_DP13 SOCKET4677_AZIF0045P001C01CS-SA    I70 @S9S_MB_2U_LIB.S9S_MB_2U(SCH_1):PAGE32
    U1  DB2 UPI1_RX_DN13 SOCKET4677_AZIF0045P001C01CS-SA    I21 @S9S_MB_2U_LIB.S9S_MB_2U(SCH_1):PAGE64

UPI_CPU0_CPU1_P0P1_DN<14> @S9S_MB_2U_LIB.S9S_MB_2U(SCH_1):UPI_CPU0_CPU1_P0P1_DN(14)
    U2  AU1 UPI0_TX_DN14 SOCKET4677_AZIF0045P001C01CS-SA    I70 @S9S_MB_2U_LIB.S9S_MB_2U(SCH_1):PAGE32
    U1  CY2 UPI1_RX_DN14 SOCKET4677_AZIF0045P001C01CS-SA    I21 @S9S_MB_2U_LIB.S9S_MB_2U(SCH_1):PAGE64

UPI_CPU0_CPU1_P0P1_DN<15> @S9S_MB_2U_LIB.S9S_MB_2U(SCH_1):UPI_CPU0_CPU1_P0P1_DN(15)
    U2  AW3 UPI0_TX_DP15 SOCKET4677_AZIF0045P001C01CS-SA    I70 @S9S_MB_2U_LIB.S9S_MB_2U(SCH_1):PAGE32
    U1  CV2 UPI1_RX_DN15 SOCKET4677_AZIF0045P001C01CS-SA    I21 @S9S_MB_2U_LIB.S9S_MB_2U(SCH_1):PAGE64

UPI_CPU0_CPU1_P0P1_DN<16> @S9S_MB_2U_LIB.S9S_MB_2U(SCH_1):UPI_CPU0_CPU1_P0P1_DN(16)
    U2  BB2 UPI0_TX_DN16 SOCKET4677_AZIF0045P001C01CS-SA    I70 @S9S_MB_2U_LIB.S9S_MB_2U(SCH_1):PAGE32
    U1  CR3 UPI1_RX_DN16 SOCKET4677_AZIF0045P001C01CS-SA    I21 @S9S_MB_2U_LIB.S9S_MB_2U(SCH_1):PAGE64

UPI_CPU0_CPU1_P0P1_DN<17> @S9S_MB_2U_LIB.S9S_MB_2U(SCH_1):UPI_CPU0_CPU1_P0P1_DN(17)
    U2  BD2 UPI0_TX_DN17 SOCKET4677_AZIF0045P001C01CS-SA    I70 @S9S_MB_2U_LIB.S9S_MB_2U(SCH_1):PAGE32
    U1  CN1 UPI1_RX_DN17 SOCKET4677_AZIF0045P001C01CS-SA    I21 @S9S_MB_2U_LIB.S9S_MB_2U(SCH_1):PAGE64

UPI_CPU0_CPU1_P0P1_DN<18> @S9S_MB_2U_LIB.S9S_MB_2U(SCH_1):UPI_CPU0_CPU1_P0P1_DN(18)
    U2  BF2 UPI0_TX_DN18 SOCKET4677_AZIF0045P001C01CS-SA    I70 @S9S_MB_2U_LIB.S9S_MB_2U(SCH_1):PAGE32
    U1  CL3 UPI1_RX_DN18 SOCKET4677_AZIF0045P001C01CS-SA    I21 @S9S_MB_2U_LIB.S9S_MB_2U(SCH_1):PAGE64

UPI_CPU0_CPU1_P0P1_DN<19> @S9S_MB_2U_LIB.S9S_MB_2U(SCH_1):UPI_CPU0_CPU1_P0P1_DN(19)
    U2  BH2 UPI0_TX_DN19 SOCKET4677_AZIF0045P001C01CS-SA    I70 @S9S_MB_2U_LIB.S9S_MB_2U(SCH_1):PAGE32
    U1  CJ1 UPI1_RX_DN19 SOCKET4677_AZIF0045P001C01CS-SA    I21 @S9S_MB_2U_LIB.S9S_MB_2U(SCH_1):PAGE64

UPI_CPU0_CPU1_P0P1_DN<1> @S9S_MB_2U_LIB.S9S_MB_2U(SCH_1):UPI_CPU0_CPU1_P0P1_DN(1)
    U2   M2 UPI0_TX_DN1 SOCKET4677_AZIF0045P001C01CS-SA    I70 @S9S_MB_2U_LIB.S9S_MB_2U(SCH_1):PAGE32
    U1  EE3 UPI1_RX_DN1 SOCKET4677_AZIF0045P001C01CS-SA    I21 @S9S_MB_2U_LIB.S9S_MB_2U(SCH_1):PAGE64

UPI_CPU0_CPU1_P0P1_DN<20> @S9S_MB_2U_LIB.S9S_MB_2U(SCH_1):UPI_CPU0_CPU1_P0P1_DN(20)
    U2  BJ1 UPI0_TX_DP20 SOCKET4677_AZIF0045P001C01CS-SA    I70 @S9S_MB_2U_LIB.S9S_MB_2U(SCH_1):PAGE32
    U1  CH2 UPI1_RX_DN20 SOCKET4677_AZIF0045P001C01CS-SA    I21 @S9S_MB_2U_LIB.S9S_MB_2U(SCH_1):PAGE64

UPI_CPU0_CPU1_P0P1_DN<21> @S9S_MB_2U_LIB.S9S_MB_2U(SCH_1):UPI_CPU0_CPU1_P0P1_DN(21)
    U2  BL3 UPI0_TX_DP21 SOCKET4677_AZIF0045P001C01CS-SA    I70 @S9S_MB_2U_LIB.S9S_MB_2U(SCH_1):PAGE32
    U1  CF2 UPI1_RX_DN21 SOCKET4677_AZIF0045P001C01CS-SA    I21 @S9S_MB_2U_LIB.S9S_MB_2U(SCH_1):PAGE64

UPI_CPU0_CPU1_P0P1_DN<22> @S9S_MB_2U_LIB.S9S_MB_2U(SCH_1):UPI_CPU0_CPU1_P0P1_DN(22)
    U2  BN3 UPI0_TX_DP22 SOCKET4677_AZIF0045P001C01CS-SA    I70 @S9S_MB_2U_LIB.S9S_MB_2U(SCH_1):PAGE32
    U1  CD2 UPI1_RX_DN22 SOCKET4677_AZIF0045P001C01CS-SA    I21 @S9S_MB_2U_LIB.S9S_MB_2U(SCH_1):PAGE64

UPI_CPU0_CPU1_P0P1_DN<23> @S9S_MB_2U_LIB.S9S_MB_2U(SCH_1):UPI_CPU0_CPU1_P0P1_DN(23)
    U2  BT2 UPI0_TX_DN23 SOCKET4677_AZIF0045P001C01CS-SA    I70 @S9S_MB_2U_LIB.S9S_MB_2U(SCH_1):PAGE32
    U1  CB2 UPI1_RX_DN23 SOCKET4677_AZIF0045P001C01CS-SA    I21 @S9S_MB_2U_LIB.S9S_MB_2U(SCH_1):PAGE64

UPI_CPU0_CPU1_P0P1_DN<2> @S9S_MB_2U_LIB.S9S_MB_2U(SCH_1):UPI_CPU0_CPU1_P0P1_DN(2)
    U2   N1 UPI0_TX_DN2 SOCKET4677_AZIF0045P001C01CS-SA    I70 @S9S_MB_2U_LIB.S9S_MB_2U(SCH_1):PAGE32
    U1  ED2 UPI1_RX_DN2 SOCKET4677_AZIF0045P001C01CS-SA    I21 @S9S_MB_2U_LIB.S9S_MB_2U(SCH_1):PAGE64

UPI_CPU0_CPU1_P0P1_DN<3> @S9S_MB_2U_LIB.S9S_MB_2U(SCH_1):UPI_CPU0_CPU1_P0P1_DN(3)
    U2   T2 UPI0_TX_DN3 SOCKET4677_AZIF0045P001C01CS-SA    I70 @S9S_MB_2U_LIB.S9S_MB_2U(SCH_1):PAGE32
    U1  EA1 UPI1_RX_DN3 SOCKET4677_AZIF0045P001C01CS-SA    I21 @S9S_MB_2U_LIB.S9S_MB_2U(SCH_1):PAGE64

UPI_CPU0_CPU1_P0P1_DN<4> @S9S_MB_2U_LIB.S9S_MB_2U(SCH_1):UPI_CPU0_CPU1_P0P1_DN(4)
    U2   U1 UPI0_TX_DN4 SOCKET4677_AZIF0045P001C01CS-SA    I70 @S9S_MB_2U_LIB.S9S_MB_2U(SCH_1):PAGE32
    U1  DY2 UPI1_RX_DN4 SOCKET4677_AZIF0045P001C01CS-SA    I21 @S9S_MB_2U_LIB.S9S_MB_2U(SCH_1):PAGE64

UPI_CPU0_CPU1_P0P1_DN<5> @S9S_MB_2U_LIB.S9S_MB_2U(SCH_1):UPI_CPU0_CPU1_P0P1_DN(5)
    U2   Y2 UPI0_TX_DN5 SOCKET4677_AZIF0045P001C01CS-SA    I70 @S9S_MB_2U_LIB.S9S_MB_2U(SCH_1):PAGE32
    U1  DU1 UPI1_RX_DN5 SOCKET4677_AZIF0045P001C01CS-SA    I21 @S9S_MB_2U_LIB.S9S_MB_2U(SCH_1):PAGE64

UPI_CPU0_CPU1_P0P1_DN<6> @S9S_MB_2U_LIB.S9S_MB_2U(SCH_1):UPI_CPU0_CPU1_P0P1_DN(6)
    U2  AA1 UPI0_TX_DN6 SOCKET4677_AZIF0045P001C01CS-SA    I70 @S9S_MB_2U_LIB.S9S_MB_2U(SCH_1):PAGE32
    U1  DT2 UPI1_RX_DN6 SOCKET4677_AZIF0045P001C01CS-SA    I21 @S9S_MB_2U_LIB.S9S_MB_2U(SCH_1):PAGE64

UPI_CPU0_CPU1_P0P1_DN<7> @S9S_MB_2U_LIB.S9S_MB_2U(SCH_1):UPI_CPU0_CPU1_P0P1_DN(7)
    U2  AD2 UPI0_TX_DN7 SOCKET4677_AZIF0045P001C01CS-SA    I70 @S9S_MB_2U_LIB.S9S_MB_2U(SCH_1):PAGE32
    U1  DN1 UPI1_RX_DN7 SOCKET4677_AZIF0045P001C01CS-SA    I21 @S9S_MB_2U_LIB.S9S_MB_2U(SCH_1):PAGE64

UPI_CPU0_CPU1_P0P1_DN<8> @S9S_MB_2U_LIB.S9S_MB_2U(SCH_1):UPI_CPU0_CPU1_P0P1_DN(8)
    U2  AF2 UPI0_TX_DN8 SOCKET4677_AZIF0045P001C01CS-SA    I70 @S9S_MB_2U_LIB.S9S_MB_2U(SCH_1):PAGE32
    U1  DL3 UPI1_RX_DN8 SOCKET4677_AZIF0045P001C01CS-SA    I21 @S9S_MB_2U_LIB.S9S_MB_2U(SCH_1):PAGE64

UPI_CPU0_CPU1_P0P1_DN<9> @S9S_MB_2U_LIB.S9S_MB_2U(SCH_1):UPI_CPU0_CPU1_P0P1_DN(9)
    U2  AH2 UPI0_TX_DN9 SOCKET4677_AZIF0045P001C01CS-SA    I70 @S9S_MB_2U_LIB.S9S_MB_2U(SCH_1):PAGE32
    U1  DJ1 UPI1_RX_DN9 SOCKET4677_AZIF0045P001C01CS-SA    I21 @S9S_MB_2U_LIB.S9S_MB_2U(SCH_1):PAGE64

UPI_CPU0_CPU1_P0P1_DP<0> @S9S_MB_2U_LIB.S9S_MB_2U(SCH_1):UPI_CPU0_CPU1_P0P1_DP(0)
    U2   J3 UPI0_TX_DP0 SOCKET4677_AZIF0045P001C01CS-SA    I70 @S9S_MB_2U_LIB.S9S_MB_2U(SCH_1):PAGE32
    U1  EJ3 UPI1_RX_DP0 SOCKET4677_AZIF0045P001C01CS-SA    I21 @S9S_MB_2U_LIB.S9S_MB_2U(SCH_1):PAGE64

UPI_CPU0_CPU1_P0P1_DP<10> @S9S_MB_2U_LIB.S9S_MB_2U(SCH_1):UPI_CPU0_CPU1_P0P1_DP(10)
    U2  AJ1 UPI0_TX_DP10 SOCKET4677_AZIF0045P001C01CS-SA    I70 @S9S_MB_2U_LIB.S9S_MB_2U(SCH_1):PAGE32
    U1  DH2 UPI1_RX_DP10 SOCKET4677_AZIF0045P001C01CS-SA    I21 @S9S_MB_2U_LIB.S9S_MB_2U(SCH_1):PAGE64

UPI_CPU0_CPU1_P0P1_DP<11> @S9S_MB_2U_LIB.S9S_MB_2U(SCH_1):UPI_CPU0_CPU1_P0P1_DP(11)
    U2  AL3 UPI0_TX_DP11 SOCKET4677_AZIF0045P001C01CS-SA    I70 @S9S_MB_2U_LIB.S9S_MB_2U(SCH_1):PAGE32
    U1  DF2 UPI1_RX_DP11 SOCKET4677_AZIF0045P001C01CS-SA    I21 @S9S_MB_2U_LIB.S9S_MB_2U(SCH_1):PAGE64

UPI_CPU0_CPU1_P0P1_DP<12> @S9S_MB_2U_LIB.S9S_MB_2U(SCH_1):UPI_CPU0_CPU1_P0P1_DP(12)
    U2  AP2 UPI0_TX_DN12 SOCKET4677_AZIF0045P001C01CS-SA    I70 @S9S_MB_2U_LIB.S9S_MB_2U(SCH_1):PAGE32
    U1  DC3 UPI1_RX_DP12 SOCKET4677_AZIF0045P001C01CS-SA    I21 @S9S_MB_2U_LIB.S9S_MB_2U(SCH_1):PAGE64

UPI_CPU0_CPU1_P0P1_DP<13> @S9S_MB_2U_LIB.S9S_MB_2U(SCH_1):UPI_CPU0_CPU1_P0P1_DP(13)
    U2  AT2 UPI0_TX_DN13 SOCKET4677_AZIF0045P001C01CS-SA    I70 @S9S_MB_2U_LIB.S9S_MB_2U(SCH_1):PAGE32
    U1  DA1 UPI1_RX_DP13 SOCKET4677_AZIF0045P001C01CS-SA    I21 @S9S_MB_2U_LIB.S9S_MB_2U(SCH_1):PAGE64

UPI_CPU0_CPU1_P0P1_DP<14> @S9S_MB_2U_LIB.S9S_MB_2U(SCH_1):UPI_CPU0_CPU1_P0P1_DP(14)
    U2  AV2 UPI0_TX_DP14 SOCKET4677_AZIF0045P001C01CS-SA    I70 @S9S_MB_2U_LIB.S9S_MB_2U(SCH_1):PAGE32
    U1  CW3 UPI1_RX_DP14 SOCKET4677_AZIF0045P001C01CS-SA    I21 @S9S_MB_2U_LIB.S9S_MB_2U(SCH_1):PAGE64

UPI_CPU0_CPU1_P0P1_DP<15> @S9S_MB_2U_LIB.S9S_MB_2U(SCH_1):UPI_CPU0_CPU1_P0P1_DP(15)
    U2  AY2 UPI0_TX_DN15 SOCKET4677_AZIF0045P001C01CS-SA    I70 @S9S_MB_2U_LIB.S9S_MB_2U(SCH_1):PAGE32
    U1  CU1 UPI1_RX_DP15 SOCKET4677_AZIF0045P001C01CS-SA    I21 @S9S_MB_2U_LIB.S9S_MB_2U(SCH_1):PAGE64

UPI_CPU0_CPU1_P0P1_DP<16> @S9S_MB_2U_LIB.S9S_MB_2U(SCH_1):UPI_CPU0_CPU1_P0P1_DP(16)
    U2  BA1 UPI0_TX_DP16 SOCKET4677_AZIF0045P001C01CS-SA    I70 @S9S_MB_2U_LIB.S9S_MB_2U(SCH_1):PAGE32
    U1  CT2 UPI1_RX_DP16 SOCKET4677_AZIF0045P001C01CS-SA    I21 @S9S_MB_2U_LIB.S9S_MB_2U(SCH_1):PAGE64

UPI_CPU0_CPU1_P0P1_DP<17> @S9S_MB_2U_LIB.S9S_MB_2U(SCH_1):UPI_CPU0_CPU1_P0P1_DP(17)
    U2  BC3 UPI0_TX_DP17 SOCKET4677_AZIF0045P001C01CS-SA    I70 @S9S_MB_2U_LIB.S9S_MB_2U(SCH_1):PAGE32
    U1  CP2 UPI1_RX_DP17 SOCKET4677_AZIF0045P001C01CS-SA    I21 @S9S_MB_2U_LIB.S9S_MB_2U(SCH_1):PAGE64

UPI_CPU0_CPU1_P0P1_DP<18> @S9S_MB_2U_LIB.S9S_MB_2U(SCH_1):UPI_CPU0_CPU1_P0P1_DP(18)
    U2  BE1 UPI0_TX_DP18 SOCKET4677_AZIF0045P001C01CS-SA    I70 @S9S_MB_2U_LIB.S9S_MB_2U(SCH_1):PAGE32
    U1  CM2 UPI1_RX_DP18 SOCKET4677_AZIF0045P001C01CS-SA    I21 @S9S_MB_2U_LIB.S9S_MB_2U(SCH_1):PAGE64

UPI_CPU0_CPU1_P0P1_DP<19> @S9S_MB_2U_LIB.S9S_MB_2U(SCH_1):UPI_CPU0_CPU1_P0P1_DP(19)
    U2  BG3 UPI0_TX_DP19 SOCKET4677_AZIF0045P001C01CS-SA    I70 @S9S_MB_2U_LIB.S9S_MB_2U(SCH_1):PAGE32
    U1  CK2 UPI1_RX_DP19 SOCKET4677_AZIF0045P001C01CS-SA    I21 @S9S_MB_2U_LIB.S9S_MB_2U(SCH_1):PAGE64

UPI_CPU0_CPU1_P0P1_DP<1> @S9S_MB_2U_LIB.S9S_MB_2U(SCH_1):UPI_CPU0_CPU1_P0P1_DP(1)
    U2   L3 UPI0_TX_DP1 SOCKET4677_AZIF0045P001C01CS-SA    I70 @S9S_MB_2U_LIB.S9S_MB_2U(SCH_1):PAGE32
    U1  EG3 UPI1_RX_DP1 SOCKET4677_AZIF0045P001C01CS-SA    I21 @S9S_MB_2U_LIB.S9S_MB_2U(SCH_1):PAGE64

UPI_CPU0_CPU1_P0P1_DP<20> @S9S_MB_2U_LIB.S9S_MB_2U(SCH_1):UPI_CPU0_CPU1_P0P1_DP(20)
    U2  BK2 UPI0_TX_DN20 SOCKET4677_AZIF0045P001C01CS-SA    I70 @S9S_MB_2U_LIB.S9S_MB_2U(SCH_1):PAGE32
    U1  CG3 UPI1_RX_DP20 SOCKET4677_AZIF0045P001C01CS-SA    I21 @S9S_MB_2U_LIB.S9S_MB_2U(SCH_1):PAGE64

UPI_CPU0_CPU1_P0P1_DP<21> @S9S_MB_2U_LIB.S9S_MB_2U(SCH_1):UPI_CPU0_CPU1_P0P1_DP(21)
    U2  BM2 UPI0_TX_DN21 SOCKET4677_AZIF0045P001C01CS-SA    I70 @S9S_MB_2U_LIB.S9S_MB_2U(SCH_1):PAGE32
    U1  CE1 UPI1_RX_DP21 SOCKET4677_AZIF0045P001C01CS-SA    I21 @S9S_MB_2U_LIB.S9S_MB_2U(SCH_1):PAGE64

UPI_CPU0_CPU1_P0P1_DP<22> @S9S_MB_2U_LIB.S9S_MB_2U(SCH_1):UPI_CPU0_CPU1_P0P1_DP(22)
    U2  BR3 UPI0_TX_DN22 SOCKET4677_AZIF0045P001C01CS-SA    I70 @S9S_MB_2U_LIB.S9S_MB_2U(SCH_1):PAGE32
    U1  CC3 UPI1_RX_DP22 SOCKET4677_AZIF0045P001C01CS-SA    I21 @S9S_MB_2U_LIB.S9S_MB_2U(SCH_1):PAGE64

UPI_CPU0_CPU1_P0P1_DP<23> @S9S_MB_2U_LIB.S9S_MB_2U(SCH_1):UPI_CPU0_CPU1_P0P1_DP(23)
    U2  BU3 UPI0_TX_DP23 SOCKET4677_AZIF0045P001C01CS-SA    I70 @S9S_MB_2U_LIB.S9S_MB_2U(SCH_1):PAGE32
    U1  BY2 UPI1_RX_DP23 SOCKET4677_AZIF0045P001C01CS-SA    I21 @S9S_MB_2U_LIB.S9S_MB_2U(SCH_1):PAGE64

UPI_CPU0_CPU1_P0P1_DP<2> @S9S_MB_2U_LIB.S9S_MB_2U(SCH_1):UPI_CPU0_CPU1_P0P1_DP(2)
    U2   P2 UPI0_TX_DP2 SOCKET4677_AZIF0045P001C01CS-SA    I70 @S9S_MB_2U_LIB.S9S_MB_2U(SCH_1):PAGE32
    U1  EC3 UPI1_RX_DP2 SOCKET4677_AZIF0045P001C01CS-SA    I21 @S9S_MB_2U_LIB.S9S_MB_2U(SCH_1):PAGE64

UPI_CPU0_CPU1_P0P1_DP<3> @S9S_MB_2U_LIB.S9S_MB_2U(SCH_1):UPI_CPU0_CPU1_P0P1_DP(3)
    U2   R3 UPI0_TX_DP3 SOCKET4677_AZIF0045P001C01CS-SA    I70 @S9S_MB_2U_LIB.S9S_MB_2U(SCH_1):PAGE32
    U1  EB2 UPI1_RX_DP3 SOCKET4677_AZIF0045P001C01CS-SA    I21 @S9S_MB_2U_LIB.S9S_MB_2U(SCH_1):PAGE64

UPI_CPU0_CPU1_P0P1_DP<4> @S9S_MB_2U_LIB.S9S_MB_2U(SCH_1):UPI_CPU0_CPU1_P0P1_DP(4)
    U2   V2 UPI0_TX_DP4 SOCKET4677_AZIF0045P001C01CS-SA    I70 @S9S_MB_2U_LIB.S9S_MB_2U(SCH_1):PAGE32
    U1  DW3 UPI1_RX_DP4 SOCKET4677_AZIF0045P001C01CS-SA    I21 @S9S_MB_2U_LIB.S9S_MB_2U(SCH_1):PAGE64

UPI_CPU0_CPU1_P0P1_DP<5> @S9S_MB_2U_LIB.S9S_MB_2U(SCH_1):UPI_CPU0_CPU1_P0P1_DP(5)
    U2   W3 UPI0_TX_DP5 SOCKET4677_AZIF0045P001C01CS-SA    I70 @S9S_MB_2U_LIB.S9S_MB_2U(SCH_1):PAGE32
    U1  DV2 UPI1_RX_DP5 SOCKET4677_AZIF0045P001C01CS-SA    I21 @S9S_MB_2U_LIB.S9S_MB_2U(SCH_1):PAGE64

UPI_CPU0_CPU1_P0P1_DP<6> @S9S_MB_2U_LIB.S9S_MB_2U(SCH_1):UPI_CPU0_CPU1_P0P1_DP(6)
    U2  AB2 UPI0_TX_DP6 SOCKET4677_AZIF0045P001C01CS-SA    I70 @S9S_MB_2U_LIB.S9S_MB_2U(SCH_1):PAGE32
    U1  DR3 UPI1_RX_DP6 SOCKET4677_AZIF0045P001C01CS-SA    I21 @S9S_MB_2U_LIB.S9S_MB_2U(SCH_1):PAGE64

UPI_CPU0_CPU1_P0P1_DP<7> @S9S_MB_2U_LIB.S9S_MB_2U(SCH_1):UPI_CPU0_CPU1_P0P1_DP(7)
    U2  AC3 UPI0_TX_DP7 SOCKET4677_AZIF0045P001C01CS-SA    I70 @S9S_MB_2U_LIB.S9S_MB_2U(SCH_1):PAGE32
    U1  DP2 UPI1_RX_DP7 SOCKET4677_AZIF0045P001C01CS-SA    I21 @S9S_MB_2U_LIB.S9S_MB_2U(SCH_1):PAGE64

UPI_CPU0_CPU1_P0P1_DP<8> @S9S_MB_2U_LIB.S9S_MB_2U(SCH_1):UPI_CPU0_CPU1_P0P1_DP(8)
    U2  AE1 UPI0_TX_DP8 SOCKET4677_AZIF0045P001C01CS-SA    I70 @S9S_MB_2U_LIB.S9S_MB_2U(SCH_1):PAGE32
    U1  DM2 UPI1_RX_DP8 SOCKET4677_AZIF0045P001C01CS-SA    I21 @S9S_MB_2U_LIB.S9S_MB_2U(SCH_1):PAGE64

UPI_CPU0_CPU1_P0P1_DP<9> @S9S_MB_2U_LIB.S9S_MB_2U(SCH_1):UPI_CPU0_CPU1_P0P1_DP(9)
    U2  AG3 UPI0_TX_DP9 SOCKET4677_AZIF0045P001C01CS-SA    I70 @S9S_MB_2U_LIB.S9S_MB_2U(SCH_1):PAGE32
    U1  DK2 UPI1_RX_DP9 SOCKET4677_AZIF0045P001C01CS-SA    I21 @S9S_MB_2U_LIB.S9S_MB_2U(SCH_1):PAGE64

UPI_CPU0_CPU1_P1P0_DN<0> @S9S_MB_2U_LIB.S9S_MB_2U(SCH_1):UPI_CPU0_CPU1_P1P0_DN(0)
    U2  EF6 UPI1_TX_DN0 SOCKET4677_AZIF0045P001C01CS-SA   I102 @S9S_MB_2U_LIB.S9S_MB_2U(SCH_1):PAGE33
    U1   K6 UPI0_RX_DN0 SOCKET4677_AZIF0045P001C01CS-SA    I51 @S9S_MB_2U_LIB.S9S_MB_2U(SCH_1):PAGE63

UPI_CPU0_CPU1_P1P0_DN<10> @S9S_MB_2U_LIB.S9S_MB_2U(SCH_1):UPI_CPU0_CPU1_P1P0_DN(10)
    U2  DF6 UPI1_TX_DP10 SOCKET4677_AZIF0045P001C01CS-SA   I102 @S9S_MB_2U_LIB.S9S_MB_2U(SCH_1):PAGE33
    U1  AK6 UPI0_RX_DN10 SOCKET4677_AZIF0045P001C01CS-SA    I51 @S9S_MB_2U_LIB.S9S_MB_2U(SCH_1):PAGE63

UPI_CPU0_CPU1_P1P0_DN<11> @S9S_MB_2U_LIB.S9S_MB_2U(SCH_1):UPI_CPU0_CPU1_P1P0_DN(11)
    U2  DC7 UPI1_TX_DP11 SOCKET4677_AZIF0045P001C01CS-SA   I102 @S9S_MB_2U_LIB.S9S_MB_2U(SCH_1):PAGE33
    U1  AN5 UPI0_RX_DN11 SOCKET4677_AZIF0045P001C01CS-SA    I51 @S9S_MB_2U_LIB.S9S_MB_2U(SCH_1):PAGE63

UPI_CPU0_CPU1_P1P0_DN<12> @S9S_MB_2U_LIB.S9S_MB_2U(SCH_1):UPI_CPU0_CPU1_P1P0_DN(12)
    U2  DB6 UPI1_TX_DP12 SOCKET4677_AZIF0045P001C01CS-SA   I102 @S9S_MB_2U_LIB.S9S_MB_2U(SCH_1):PAGE33
    U1  AP6 UPI0_RX_DN12 SOCKET4677_AZIF0045P001C01CS-SA    I51 @S9S_MB_2U_LIB.S9S_MB_2U(SCH_1):PAGE63

UPI_CPU0_CPU1_P1P0_DN<13> @S9S_MB_2U_LIB.S9S_MB_2U(SCH_1):UPI_CPU0_CPU1_P1P0_DN(13)
    U2  CW7 UPI1_TX_DP13 SOCKET4677_AZIF0045P001C01CS-SA   I102 @S9S_MB_2U_LIB.S9S_MB_2U(SCH_1):PAGE33
    U1  AU5 UPI0_RX_DN13 SOCKET4677_AZIF0045P001C01CS-SA    I51 @S9S_MB_2U_LIB.S9S_MB_2U(SCH_1):PAGE63

UPI_CPU0_CPU1_P1P0_DN<14> @S9S_MB_2U_LIB.S9S_MB_2U(SCH_1):UPI_CPU0_CPU1_P1P0_DN(14)
    U2  CV6 UPI1_TX_DP14 SOCKET4677_AZIF0045P001C01CS-SA   I102 @S9S_MB_2U_LIB.S9S_MB_2U(SCH_1):PAGE33
    U1  AV6 UPI0_RX_DN14 SOCKET4677_AZIF0045P001C01CS-SA    I51 @S9S_MB_2U_LIB.S9S_MB_2U(SCH_1):PAGE63

UPI_CPU0_CPU1_P1P0_DN<15> @S9S_MB_2U_LIB.S9S_MB_2U(SCH_1):UPI_CPU0_CPU1_P1P0_DN(15)
    U2  CR7 UPI1_TX_DP15 SOCKET4677_AZIF0045P001C01CS-SA   I102 @S9S_MB_2U_LIB.S9S_MB_2U(SCH_1):PAGE33
    U1  BA5 UPI0_RX_DN15 SOCKET4677_AZIF0045P001C01CS-SA    I51 @S9S_MB_2U_LIB.S9S_MB_2U(SCH_1):PAGE63

UPI_CPU0_CPU1_P1P0_DN<16> @S9S_MB_2U_LIB.S9S_MB_2U(SCH_1):UPI_CPU0_CPU1_P1P0_DN(16)
    U2  CP6 UPI1_TX_DP16 SOCKET4677_AZIF0045P001C01CS-SA   I102 @S9S_MB_2U_LIB.S9S_MB_2U(SCH_1):PAGE33
    U1  BB6 UPI0_RX_DN16 SOCKET4677_AZIF0045P001C01CS-SA    I51 @S9S_MB_2U_LIB.S9S_MB_2U(SCH_1):PAGE63

UPI_CPU0_CPU1_P1P0_DN<17> @S9S_MB_2U_LIB.S9S_MB_2U(SCH_1):UPI_CPU0_CPU1_P1P0_DN(17)
    U2  CL7 UPI1_TX_DP17 SOCKET4677_AZIF0045P001C01CS-SA   I102 @S9S_MB_2U_LIB.S9S_MB_2U(SCH_1):PAGE33
    U1  BE5 UPI0_RX_DN17 SOCKET4677_AZIF0045P001C01CS-SA    I51 @S9S_MB_2U_LIB.S9S_MB_2U(SCH_1):PAGE63

UPI_CPU0_CPU1_P1P0_DN<18> @S9S_MB_2U_LIB.S9S_MB_2U(SCH_1):UPI_CPU0_CPU1_P1P0_DN(18)
    U2  CK6 UPI1_TX_DP18 SOCKET4677_AZIF0045P001C01CS-SA   I102 @S9S_MB_2U_LIB.S9S_MB_2U(SCH_1):PAGE33
    U1  BF6 UPI0_RX_DN18 SOCKET4677_AZIF0045P001C01CS-SA    I51 @S9S_MB_2U_LIB.S9S_MB_2U(SCH_1):PAGE63

UPI_CPU0_CPU1_P1P0_DN<19> @S9S_MB_2U_LIB.S9S_MB_2U(SCH_1):UPI_CPU0_CPU1_P1P0_DN(19)
    U2  CG7 UPI1_TX_DP19 SOCKET4677_AZIF0045P001C01CS-SA   I102 @S9S_MB_2U_LIB.S9S_MB_2U(SCH_1):PAGE33
    U1  BJ5 UPI0_RX_DN19 SOCKET4677_AZIF0045P001C01CS-SA    I51 @S9S_MB_2U_LIB.S9S_MB_2U(SCH_1):PAGE63

UPI_CPU0_CPU1_P1P0_DN<1> @S9S_MB_2U_LIB.S9S_MB_2U(SCH_1):UPI_CPU0_CPU1_P1P0_DN(1)
    U2  EC7 UPI1_TX_DN1 SOCKET4677_AZIF0045P001C01CS-SA   I102 @S9S_MB_2U_LIB.S9S_MB_2U(SCH_1):PAGE33
    U1   N5 UPI0_RX_DN1 SOCKET4677_AZIF0045P001C01CS-SA    I51 @S9S_MB_2U_LIB.S9S_MB_2U(SCH_1):PAGE63

UPI_CPU0_CPU1_P1P0_DN<20> @S9S_MB_2U_LIB.S9S_MB_2U(SCH_1):UPI_CPU0_CPU1_P1P0_DN(20)
    U2  CF6 UPI1_TX_DP20 SOCKET4677_AZIF0045P001C01CS-SA   I102 @S9S_MB_2U_LIB.S9S_MB_2U(SCH_1):PAGE33
    U1  BK6 UPI0_RX_DN20 SOCKET4677_AZIF0045P001C01CS-SA    I51 @S9S_MB_2U_LIB.S9S_MB_2U(SCH_1):PAGE63

UPI_CPU0_CPU1_P1P0_DN<21> @S9S_MB_2U_LIB.S9S_MB_2U(SCH_1):UPI_CPU0_CPU1_P1P0_DN(21)
    U2  CC7 UPI1_TX_DP21 SOCKET4677_AZIF0045P001C01CS-SA   I102 @S9S_MB_2U_LIB.S9S_MB_2U(SCH_1):PAGE33
    U1  BN5 UPI0_RX_DN21 SOCKET4677_AZIF0045P001C01CS-SA    I51 @S9S_MB_2U_LIB.S9S_MB_2U(SCH_1):PAGE63

UPI_CPU0_CPU1_P1P0_DN<22> @S9S_MB_2U_LIB.S9S_MB_2U(SCH_1):UPI_CPU0_CPU1_P1P0_DN(22)
    U2  CA5 UPI1_TX_DN22 SOCKET4677_AZIF0045P001C01CS-SA   I102 @S9S_MB_2U_LIB.S9S_MB_2U(SCH_1):PAGE33
    U1  BR7 UPI0_RX_DN22 SOCKET4677_AZIF0045P001C01CS-SA    I51 @S9S_MB_2U_LIB.S9S_MB_2U(SCH_1):PAGE63

UPI_CPU0_CPU1_P1P0_DN<23> @S9S_MB_2U_LIB.S9S_MB_2U(SCH_1):UPI_CPU0_CPU1_P1P0_DN(23)
    U2  BW7 UPI1_TX_DP23 SOCKET4677_AZIF0045P001C01CS-SA   I102 @S9S_MB_2U_LIB.S9S_MB_2U(SCH_1):PAGE33
    U1  BU5 UPI0_RX_DN23 SOCKET4677_AZIF0045P001C01CS-SA    I51 @S9S_MB_2U_LIB.S9S_MB_2U(SCH_1):PAGE63

UPI_CPU0_CPU1_P1P0_DN<2> @S9S_MB_2U_LIB.S9S_MB_2U(SCH_1):UPI_CPU0_CPU1_P1P0_DN(2)
    U2  EB6 UPI1_TX_DN2 SOCKET4677_AZIF0045P001C01CS-SA   I102 @S9S_MB_2U_LIB.S9S_MB_2U(SCH_1):PAGE33
    U1   P6 UPI0_RX_DN2 SOCKET4677_AZIF0045P001C01CS-SA    I51 @S9S_MB_2U_LIB.S9S_MB_2U(SCH_1):PAGE63

UPI_CPU0_CPU1_P1P0_DN<3> @S9S_MB_2U_LIB.S9S_MB_2U(SCH_1):UPI_CPU0_CPU1_P1P0_DN(3)
    U2  DW7 UPI1_TX_DP3 SOCKET4677_AZIF0045P001C01CS-SA   I102 @S9S_MB_2U_LIB.S9S_MB_2U(SCH_1):PAGE33
    U1   U5 UPI0_RX_DN3 SOCKET4677_AZIF0045P001C01CS-SA    I51 @S9S_MB_2U_LIB.S9S_MB_2U(SCH_1):PAGE63

UPI_CPU0_CPU1_P1P0_DN<4> @S9S_MB_2U_LIB.S9S_MB_2U(SCH_1):UPI_CPU0_CPU1_P1P0_DN(4)
    U2  DV6 UPI1_TX_DN4 SOCKET4677_AZIF0045P001C01CS-SA   I102 @S9S_MB_2U_LIB.S9S_MB_2U(SCH_1):PAGE33
    U1   V6 UPI0_RX_DN4 SOCKET4677_AZIF0045P001C01CS-SA    I51 @S9S_MB_2U_LIB.S9S_MB_2U(SCH_1):PAGE63

UPI_CPU0_CPU1_P1P0_DN<5> @S9S_MB_2U_LIB.S9S_MB_2U(SCH_1):UPI_CPU0_CPU1_P1P0_DN(5)
    U2  DR7 UPI1_TX_DP5 SOCKET4677_AZIF0045P001C01CS-SA   I102 @S9S_MB_2U_LIB.S9S_MB_2U(SCH_1):PAGE33
    U1  AA5 UPI0_RX_DN5 SOCKET4677_AZIF0045P001C01CS-SA    I51 @S9S_MB_2U_LIB.S9S_MB_2U(SCH_1):PAGE63

UPI_CPU0_CPU1_P1P0_DN<6> @S9S_MB_2U_LIB.S9S_MB_2U(SCH_1):UPI_CPU0_CPU1_P1P0_DN(6)
    U2  DP6 UPI1_TX_DN6 SOCKET4677_AZIF0045P001C01CS-SA   I102 @S9S_MB_2U_LIB.S9S_MB_2U(SCH_1):PAGE33
    U1  AB6 UPI0_RX_DN6 SOCKET4677_AZIF0045P001C01CS-SA    I51 @S9S_MB_2U_LIB.S9S_MB_2U(SCH_1):PAGE63

UPI_CPU0_CPU1_P1P0_DN<7> @S9S_MB_2U_LIB.S9S_MB_2U(SCH_1):UPI_CPU0_CPU1_P1P0_DN(7)
    U2  DL7 UPI1_TX_DN7 SOCKET4677_AZIF0045P001C01CS-SA   I102 @S9S_MB_2U_LIB.S9S_MB_2U(SCH_1):PAGE33
    U1  AE5 UPI0_RX_DN7 SOCKET4677_AZIF0045P001C01CS-SA    I51 @S9S_MB_2U_LIB.S9S_MB_2U(SCH_1):PAGE63

UPI_CPU0_CPU1_P1P0_DN<8> @S9S_MB_2U_LIB.S9S_MB_2U(SCH_1):UPI_CPU0_CPU1_P1P0_DN(8)
    U2  DK6 UPI1_TX_DN8 SOCKET4677_AZIF0045P001C01CS-SA   I102 @S9S_MB_2U_LIB.S9S_MB_2U(SCH_1):PAGE33
    U1  AF6 UPI0_RX_DN8 SOCKET4677_AZIF0045P001C01CS-SA    I51 @S9S_MB_2U_LIB.S9S_MB_2U(SCH_1):PAGE63

UPI_CPU0_CPU1_P1P0_DN<9> @S9S_MB_2U_LIB.S9S_MB_2U(SCH_1):UPI_CPU0_CPU1_P1P0_DN(9)
    U2  DH6 UPI1_TX_DN9 SOCKET4677_AZIF0045P001C01CS-SA   I102 @S9S_MB_2U_LIB.S9S_MB_2U(SCH_1):PAGE33
    U1  AH6 UPI0_RX_DN9 SOCKET4677_AZIF0045P001C01CS-SA    I51 @S9S_MB_2U_LIB.S9S_MB_2U(SCH_1):PAGE63

UPI_CPU0_CPU1_P1P0_DP<0> @S9S_MB_2U_LIB.S9S_MB_2U(SCH_1):UPI_CPU0_CPU1_P1P0_DP(0)
    U2  EE5 UPI1_TX_DP0 SOCKET4677_AZIF0045P001C01CS-SA   I102 @S9S_MB_2U_LIB.S9S_MB_2U(SCH_1):PAGE33
    U1   L7 UPI0_RX_DP0 SOCKET4677_AZIF0045P001C01CS-SA    I51 @S9S_MB_2U_LIB.S9S_MB_2U(SCH_1):PAGE63

UPI_CPU0_CPU1_P1P0_DP<10> @S9S_MB_2U_LIB.S9S_MB_2U(SCH_1):UPI_CPU0_CPU1_P1P0_DP(10)
    U2  DE5 UPI1_TX_DN10 SOCKET4677_AZIF0045P001C01CS-SA   I102 @S9S_MB_2U_LIB.S9S_MB_2U(SCH_1):PAGE33
    U1  AL7 UPI0_RX_DP10 SOCKET4677_AZIF0045P001C01CS-SA    I51 @S9S_MB_2U_LIB.S9S_MB_2U(SCH_1):PAGE63

UPI_CPU0_CPU1_P1P0_DP<11> @S9S_MB_2U_LIB.S9S_MB_2U(SCH_1):UPI_CPU0_CPU1_P1P0_DP(11)
    U2  DD6 UPI1_TX_DN11 SOCKET4677_AZIF0045P001C01CS-SA   I102 @S9S_MB_2U_LIB.S9S_MB_2U(SCH_1):PAGE33
    U1  AM6 UPI0_RX_DP11 SOCKET4677_AZIF0045P001C01CS-SA    I51 @S9S_MB_2U_LIB.S9S_MB_2U(SCH_1):PAGE63

UPI_CPU0_CPU1_P1P0_DP<12> @S9S_MB_2U_LIB.S9S_MB_2U(SCH_1):UPI_CPU0_CPU1_P1P0_DP(12)
    U2  DA5 UPI1_TX_DN12 SOCKET4677_AZIF0045P001C01CS-SA   I102 @S9S_MB_2U_LIB.S9S_MB_2U(SCH_1):PAGE33
    U1  AR7 UPI0_RX_DP12 SOCKET4677_AZIF0045P001C01CS-SA    I51 @S9S_MB_2U_LIB.S9S_MB_2U(SCH_1):PAGE63

UPI_CPU0_CPU1_P1P0_DP<13> @S9S_MB_2U_LIB.S9S_MB_2U(SCH_1):UPI_CPU0_CPU1_P1P0_DP(13)
    U2  CY6 UPI1_TX_DN13 SOCKET4677_AZIF0045P001C01CS-SA   I102 @S9S_MB_2U_LIB.S9S_MB_2U(SCH_1):PAGE33
    U1  AT6 UPI0_RX_DP13 SOCKET4677_AZIF0045P001C01CS-SA    I51 @S9S_MB_2U_LIB.S9S_MB_2U(SCH_1):PAGE63

UPI_CPU0_CPU1_P1P0_DP<14> @S9S_MB_2U_LIB.S9S_MB_2U(SCH_1):UPI_CPU0_CPU1_P1P0_DP(14)
    U2  CU5 UPI1_TX_DN14 SOCKET4677_AZIF0045P001C01CS-SA   I102 @S9S_MB_2U_LIB.S9S_MB_2U(SCH_1):PAGE33
    U1  AW7 UPI0_RX_DP14 SOCKET4677_AZIF0045P001C01CS-SA    I51 @S9S_MB_2U_LIB.S9S_MB_2U(SCH_1):PAGE63

UPI_CPU0_CPU1_P1P0_DP<15> @S9S_MB_2U_LIB.S9S_MB_2U(SCH_1):UPI_CPU0_CPU1_P1P0_DP(15)
    U2  CT6 UPI1_TX_DN15 SOCKET4677_AZIF0045P001C01CS-SA   I102 @S9S_MB_2U_LIB.S9S_MB_2U(SCH_1):PAGE33
    U1  AY6 UPI0_RX_DP15 SOCKET4677_AZIF0045P001C01CS-SA    I51 @S9S_MB_2U_LIB.S9S_MB_2U(SCH_1):PAGE63

UPI_CPU0_CPU1_P1P0_DP<16> @S9S_MB_2U_LIB.S9S_MB_2U(SCH_1):UPI_CPU0_CPU1_P1P0_DP(16)
    U2  CN5 UPI1_TX_DN16 SOCKET4677_AZIF0045P001C01CS-SA   I102 @S9S_MB_2U_LIB.S9S_MB_2U(SCH_1):PAGE33
    U1  BC7 UPI0_RX_DP16 SOCKET4677_AZIF0045P001C01CS-SA    I51 @S9S_MB_2U_LIB.S9S_MB_2U(SCH_1):PAGE63

UPI_CPU0_CPU1_P1P0_DP<17> @S9S_MB_2U_LIB.S9S_MB_2U(SCH_1):UPI_CPU0_CPU1_P1P0_DP(17)
    U2  CM6 UPI1_TX_DN17 SOCKET4677_AZIF0045P001C01CS-SA   I102 @S9S_MB_2U_LIB.S9S_MB_2U(SCH_1):PAGE33
    U1  BD6 UPI0_RX_DP17 SOCKET4677_AZIF0045P001C01CS-SA    I51 @S9S_MB_2U_LIB.S9S_MB_2U(SCH_1):PAGE63

UPI_CPU0_CPU1_P1P0_DP<18> @S9S_MB_2U_LIB.S9S_MB_2U(SCH_1):UPI_CPU0_CPU1_P1P0_DP(18)
    U2  CJ5 UPI1_TX_DN18 SOCKET4677_AZIF0045P001C01CS-SA   I102 @S9S_MB_2U_LIB.S9S_MB_2U(SCH_1):PAGE33
    U1  BG7 UPI0_RX_DP18 SOCKET4677_AZIF0045P001C01CS-SA    I51 @S9S_MB_2U_LIB.S9S_MB_2U(SCH_1):PAGE63

UPI_CPU0_CPU1_P1P0_DP<19> @S9S_MB_2U_LIB.S9S_MB_2U(SCH_1):UPI_CPU0_CPU1_P1P0_DP(19)
    U2  CH6 UPI1_TX_DN19 SOCKET4677_AZIF0045P001C01CS-SA   I102 @S9S_MB_2U_LIB.S9S_MB_2U(SCH_1):PAGE33
    U1  BH6 UPI0_RX_DP19 SOCKET4677_AZIF0045P001C01CS-SA    I51 @S9S_MB_2U_LIB.S9S_MB_2U(SCH_1):PAGE63

UPI_CPU0_CPU1_P1P0_DP<1> @S9S_MB_2U_LIB.S9S_MB_2U(SCH_1):UPI_CPU0_CPU1_P1P0_DP(1)
    U2  ED6 UPI1_TX_DP1 SOCKET4677_AZIF0045P001C01CS-SA   I102 @S9S_MB_2U_LIB.S9S_MB_2U(SCH_1):PAGE33
    U1   M6 UPI0_RX_DP1 SOCKET4677_AZIF0045P001C01CS-SA    I51 @S9S_MB_2U_LIB.S9S_MB_2U(SCH_1):PAGE63

UPI_CPU0_CPU1_P1P0_DP<20> @S9S_MB_2U_LIB.S9S_MB_2U(SCH_1):UPI_CPU0_CPU1_P1P0_DP(20)
    U2  CE5 UPI1_TX_DN20 SOCKET4677_AZIF0045P001C01CS-SA   I102 @S9S_MB_2U_LIB.S9S_MB_2U(SCH_1):PAGE33
    U1  BL7 UPI0_RX_DP20 SOCKET4677_AZIF0045P001C01CS-SA    I51 @S9S_MB_2U_LIB.S9S_MB_2U(SCH_1):PAGE63

UPI_CPU0_CPU1_P1P0_DP<21> @S9S_MB_2U_LIB.S9S_MB_2U(SCH_1):UPI_CPU0_CPU1_P1P0_DP(21)
    U2  CD6 UPI1_TX_DN21 SOCKET4677_AZIF0045P001C01CS-SA   I102 @S9S_MB_2U_LIB.S9S_MB_2U(SCH_1):PAGE33
    U1  BM6 UPI0_RX_DP21 SOCKET4677_AZIF0045P001C01CS-SA    I51 @S9S_MB_2U_LIB.S9S_MB_2U(SCH_1):PAGE63

UPI_CPU0_CPU1_P1P0_DP<22> @S9S_MB_2U_LIB.S9S_MB_2U(SCH_1):UPI_CPU0_CPU1_P1P0_DP(22)
    U2  CB6 UPI1_TX_DP22 SOCKET4677_AZIF0045P001C01CS-SA   I102 @S9S_MB_2U_LIB.S9S_MB_2U(SCH_1):PAGE33
    U1  BP6 UPI0_RX_DP22 SOCKET4677_AZIF0045P001C01CS-SA    I51 @S9S_MB_2U_LIB.S9S_MB_2U(SCH_1):PAGE63

UPI_CPU0_CPU1_P1P0_DP<23> @S9S_MB_2U_LIB.S9S_MB_2U(SCH_1):UPI_CPU0_CPU1_P1P0_DP(23)
    U2  BY6 UPI1_TX_DN23 SOCKET4677_AZIF0045P001C01CS-SA   I102 @S9S_MB_2U_LIB.S9S_MB_2U(SCH_1):PAGE33
    U1  BT6 UPI0_RX_DP23 SOCKET4677_AZIF0045P001C01CS-SA    I51 @S9S_MB_2U_LIB.S9S_MB_2U(SCH_1):PAGE63

UPI_CPU0_CPU1_P1P0_DP<2> @S9S_MB_2U_LIB.S9S_MB_2U(SCH_1):UPI_CPU0_CPU1_P1P0_DP(2)
    U2  EA5 UPI1_TX_DP2 SOCKET4677_AZIF0045P001C01CS-SA   I102 @S9S_MB_2U_LIB.S9S_MB_2U(SCH_1):PAGE33
    U1   R7 UPI0_RX_DP2 SOCKET4677_AZIF0045P001C01CS-SA    I51 @S9S_MB_2U_LIB.S9S_MB_2U(SCH_1):PAGE63

UPI_CPU0_CPU1_P1P0_DP<3> @S9S_MB_2U_LIB.S9S_MB_2U(SCH_1):UPI_CPU0_CPU1_P1P0_DP(3)
    U2  DY6 UPI1_TX_DN3 SOCKET4677_AZIF0045P001C01CS-SA   I102 @S9S_MB_2U_LIB.S9S_MB_2U(SCH_1):PAGE33
    U1   T6 UPI0_RX_DP3 SOCKET4677_AZIF0045P001C01CS-SA    I51 @S9S_MB_2U_LIB.S9S_MB_2U(SCH_1):PAGE63

UPI_CPU0_CPU1_P1P0_DP<4> @S9S_MB_2U_LIB.S9S_MB_2U(SCH_1):UPI_CPU0_CPU1_P1P0_DP(4)
    U2  DU5 UPI1_TX_DP4 SOCKET4677_AZIF0045P001C01CS-SA   I102 @S9S_MB_2U_LIB.S9S_MB_2U(SCH_1):PAGE33
    U1   W7 UPI0_RX_DP4 SOCKET4677_AZIF0045P001C01CS-SA    I51 @S9S_MB_2U_LIB.S9S_MB_2U(SCH_1):PAGE63

UPI_CPU0_CPU1_P1P0_DP<5> @S9S_MB_2U_LIB.S9S_MB_2U(SCH_1):UPI_CPU0_CPU1_P1P0_DP(5)
    U2  DT6 UPI1_TX_DN5 SOCKET4677_AZIF0045P001C01CS-SA   I102 @S9S_MB_2U_LIB.S9S_MB_2U(SCH_1):PAGE33
    U1   Y6 UPI0_RX_DP5 SOCKET4677_AZIF0045P001C01CS-SA    I51 @S9S_MB_2U_LIB.S9S_MB_2U(SCH_1):PAGE63

UPI_CPU0_CPU1_P1P0_DP<6> @S9S_MB_2U_LIB.S9S_MB_2U(SCH_1):UPI_CPU0_CPU1_P1P0_DP(6)
    U2  DN5 UPI1_TX_DP6 SOCKET4677_AZIF0045P001C01CS-SA   I102 @S9S_MB_2U_LIB.S9S_MB_2U(SCH_1):PAGE33
    U1  AC7 UPI0_RX_DP6 SOCKET4677_AZIF0045P001C01CS-SA    I51 @S9S_MB_2U_LIB.S9S_MB_2U(SCH_1):PAGE63

UPI_CPU0_CPU1_P1P0_DP<7> @S9S_MB_2U_LIB.S9S_MB_2U(SCH_1):UPI_CPU0_CPU1_P1P0_DP(7)
    U2  DM6 UPI1_TX_DP7 SOCKET4677_AZIF0045P001C01CS-SA   I102 @S9S_MB_2U_LIB.S9S_MB_2U(SCH_1):PAGE33
    U1  AD6 UPI0_RX_DP7 SOCKET4677_AZIF0045P001C01CS-SA    I51 @S9S_MB_2U_LIB.S9S_MB_2U(SCH_1):PAGE63

UPI_CPU0_CPU1_P1P0_DP<8> @S9S_MB_2U_LIB.S9S_MB_2U(SCH_1):UPI_CPU0_CPU1_P1P0_DP(8)
    U2  DJ5 UPI1_TX_DP8 SOCKET4677_AZIF0045P001C01CS-SA   I102 @S9S_MB_2U_LIB.S9S_MB_2U(SCH_1):PAGE33
    U1  AG7 UPI0_RX_DP8 SOCKET4677_AZIF0045P001C01CS-SA    I51 @S9S_MB_2U_LIB.S9S_MB_2U(SCH_1):PAGE63

UPI_CPU0_CPU1_P1P0_DP<9> @S9S_MB_2U_LIB.S9S_MB_2U(SCH_1):UPI_CPU0_CPU1_P1P0_DP(9)
    U2  DG7 UPI1_TX_DP9 SOCKET4677_AZIF0045P001C01CS-SA   I102 @S9S_MB_2U_LIB.S9S_MB_2U(SCH_1):PAGE33
    U1  AJ5 UPI0_RX_DP9 SOCKET4677_AZIF0045P001C01CS-SA    I51 @S9S_MB_2U_LIB.S9S_MB_2U(SCH_1):PAGE63

UPI_CPU0_CPU1_P2P2_DN<0> @S9S_MB_2U_LIB.S9S_MB_2U(SCH_1):UPI_CPU0_CPU1_P2P2_DN(0)
    U2 BM71 UPI2_TX_DN23 SOCKET4677_AZIF0045P001C01CS-SA   I102 @S9S_MB_2U_LIB.S9S_MB_2U(SCH_1):PAGE34
    U1  E80 UPI2_RX_DN0 SOCKET4677_AZIF0045P001C01CS-SA    I16 @S9S_MB_2U_LIB.S9S_MB_2U(SCH_1):PAGE65

UPI_CPU0_CPU1_P2P2_DN<10> @S9S_MB_2U_LIB.S9S_MB_2U(SCH_1):UPI_CPU0_CPU1_P2P2_DN(10)
    U2 AN82 UPI2_TX_DN13 SOCKET4677_AZIF0045P001C01CS-SA   I102 @S9S_MB_2U_LIB.S9S_MB_2U(SCH_1):PAGE34
    U1 AJ80 UPI2_RX_DN10 SOCKET4677_AZIF0045P001C01CS-SA    I16 @S9S_MB_2U_LIB.S9S_MB_2U(SCH_1):PAGE65

UPI_CPU0_CPU1_P2P2_DN<11> @S9S_MB_2U_LIB.S9S_MB_2U(SCH_1):UPI_CPU0_CPU1_P2P2_DN(11)
    U2 AM81 UPI2_TX_DN12 SOCKET4677_AZIF0045P001C01CS-SA   I102 @S9S_MB_2U_LIB.S9S_MB_2U(SCH_1):PAGE34
    U1 AG82 UPI2_RX_DN11 SOCKET4677_AZIF0045P001C01CS-SA    I16 @S9S_MB_2U_LIB.S9S_MB_2U(SCH_1):PAGE65

UPI_CPU0_CPU1_P2P2_DN<12> @S9S_MB_2U_LIB.S9S_MB_2U(SCH_1):UPI_CPU0_CPU1_P2P2_DN(12)
    U2 AU78 UPI2_TX_DN11 SOCKET4677_AZIF0045P001C01CS-SA   I102 @S9S_MB_2U_LIB.S9S_MB_2U(SCH_1):PAGE34
    U1 BA72 UPI2_RX_DN12 SOCKET4677_AZIF0045P001C01CS-SA    I16 @S9S_MB_2U_LIB.S9S_MB_2U(SCH_1):PAGE65

UPI_CPU0_CPU1_P2P2_DN<13> @S9S_MB_2U_LIB.S9S_MB_2U(SCH_1):UPI_CPU0_CPU1_P2P2_DN(13)
    U2 AW78 UPI2_TX_DN10 SOCKET4677_AZIF0045P001C01CS-SA   I102 @S9S_MB_2U_LIB.S9S_MB_2U(SCH_1):PAGE34
    U1 AV73 UPI2_RX_DN13 SOCKET4677_AZIF0045P001C01CS-SA    I16 @S9S_MB_2U_LIB.S9S_MB_2U(SCH_1):PAGE65

UPI_CPU0_CPU1_P2P2_DN<14> @S9S_MB_2U_LIB.S9S_MB_2U(SCH_1):UPI_CPU0_CPU1_P2P2_DN(14)
    U2  Y81 UPI2_TX_DN9 SOCKET4677_AZIF0045P001C01CS-SA   I102 @S9S_MB_2U_LIB.S9S_MB_2U(SCH_1):PAGE34
    U1 AY75 UPI2_RX_DN14 SOCKET4677_AZIF0045P001C01CS-SA    I16 @S9S_MB_2U_LIB.S9S_MB_2U(SCH_1):PAGE65

UPI_CPU0_CPU1_P2P2_DN<15> @S9S_MB_2U_LIB.S9S_MB_2U(SCH_1):UPI_CPU0_CPU1_P2P2_DN(15)
    U2  V83 UPI2_TX_DN8 SOCKET4677_AZIF0045P001C01CS-SA   I102 @S9S_MB_2U_LIB.S9S_MB_2U(SCH_1):PAGE34
    U1 BB75 UPI2_RX_DN15 SOCKET4677_AZIF0045P001C01CS-SA    I16 @S9S_MB_2U_LIB.S9S_MB_2U(SCH_1):PAGE65

UPI_CPU0_CPU1_P2P2_DN<16> @S9S_MB_2U_LIB.S9S_MB_2U(SCH_1):UPI_CPU0_CPU1_P2P2_DN(16)
    U2  U80 UPI2_TX_DN7 SOCKET4677_AZIF0045P001C01CS-SA   I102 @S9S_MB_2U_LIB.S9S_MB_2U(SCH_1):PAGE34
    U1 AW74 UPI2_RX_DN16 SOCKET4677_AZIF0045P001C01CS-SA    I16 @S9S_MB_2U_LIB.S9S_MB_2U(SCH_1):PAGE65

UPI_CPU0_CPU1_P2P2_DN<17> @S9S_MB_2U_LIB.S9S_MB_2U(SCH_1):UPI_CPU0_CPU1_P2P2_DN(17)
    U2  R82 UPI2_TX_DN6 SOCKET4677_AZIF0045P001C01CS-SA   I102 @S9S_MB_2U_LIB.S9S_MB_2U(SCH_1):PAGE34
    U1 BH75 UPI2_RX_DN17 SOCKET4677_AZIF0045P001C01CS-SA    I16 @S9S_MB_2U_LIB.S9S_MB_2U(SCH_1):PAGE65

UPI_CPU0_CPU1_P2P2_DN<18> @S9S_MB_2U_LIB.S9S_MB_2U(SCH_1):UPI_CPU0_CPU1_P2P2_DN(18)
    U2  P81 UPI2_TX_DN5 SOCKET4677_AZIF0045P001C01CS-SA   I102 @S9S_MB_2U_LIB.S9S_MB_2U(SCH_1):PAGE34
    U1 BJ76 UPI2_RX_DN18 SOCKET4677_AZIF0045P001C01CS-SA    I16 @S9S_MB_2U_LIB.S9S_MB_2U(SCH_1):PAGE65

UPI_CPU0_CPU1_P2P2_DN<19> @S9S_MB_2U_LIB.S9S_MB_2U(SCH_1):UPI_CPU0_CPU1_P2P2_DN(19)
    U2  H85 UPI2_TX_DN4 SOCKET4677_AZIF0045P001C01CS-SA   I102 @S9S_MB_2U_LIB.S9S_MB_2U(SCH_1):PAGE34
    U1 BL76 UPI2_RX_DN19 SOCKET4677_AZIF0045P001C01CS-SA    I16 @S9S_MB_2U_LIB.S9S_MB_2U(SCH_1):PAGE65

UPI_CPU0_CPU1_P2P2_DN<1> @S9S_MB_2U_LIB.S9S_MB_2U(SCH_1):UPI_CPU0_CPU1_P2P2_DN(1)
    U2 BG80 UPI2_TX_DN22 SOCKET4677_AZIF0045P001C01CS-SA   I102 @S9S_MB_2U_LIB.S9S_MB_2U(SCH_1):PAGE34
    U1  F81 UPI2_RX_DN1 SOCKET4677_AZIF0045P001C01CS-SA    I16 @S9S_MB_2U_LIB.S9S_MB_2U(SCH_1):PAGE65

UPI_CPU0_CPU1_P2P2_DN<20> @S9S_MB_2U_LIB.S9S_MB_2U(SCH_1):UPI_CPU0_CPU1_P2P2_DN(20)
    U2  F87 UPI2_TX_DN3 SOCKET4677_AZIF0045P001C01CS-SA   I102 @S9S_MB_2U_LIB.S9S_MB_2U(SCH_1):PAGE34
    U1 BG74 UPI2_RX_DN20 SOCKET4677_AZIF0045P001C01CS-SA    I16 @S9S_MB_2U_LIB.S9S_MB_2U(SCH_1):PAGE65

UPI_CPU0_CPU1_P2P2_DN<21> @S9S_MB_2U_LIB.S9S_MB_2U(SCH_1):UPI_CPU0_CPU1_P2P2_DN(21)
    U2  D87 UPI2_TX_DN2 SOCKET4677_AZIF0045P001C01CS-SA   I102 @S9S_MB_2U_LIB.S9S_MB_2U(SCH_1):PAGE34
    U1 BN74 UPI2_RX_DN21 SOCKET4677_AZIF0045P001C01CS-SA    I16 @S9S_MB_2U_LIB.S9S_MB_2U(SCH_1):PAGE65

UPI_CPU0_CPU1_P2P2_DN<22> @S9S_MB_2U_LIB.S9S_MB_2U(SCH_1):UPI_CPU0_CPU1_P2P2_DN(22)
    U2  E84 UPI2_TX_DN1 SOCKET4677_AZIF0045P001C01CS-SA   I102 @S9S_MB_2U_LIB.S9S_MB_2U(SCH_1):PAGE34
    U1 BK73 UPI2_RX_DN22 SOCKET4677_AZIF0045P001C01CS-SA    I16 @S9S_MB_2U_LIB.S9S_MB_2U(SCH_1):PAGE65

UPI_CPU0_CPU1_P2P2_DN<23> @S9S_MB_2U_LIB.S9S_MB_2U(SCH_1):UPI_CPU0_CPU1_P2P2_DN(23)
    U2  B85 UPI2_TX_DN0 SOCKET4677_AZIF0045P001C01CS-SA   I102 @S9S_MB_2U_LIB.S9S_MB_2U(SCH_1):PAGE34
    U1 BD73 UPI2_RX_DN23 SOCKET4677_AZIF0045P001C01CS-SA    I16 @S9S_MB_2U_LIB.S9S_MB_2U(SCH_1):PAGE65

UPI_CPU0_CPU1_P2P2_DN<2> @S9S_MB_2U_LIB.S9S_MB_2U(SCH_1):UPI_CPU0_CPU1_P2P2_DN(2)
    U2 BF81 UPI2_TX_DN21 SOCKET4677_AZIF0045P001C01CS-SA   I102 @S9S_MB_2U_LIB.S9S_MB_2U(SCH_1):PAGE34
    U1  G82 UPI2_RX_DN2 SOCKET4677_AZIF0045P001C01CS-SA    I16 @S9S_MB_2U_LIB.S9S_MB_2U(SCH_1):PAGE65

UPI_CPU0_CPU1_P2P2_DN<3> @S9S_MB_2U_LIB.S9S_MB_2U(SCH_1):UPI_CPU0_CPU1_P2P2_DN(3)
    U2 BD79 UPI2_TX_DN20 SOCKET4677_AZIF0045P001C01CS-SA   I102 @S9S_MB_2U_LIB.S9S_MB_2U(SCH_1):PAGE34
    U1  K79 UPI2_RX_DN3 SOCKET4677_AZIF0045P001C01CS-SA    I16 @S9S_MB_2U_LIB.S9S_MB_2U(SCH_1):PAGE65

UPI_CPU0_CPU1_P2P2_DN<4> @S9S_MB_2U_LIB.S9S_MB_2U(SCH_1):UPI_CPU0_CPU1_P2P2_DN(4)
    U2 BE82 UPI2_TX_DN19 SOCKET4677_AZIF0045P001C01CS-SA   I102 @S9S_MB_2U_LIB.S9S_MB_2U(SCH_1):PAGE34
    U1  J82 UPI2_RX_DN4 SOCKET4677_AZIF0045P001C01CS-SA    I16 @S9S_MB_2U_LIB.S9S_MB_2U(SCH_1):PAGE65

UPI_CPU0_CPU1_P2P2_DN<5> @S9S_MB_2U_LIB.S9S_MB_2U(SCH_1):UPI_CPU0_CPU1_P2P2_DN(5)
    U2 BC82 UPI2_TX_DN18 SOCKET4677_AZIF0045P001C01CS-SA   I102 @S9S_MB_2U_LIB.S9S_MB_2U(SCH_1):PAGE34
    U1  L80 UPI2_RX_DN5 SOCKET4677_AZIF0045P001C01CS-SA    I16 @S9S_MB_2U_LIB.S9S_MB_2U(SCH_1):PAGE65

UPI_CPU0_CPU1_P2P2_DN<6> @S9S_MB_2U_LIB.S9S_MB_2U(SCH_1):UPI_CPU0_CPU1_P2P2_DN(6)
    U2 BA80 UPI2_TX_DN17 SOCKET4677_AZIF0045P001C01CS-SA   I102 @S9S_MB_2U_LIB.S9S_MB_2U(SCH_1):PAGE34
    U1 AC80 UPI2_RX_DN6 SOCKET4677_AZIF0045P001C01CS-SA    I16 @S9S_MB_2U_LIB.S9S_MB_2U(SCH_1):PAGE65

UPI_CPU0_CPU1_P2P2_DN<7> @S9S_MB_2U_LIB.S9S_MB_2U(SCH_1):UPI_CPU0_CPU1_P2P2_DN(7)
    U2 AV81 UPI2_TX_DN16 SOCKET4677_AZIF0045P001C01CS-SA   I102 @S9S_MB_2U_LIB.S9S_MB_2U(SCH_1):PAGE34
    U1 AD81 UPI2_RX_DN7 SOCKET4677_AZIF0045P001C01CS-SA    I16 @S9S_MB_2U_LIB.S9S_MB_2U(SCH_1):PAGE65

UPI_CPU0_CPU1_P2P2_DN<8> @S9S_MB_2U_LIB.S9S_MB_2U(SCH_1):UPI_CPU0_CPU1_P2P2_DN(8)
    U2 AT83 UPI2_TX_DN15 SOCKET4677_AZIF0045P001C01CS-SA   I102 @S9S_MB_2U_LIB.S9S_MB_2U(SCH_1):PAGE34
    U1 AF79 UPI2_RX_DN8 SOCKET4677_AZIF0045P001C01CS-SA    I16 @S9S_MB_2U_LIB.S9S_MB_2U(SCH_1):PAGE65

UPI_CPU0_CPU1_P2P2_DN<9> @S9S_MB_2U_LIB.S9S_MB_2U(SCH_1):UPI_CPU0_CPU1_P2P2_DN(9)
    U2 AR80 UPI2_TX_DN14 SOCKET4677_AZIF0045P001C01CS-SA   I102 @S9S_MB_2U_LIB.S9S_MB_2U(SCH_1):PAGE34
    U1 AE82 UPI2_RX_DN9 SOCKET4677_AZIF0045P001C01CS-SA    I16 @S9S_MB_2U_LIB.S9S_MB_2U(SCH_1):PAGE65

UPI_CPU0_CPU1_P2P2_DP<0> @S9S_MB_2U_LIB.S9S_MB_2U(SCH_1):UPI_CPU0_CPU1_P2P2_DP(0)
    U2 BN72 UPI2_TX_DP23 SOCKET4677_AZIF0045P001C01CS-SA   I102 @S9S_MB_2U_LIB.S9S_MB_2U(SCH_1):PAGE34
    U1  G80 UPI2_RX_DP0 SOCKET4677_AZIF0045P001C01CS-SA    I16 @S9S_MB_2U_LIB.S9S_MB_2U(SCH_1):PAGE65

UPI_CPU0_CPU1_P2P2_DP<10> @S9S_MB_2U_LIB.S9S_MB_2U(SCH_1):UPI_CPU0_CPU1_P2P2_DP(10)
    U2 AM83 UPI2_TX_DP13 SOCKET4677_AZIF0045P001C01CS-SA   I102 @S9S_MB_2U_LIB.S9S_MB_2U(SCH_1):PAGE34
    U1 AH81 UPI2_RX_DP10 SOCKET4677_AZIF0045P001C01CS-SA    I16 @S9S_MB_2U_LIB.S9S_MB_2U(SCH_1):PAGE65

UPI_CPU0_CPU1_P2P2_DP<11> @S9S_MB_2U_LIB.S9S_MB_2U(SCH_1):UPI_CPU0_CPU1_P2P2_DP(11)
    U2 AP81 UPI2_TX_DP12 SOCKET4677_AZIF0045P001C01CS-SA   I102 @S9S_MB_2U_LIB.S9S_MB_2U(SCH_1):PAGE34
    U1 AJ82 UPI2_RX_DP11 SOCKET4677_AZIF0045P001C01CS-SA    I16 @S9S_MB_2U_LIB.S9S_MB_2U(SCH_1):PAGE65

UPI_CPU0_CPU1_P2P2_DP<12> @S9S_MB_2U_LIB.S9S_MB_2U(SCH_1):UPI_CPU0_CPU1_P2P2_DP(12)
    U2 AV79 UPI2_TX_DP11 SOCKET4677_AZIF0045P001C01CS-SA   I102 @S9S_MB_2U_LIB.S9S_MB_2U(SCH_1):PAGE34
    U1 BB73 UPI2_RX_DP12 SOCKET4677_AZIF0045P001C01CS-SA    I16 @S9S_MB_2U_LIB.S9S_MB_2U(SCH_1):PAGE65

UPI_CPU0_CPU1_P2P2_DP<13> @S9S_MB_2U_LIB.S9S_MB_2U(SCH_1):UPI_CPU0_CPU1_P2P2_DP(13)
    U2 BA78 UPI2_TX_DP10 SOCKET4677_AZIF0045P001C01CS-SA   I102 @S9S_MB_2U_LIB.S9S_MB_2U(SCH_1):PAGE34
    U1 AY73 UPI2_RX_DP13 SOCKET4677_AZIF0045P001C01CS-SA    I16 @S9S_MB_2U_LIB.S9S_MB_2U(SCH_1):PAGE65

UPI_CPU0_CPU1_P2P2_DP<14> @S9S_MB_2U_LIB.S9S_MB_2U(SCH_1):UPI_CPU0_CPU1_P2P2_DP(14)
    U2  W82 UPI2_TX_DP9 SOCKET4677_AZIF0045P001C01CS-SA   I102 @S9S_MB_2U_LIB.S9S_MB_2U(SCH_1):PAGE34
    U1 BA76 UPI2_RX_DP14 SOCKET4677_AZIF0045P001C01CS-SA    I16 @S9S_MB_2U_LIB.S9S_MB_2U(SCH_1):PAGE65

UPI_CPU0_CPU1_P2P2_DP<15> @S9S_MB_2U_LIB.S9S_MB_2U(SCH_1):UPI_CPU0_CPU1_P2P2_DP(15)
    U2  Y83 UPI2_TX_DP8 SOCKET4677_AZIF0045P001C01CS-SA   I102 @S9S_MB_2U_LIB.S9S_MB_2U(SCH_1):PAGE34
    U1 BD75 UPI2_RX_DP15 SOCKET4677_AZIF0045P001C01CS-SA    I16 @S9S_MB_2U_LIB.S9S_MB_2U(SCH_1):PAGE65

UPI_CPU0_CPU1_P2P2_DP<16> @S9S_MB_2U_LIB.S9S_MB_2U(SCH_1):UPI_CPU0_CPU1_P2P2_DP(16)
    U2  V81 UPI2_TX_DP7 SOCKET4677_AZIF0045P001C01CS-SA   I102 @S9S_MB_2U_LIB.S9S_MB_2U(SCH_1):PAGE34
    U1 AV75 UPI2_RX_DP16 SOCKET4677_AZIF0045P001C01CS-SA    I16 @S9S_MB_2U_LIB.S9S_MB_2U(SCH_1):PAGE65

UPI_CPU0_CPU1_P2P2_DP<17> @S9S_MB_2U_LIB.S9S_MB_2U(SCH_1):UPI_CPU0_CPU1_P2P2_DP(17)
    U2  P83 UPI2_TX_DP6 SOCKET4677_AZIF0045P001C01CS-SA   I102 @S9S_MB_2U_LIB.S9S_MB_2U(SCH_1):PAGE34
    U1 BG76 UPI2_RX_DP17 SOCKET4677_AZIF0045P001C01CS-SA    I16 @S9S_MB_2U_LIB.S9S_MB_2U(SCH_1):PAGE65

UPI_CPU0_CPU1_P2P2_DP<18> @S9S_MB_2U_LIB.S9S_MB_2U(SCH_1):UPI_CPU0_CPU1_P2P2_DP(18)
    U2  T81 UPI2_TX_DP5 SOCKET4677_AZIF0045P001C01CS-SA   I102 @S9S_MB_2U_LIB.S9S_MB_2U(SCH_1):PAGE34
    U1 BK77 UPI2_RX_DP18 SOCKET4677_AZIF0045P001C01CS-SA    I16 @S9S_MB_2U_LIB.S9S_MB_2U(SCH_1):PAGE65

UPI_CPU0_CPU1_P2P2_DP<19> @S9S_MB_2U_LIB.S9S_MB_2U(SCH_1):UPI_CPU0_CPU1_P2P2_DP(19)
    U2  G86 UPI2_TX_DP4 SOCKET4677_AZIF0045P001C01CS-SA   I102 @S9S_MB_2U_LIB.S9S_MB_2U(SCH_1):PAGE34
    U1 BN76 UPI2_RX_DP19 SOCKET4677_AZIF0045P001C01CS-SA    I16 @S9S_MB_2U_LIB.S9S_MB_2U(SCH_1):PAGE65

UPI_CPU0_CPU1_P2P2_DP<1> @S9S_MB_2U_LIB.S9S_MB_2U(SCH_1):UPI_CPU0_CPU1_P2P2_DP(1)
    U2 BE80 UPI2_TX_DP22 SOCKET4677_AZIF0045P001C01CS-SA   I102 @S9S_MB_2U_LIB.S9S_MB_2U(SCH_1):PAGE34
    U1  E82 UPI2_RX_DP1 SOCKET4677_AZIF0045P001C01CS-SA    I16 @S9S_MB_2U_LIB.S9S_MB_2U(SCH_1):PAGE65

UPI_CPU0_CPU1_P2P2_DP<20> @S9S_MB_2U_LIB.S9S_MB_2U(SCH_1):UPI_CPU0_CPU1_P2P2_DP(20)
    U2  H87 UPI2_TX_DP3 SOCKET4677_AZIF0045P001C01CS-SA   I102 @S9S_MB_2U_LIB.S9S_MB_2U(SCH_1):PAGE34
    U1 BJ74 UPI2_RX_DP20 SOCKET4677_AZIF0045P001C01CS-SA    I16 @S9S_MB_2U_LIB.S9S_MB_2U(SCH_1):PAGE65

UPI_CPU0_CPU1_P2P2_DP<21> @S9S_MB_2U_LIB.S9S_MB_2U(SCH_1):UPI_CPU0_CPU1_P2P2_DP(21)
    U2  E88 UPI2_TX_DP2 SOCKET4677_AZIF0045P001C01CS-SA   I102 @S9S_MB_2U_LIB.S9S_MB_2U(SCH_1):PAGE34
    U1 BM75 UPI2_RX_DP21 SOCKET4677_AZIF0045P001C01CS-SA    I16 @S9S_MB_2U_LIB.S9S_MB_2U(SCH_1):PAGE65

UPI_CPU0_CPU1_P2P2_DP<22> @S9S_MB_2U_LIB.S9S_MB_2U(SCH_1):UPI_CPU0_CPU1_P2P2_DP(22)
    U2  F85 UPI2_TX_DP1 SOCKET4677_AZIF0045P001C01CS-SA   I102 @S9S_MB_2U_LIB.S9S_MB_2U(SCH_1):PAGE34
    U1 BL74 UPI2_RX_DP22 SOCKET4677_AZIF0045P001C01CS-SA    I16 @S9S_MB_2U_LIB.S9S_MB_2U(SCH_1):PAGE65

UPI_CPU0_CPU1_P2P2_DP<23> @S9S_MB_2U_LIB.S9S_MB_2U(SCH_1):UPI_CPU0_CPU1_P2P2_DP(23)
    U2  D85 UPI2_TX_DP0 SOCKET4677_AZIF0045P001C01CS-SA   I102 @S9S_MB_2U_LIB.S9S_MB_2U(SCH_1):PAGE34
    U1 BC74 UPI2_RX_DP23 SOCKET4677_AZIF0045P001C01CS-SA    I16 @S9S_MB_2U_LIB.S9S_MB_2U(SCH_1):PAGE65

UPI_CPU0_CPU1_P2P2_DP<2> @S9S_MB_2U_LIB.S9S_MB_2U(SCH_1):UPI_CPU0_CPU1_P2P2_DP(2)
    U2 BG82 UPI2_TX_DP21 SOCKET4677_AZIF0045P001C01CS-SA   I102 @S9S_MB_2U_LIB.S9S_MB_2U(SCH_1):PAGE34
    U1  H83 UPI2_RX_DP2 SOCKET4677_AZIF0045P001C01CS-SA    I16 @S9S_MB_2U_LIB.S9S_MB_2U(SCH_1):PAGE65

UPI_CPU0_CPU1_P2P2_DP<3> @S9S_MB_2U_LIB.S9S_MB_2U(SCH_1):UPI_CPU0_CPU1_P2P2_DP(3)
    U2 BC80 UPI2_TX_DP20 SOCKET4677_AZIF0045P001C01CS-SA   I102 @S9S_MB_2U_LIB.S9S_MB_2U(SCH_1):PAGE34
    U1  M79 UPI2_RX_DP3 SOCKET4677_AZIF0045P001C01CS-SA    I16 @S9S_MB_2U_LIB.S9S_MB_2U(SCH_1):PAGE65

UPI_CPU0_CPU1_P2P2_DP<4> @S9S_MB_2U_LIB.S9S_MB_2U(SCH_1):UPI_CPU0_CPU1_P2P2_DP(4)
    U2 BD83 UPI2_TX_DP19 SOCKET4677_AZIF0045P001C01CS-SA   I102 @S9S_MB_2U_LIB.S9S_MB_2U(SCH_1):PAGE34
    U1  L82 UPI2_RX_DP4 SOCKET4677_AZIF0045P001C01CS-SA    I16 @S9S_MB_2U_LIB.S9S_MB_2U(SCH_1):PAGE65

UPI_CPU0_CPU1_P2P2_DP<5> @S9S_MB_2U_LIB.S9S_MB_2U(SCH_1):UPI_CPU0_CPU1_P2P2_DP(5)
    U2 BA82 UPI2_TX_DP18 SOCKET4677_AZIF0045P001C01CS-SA   I102 @S9S_MB_2U_LIB.S9S_MB_2U(SCH_1):PAGE34
    U1  K81 UPI2_RX_DP5 SOCKET4677_AZIF0045P001C01CS-SA    I16 @S9S_MB_2U_LIB.S9S_MB_2U(SCH_1):PAGE65

UPI_CPU0_CPU1_P2P2_DP<6> @S9S_MB_2U_LIB.S9S_MB_2U(SCH_1):UPI_CPU0_CPU1_P2P2_DP(6)
    U2 BB81 UPI2_TX_DP17 SOCKET4677_AZIF0045P001C01CS-SA   I102 @S9S_MB_2U_LIB.S9S_MB_2U(SCH_1):PAGE34
    U1 AE80 UPI2_RX_DP6 SOCKET4677_AZIF0045P001C01CS-SA    I16 @S9S_MB_2U_LIB.S9S_MB_2U(SCH_1):PAGE65

UPI_CPU0_CPU1_P2P2_DP<7> @S9S_MB_2U_LIB.S9S_MB_2U(SCH_1):UPI_CPU0_CPU1_P2P2_DP(7)
    U2 AU82 UPI2_TX_DP16 SOCKET4677_AZIF0045P001C01CS-SA   I102 @S9S_MB_2U_LIB.S9S_MB_2U(SCH_1):PAGE34
    U1 AC82 UPI2_RX_DP7 SOCKET4677_AZIF0045P001C01CS-SA    I16 @S9S_MB_2U_LIB.S9S_MB_2U(SCH_1):PAGE65

UPI_CPU0_CPU1_P2P2_DP<8> @S9S_MB_2U_LIB.S9S_MB_2U(SCH_1):UPI_CPU0_CPU1_P2P2_DP(8)
    U2 AV83 UPI2_TX_DP15 SOCKET4677_AZIF0045P001C01CS-SA   I102 @S9S_MB_2U_LIB.S9S_MB_2U(SCH_1):PAGE34
    U1 AG80 UPI2_RX_DP8 SOCKET4677_AZIF0045P001C01CS-SA    I16 @S9S_MB_2U_LIB.S9S_MB_2U(SCH_1):PAGE65

UPI_CPU0_CPU1_P2P2_DP<9> @S9S_MB_2U_LIB.S9S_MB_2U(SCH_1):UPI_CPU0_CPU1_P2P2_DP(9)
    U2 AT81 UPI2_TX_DP14 SOCKET4677_AZIF0045P001C01CS-SA   I102 @S9S_MB_2U_LIB.S9S_MB_2U(SCH_1):PAGE34
    U1 AF83 UPI2_RX_DP9 SOCKET4677_AZIF0045P001C01CS-SA    I16 @S9S_MB_2U_LIB.S9S_MB_2U(SCH_1):PAGE65

UPI_CPU1_CPU0_P0P1_DN<0> @S9S_MB_2U_LIB.S9S_MB_2U(SCH_1):UPI_CPU1_CPU0_P0P1_DN(0)
    U2  EH2 UPI1_RX_DN0 SOCKET4677_AZIF0045P001C01CS-SA   I102 @S9S_MB_2U_LIB.S9S_MB_2U(SCH_1):PAGE33
    U1   K4 UPI0_TX_DN0 SOCKET4677_AZIF0045P001C01CS-SA    I51 @S9S_MB_2U_LIB.S9S_MB_2U(SCH_1):PAGE63

UPI_CPU1_CPU0_P0P1_DN<10> @S9S_MB_2U_LIB.S9S_MB_2U(SCH_1):UPI_CPU1_CPU0_P0P1_DN(10)
    U2  DG3 UPI1_RX_DN10 SOCKET4677_AZIF0045P001C01CS-SA   I102 @S9S_MB_2U_LIB.S9S_MB_2U(SCH_1):PAGE33
    U1  AK2 UPI0_TX_DN10 SOCKET4677_AZIF0045P001C01CS-SA    I51 @S9S_MB_2U_LIB.S9S_MB_2U(SCH_1):PAGE63

UPI_CPU1_CPU0_P0P1_DN<11> @S9S_MB_2U_LIB.S9S_MB_2U(SCH_1):UPI_CPU1_CPU0_P0P1_DN(11)
    U2  DE1 UPI1_RX_DN11 SOCKET4677_AZIF0045P001C01CS-SA   I102 @S9S_MB_2U_LIB.S9S_MB_2U(SCH_1):PAGE33
    U1  AM2 UPI0_TX_DN11 SOCKET4677_AZIF0045P001C01CS-SA    I51 @S9S_MB_2U_LIB.S9S_MB_2U(SCH_1):PAGE63

UPI_CPU1_CPU0_P0P1_DN<12> @S9S_MB_2U_LIB.S9S_MB_2U(SCH_1):UPI_CPU1_CPU0_P0P1_DN(12)
    U2  DC3 UPI1_RX_DP12 SOCKET4677_AZIF0045P001C01CS-SA   I102 @S9S_MB_2U_LIB.S9S_MB_2U(SCH_1):PAGE33
    U1  AP2 UPI0_TX_DN12 SOCKET4677_AZIF0045P001C01CS-SA    I51 @S9S_MB_2U_LIB.S9S_MB_2U(SCH_1):PAGE63

UPI_CPU1_CPU0_P0P1_DN<13> @S9S_MB_2U_LIB.S9S_MB_2U(SCH_1):UPI_CPU1_CPU0_P0P1_DN(13)
    U2  DB2 UPI1_RX_DN13 SOCKET4677_AZIF0045P001C01CS-SA   I102 @S9S_MB_2U_LIB.S9S_MB_2U(SCH_1):PAGE33
    U1  AT2 UPI0_TX_DN13 SOCKET4677_AZIF0045P001C01CS-SA    I51 @S9S_MB_2U_LIB.S9S_MB_2U(SCH_1):PAGE63

UPI_CPU1_CPU0_P0P1_DN<14> @S9S_MB_2U_LIB.S9S_MB_2U(SCH_1):UPI_CPU1_CPU0_P0P1_DN(14)
    U2  CY2 UPI1_RX_DN14 SOCKET4677_AZIF0045P001C01CS-SA   I102 @S9S_MB_2U_LIB.S9S_MB_2U(SCH_1):PAGE33
    U1  AU1 UPI0_TX_DN14 SOCKET4677_AZIF0045P001C01CS-SA    I51 @S9S_MB_2U_LIB.S9S_MB_2U(SCH_1):PAGE63

UPI_CPU1_CPU0_P0P1_DN<15> @S9S_MB_2U_LIB.S9S_MB_2U(SCH_1):UPI_CPU1_CPU0_P0P1_DN(15)
    U2  CV2 UPI1_RX_DN15 SOCKET4677_AZIF0045P001C01CS-SA   I102 @S9S_MB_2U_LIB.S9S_MB_2U(SCH_1):PAGE33
    U1  AY2 UPI0_TX_DN15 SOCKET4677_AZIF0045P001C01CS-SA    I51 @S9S_MB_2U_LIB.S9S_MB_2U(SCH_1):PAGE63

UPI_CPU1_CPU0_P0P1_DN<16> @S9S_MB_2U_LIB.S9S_MB_2U(SCH_1):UPI_CPU1_CPU0_P0P1_DN(16)
    U2  CR3 UPI1_RX_DN16 SOCKET4677_AZIF0045P001C01CS-SA   I102 @S9S_MB_2U_LIB.S9S_MB_2U(SCH_1):PAGE33
    U1  BB2 UPI0_TX_DN16 SOCKET4677_AZIF0045P001C01CS-SA    I51 @S9S_MB_2U_LIB.S9S_MB_2U(SCH_1):PAGE63

UPI_CPU1_CPU0_P0P1_DN<17> @S9S_MB_2U_LIB.S9S_MB_2U(SCH_1):UPI_CPU1_CPU0_P0P1_DN(17)
    U2  CP2 UPI1_RX_DP17 SOCKET4677_AZIF0045P001C01CS-SA   I102 @S9S_MB_2U_LIB.S9S_MB_2U(SCH_1):PAGE33
    U1  BD2 UPI0_TX_DN17 SOCKET4677_AZIF0045P001C01CS-SA    I51 @S9S_MB_2U_LIB.S9S_MB_2U(SCH_1):PAGE63

UPI_CPU1_CPU0_P0P1_DN<18> @S9S_MB_2U_LIB.S9S_MB_2U(SCH_1):UPI_CPU1_CPU0_P0P1_DN(18)
    U2  CL3 UPI1_RX_DN18 SOCKET4677_AZIF0045P001C01CS-SA   I102 @S9S_MB_2U_LIB.S9S_MB_2U(SCH_1):PAGE33
    U1  BF2 UPI0_TX_DN18 SOCKET4677_AZIF0045P001C01CS-SA    I51 @S9S_MB_2U_LIB.S9S_MB_2U(SCH_1):PAGE63

UPI_CPU1_CPU0_P0P1_DN<19> @S9S_MB_2U_LIB.S9S_MB_2U(SCH_1):UPI_CPU1_CPU0_P0P1_DN(19)
    U2  CK2 UPI1_RX_DP19 SOCKET4677_AZIF0045P001C01CS-SA   I102 @S9S_MB_2U_LIB.S9S_MB_2U(SCH_1):PAGE33
    U1  BH2 UPI0_TX_DN19 SOCKET4677_AZIF0045P001C01CS-SA    I51 @S9S_MB_2U_LIB.S9S_MB_2U(SCH_1):PAGE63

UPI_CPU1_CPU0_P0P1_DN<1> @S9S_MB_2U_LIB.S9S_MB_2U(SCH_1):UPI_CPU1_CPU0_P0P1_DN(1)
    U2  EE3 UPI1_RX_DN1 SOCKET4677_AZIF0045P001C01CS-SA   I102 @S9S_MB_2U_LIB.S9S_MB_2U(SCH_1):PAGE33
    U1   M2 UPI0_TX_DN1 SOCKET4677_AZIF0045P001C01CS-SA    I51 @S9S_MB_2U_LIB.S9S_MB_2U(SCH_1):PAGE63

UPI_CPU1_CPU0_P0P1_DN<20> @S9S_MB_2U_LIB.S9S_MB_2U(SCH_1):UPI_CPU1_CPU0_P0P1_DN(20)
    U2  CG3 UPI1_RX_DP20 SOCKET4677_AZIF0045P001C01CS-SA   I102 @S9S_MB_2U_LIB.S9S_MB_2U(SCH_1):PAGE33
    U1  BK2 UPI0_TX_DN20 SOCKET4677_AZIF0045P001C01CS-SA    I51 @S9S_MB_2U_LIB.S9S_MB_2U(SCH_1):PAGE63

UPI_CPU1_CPU0_P0P1_DN<21> @S9S_MB_2U_LIB.S9S_MB_2U(SCH_1):UPI_CPU1_CPU0_P0P1_DN(21)
    U2  CF2 UPI1_RX_DN21 SOCKET4677_AZIF0045P001C01CS-SA   I102 @S9S_MB_2U_LIB.S9S_MB_2U(SCH_1):PAGE33
    U1  BM2 UPI0_TX_DN21 SOCKET4677_AZIF0045P001C01CS-SA    I51 @S9S_MB_2U_LIB.S9S_MB_2U(SCH_1):PAGE63

UPI_CPU1_CPU0_P0P1_DN<22> @S9S_MB_2U_LIB.S9S_MB_2U(SCH_1):UPI_CPU1_CPU0_P0P1_DN(22)
    U2  CC3 UPI1_RX_DP22 SOCKET4677_AZIF0045P001C01CS-SA   I102 @S9S_MB_2U_LIB.S9S_MB_2U(SCH_1):PAGE33
    U1  BR3 UPI0_TX_DN22 SOCKET4677_AZIF0045P001C01CS-SA    I51 @S9S_MB_2U_LIB.S9S_MB_2U(SCH_1):PAGE63

UPI_CPU1_CPU0_P0P1_DN<23> @S9S_MB_2U_LIB.S9S_MB_2U(SCH_1):UPI_CPU1_CPU0_P0P1_DN(23)
    U2  BY2 UPI1_RX_DP23 SOCKET4677_AZIF0045P001C01CS-SA   I102 @S9S_MB_2U_LIB.S9S_MB_2U(SCH_1):PAGE33
    U1  BT2 UPI0_TX_DN23 SOCKET4677_AZIF0045P001C01CS-SA    I51 @S9S_MB_2U_LIB.S9S_MB_2U(SCH_1):PAGE63

UPI_CPU1_CPU0_P0P1_DN<2> @S9S_MB_2U_LIB.S9S_MB_2U(SCH_1):UPI_CPU1_CPU0_P0P1_DN(2)
    U2  EC3 UPI1_RX_DP2 SOCKET4677_AZIF0045P001C01CS-SA   I102 @S9S_MB_2U_LIB.S9S_MB_2U(SCH_1):PAGE33
    U1   N1 UPI0_TX_DN2 SOCKET4677_AZIF0045P001C01CS-SA    I51 @S9S_MB_2U_LIB.S9S_MB_2U(SCH_1):PAGE63

UPI_CPU1_CPU0_P0P1_DN<3> @S9S_MB_2U_LIB.S9S_MB_2U(SCH_1):UPI_CPU1_CPU0_P0P1_DN(3)
    U2  EA1 UPI1_RX_DN3 SOCKET4677_AZIF0045P001C01CS-SA   I102 @S9S_MB_2U_LIB.S9S_MB_2U(SCH_1):PAGE33
    U1   T2 UPI0_TX_DN3 SOCKET4677_AZIF0045P001C01CS-SA    I51 @S9S_MB_2U_LIB.S9S_MB_2U(SCH_1):PAGE63

UPI_CPU1_CPU0_P0P1_DN<4> @S9S_MB_2U_LIB.S9S_MB_2U(SCH_1):UPI_CPU1_CPU0_P0P1_DN(4)
    U2  DY2 UPI1_RX_DN4 SOCKET4677_AZIF0045P001C01CS-SA   I102 @S9S_MB_2U_LIB.S9S_MB_2U(SCH_1):PAGE33
    U1   U1 UPI0_TX_DN4 SOCKET4677_AZIF0045P001C01CS-SA    I51 @S9S_MB_2U_LIB.S9S_MB_2U(SCH_1):PAGE63

UPI_CPU1_CPU0_P0P1_DN<5> @S9S_MB_2U_LIB.S9S_MB_2U(SCH_1):UPI_CPU1_CPU0_P0P1_DN(5)
    U2  DU1 UPI1_RX_DN5 SOCKET4677_AZIF0045P001C01CS-SA   I102 @S9S_MB_2U_LIB.S9S_MB_2U(SCH_1):PAGE33
    U1   Y2 UPI0_TX_DN5 SOCKET4677_AZIF0045P001C01CS-SA    I51 @S9S_MB_2U_LIB.S9S_MB_2U(SCH_1):PAGE63

UPI_CPU1_CPU0_P0P1_DN<6> @S9S_MB_2U_LIB.S9S_MB_2U(SCH_1):UPI_CPU1_CPU0_P0P1_DN(6)
    U2  DT2 UPI1_RX_DN6 SOCKET4677_AZIF0045P001C01CS-SA   I102 @S9S_MB_2U_LIB.S9S_MB_2U(SCH_1):PAGE33
    U1  AA1 UPI0_TX_DN6 SOCKET4677_AZIF0045P001C01CS-SA    I51 @S9S_MB_2U_LIB.S9S_MB_2U(SCH_1):PAGE63

UPI_CPU1_CPU0_P0P1_DN<7> @S9S_MB_2U_LIB.S9S_MB_2U(SCH_1):UPI_CPU1_CPU0_P0P1_DN(7)
    U2  DN1 UPI1_RX_DN7 SOCKET4677_AZIF0045P001C01CS-SA   I102 @S9S_MB_2U_LIB.S9S_MB_2U(SCH_1):PAGE33
    U1  AD2 UPI0_TX_DN7 SOCKET4677_AZIF0045P001C01CS-SA    I51 @S9S_MB_2U_LIB.S9S_MB_2U(SCH_1):PAGE63

UPI_CPU1_CPU0_P0P1_DN<8> @S9S_MB_2U_LIB.S9S_MB_2U(SCH_1):UPI_CPU1_CPU0_P0P1_DN(8)
    U2  DL3 UPI1_RX_DN8 SOCKET4677_AZIF0045P001C01CS-SA   I102 @S9S_MB_2U_LIB.S9S_MB_2U(SCH_1):PAGE33
    U1  AF2 UPI0_TX_DN8 SOCKET4677_AZIF0045P001C01CS-SA    I51 @S9S_MB_2U_LIB.S9S_MB_2U(SCH_1):PAGE63

UPI_CPU1_CPU0_P0P1_DN<9> @S9S_MB_2U_LIB.S9S_MB_2U(SCH_1):UPI_CPU1_CPU0_P0P1_DN(9)
    U2  DJ1 UPI1_RX_DN9 SOCKET4677_AZIF0045P001C01CS-SA   I102 @S9S_MB_2U_LIB.S9S_MB_2U(SCH_1):PAGE33
    U1  AH2 UPI0_TX_DN9 SOCKET4677_AZIF0045P001C01CS-SA    I51 @S9S_MB_2U_LIB.S9S_MB_2U(SCH_1):PAGE63

UPI_CPU1_CPU0_P0P1_DP<0> @S9S_MB_2U_LIB.S9S_MB_2U(SCH_1):UPI_CPU1_CPU0_P0P1_DP(0)
    U2  EJ3 UPI1_RX_DP0 SOCKET4677_AZIF0045P001C01CS-SA   I102 @S9S_MB_2U_LIB.S9S_MB_2U(SCH_1):PAGE33
    U1   J3 UPI0_TX_DP0 SOCKET4677_AZIF0045P001C01CS-SA    I51 @S9S_MB_2U_LIB.S9S_MB_2U(SCH_1):PAGE63

UPI_CPU1_CPU0_P0P1_DP<10> @S9S_MB_2U_LIB.S9S_MB_2U(SCH_1):UPI_CPU1_CPU0_P0P1_DP(10)
    U2  DH2 UPI1_RX_DP10 SOCKET4677_AZIF0045P001C01CS-SA   I102 @S9S_MB_2U_LIB.S9S_MB_2U(SCH_1):PAGE33
    U1  AJ1 UPI0_TX_DP10 SOCKET4677_AZIF0045P001C01CS-SA    I51 @S9S_MB_2U_LIB.S9S_MB_2U(SCH_1):PAGE63

UPI_CPU1_CPU0_P0P1_DP<11> @S9S_MB_2U_LIB.S9S_MB_2U(SCH_1):UPI_CPU1_CPU0_P0P1_DP(11)
    U2  DF2 UPI1_RX_DP11 SOCKET4677_AZIF0045P001C01CS-SA   I102 @S9S_MB_2U_LIB.S9S_MB_2U(SCH_1):PAGE33
    U1  AL3 UPI0_TX_DP11 SOCKET4677_AZIF0045P001C01CS-SA    I51 @S9S_MB_2U_LIB.S9S_MB_2U(SCH_1):PAGE63

UPI_CPU1_CPU0_P0P1_DP<12> @S9S_MB_2U_LIB.S9S_MB_2U(SCH_1):UPI_CPU1_CPU0_P0P1_DP(12)
    U2  DD2 UPI1_RX_DN12 SOCKET4677_AZIF0045P001C01CS-SA   I102 @S9S_MB_2U_LIB.S9S_MB_2U(SCH_1):PAGE33
    U1  AN1 UPI0_TX_DP12 SOCKET4677_AZIF0045P001C01CS-SA    I51 @S9S_MB_2U_LIB.S9S_MB_2U(SCH_1):PAGE63

UPI_CPU1_CPU0_P0P1_DP<13> @S9S_MB_2U_LIB.S9S_MB_2U(SCH_1):UPI_CPU1_CPU0_P0P1_DP(13)
    U2  DA1 UPI1_RX_DP13 SOCKET4677_AZIF0045P001C01CS-SA   I102 @S9S_MB_2U_LIB.S9S_MB_2U(SCH_1):PAGE33
    U1  AR3 UPI0_TX_DP13 SOCKET4677_AZIF0045P001C01CS-SA    I51 @S9S_MB_2U_LIB.S9S_MB_2U(SCH_1):PAGE63

UPI_CPU1_CPU0_P0P1_DP<14> @S9S_MB_2U_LIB.S9S_MB_2U(SCH_1):UPI_CPU1_CPU0_P0P1_DP(14)
    U2  CW3 UPI1_RX_DP14 SOCKET4677_AZIF0045P001C01CS-SA   I102 @S9S_MB_2U_LIB.S9S_MB_2U(SCH_1):PAGE33
    U1  AV2 UPI0_TX_DP14 SOCKET4677_AZIF0045P001C01CS-SA    I51 @S9S_MB_2U_LIB.S9S_MB_2U(SCH_1):PAGE63

UPI_CPU1_CPU0_P0P1_DP<15> @S9S_MB_2U_LIB.S9S_MB_2U(SCH_1):UPI_CPU1_CPU0_P0P1_DP(15)
    U2  CU1 UPI1_RX_DP15 SOCKET4677_AZIF0045P001C01CS-SA   I102 @S9S_MB_2U_LIB.S9S_MB_2U(SCH_1):PAGE33
    U1  AW3 UPI0_TX_DP15 SOCKET4677_AZIF0045P001C01CS-SA    I51 @S9S_MB_2U_LIB.S9S_MB_2U(SCH_1):PAGE63

UPI_CPU1_CPU0_P0P1_DP<16> @S9S_MB_2U_LIB.S9S_MB_2U(SCH_1):UPI_CPU1_CPU0_P0P1_DP(16)
    U2  CT2 UPI1_RX_DP16 SOCKET4677_AZIF0045P001C01CS-SA   I102 @S9S_MB_2U_LIB.S9S_MB_2U(SCH_1):PAGE33
    U1  BA1 UPI0_TX_DP16 SOCKET4677_AZIF0045P001C01CS-SA    I51 @S9S_MB_2U_LIB.S9S_MB_2U(SCH_1):PAGE63

UPI_CPU1_CPU0_P0P1_DP<17> @S9S_MB_2U_LIB.S9S_MB_2U(SCH_1):UPI_CPU1_CPU0_P0P1_DP(17)
    U2  CN1 UPI1_RX_DN17 SOCKET4677_AZIF0045P001C01CS-SA   I102 @S9S_MB_2U_LIB.S9S_MB_2U(SCH_1):PAGE33
    U1  BC3 UPI0_TX_DP17 SOCKET4677_AZIF0045P001C01CS-SA    I51 @S9S_MB_2U_LIB.S9S_MB_2U(SCH_1):PAGE63

UPI_CPU1_CPU0_P0P1_DP<18> @S9S_MB_2U_LIB.S9S_MB_2U(SCH_1):UPI_CPU1_CPU0_P0P1_DP(18)
    U2  CM2 UPI1_RX_DP18 SOCKET4677_AZIF0045P001C01CS-SA   I102 @S9S_MB_2U_LIB.S9S_MB_2U(SCH_1):PAGE33
    U1  BE1 UPI0_TX_DP18 SOCKET4677_AZIF0045P001C01CS-SA    I51 @S9S_MB_2U_LIB.S9S_MB_2U(SCH_1):PAGE63

UPI_CPU1_CPU0_P0P1_DP<19> @S9S_MB_2U_LIB.S9S_MB_2U(SCH_1):UPI_CPU1_CPU0_P0P1_DP(19)
    U2  CJ1 UPI1_RX_DN19 SOCKET4677_AZIF0045P001C01CS-SA   I102 @S9S_MB_2U_LIB.S9S_MB_2U(SCH_1):PAGE33
    U1  BG3 UPI0_TX_DP19 SOCKET4677_AZIF0045P001C01CS-SA    I51 @S9S_MB_2U_LIB.S9S_MB_2U(SCH_1):PAGE63

UPI_CPU1_CPU0_P0P1_DP<1> @S9S_MB_2U_LIB.S9S_MB_2U(SCH_1):UPI_CPU1_CPU0_P0P1_DP(1)
    U2  EG3 UPI1_RX_DP1 SOCKET4677_AZIF0045P001C01CS-SA   I102 @S9S_MB_2U_LIB.S9S_MB_2U(SCH_1):PAGE33
    U1   L3 UPI0_TX_DP1 SOCKET4677_AZIF0045P001C01CS-SA    I51 @S9S_MB_2U_LIB.S9S_MB_2U(SCH_1):PAGE63

UPI_CPU1_CPU0_P0P1_DP<20> @S9S_MB_2U_LIB.S9S_MB_2U(SCH_1):UPI_CPU1_CPU0_P0P1_DP(20)
    U2  CH2 UPI1_RX_DN20 SOCKET4677_AZIF0045P001C01CS-SA   I102 @S9S_MB_2U_LIB.S9S_MB_2U(SCH_1):PAGE33
    U1  BJ1 UPI0_TX_DP20 SOCKET4677_AZIF0045P001C01CS-SA    I51 @S9S_MB_2U_LIB.S9S_MB_2U(SCH_1):PAGE63

UPI_CPU1_CPU0_P0P1_DP<21> @S9S_MB_2U_LIB.S9S_MB_2U(SCH_1):UPI_CPU1_CPU0_P0P1_DP(21)
    U2  CE1 UPI1_RX_DP21 SOCKET4677_AZIF0045P001C01CS-SA   I102 @S9S_MB_2U_LIB.S9S_MB_2U(SCH_1):PAGE33
    U1  BL3 UPI0_TX_DP21 SOCKET4677_AZIF0045P001C01CS-SA    I51 @S9S_MB_2U_LIB.S9S_MB_2U(SCH_1):PAGE63

UPI_CPU1_CPU0_P0P1_DP<22> @S9S_MB_2U_LIB.S9S_MB_2U(SCH_1):UPI_CPU1_CPU0_P0P1_DP(22)
    U2  CD2 UPI1_RX_DN22 SOCKET4677_AZIF0045P001C01CS-SA   I102 @S9S_MB_2U_LIB.S9S_MB_2U(SCH_1):PAGE33
    U1  BN3 UPI0_TX_DP22 SOCKET4677_AZIF0045P001C01CS-SA    I51 @S9S_MB_2U_LIB.S9S_MB_2U(SCH_1):PAGE63

UPI_CPU1_CPU0_P0P1_DP<23> @S9S_MB_2U_LIB.S9S_MB_2U(SCH_1):UPI_CPU1_CPU0_P0P1_DP(23)
    U2  CB2 UPI1_RX_DN23 SOCKET4677_AZIF0045P001C01CS-SA   I102 @S9S_MB_2U_LIB.S9S_MB_2U(SCH_1):PAGE33
    U1  BU3 UPI0_TX_DP23 SOCKET4677_AZIF0045P001C01CS-SA    I51 @S9S_MB_2U_LIB.S9S_MB_2U(SCH_1):PAGE63

UPI_CPU1_CPU0_P0P1_DP<2> @S9S_MB_2U_LIB.S9S_MB_2U(SCH_1):UPI_CPU1_CPU0_P0P1_DP(2)
    U2  ED2 UPI1_RX_DN2 SOCKET4677_AZIF0045P001C01CS-SA   I102 @S9S_MB_2U_LIB.S9S_MB_2U(SCH_1):PAGE33
    U1   P2 UPI0_TX_DP2 SOCKET4677_AZIF0045P001C01CS-SA    I51 @S9S_MB_2U_LIB.S9S_MB_2U(SCH_1):PAGE63

UPI_CPU1_CPU0_P0P1_DP<3> @S9S_MB_2U_LIB.S9S_MB_2U(SCH_1):UPI_CPU1_CPU0_P0P1_DP(3)
    U2  EB2 UPI1_RX_DP3 SOCKET4677_AZIF0045P001C01CS-SA   I102 @S9S_MB_2U_LIB.S9S_MB_2U(SCH_1):PAGE33
    U1   R3 UPI0_TX_DP3 SOCKET4677_AZIF0045P001C01CS-SA    I51 @S9S_MB_2U_LIB.S9S_MB_2U(SCH_1):PAGE63

UPI_CPU1_CPU0_P0P1_DP<4> @S9S_MB_2U_LIB.S9S_MB_2U(SCH_1):UPI_CPU1_CPU0_P0P1_DP(4)
    U2  DW3 UPI1_RX_DP4 SOCKET4677_AZIF0045P001C01CS-SA   I102 @S9S_MB_2U_LIB.S9S_MB_2U(SCH_1):PAGE33
    U1   V2 UPI0_TX_DP4 SOCKET4677_AZIF0045P001C01CS-SA    I51 @S9S_MB_2U_LIB.S9S_MB_2U(SCH_1):PAGE63

UPI_CPU1_CPU0_P0P1_DP<5> @S9S_MB_2U_LIB.S9S_MB_2U(SCH_1):UPI_CPU1_CPU0_P0P1_DP(5)
    U2  DV2 UPI1_RX_DP5 SOCKET4677_AZIF0045P001C01CS-SA   I102 @S9S_MB_2U_LIB.S9S_MB_2U(SCH_1):PAGE33
    U1   W3 UPI0_TX_DP5 SOCKET4677_AZIF0045P001C01CS-SA    I51 @S9S_MB_2U_LIB.S9S_MB_2U(SCH_1):PAGE63

UPI_CPU1_CPU0_P0P1_DP<6> @S9S_MB_2U_LIB.S9S_MB_2U(SCH_1):UPI_CPU1_CPU0_P0P1_DP(6)
    U2  DR3 UPI1_RX_DP6 SOCKET4677_AZIF0045P001C01CS-SA   I102 @S9S_MB_2U_LIB.S9S_MB_2U(SCH_1):PAGE33
    U1  AB2 UPI0_TX_DP6 SOCKET4677_AZIF0045P001C01CS-SA    I51 @S9S_MB_2U_LIB.S9S_MB_2U(SCH_1):PAGE63

UPI_CPU1_CPU0_P0P1_DP<7> @S9S_MB_2U_LIB.S9S_MB_2U(SCH_1):UPI_CPU1_CPU0_P0P1_DP(7)
    U2  DP2 UPI1_RX_DP7 SOCKET4677_AZIF0045P001C01CS-SA   I102 @S9S_MB_2U_LIB.S9S_MB_2U(SCH_1):PAGE33
    U1  AC3 UPI0_TX_DP7 SOCKET4677_AZIF0045P001C01CS-SA    I51 @S9S_MB_2U_LIB.S9S_MB_2U(SCH_1):PAGE63

UPI_CPU1_CPU0_P0P1_DP<8> @S9S_MB_2U_LIB.S9S_MB_2U(SCH_1):UPI_CPU1_CPU0_P0P1_DP(8)
    U2  DM2 UPI1_RX_DP8 SOCKET4677_AZIF0045P001C01CS-SA   I102 @S9S_MB_2U_LIB.S9S_MB_2U(SCH_1):PAGE33
    U1  AE1 UPI0_TX_DP8 SOCKET4677_AZIF0045P001C01CS-SA    I51 @S9S_MB_2U_LIB.S9S_MB_2U(SCH_1):PAGE63

UPI_CPU1_CPU0_P0P1_DP<9> @S9S_MB_2U_LIB.S9S_MB_2U(SCH_1):UPI_CPU1_CPU0_P0P1_DP(9)
    U2  DK2 UPI1_RX_DP9 SOCKET4677_AZIF0045P001C01CS-SA   I102 @S9S_MB_2U_LIB.S9S_MB_2U(SCH_1):PAGE33
    U1  AG3 UPI0_TX_DP9 SOCKET4677_AZIF0045P001C01CS-SA    I51 @S9S_MB_2U_LIB.S9S_MB_2U(SCH_1):PAGE63

UPI_CPU1_CPU0_P1P0_DN<0> @S9S_MB_2U_LIB.S9S_MB_2U(SCH_1):UPI_CPU1_CPU0_P1P0_DN(0)
    U2   K6 UPI0_RX_DN0 SOCKET4677_AZIF0045P001C01CS-SA    I70 @S9S_MB_2U_LIB.S9S_MB_2U(SCH_1):PAGE32
    U1  EF6 UPI1_TX_DN0 SOCKET4677_AZIF0045P001C01CS-SA    I21 @S9S_MB_2U_LIB.S9S_MB_2U(SCH_1):PAGE64

UPI_CPU1_CPU0_P1P0_DN<10> @S9S_MB_2U_LIB.S9S_MB_2U(SCH_1):UPI_CPU1_CPU0_P1P0_DN(10)
    U2  AL7 UPI0_RX_DP10 SOCKET4677_AZIF0045P001C01CS-SA    I70 @S9S_MB_2U_LIB.S9S_MB_2U(SCH_1):PAGE32
    U1  DE5 UPI1_TX_DN10 SOCKET4677_AZIF0045P001C01CS-SA    I21 @S9S_MB_2U_LIB.S9S_MB_2U(SCH_1):PAGE64

UPI_CPU1_CPU0_P1P0_DN<11> @S9S_MB_2U_LIB.S9S_MB_2U(SCH_1):UPI_CPU1_CPU0_P1P0_DN(11)
    U2  AM6 UPI0_RX_DP11 SOCKET4677_AZIF0045P001C01CS-SA    I70 @S9S_MB_2U_LIB.S9S_MB_2U(SCH_1):PAGE32
    U1  DD6 UPI1_TX_DN11 SOCKET4677_AZIF0045P001C01CS-SA    I21 @S9S_MB_2U_LIB.S9S_MB_2U(SCH_1):PAGE64

UPI_CPU1_CPU0_P1P0_DN<12> @S9S_MB_2U_LIB.S9S_MB_2U(SCH_1):UPI_CPU1_CPU0_P1P0_DN(12)
    U2  AR7 UPI0_RX_DP12 SOCKET4677_AZIF0045P001C01CS-SA    I70 @S9S_MB_2U_LIB.S9S_MB_2U(SCH_1):PAGE32
    U1  DA5 UPI1_TX_DN12 SOCKET4677_AZIF0045P001C01CS-SA    I21 @S9S_MB_2U_LIB.S9S_MB_2U(SCH_1):PAGE64

UPI_CPU1_CPU0_P1P0_DN<13> @S9S_MB_2U_LIB.S9S_MB_2U(SCH_1):UPI_CPU1_CPU0_P1P0_DN(13)
    U2  AT6 UPI0_RX_DP13 SOCKET4677_AZIF0045P001C01CS-SA    I70 @S9S_MB_2U_LIB.S9S_MB_2U(SCH_1):PAGE32
    U1  CY6 UPI1_TX_DN13 SOCKET4677_AZIF0045P001C01CS-SA    I21 @S9S_MB_2U_LIB.S9S_MB_2U(SCH_1):PAGE64

UPI_CPU1_CPU0_P1P0_DN<14> @S9S_MB_2U_LIB.S9S_MB_2U(SCH_1):UPI_CPU1_CPU0_P1P0_DN(14)
    U2  AW7 UPI0_RX_DP14 SOCKET4677_AZIF0045P001C01CS-SA    I70 @S9S_MB_2U_LIB.S9S_MB_2U(SCH_1):PAGE32
    U1  CU5 UPI1_TX_DN14 SOCKET4677_AZIF0045P001C01CS-SA    I21 @S9S_MB_2U_LIB.S9S_MB_2U(SCH_1):PAGE64

UPI_CPU1_CPU0_P1P0_DN<15> @S9S_MB_2U_LIB.S9S_MB_2U(SCH_1):UPI_CPU1_CPU0_P1P0_DN(15)
    U2  AY6 UPI0_RX_DP15 SOCKET4677_AZIF0045P001C01CS-SA    I70 @S9S_MB_2U_LIB.S9S_MB_2U(SCH_1):PAGE32
    U1  CT6 UPI1_TX_DN15 SOCKET4677_AZIF0045P001C01CS-SA    I21 @S9S_MB_2U_LIB.S9S_MB_2U(SCH_1):PAGE64

UPI_CPU1_CPU0_P1P0_DN<16> @S9S_MB_2U_LIB.S9S_MB_2U(SCH_1):UPI_CPU1_CPU0_P1P0_DN(16)
    U2  BC7 UPI0_RX_DP16 SOCKET4677_AZIF0045P001C01CS-SA    I70 @S9S_MB_2U_LIB.S9S_MB_2U(SCH_1):PAGE32
    U1  CN5 UPI1_TX_DN16 SOCKET4677_AZIF0045P001C01CS-SA    I21 @S9S_MB_2U_LIB.S9S_MB_2U(SCH_1):PAGE64

UPI_CPU1_CPU0_P1P0_DN<17> @S9S_MB_2U_LIB.S9S_MB_2U(SCH_1):UPI_CPU1_CPU0_P1P0_DN(17)
    U2  BD6 UPI0_RX_DP17 SOCKET4677_AZIF0045P001C01CS-SA    I70 @S9S_MB_2U_LIB.S9S_MB_2U(SCH_1):PAGE32
    U1  CM6 UPI1_TX_DN17 SOCKET4677_AZIF0045P001C01CS-SA    I21 @S9S_MB_2U_LIB.S9S_MB_2U(SCH_1):PAGE64

UPI_CPU1_CPU0_P1P0_DN<18> @S9S_MB_2U_LIB.S9S_MB_2U(SCH_1):UPI_CPU1_CPU0_P1P0_DN(18)
    U2  BG7 UPI0_RX_DP18 SOCKET4677_AZIF0045P001C01CS-SA    I70 @S9S_MB_2U_LIB.S9S_MB_2U(SCH_1):PAGE32
    U1  CJ5 UPI1_TX_DN18 SOCKET4677_AZIF0045P001C01CS-SA    I21 @S9S_MB_2U_LIB.S9S_MB_2U(SCH_1):PAGE64

UPI_CPU1_CPU0_P1P0_DN<19> @S9S_MB_2U_LIB.S9S_MB_2U(SCH_1):UPI_CPU1_CPU0_P1P0_DN(19)
    U2  BH6 UPI0_RX_DP19 SOCKET4677_AZIF0045P001C01CS-SA    I70 @S9S_MB_2U_LIB.S9S_MB_2U(SCH_1):PAGE32
    U1  CH6 UPI1_TX_DN19 SOCKET4677_AZIF0045P001C01CS-SA    I21 @S9S_MB_2U_LIB.S9S_MB_2U(SCH_1):PAGE64

UPI_CPU1_CPU0_P1P0_DN<1> @S9S_MB_2U_LIB.S9S_MB_2U(SCH_1):UPI_CPU1_CPU0_P1P0_DN(1)
    U2   N5 UPI0_RX_DN1 SOCKET4677_AZIF0045P001C01CS-SA    I70 @S9S_MB_2U_LIB.S9S_MB_2U(SCH_1):PAGE32
    U1  EC7 UPI1_TX_DN1 SOCKET4677_AZIF0045P001C01CS-SA    I21 @S9S_MB_2U_LIB.S9S_MB_2U(SCH_1):PAGE64

UPI_CPU1_CPU0_P1P0_DN<20> @S9S_MB_2U_LIB.S9S_MB_2U(SCH_1):UPI_CPU1_CPU0_P1P0_DN(20)
    U2  BL7 UPI0_RX_DP20 SOCKET4677_AZIF0045P001C01CS-SA    I70 @S9S_MB_2U_LIB.S9S_MB_2U(SCH_1):PAGE32
    U1  CE5 UPI1_TX_DN20 SOCKET4677_AZIF0045P001C01CS-SA    I21 @S9S_MB_2U_LIB.S9S_MB_2U(SCH_1):PAGE64

UPI_CPU1_CPU0_P1P0_DN<21> @S9S_MB_2U_LIB.S9S_MB_2U(SCH_1):UPI_CPU1_CPU0_P1P0_DN(21)
    U2  BM6 UPI0_RX_DP21 SOCKET4677_AZIF0045P001C01CS-SA    I70 @S9S_MB_2U_LIB.S9S_MB_2U(SCH_1):PAGE32
    U1  CD6 UPI1_TX_DN21 SOCKET4677_AZIF0045P001C01CS-SA    I21 @S9S_MB_2U_LIB.S9S_MB_2U(SCH_1):PAGE64

UPI_CPU1_CPU0_P1P0_DN<22> @S9S_MB_2U_LIB.S9S_MB_2U(SCH_1):UPI_CPU1_CPU0_P1P0_DN(22)
    U2  BR7 UPI0_RX_DN22 SOCKET4677_AZIF0045P001C01CS-SA    I70 @S9S_MB_2U_LIB.S9S_MB_2U(SCH_1):PAGE32
    U1  CA5 UPI1_TX_DN22 SOCKET4677_AZIF0045P001C01CS-SA    I21 @S9S_MB_2U_LIB.S9S_MB_2U(SCH_1):PAGE64

UPI_CPU1_CPU0_P1P0_DN<23> @S9S_MB_2U_LIB.S9S_MB_2U(SCH_1):UPI_CPU1_CPU0_P1P0_DN(23)
    U2  BT6 UPI0_RX_DP23 SOCKET4677_AZIF0045P001C01CS-SA    I70 @S9S_MB_2U_LIB.S9S_MB_2U(SCH_1):PAGE32
    U1  BY6 UPI1_TX_DN23 SOCKET4677_AZIF0045P001C01CS-SA    I21 @S9S_MB_2U_LIB.S9S_MB_2U(SCH_1):PAGE64

UPI_CPU1_CPU0_P1P0_DN<2> @S9S_MB_2U_LIB.S9S_MB_2U(SCH_1):UPI_CPU1_CPU0_P1P0_DN(2)
    U2   P6 UPI0_RX_DN2 SOCKET4677_AZIF0045P001C01CS-SA    I70 @S9S_MB_2U_LIB.S9S_MB_2U(SCH_1):PAGE32
    U1  EB6 UPI1_TX_DN2 SOCKET4677_AZIF0045P001C01CS-SA    I21 @S9S_MB_2U_LIB.S9S_MB_2U(SCH_1):PAGE64

UPI_CPU1_CPU0_P1P0_DN<3> @S9S_MB_2U_LIB.S9S_MB_2U(SCH_1):UPI_CPU1_CPU0_P1P0_DN(3)
    U2   T6 UPI0_RX_DP3 SOCKET4677_AZIF0045P001C01CS-SA    I70 @S9S_MB_2U_LIB.S9S_MB_2U(SCH_1):PAGE32
    U1  DY6 UPI1_TX_DN3 SOCKET4677_AZIF0045P001C01CS-SA    I21 @S9S_MB_2U_LIB.S9S_MB_2U(SCH_1):PAGE64

UPI_CPU1_CPU0_P1P0_DN<4> @S9S_MB_2U_LIB.S9S_MB_2U(SCH_1):UPI_CPU1_CPU0_P1P0_DN(4)
    U2   V6 UPI0_RX_DN4 SOCKET4677_AZIF0045P001C01CS-SA    I70 @S9S_MB_2U_LIB.S9S_MB_2U(SCH_1):PAGE32
    U1  DV6 UPI1_TX_DN4 SOCKET4677_AZIF0045P001C01CS-SA    I21 @S9S_MB_2U_LIB.S9S_MB_2U(SCH_1):PAGE64

UPI_CPU1_CPU0_P1P0_DN<5> @S9S_MB_2U_LIB.S9S_MB_2U(SCH_1):UPI_CPU1_CPU0_P1P0_DN(5)
    U2   Y6 UPI0_RX_DP5 SOCKET4677_AZIF0045P001C01CS-SA    I70 @S9S_MB_2U_LIB.S9S_MB_2U(SCH_1):PAGE32
    U1  DT6 UPI1_TX_DN5 SOCKET4677_AZIF0045P001C01CS-SA    I21 @S9S_MB_2U_LIB.S9S_MB_2U(SCH_1):PAGE64

UPI_CPU1_CPU0_P1P0_DN<6> @S9S_MB_2U_LIB.S9S_MB_2U(SCH_1):UPI_CPU1_CPU0_P1P0_DN(6)
    U2  AB6 UPI0_RX_DN6 SOCKET4677_AZIF0045P001C01CS-SA    I70 @S9S_MB_2U_LIB.S9S_MB_2U(SCH_1):PAGE32
    U1  DP6 UPI1_TX_DN6 SOCKET4677_AZIF0045P001C01CS-SA    I21 @S9S_MB_2U_LIB.S9S_MB_2U(SCH_1):PAGE64

UPI_CPU1_CPU0_P1P0_DN<7> @S9S_MB_2U_LIB.S9S_MB_2U(SCH_1):UPI_CPU1_CPU0_P1P0_DN(7)
    U2  AE5 UPI0_RX_DN7 SOCKET4677_AZIF0045P001C01CS-SA    I70 @S9S_MB_2U_LIB.S9S_MB_2U(SCH_1):PAGE32
    U1  DL7 UPI1_TX_DN7 SOCKET4677_AZIF0045P001C01CS-SA    I21 @S9S_MB_2U_LIB.S9S_MB_2U(SCH_1):PAGE64

UPI_CPU1_CPU0_P1P0_DN<8> @S9S_MB_2U_LIB.S9S_MB_2U(SCH_1):UPI_CPU1_CPU0_P1P0_DN(8)
    U2  AF6 UPI0_RX_DN8 SOCKET4677_AZIF0045P001C01CS-SA    I70 @S9S_MB_2U_LIB.S9S_MB_2U(SCH_1):PAGE32
    U1  DK6 UPI1_TX_DN8 SOCKET4677_AZIF0045P001C01CS-SA    I21 @S9S_MB_2U_LIB.S9S_MB_2U(SCH_1):PAGE64

UPI_CPU1_CPU0_P1P0_DN<9> @S9S_MB_2U_LIB.S9S_MB_2U(SCH_1):UPI_CPU1_CPU0_P1P0_DN(9)
    U2  AH6 UPI0_RX_DN9 SOCKET4677_AZIF0045P001C01CS-SA    I70 @S9S_MB_2U_LIB.S9S_MB_2U(SCH_1):PAGE32
    U1  DH6 UPI1_TX_DN9 SOCKET4677_AZIF0045P001C01CS-SA    I21 @S9S_MB_2U_LIB.S9S_MB_2U(SCH_1):PAGE64

UPI_CPU1_CPU0_P1P0_DP<0> @S9S_MB_2U_LIB.S9S_MB_2U(SCH_1):UPI_CPU1_CPU0_P1P0_DP(0)
    U2   L7 UPI0_RX_DP0 SOCKET4677_AZIF0045P001C01CS-SA    I70 @S9S_MB_2U_LIB.S9S_MB_2U(SCH_1):PAGE32
    U1  EE5 UPI1_TX_DP0 SOCKET4677_AZIF0045P001C01CS-SA    I21 @S9S_MB_2U_LIB.S9S_MB_2U(SCH_1):PAGE64

UPI_CPU1_CPU0_P1P0_DP<10> @S9S_MB_2U_LIB.S9S_MB_2U(SCH_1):UPI_CPU1_CPU0_P1P0_DP(10)
    U2  AK6 UPI0_RX_DN10 SOCKET4677_AZIF0045P001C01CS-SA    I70 @S9S_MB_2U_LIB.S9S_MB_2U(SCH_1):PAGE32
    U1  DF6 UPI1_TX_DP10 SOCKET4677_AZIF0045P001C01CS-SA    I21 @S9S_MB_2U_LIB.S9S_MB_2U(SCH_1):PAGE64

UPI_CPU1_CPU0_P1P0_DP<11> @S9S_MB_2U_LIB.S9S_MB_2U(SCH_1):UPI_CPU1_CPU0_P1P0_DP(11)
    U2  AN5 UPI0_RX_DN11 SOCKET4677_AZIF0045P001C01CS-SA    I70 @S9S_MB_2U_LIB.S9S_MB_2U(SCH_1):PAGE32
    U1  DC7 UPI1_TX_DP11 SOCKET4677_AZIF0045P001C01CS-SA    I21 @S9S_MB_2U_LIB.S9S_MB_2U(SCH_1):PAGE64

UPI_CPU1_CPU0_P1P0_DP<12> @S9S_MB_2U_LIB.S9S_MB_2U(SCH_1):UPI_CPU1_CPU0_P1P0_DP(12)
    U2  AP6 UPI0_RX_DN12 SOCKET4677_AZIF0045P001C01CS-SA    I70 @S9S_MB_2U_LIB.S9S_MB_2U(SCH_1):PAGE32
    U1  DB6 UPI1_TX_DP12 SOCKET4677_AZIF0045P001C01CS-SA    I21 @S9S_MB_2U_LIB.S9S_MB_2U(SCH_1):PAGE64

UPI_CPU1_CPU0_P1P0_DP<13> @S9S_MB_2U_LIB.S9S_MB_2U(SCH_1):UPI_CPU1_CPU0_P1P0_DP(13)
    U2  AU5 UPI0_RX_DN13 SOCKET4677_AZIF0045P001C01CS-SA    I70 @S9S_MB_2U_LIB.S9S_MB_2U(SCH_1):PAGE32
    U1  CW7 UPI1_TX_DP13 SOCKET4677_AZIF0045P001C01CS-SA    I21 @S9S_MB_2U_LIB.S9S_MB_2U(SCH_1):PAGE64

UPI_CPU1_CPU0_P1P0_DP<14> @S9S_MB_2U_LIB.S9S_MB_2U(SCH_1):UPI_CPU1_CPU0_P1P0_DP(14)
    U2  AV6 UPI0_RX_DN14 SOCKET4677_AZIF0045P001C01CS-SA    I70 @S9S_MB_2U_LIB.S9S_MB_2U(SCH_1):PAGE32
    U1  CV6 UPI1_TX_DP14 SOCKET4677_AZIF0045P001C01CS-SA    I21 @S9S_MB_2U_LIB.S9S_MB_2U(SCH_1):PAGE64

UPI_CPU1_CPU0_P1P0_DP<15> @S9S_MB_2U_LIB.S9S_MB_2U(SCH_1):UPI_CPU1_CPU0_P1P0_DP(15)
    U2  BA5 UPI0_RX_DN15 SOCKET4677_AZIF0045P001C01CS-SA    I70 @S9S_MB_2U_LIB.S9S_MB_2U(SCH_1):PAGE32
    U1  CR7 UPI1_TX_DP15 SOCKET4677_AZIF0045P001C01CS-SA    I21 @S9S_MB_2U_LIB.S9S_MB_2U(SCH_1):PAGE64

UPI_CPU1_CPU0_P1P0_DP<16> @S9S_MB_2U_LIB.S9S_MB_2U(SCH_1):UPI_CPU1_CPU0_P1P0_DP(16)
    U2  BB6 UPI0_RX_DN16 SOCKET4677_AZIF0045P001C01CS-SA    I70 @S9S_MB_2U_LIB.S9S_MB_2U(SCH_1):PAGE32
    U1  CP6 UPI1_TX_DP16 SOCKET4677_AZIF0045P001C01CS-SA    I21 @S9S_MB_2U_LIB.S9S_MB_2U(SCH_1):PAGE64

UPI_CPU1_CPU0_P1P0_DP<17> @S9S_MB_2U_LIB.S9S_MB_2U(SCH_1):UPI_CPU1_CPU0_P1P0_DP(17)
    U2  BE5 UPI0_RX_DN17 SOCKET4677_AZIF0045P001C01CS-SA    I70 @S9S_MB_2U_LIB.S9S_MB_2U(SCH_1):PAGE32
    U1  CL7 UPI1_TX_DP17 SOCKET4677_AZIF0045P001C01CS-SA    I21 @S9S_MB_2U_LIB.S9S_MB_2U(SCH_1):PAGE64

UPI_CPU1_CPU0_P1P0_DP<18> @S9S_MB_2U_LIB.S9S_MB_2U(SCH_1):UPI_CPU1_CPU0_P1P0_DP(18)
    U2  BF6 UPI0_RX_DN18 SOCKET4677_AZIF0045P001C01CS-SA    I70 @S9S_MB_2U_LIB.S9S_MB_2U(SCH_1):PAGE32
    U1  CK6 UPI1_TX_DP18 SOCKET4677_AZIF0045P001C01CS-SA    I21 @S9S_MB_2U_LIB.S9S_MB_2U(SCH_1):PAGE64

UPI_CPU1_CPU0_P1P0_DP<19> @S9S_MB_2U_LIB.S9S_MB_2U(SCH_1):UPI_CPU1_CPU0_P1P0_DP(19)
    U2  BJ5 UPI0_RX_DN19 SOCKET4677_AZIF0045P001C01CS-SA    I70 @S9S_MB_2U_LIB.S9S_MB_2U(SCH_1):PAGE32
    U1  CG7 UPI1_TX_DP19 SOCKET4677_AZIF0045P001C01CS-SA    I21 @S9S_MB_2U_LIB.S9S_MB_2U(SCH_1):PAGE64

UPI_CPU1_CPU0_P1P0_DP<1> @S9S_MB_2U_LIB.S9S_MB_2U(SCH_1):UPI_CPU1_CPU0_P1P0_DP(1)
    U2   M6 UPI0_RX_DP1 SOCKET4677_AZIF0045P001C01CS-SA    I70 @S9S_MB_2U_LIB.S9S_MB_2U(SCH_1):PAGE32
    U1  ED6 UPI1_TX_DP1 SOCKET4677_AZIF0045P001C01CS-SA    I21 @S9S_MB_2U_LIB.S9S_MB_2U(SCH_1):PAGE64

UPI_CPU1_CPU0_P1P0_DP<20> @S9S_MB_2U_LIB.S9S_MB_2U(SCH_1):UPI_CPU1_CPU0_P1P0_DP(20)
    U2  BK6 UPI0_RX_DN20 SOCKET4677_AZIF0045P001C01CS-SA    I70 @S9S_MB_2U_LIB.S9S_MB_2U(SCH_1):PAGE32
    U1  CF6 UPI1_TX_DP20 SOCKET4677_AZIF0045P001C01CS-SA    I21 @S9S_MB_2U_LIB.S9S_MB_2U(SCH_1):PAGE64

UPI_CPU1_CPU0_P1P0_DP<21> @S9S_MB_2U_LIB.S9S_MB_2U(SCH_1):UPI_CPU1_CPU0_P1P0_DP(21)
    U2  BN5 UPI0_RX_DN21 SOCKET4677_AZIF0045P001C01CS-SA    I70 @S9S_MB_2U_LIB.S9S_MB_2U(SCH_1):PAGE32
    U1  CC7 UPI1_TX_DP21 SOCKET4677_AZIF0045P001C01CS-SA    I21 @S9S_MB_2U_LIB.S9S_MB_2U(SCH_1):PAGE64

UPI_CPU1_CPU0_P1P0_DP<22> @S9S_MB_2U_LIB.S9S_MB_2U(SCH_1):UPI_CPU1_CPU0_P1P0_DP(22)
    U2  BP6 UPI0_RX_DP22 SOCKET4677_AZIF0045P001C01CS-SA    I70 @S9S_MB_2U_LIB.S9S_MB_2U(SCH_1):PAGE32
    U1  CB6 UPI1_TX_DP22 SOCKET4677_AZIF0045P001C01CS-SA    I21 @S9S_MB_2U_LIB.S9S_MB_2U(SCH_1):PAGE64

UPI_CPU1_CPU0_P1P0_DP<23> @S9S_MB_2U_LIB.S9S_MB_2U(SCH_1):UPI_CPU1_CPU0_P1P0_DP(23)
    U2  BU5 UPI0_RX_DN23 SOCKET4677_AZIF0045P001C01CS-SA    I70 @S9S_MB_2U_LIB.S9S_MB_2U(SCH_1):PAGE32
    U1  BW7 UPI1_TX_DP23 SOCKET4677_AZIF0045P001C01CS-SA    I21 @S9S_MB_2U_LIB.S9S_MB_2U(SCH_1):PAGE64

UPI_CPU1_CPU0_P1P0_DP<2> @S9S_MB_2U_LIB.S9S_MB_2U(SCH_1):UPI_CPU1_CPU0_P1P0_DP(2)
    U2   R7 UPI0_RX_DP2 SOCKET4677_AZIF0045P001C01CS-SA    I70 @S9S_MB_2U_LIB.S9S_MB_2U(SCH_1):PAGE32
    U1  EA5 UPI1_TX_DP2 SOCKET4677_AZIF0045P001C01CS-SA    I21 @S9S_MB_2U_LIB.S9S_MB_2U(SCH_1):PAGE64

UPI_CPU1_CPU0_P1P0_DP<3> @S9S_MB_2U_LIB.S9S_MB_2U(SCH_1):UPI_CPU1_CPU0_P1P0_DP(3)
    U2   U5 UPI0_RX_DN3 SOCKET4677_AZIF0045P001C01CS-SA    I70 @S9S_MB_2U_LIB.S9S_MB_2U(SCH_1):PAGE32
    U1  DW7 UPI1_TX_DP3 SOCKET4677_AZIF0045P001C01CS-SA    I21 @S9S_MB_2U_LIB.S9S_MB_2U(SCH_1):PAGE64

UPI_CPU1_CPU0_P1P0_DP<4> @S9S_MB_2U_LIB.S9S_MB_2U(SCH_1):UPI_CPU1_CPU0_P1P0_DP(4)
    U2   W7 UPI0_RX_DP4 SOCKET4677_AZIF0045P001C01CS-SA    I70 @S9S_MB_2U_LIB.S9S_MB_2U(SCH_1):PAGE32
    U1  DU5 UPI1_TX_DP4 SOCKET4677_AZIF0045P001C01CS-SA    I21 @S9S_MB_2U_LIB.S9S_MB_2U(SCH_1):PAGE64

UPI_CPU1_CPU0_P1P0_DP<5> @S9S_MB_2U_LIB.S9S_MB_2U(SCH_1):UPI_CPU1_CPU0_P1P0_DP(5)
    U2  AA5 UPI0_RX_DN5 SOCKET4677_AZIF0045P001C01CS-SA    I70 @S9S_MB_2U_LIB.S9S_MB_2U(SCH_1):PAGE32
    U1  DR7 UPI1_TX_DP5 SOCKET4677_AZIF0045P001C01CS-SA    I21 @S9S_MB_2U_LIB.S9S_MB_2U(SCH_1):PAGE64

UPI_CPU1_CPU0_P1P0_DP<6> @S9S_MB_2U_LIB.S9S_MB_2U(SCH_1):UPI_CPU1_CPU0_P1P0_DP(6)
    U2  AC7 UPI0_RX_DP6 SOCKET4677_AZIF0045P001C01CS-SA    I70 @S9S_MB_2U_LIB.S9S_MB_2U(SCH_1):PAGE32
    U1  DN5 UPI1_TX_DP6 SOCKET4677_AZIF0045P001C01CS-SA    I21 @S9S_MB_2U_LIB.S9S_MB_2U(SCH_1):PAGE64

UPI_CPU1_CPU0_P1P0_DP<7> @S9S_MB_2U_LIB.S9S_MB_2U(SCH_1):UPI_CPU1_CPU0_P1P0_DP(7)
    U2  AD6 UPI0_RX_DP7 SOCKET4677_AZIF0045P001C01CS-SA    I70 @S9S_MB_2U_LIB.S9S_MB_2U(SCH_1):PAGE32
    U1  DM6 UPI1_TX_DP7 SOCKET4677_AZIF0045P001C01CS-SA    I21 @S9S_MB_2U_LIB.S9S_MB_2U(SCH_1):PAGE64

UPI_CPU1_CPU0_P1P0_DP<8> @S9S_MB_2U_LIB.S9S_MB_2U(SCH_1):UPI_CPU1_CPU0_P1P0_DP(8)
    U2  AG7 UPI0_RX_DP8 SOCKET4677_AZIF0045P001C01CS-SA    I70 @S9S_MB_2U_LIB.S9S_MB_2U(SCH_1):PAGE32
    U1  DJ5 UPI1_TX_DP8 SOCKET4677_AZIF0045P001C01CS-SA    I21 @S9S_MB_2U_LIB.S9S_MB_2U(SCH_1):PAGE64

UPI_CPU1_CPU0_P1P0_DP<9> @S9S_MB_2U_LIB.S9S_MB_2U(SCH_1):UPI_CPU1_CPU0_P1P0_DP(9)
    U2  AJ5 UPI0_RX_DP9 SOCKET4677_AZIF0045P001C01CS-SA    I70 @S9S_MB_2U_LIB.S9S_MB_2U(SCH_1):PAGE32
    U1  DG7 UPI1_TX_DP9 SOCKET4677_AZIF0045P001C01CS-SA    I21 @S9S_MB_2U_LIB.S9S_MB_2U(SCH_1):PAGE64

UPI_CPU1_CPU0_P2P2_DN<0> @S9S_MB_2U_LIB.S9S_MB_2U(SCH_1):UPI_CPU1_CPU0_P2P2_DN(0)
    U2 BC74 UPI2_RX_DP23 SOCKET4677_AZIF0045P001C01CS-SA   I102 @S9S_MB_2U_LIB.S9S_MB_2U(SCH_1):PAGE34
    U1  B85 UPI2_TX_DN0 SOCKET4677_AZIF0045P001C01CS-SA    I16 @S9S_MB_2U_LIB.S9S_MB_2U(SCH_1):PAGE65

UPI_CPU1_CPU0_P2P2_DN<10> @S9S_MB_2U_LIB.S9S_MB_2U(SCH_1):UPI_CPU1_CPU0_P2P2_DN(10)
    U2 AV73 UPI2_RX_DN13 SOCKET4677_AZIF0045P001C01CS-SA   I102 @S9S_MB_2U_LIB.S9S_MB_2U(SCH_1):PAGE34
    U1 AW78 UPI2_TX_DN10 SOCKET4677_AZIF0045P001C01CS-SA    I16 @S9S_MB_2U_LIB.S9S_MB_2U(SCH_1):PAGE65

UPI_CPU1_CPU0_P2P2_DN<11> @S9S_MB_2U_LIB.S9S_MB_2U(SCH_1):UPI_CPU1_CPU0_P2P2_DN(11)
    U2 BB73 UPI2_RX_DP12 SOCKET4677_AZIF0045P001C01CS-SA   I102 @S9S_MB_2U_LIB.S9S_MB_2U(SCH_1):PAGE34
    U1 AU78 UPI2_TX_DN11 SOCKET4677_AZIF0045P001C01CS-SA    I16 @S9S_MB_2U_LIB.S9S_MB_2U(SCH_1):PAGE65

UPI_CPU1_CPU0_P2P2_DN<12> @S9S_MB_2U_LIB.S9S_MB_2U(SCH_1):UPI_CPU1_CPU0_P2P2_DN(12)
    U2 AJ82 UPI2_RX_DP11 SOCKET4677_AZIF0045P001C01CS-SA   I102 @S9S_MB_2U_LIB.S9S_MB_2U(SCH_1):PAGE34
    U1 AM81 UPI2_TX_DN12 SOCKET4677_AZIF0045P001C01CS-SA    I16 @S9S_MB_2U_LIB.S9S_MB_2U(SCH_1):PAGE65

UPI_CPU1_CPU0_P2P2_DN<13> @S9S_MB_2U_LIB.S9S_MB_2U(SCH_1):UPI_CPU1_CPU0_P2P2_DN(13)
    U2 AJ80 UPI2_RX_DN10 SOCKET4677_AZIF0045P001C01CS-SA   I102 @S9S_MB_2U_LIB.S9S_MB_2U(SCH_1):PAGE34
    U1 AN82 UPI2_TX_DN13 SOCKET4677_AZIF0045P001C01CS-SA    I16 @S9S_MB_2U_LIB.S9S_MB_2U(SCH_1):PAGE65

UPI_CPU1_CPU0_P2P2_DN<14> @S9S_MB_2U_LIB.S9S_MB_2U(SCH_1):UPI_CPU1_CPU0_P2P2_DN(14)
    U2 AF83 UPI2_RX_DP9 SOCKET4677_AZIF0045P001C01CS-SA   I102 @S9S_MB_2U_LIB.S9S_MB_2U(SCH_1):PAGE34
    U1 AR80 UPI2_TX_DN14 SOCKET4677_AZIF0045P001C01CS-SA    I16 @S9S_MB_2U_LIB.S9S_MB_2U(SCH_1):PAGE65

UPI_CPU1_CPU0_P2P2_DN<15> @S9S_MB_2U_LIB.S9S_MB_2U(SCH_1):UPI_CPU1_CPU0_P2P2_DN(15)
    U2 AG80 UPI2_RX_DP8 SOCKET4677_AZIF0045P001C01CS-SA   I102 @S9S_MB_2U_LIB.S9S_MB_2U(SCH_1):PAGE34
    U1 AT83 UPI2_TX_DN15 SOCKET4677_AZIF0045P001C01CS-SA    I16 @S9S_MB_2U_LIB.S9S_MB_2U(SCH_1):PAGE65

UPI_CPU1_CPU0_P2P2_DN<16> @S9S_MB_2U_LIB.S9S_MB_2U(SCH_1):UPI_CPU1_CPU0_P2P2_DN(16)
    U2 AC82 UPI2_RX_DP7 SOCKET4677_AZIF0045P001C01CS-SA   I102 @S9S_MB_2U_LIB.S9S_MB_2U(SCH_1):PAGE34
    U1 AV81 UPI2_TX_DN16 SOCKET4677_AZIF0045P001C01CS-SA    I16 @S9S_MB_2U_LIB.S9S_MB_2U(SCH_1):PAGE65

UPI_CPU1_CPU0_P2P2_DN<17> @S9S_MB_2U_LIB.S9S_MB_2U(SCH_1):UPI_CPU1_CPU0_P2P2_DN(17)
    U2 AC80 UPI2_RX_DN6 SOCKET4677_AZIF0045P001C01CS-SA   I102 @S9S_MB_2U_LIB.S9S_MB_2U(SCH_1):PAGE34
    U1 BA80 UPI2_TX_DN17 SOCKET4677_AZIF0045P001C01CS-SA    I16 @S9S_MB_2U_LIB.S9S_MB_2U(SCH_1):PAGE65

UPI_CPU1_CPU0_P2P2_DN<18> @S9S_MB_2U_LIB.S9S_MB_2U(SCH_1):UPI_CPU1_CPU0_P2P2_DN(18)
    U2  L80 UPI2_RX_DN5 SOCKET4677_AZIF0045P001C01CS-SA   I102 @S9S_MB_2U_LIB.S9S_MB_2U(SCH_1):PAGE34
    U1 BC82 UPI2_TX_DN18 SOCKET4677_AZIF0045P001C01CS-SA    I16 @S9S_MB_2U_LIB.S9S_MB_2U(SCH_1):PAGE65

UPI_CPU1_CPU0_P2P2_DN<19> @S9S_MB_2U_LIB.S9S_MB_2U(SCH_1):UPI_CPU1_CPU0_P2P2_DN(19)
    U2  J82 UPI2_RX_DN4 SOCKET4677_AZIF0045P001C01CS-SA   I102 @S9S_MB_2U_LIB.S9S_MB_2U(SCH_1):PAGE34
    U1 BE82 UPI2_TX_DN19 SOCKET4677_AZIF0045P001C01CS-SA    I16 @S9S_MB_2U_LIB.S9S_MB_2U(SCH_1):PAGE65

UPI_CPU1_CPU0_P2P2_DN<1> @S9S_MB_2U_LIB.S9S_MB_2U(SCH_1):UPI_CPU1_CPU0_P2P2_DN(1)
    U2 BK73 UPI2_RX_DN22 SOCKET4677_AZIF0045P001C01CS-SA   I102 @S9S_MB_2U_LIB.S9S_MB_2U(SCH_1):PAGE34
    U1  E84 UPI2_TX_DN1 SOCKET4677_AZIF0045P001C01CS-SA    I16 @S9S_MB_2U_LIB.S9S_MB_2U(SCH_1):PAGE65

UPI_CPU1_CPU0_P2P2_DN<20> @S9S_MB_2U_LIB.S9S_MB_2U(SCH_1):UPI_CPU1_CPU0_P2P2_DN(20)
    U2  K79 UPI2_RX_DN3 SOCKET4677_AZIF0045P001C01CS-SA   I102 @S9S_MB_2U_LIB.S9S_MB_2U(SCH_1):PAGE34
    U1 BD79 UPI2_TX_DN20 SOCKET4677_AZIF0045P001C01CS-SA    I16 @S9S_MB_2U_LIB.S9S_MB_2U(SCH_1):PAGE65

UPI_CPU1_CPU0_P2P2_DN<21> @S9S_MB_2U_LIB.S9S_MB_2U(SCH_1):UPI_CPU1_CPU0_P2P2_DN(21)
    U2  G82 UPI2_RX_DN2 SOCKET4677_AZIF0045P001C01CS-SA   I102 @S9S_MB_2U_LIB.S9S_MB_2U(SCH_1):PAGE34
    U1 BF81 UPI2_TX_DN21 SOCKET4677_AZIF0045P001C01CS-SA    I16 @S9S_MB_2U_LIB.S9S_MB_2U(SCH_1):PAGE65

UPI_CPU1_CPU0_P2P2_DN<22> @S9S_MB_2U_LIB.S9S_MB_2U(SCH_1):UPI_CPU1_CPU0_P2P2_DN(22)
    U2  E82 UPI2_RX_DP1 SOCKET4677_AZIF0045P001C01CS-SA   I102 @S9S_MB_2U_LIB.S9S_MB_2U(SCH_1):PAGE34
    U1 BG80 UPI2_TX_DN22 SOCKET4677_AZIF0045P001C01CS-SA    I16 @S9S_MB_2U_LIB.S9S_MB_2U(SCH_1):PAGE65

UPI_CPU1_CPU0_P2P2_DN<23> @S9S_MB_2U_LIB.S9S_MB_2U(SCH_1):UPI_CPU1_CPU0_P2P2_DN(23)
    U2  E80 UPI2_RX_DN0 SOCKET4677_AZIF0045P001C01CS-SA   I102 @S9S_MB_2U_LIB.S9S_MB_2U(SCH_1):PAGE34
    U1 BM71 UPI2_TX_DN23 SOCKET4677_AZIF0045P001C01CS-SA    I16 @S9S_MB_2U_LIB.S9S_MB_2U(SCH_1):PAGE65

UPI_CPU1_CPU0_P2P2_DN<2> @S9S_MB_2U_LIB.S9S_MB_2U(SCH_1):UPI_CPU1_CPU0_P2P2_DN(2)
    U2 BM75 UPI2_RX_DP21 SOCKET4677_AZIF0045P001C01CS-SA   I102 @S9S_MB_2U_LIB.S9S_MB_2U(SCH_1):PAGE34
    U1  D87 UPI2_TX_DN2 SOCKET4677_AZIF0045P001C01CS-SA    I16 @S9S_MB_2U_LIB.S9S_MB_2U(SCH_1):PAGE65

UPI_CPU1_CPU0_P2P2_DN<3> @S9S_MB_2U_LIB.S9S_MB_2U(SCH_1):UPI_CPU1_CPU0_P2P2_DN(3)
    U2 BJ74 UPI2_RX_DP20 SOCKET4677_AZIF0045P001C01CS-SA   I102 @S9S_MB_2U_LIB.S9S_MB_2U(SCH_1):PAGE34
    U1  F87 UPI2_TX_DN3 SOCKET4677_AZIF0045P001C01CS-SA    I16 @S9S_MB_2U_LIB.S9S_MB_2U(SCH_1):PAGE65

UPI_CPU1_CPU0_P2P2_DN<4> @S9S_MB_2U_LIB.S9S_MB_2U(SCH_1):UPI_CPU1_CPU0_P2P2_DN(4)
    U2 BN76 UPI2_RX_DP19 SOCKET4677_AZIF0045P001C01CS-SA   I102 @S9S_MB_2U_LIB.S9S_MB_2U(SCH_1):PAGE34
    U1  H85 UPI2_TX_DN4 SOCKET4677_AZIF0045P001C01CS-SA    I16 @S9S_MB_2U_LIB.S9S_MB_2U(SCH_1):PAGE65

UPI_CPU1_CPU0_P2P2_DN<5> @S9S_MB_2U_LIB.S9S_MB_2U(SCH_1):UPI_CPU1_CPU0_P2P2_DN(5)
    U2 BJ76 UPI2_RX_DN18 SOCKET4677_AZIF0045P001C01CS-SA   I102 @S9S_MB_2U_LIB.S9S_MB_2U(SCH_1):PAGE34
    U1  P81 UPI2_TX_DN5 SOCKET4677_AZIF0045P001C01CS-SA    I16 @S9S_MB_2U_LIB.S9S_MB_2U(SCH_1):PAGE65

UPI_CPU1_CPU0_P2P2_DN<6> @S9S_MB_2U_LIB.S9S_MB_2U(SCH_1):UPI_CPU1_CPU0_P2P2_DN(6)
    U2 BH75 UPI2_RX_DN17 SOCKET4677_AZIF0045P001C01CS-SA   I102 @S9S_MB_2U_LIB.S9S_MB_2U(SCH_1):PAGE34
    U1  R82 UPI2_TX_DN6 SOCKET4677_AZIF0045P001C01CS-SA    I16 @S9S_MB_2U_LIB.S9S_MB_2U(SCH_1):PAGE65

UPI_CPU1_CPU0_P2P2_DN<7> @S9S_MB_2U_LIB.S9S_MB_2U(SCH_1):UPI_CPU1_CPU0_P2P2_DN(7)
    U2 AV75 UPI2_RX_DP16 SOCKET4677_AZIF0045P001C01CS-SA   I102 @S9S_MB_2U_LIB.S9S_MB_2U(SCH_1):PAGE34
    U1  U80 UPI2_TX_DN7 SOCKET4677_AZIF0045P001C01CS-SA    I16 @S9S_MB_2U_LIB.S9S_MB_2U(SCH_1):PAGE65

UPI_CPU1_CPU0_P2P2_DN<8> @S9S_MB_2U_LIB.S9S_MB_2U(SCH_1):UPI_CPU1_CPU0_P2P2_DN(8)
    U2 BD75 UPI2_RX_DP15 SOCKET4677_AZIF0045P001C01CS-SA   I102 @S9S_MB_2U_LIB.S9S_MB_2U(SCH_1):PAGE34
    U1  V83 UPI2_TX_DN8 SOCKET4677_AZIF0045P001C01CS-SA    I16 @S9S_MB_2U_LIB.S9S_MB_2U(SCH_1):PAGE65

UPI_CPU1_CPU0_P2P2_DN<9> @S9S_MB_2U_LIB.S9S_MB_2U(SCH_1):UPI_CPU1_CPU0_P2P2_DN(9)
    U2 AY75 UPI2_RX_DN14 SOCKET4677_AZIF0045P001C01CS-SA   I102 @S9S_MB_2U_LIB.S9S_MB_2U(SCH_1):PAGE34
    U1  Y81 UPI2_TX_DN9 SOCKET4677_AZIF0045P001C01CS-SA    I16 @S9S_MB_2U_LIB.S9S_MB_2U(SCH_1):PAGE65

UPI_CPU1_CPU0_P2P2_DP<0> @S9S_MB_2U_LIB.S9S_MB_2U(SCH_1):UPI_CPU1_CPU0_P2P2_DP(0)
    U2 BD73 UPI2_RX_DN23 SOCKET4677_AZIF0045P001C01CS-SA   I102 @S9S_MB_2U_LIB.S9S_MB_2U(SCH_1):PAGE34
    U1  D85 UPI2_TX_DP0 SOCKET4677_AZIF0045P001C01CS-SA    I16 @S9S_MB_2U_LIB.S9S_MB_2U(SCH_1):PAGE65

UPI_CPU1_CPU0_P2P2_DP<10> @S9S_MB_2U_LIB.S9S_MB_2U(SCH_1):UPI_CPU1_CPU0_P2P2_DP(10)
    U2 AY73 UPI2_RX_DP13 SOCKET4677_AZIF0045P001C01CS-SA   I102 @S9S_MB_2U_LIB.S9S_MB_2U(SCH_1):PAGE34
    U1 BA78 UPI2_TX_DP10 SOCKET4677_AZIF0045P001C01CS-SA    I16 @S9S_MB_2U_LIB.S9S_MB_2U(SCH_1):PAGE65

UPI_CPU1_CPU0_P2P2_DP<11> @S9S_MB_2U_LIB.S9S_MB_2U(SCH_1):UPI_CPU1_CPU0_P2P2_DP(11)
    U2 BA72 UPI2_RX_DN12 SOCKET4677_AZIF0045P001C01CS-SA   I102 @S9S_MB_2U_LIB.S9S_MB_2U(SCH_1):PAGE34
    U1 AV79 UPI2_TX_DP11 SOCKET4677_AZIF0045P001C01CS-SA    I16 @S9S_MB_2U_LIB.S9S_MB_2U(SCH_1):PAGE65

UPI_CPU1_CPU0_P2P2_DP<12> @S9S_MB_2U_LIB.S9S_MB_2U(SCH_1):UPI_CPU1_CPU0_P2P2_DP(12)
    U2 AG82 UPI2_RX_DN11 SOCKET4677_AZIF0045P001C01CS-SA   I102 @S9S_MB_2U_LIB.S9S_MB_2U(SCH_1):PAGE34
    U1 AP81 UPI2_TX_DP12 SOCKET4677_AZIF0045P001C01CS-SA    I16 @S9S_MB_2U_LIB.S9S_MB_2U(SCH_1):PAGE65

UPI_CPU1_CPU0_P2P2_DP<13> @S9S_MB_2U_LIB.S9S_MB_2U(SCH_1):UPI_CPU1_CPU0_P2P2_DP(13)
    U2 AH81 UPI2_RX_DP10 SOCKET4677_AZIF0045P001C01CS-SA   I102 @S9S_MB_2U_LIB.S9S_MB_2U(SCH_1):PAGE34
    U1 AM83 UPI2_TX_DP13 SOCKET4677_AZIF0045P001C01CS-SA    I16 @S9S_MB_2U_LIB.S9S_MB_2U(SCH_1):PAGE65

UPI_CPU1_CPU0_P2P2_DP<14> @S9S_MB_2U_LIB.S9S_MB_2U(SCH_1):UPI_CPU1_CPU0_P2P2_DP(14)
    U2 AE82 UPI2_RX_DN9 SOCKET4677_AZIF0045P001C01CS-SA   I102 @S9S_MB_2U_LIB.S9S_MB_2U(SCH_1):PAGE34
    U1 AT81 UPI2_TX_DP14 SOCKET4677_AZIF0045P001C01CS-SA    I16 @S9S_MB_2U_LIB.S9S_MB_2U(SCH_1):PAGE65

UPI_CPU1_CPU0_P2P2_DP<15> @S9S_MB_2U_LIB.S9S_MB_2U(SCH_1):UPI_CPU1_CPU0_P2P2_DP(15)
    U2 AF79 UPI2_RX_DN8 SOCKET4677_AZIF0045P001C01CS-SA   I102 @S9S_MB_2U_LIB.S9S_MB_2U(SCH_1):PAGE34
    U1 AV83 UPI2_TX_DP15 SOCKET4677_AZIF0045P001C01CS-SA    I16 @S9S_MB_2U_LIB.S9S_MB_2U(SCH_1):PAGE65

UPI_CPU1_CPU0_P2P2_DP<16> @S9S_MB_2U_LIB.S9S_MB_2U(SCH_1):UPI_CPU1_CPU0_P2P2_DP(16)
    U2 AD81 UPI2_RX_DN7 SOCKET4677_AZIF0045P001C01CS-SA   I102 @S9S_MB_2U_LIB.S9S_MB_2U(SCH_1):PAGE34
    U1 AU82 UPI2_TX_DP16 SOCKET4677_AZIF0045P001C01CS-SA    I16 @S9S_MB_2U_LIB.S9S_MB_2U(SCH_1):PAGE65

UPI_CPU1_CPU0_P2P2_DP<17> @S9S_MB_2U_LIB.S9S_MB_2U(SCH_1):UPI_CPU1_CPU0_P2P2_DP(17)
    U2 AE80 UPI2_RX_DP6 SOCKET4677_AZIF0045P001C01CS-SA   I102 @S9S_MB_2U_LIB.S9S_MB_2U(SCH_1):PAGE34
    U1 BB81 UPI2_TX_DP17 SOCKET4677_AZIF0045P001C01CS-SA    I16 @S9S_MB_2U_LIB.S9S_MB_2U(SCH_1):PAGE65

UPI_CPU1_CPU0_P2P2_DP<18> @S9S_MB_2U_LIB.S9S_MB_2U(SCH_1):UPI_CPU1_CPU0_P2P2_DP(18)
    U2  K81 UPI2_RX_DP5 SOCKET4677_AZIF0045P001C01CS-SA   I102 @S9S_MB_2U_LIB.S9S_MB_2U(SCH_1):PAGE34
    U1 BA82 UPI2_TX_DP18 SOCKET4677_AZIF0045P001C01CS-SA    I16 @S9S_MB_2U_LIB.S9S_MB_2U(SCH_1):PAGE65

UPI_CPU1_CPU0_P2P2_DP<19> @S9S_MB_2U_LIB.S9S_MB_2U(SCH_1):UPI_CPU1_CPU0_P2P2_DP(19)
    U2  L82 UPI2_RX_DP4 SOCKET4677_AZIF0045P001C01CS-SA   I102 @S9S_MB_2U_LIB.S9S_MB_2U(SCH_1):PAGE34
    U1 BD83 UPI2_TX_DP19 SOCKET4677_AZIF0045P001C01CS-SA    I16 @S9S_MB_2U_LIB.S9S_MB_2U(SCH_1):PAGE65

UPI_CPU1_CPU0_P2P2_DP<1> @S9S_MB_2U_LIB.S9S_MB_2U(SCH_1):UPI_CPU1_CPU0_P2P2_DP(1)
    U2 BL74 UPI2_RX_DP22 SOCKET4677_AZIF0045P001C01CS-SA   I102 @S9S_MB_2U_LIB.S9S_MB_2U(SCH_1):PAGE34
    U1  F85 UPI2_TX_DP1 SOCKET4677_AZIF0045P001C01CS-SA    I16 @S9S_MB_2U_LIB.S9S_MB_2U(SCH_1):PAGE65

UPI_CPU1_CPU0_P2P2_DP<20> @S9S_MB_2U_LIB.S9S_MB_2U(SCH_1):UPI_CPU1_CPU0_P2P2_DP(20)
    U2  M79 UPI2_RX_DP3 SOCKET4677_AZIF0045P001C01CS-SA   I102 @S9S_MB_2U_LIB.S9S_MB_2U(SCH_1):PAGE34
    U1 BC80 UPI2_TX_DP20 SOCKET4677_AZIF0045P001C01CS-SA    I16 @S9S_MB_2U_LIB.S9S_MB_2U(SCH_1):PAGE65

UPI_CPU1_CPU0_P2P2_DP<21> @S9S_MB_2U_LIB.S9S_MB_2U(SCH_1):UPI_CPU1_CPU0_P2P2_DP(21)
    U2  H83 UPI2_RX_DP2 SOCKET4677_AZIF0045P001C01CS-SA   I102 @S9S_MB_2U_LIB.S9S_MB_2U(SCH_1):PAGE34
    U1 BG82 UPI2_TX_DP21 SOCKET4677_AZIF0045P001C01CS-SA    I16 @S9S_MB_2U_LIB.S9S_MB_2U(SCH_1):PAGE65

UPI_CPU1_CPU0_P2P2_DP<22> @S9S_MB_2U_LIB.S9S_MB_2U(SCH_1):UPI_CPU1_CPU0_P2P2_DP(22)
    U2  F81 UPI2_RX_DN1 SOCKET4677_AZIF0045P001C01CS-SA   I102 @S9S_MB_2U_LIB.S9S_MB_2U(SCH_1):PAGE34
    U1 BE80 UPI2_TX_DP22 SOCKET4677_AZIF0045P001C01CS-SA    I16 @S9S_MB_2U_LIB.S9S_MB_2U(SCH_1):PAGE65

UPI_CPU1_CPU0_P2P2_DP<23> @S9S_MB_2U_LIB.S9S_MB_2U(SCH_1):UPI_CPU1_CPU0_P2P2_DP(23)
    U2  G80 UPI2_RX_DP0 SOCKET4677_AZIF0045P001C01CS-SA   I102 @S9S_MB_2U_LIB.S9S_MB_2U(SCH_1):PAGE34
    U1 BN72 UPI2_TX_DP23 SOCKET4677_AZIF0045P001C01CS-SA    I16 @S9S_MB_2U_LIB.S9S_MB_2U(SCH_1):PAGE65

UPI_CPU1_CPU0_P2P2_DP<2> @S9S_MB_2U_LIB.S9S_MB_2U(SCH_1):UPI_CPU1_CPU0_P2P2_DP(2)
    U2 BN74 UPI2_RX_DN21 SOCKET4677_AZIF0045P001C01CS-SA   I102 @S9S_MB_2U_LIB.S9S_MB_2U(SCH_1):PAGE34
    U1  E88 UPI2_TX_DP2 SOCKET4677_AZIF0045P001C01CS-SA    I16 @S9S_MB_2U_LIB.S9S_MB_2U(SCH_1):PAGE65

UPI_CPU1_CPU0_P2P2_DP<3> @S9S_MB_2U_LIB.S9S_MB_2U(SCH_1):UPI_CPU1_CPU0_P2P2_DP(3)
    U2 BG74 UPI2_RX_DN20 SOCKET4677_AZIF0045P001C01CS-SA   I102 @S9S_MB_2U_LIB.S9S_MB_2U(SCH_1):PAGE34
    U1  H87 UPI2_TX_DP3 SOCKET4677_AZIF0045P001C01CS-SA    I16 @S9S_MB_2U_LIB.S9S_MB_2U(SCH_1):PAGE65

UPI_CPU1_CPU0_P2P2_DP<4> @S9S_MB_2U_LIB.S9S_MB_2U(SCH_1):UPI_CPU1_CPU0_P2P2_DP(4)
    U2 BL76 UPI2_RX_DN19 SOCKET4677_AZIF0045P001C01CS-SA   I102 @S9S_MB_2U_LIB.S9S_MB_2U(SCH_1):PAGE34
    U1  G86 UPI2_TX_DP4 SOCKET4677_AZIF0045P001C01CS-SA    I16 @S9S_MB_2U_LIB.S9S_MB_2U(SCH_1):PAGE65

UPI_CPU1_CPU0_P2P2_DP<5> @S9S_MB_2U_LIB.S9S_MB_2U(SCH_1):UPI_CPU1_CPU0_P2P2_DP(5)
    U2 BK77 UPI2_RX_DP18 SOCKET4677_AZIF0045P001C01CS-SA   I102 @S9S_MB_2U_LIB.S9S_MB_2U(SCH_1):PAGE34
    U1  T81 UPI2_TX_DP5 SOCKET4677_AZIF0045P001C01CS-SA    I16 @S9S_MB_2U_LIB.S9S_MB_2U(SCH_1):PAGE65

UPI_CPU1_CPU0_P2P2_DP<6> @S9S_MB_2U_LIB.S9S_MB_2U(SCH_1):UPI_CPU1_CPU0_P2P2_DP(6)
    U2 BG76 UPI2_RX_DP17 SOCKET4677_AZIF0045P001C01CS-SA   I102 @S9S_MB_2U_LIB.S9S_MB_2U(SCH_1):PAGE34
    U1  P83 UPI2_TX_DP6 SOCKET4677_AZIF0045P001C01CS-SA    I16 @S9S_MB_2U_LIB.S9S_MB_2U(SCH_1):PAGE65

UPI_CPU1_CPU0_P2P2_DP<7> @S9S_MB_2U_LIB.S9S_MB_2U(SCH_1):UPI_CPU1_CPU0_P2P2_DP(7)
    U2 AW74 UPI2_RX_DN16 SOCKET4677_AZIF0045P001C01CS-SA   I102 @S9S_MB_2U_LIB.S9S_MB_2U(SCH_1):PAGE34
    U1  V81 UPI2_TX_DP7 SOCKET4677_AZIF0045P001C01CS-SA    I16 @S9S_MB_2U_LIB.S9S_MB_2U(SCH_1):PAGE65

UPI_CPU1_CPU0_P2P2_DP<8> @S9S_MB_2U_LIB.S9S_MB_2U(SCH_1):UPI_CPU1_CPU0_P2P2_DP(8)
    U2 BB75 UPI2_RX_DN15 SOCKET4677_AZIF0045P001C01CS-SA   I102 @S9S_MB_2U_LIB.S9S_MB_2U(SCH_1):PAGE34
    U1  Y83 UPI2_TX_DP8 SOCKET4677_AZIF0045P001C01CS-SA    I16 @S9S_MB_2U_LIB.S9S_MB_2U(SCH_1):PAGE65

UPI_CPU1_CPU0_P2P2_DP<9> @S9S_MB_2U_LIB.S9S_MB_2U(SCH_1):UPI_CPU1_CPU0_P2P2_DP(9)
    U2 BA76 UPI2_RX_DP14 SOCKET4677_AZIF0045P001C01CS-SA   I102 @S9S_MB_2U_LIB.S9S_MB_2U(SCH_1):PAGE34
    U1  W82 UPI2_TX_DP9 SOCKET4677_AZIF0045P001C01CS-SA    I16 @S9S_MB_2U_LIB.S9S_MB_2U(SCH_1):PAGE65

USB2_0_DN @S9S_MB_2U_LIB.S9S_MB_2U(SCH_1):USB2_0_DN
    U4 AR42 USB2N_0 EMMITSBURG_REV0P9-GFNOCPU04302A    I11 @S9S_MB_2U_LIB.S9S_MB_2U(SCH_1):PAGE172
 R4474    1      A Q_RES_0402LF-0,5%,1/16W,CHIP,CA    I72 @S9S_MB_2U_LIB.S9S_MB_2U(SCH_1):PAGE194
 R4472    2      B Q_RES_0402LF-0,5%,1/16W,EMPTY,A    I78 @S9S_MB_2U_LIB.S9S_MB_2U(SCH_1):PAGE194

USB2_0_DP @S9S_MB_2U_LIB.S9S_MB_2U(SCH_1):USB2_0_DP
    U4 AR40 USB2P_0 EMMITSBURG_REV0P9-GFNOCPU04302A    I11 @S9S_MB_2U_LIB.S9S_MB_2U(SCH_1):PAGE172
 R4473    1      A Q_RES_0402LF-0,5%,1/16W,CHIP,CA    I73 @S9S_MB_2U_LIB.S9S_MB_2U(SCH_1):PAGE194
 R4471    2      B Q_RES_0402LF-0,5%,1/16W,EMPTY,A    I77 @S9S_MB_2U_LIB.S9S_MB_2U(SCH_1):PAGE194

USB2_3_DN @S9S_MB_2U_LIB.S9S_MB_2U(SCH_1):USB2_3_DN
    U4 AN42 USB2N_3 EMMITSBURG_REV0P9-GFNOCPU04302A    I11 @S9S_MB_2U_LIB.S9S_MB_2U(SCH_1):PAGE172
  R444    2      B Q_RES_0402LF-0,5%,1/16W,CHIP,CA   I118 @S9S_MB_2U_LIB.S9S_MB_2U(SCH_1):PAGE150

USB2_3_DP @S9S_MB_2U_LIB.S9S_MB_2U(SCH_1):USB2_3_DP
    U4 AN40 USB2P_3 EMMITSBURG_REV0P9-GFNOCPU04302A    I11 @S9S_MB_2U_LIB.S9S_MB_2U(SCH_1):PAGE172
  R445    2      B Q_RES_0402LF-0,5%,1/16W,CHIP,CA   I119 @S9S_MB_2U_LIB.S9S_MB_2U(SCH_1):PAGE150

USB2_5_DN @S9S_MB_2U_LIB.S9S_MB_2U(SCH_1):USB2_5_DN
    U4 AL43 USB2N_5 EMMITSBURG_REV0P9-GFNOCPU04302A    I11 @S9S_MB_2U_LIB.S9S_MB_2U(SCH_1):PAGE172
 R3177    2      B Q_RES_0402LF-0,5%,1/16W,CHIP,CA   I148 @S9S_MB_2U_LIB.S9S_MB_2U(SCH_1):PAGE146

USB2_5_DP @S9S_MB_2U_LIB.S9S_MB_2U(SCH_1):USB2_5_DP
    U4 AL41 USB2P_5 EMMITSBURG_REV0P9-GFNOCPU04302A    I11 @S9S_MB_2U_LIB.S9S_MB_2U(SCH_1):PAGE172
 R3178    2      B Q_RES_0402LF-0,5%,1/16W,CHIP,CA   I147 @S9S_MB_2U_LIB.S9S_MB_2U(SCH_1):PAGE146

USB2_5_R1_DN @S9S_MB_2U_LIB.S9S_MB_2U(SCH_1):USB2_5_R1_DN
 R3177    1      A Q_RES_0402LF-0,5%,1/16W,CHIP,CA   I148 @S9S_MB_2U_LIB.S9S_MB_2U(SCH_1):PAGE146
   J35  A68 USB_DATN SCONN168_ME1016810202011-SCONNA   I303 @S9S_MB_2U_LIB.S9S_MB_2U(SCH_1):PAGE146

USB2_5_R1_DP @S9S_MB_2U_LIB.S9S_MB_2U(SCH_1):USB2_5_R1_DP
 R3178    1      A Q_RES_0402LF-0,5%,1/16W,CHIP,CA   I147 @S9S_MB_2U_LIB.S9S_MB_2U(SCH_1):PAGE146
   J35  A69 USB_DATP SCONN168_ME1016810202011-SCONNA   I303 @S9S_MB_2U_LIB.S9S_MB_2U(SCH_1):PAGE146

USB2_7_DN @S9S_MB_2U_LIB.S9S_MB_2U(SCH_1):USB2_7_DN
    U4 AK42 USB2N_7 EMMITSBURG_REV0P9-GFNOCPU04302A    I11 @S9S_MB_2U_LIB.S9S_MB_2U(SCH_1):PAGE172
 R2257    2      B Q_RES_0402LF-0,5%,1/16W,EMPTY,A   I164 @S9S_MB_2U_LIB.S9S_MB_2U(SCH_1):PAGE227

USB2_7_DP @S9S_MB_2U_LIB.S9S_MB_2U(SCH_1):USB2_7_DP
    U4 AK40 USB2P_7 EMMITSBURG_REV0P9-GFNOCPU04302A    I11 @S9S_MB_2U_LIB.S9S_MB_2U(SCH_1):PAGE172
 R2256    2      B Q_RES_0402LF-0,5%,1/16W,EMPTY,A   I167 @S9S_MB_2U_LIB.S9S_MB_2U(SCH_1):PAGE227

USB2_7_R_DN @S9S_MB_2U_LIB.S9S_MB_2U(SCH_1):USB2_7_R_DN
 R2257    1      A Q_RES_0402LF-0,5%,1/16W,EMPTY,A   I164 @S9S_MB_2U_LIB.S9S_MB_2U(SCH_1):PAGE227
   J41  OB9 RBT_RXD0 SCONN168_ME1016810202011-SCONNA   I173 @S9S_MB_2U_LIB.S9S_MB_2U(SCH_1):PAGE227

USB2_7_R_DP @S9S_MB_2U_LIB.S9S_MB_2U(SCH_1):USB2_7_R_DP
 R2256    1      A Q_RES_0402LF-0,5%,1/16W,EMPTY,A   I167 @S9S_MB_2U_LIB.S9S_MB_2U(SCH_1):PAGE227
   J41  OB8 RBT_RXD1 SCONN168_ME1016810202011-SCONNA   I173 @S9S_MB_2U_LIB.S9S_MB_2U(SCH_1):PAGE227

USB2_8_DN @S9S_MB_2U_LIB.S9S_MB_2U(SCH_1):USB2_8_DN
    U4 AW42 USB2N_8 EMMITSBURG_REV0P9-GFNOCPU04302A    I11 @S9S_MB_2U_LIB.S9S_MB_2U(SCH_1):PAGE172
   J41  B54 PETP11 SCONN168_ME1016810202011-SCONNA   I173 @S9S_MB_2U_LIB.S9S_MB_2U(SCH_1):PAGE227

USB2_8_DP @S9S_MB_2U_LIB.S9S_MB_2U(SCH_1):USB2_8_DP
    U4 AW40 USB2P_8 EMMITSBURG_REV0P9-GFNOCPU04302A    I11 @S9S_MB_2U_LIB.S9S_MB_2U(SCH_1):PAGE172
   J41  B53 PETN11 SCONN168_ME1016810202011-SCONNA   I173 @S9S_MB_2U_LIB.S9S_MB_2U(SCH_1):PAGE227

USB2_HOST_BMC_B_BUF_DN @S9S_MB_2U_LIB.S9S_MB_2U(SCH_1):USB2_HOST_BMC_B_BUF_DN
 R2791    2      B Q_RES_0402LF-0,5%,1/16W,EMPTY,A    I97 @S9S_MB_2U_LIB.S9S_MB_2U(SCH_1):PAGE155
 R2789    1      A Q_RES_0402LF-0,5%,1/16W,EMPTY,A    I98 @S9S_MB_2U_LIB.S9S_MB_2U(SCH_1):PAGE155
 R4483    1      A Q_RES_0402LF-49.9,1%,1/16W,EMPA   I206 @S9S_MB_2U_LIB.S9S_MB_2U(SCH_1):PAGE155

USB2_HOST_BMC_B_BUF_DP @S9S_MB_2U_LIB.S9S_MB_2U(SCH_1):USB2_HOST_BMC_B_BUF_DP
 R2790    2      B Q_RES_0402LF-0,5%,1/16W,EMPTY,A    I96 @S9S_MB_2U_LIB.S9S_MB_2U(SCH_1):PAGE155
 R2788    1      A Q_RES_0402LF-0,5%,1/16W,EMPTY,A    I99 @S9S_MB_2U_LIB.S9S_MB_2U(SCH_1):PAGE155
 R4482    1      A Q_RES_0402LF-49.9,1%,1/16W,EMPA   I208 @S9S_MB_2U_LIB.S9S_MB_2U(SCH_1):PAGE155

USB2_HOST_BMC_B_DN @S9S_MB_2U_LIB.S9S_MB_2U(SCH_1):USB2_HOST_BMC_B_DN
 R2791    1      A Q_RES_0402LF-0,5%,1/16W,EMPTY,A    I97 @S9S_MB_2U_LIB.S9S_MB_2U(SCH_1):PAGE155
 R3652    2      B Q_RES_0402LF-0,5%,1/16W,CHIP,CA   I137 @S9S_MB_2U_LIB.S9S_MB_2U(SCH_1):PAGE155
 R4420    1      A Q_RES_0402LF-49.9,1%,1/16W,EMPA   I202 @S9S_MB_2U_LIB.S9S_MB_2U(SCH_1):PAGE155
   J41  B51 PETP10 SCONN168_ME1016810202011-SCONNA   I173 @S9S_MB_2U_LIB.S9S_MB_2U(SCH_1):PAGE227

USB2_HOST_BMC_B_DP @S9S_MB_2U_LIB.S9S_MB_2U(SCH_1):USB2_HOST_BMC_B_DP
 R2790    1      A Q_RES_0402LF-0,5%,1/16W,EMPTY,A    I96 @S9S_MB_2U_LIB.S9S_MB_2U(SCH_1):PAGE155
 R3651    2      B Q_RES_0402LF-0,5%,1/16W,CHIP,CA   I138 @S9S_MB_2U_LIB.S9S_MB_2U(SCH_1):PAGE155
 R4419    1      A Q_RES_0402LF-49.9,1%,1/16W,EMPA   I203 @S9S_MB_2U_LIB.S9S_MB_2U(SCH_1):PAGE155
   J41  B50 PETN10 SCONN168_ME1016810202011-SCONNA   I173 @S9S_MB_2U_LIB.S9S_MB_2U(SCH_1):PAGE227

USB2_HOST_PCH_0_DN @S9S_MB_2U_LIB.S9S_MB_2U(SCH_1):USB2_HOST_PCH_0_DN
 R4461    1      A Q_RES_0402LF-0,5%,1/16W,CHIP,CA    I19 @S9S_MB_2U_LIB.S9S_MB_2U(SCH_1):PAGE194
 R4474    2      B Q_RES_0402LF-0,5%,1/16W,CHIP,CA    I72 @S9S_MB_2U_LIB.S9S_MB_2U(SCH_1):PAGE194
 R4487    1      A Q_RES_0402LF-49.9,1%,1/16W,EMPA    I88 @S9S_MB_2U_LIB.S9S_MB_2U(SCH_1):PAGE194

USB2_HOST_PCH_0_DP @S9S_MB_2U_LIB.S9S_MB_2U(SCH_1):USB2_HOST_PCH_0_DP
 R4460    1      A Q_RES_0402LF-0,5%,1/16W,CHIP,CA    I18 @S9S_MB_2U_LIB.S9S_MB_2U(SCH_1):PAGE194
 R4473    2      B Q_RES_0402LF-0,5%,1/16W,CHIP,CA    I73 @S9S_MB_2U_LIB.S9S_MB_2U(SCH_1):PAGE194
 R4486    1      A Q_RES_0402LF-49.9,1%,1/16W,EMPA    I90 @S9S_MB_2U_LIB.S9S_MB_2U(SCH_1):PAGE194

USB2_HUB_2_BUF_EXT_DN @S9S_MB_2U_LIB.S9S_MB_2U(SCH_1):USB2_HUB_2_BUF_EXT_DN
 R4468    2      B Q_RES_0402LF-0,5%,1/16W,CHIP,CA    I60 @S9S_MB_2U_LIB.S9S_MB_2U(SCH_1):PAGE194
   J41  B57 PETP12 SCONN168_ME1016810202011-SCONNA   I173 @S9S_MB_2U_LIB.S9S_MB_2U(SCH_1):PAGE227

USB2_HUB_2_BUF_EXT_DP @S9S_MB_2U_LIB.S9S_MB_2U(SCH_1):USB2_HUB_2_BUF_EXT_DP
 R4467    2      B Q_RES_0402LF-0,5%,1/16W,CHIP,CA    I61 @S9S_MB_2U_LIB.S9S_MB_2U(SCH_1):PAGE194
   J41  B56 PETN12 SCONN168_ME1016810202011-SCONNA   I173 @S9S_MB_2U_LIB.S9S_MB_2U(SCH_1):PAGE227

USB2_HUB_2_BUF_EXT_R_DN @S9S_MB_2U_LIB.S9S_MB_2U(SCH_1):USB2_HUB_2_BUF_EXT_R_DN
 R4455    2      B Q_RES_0402LF-0,5%,1/16W,EMPTY,A    I16 @S9S_MB_2U_LIB.S9S_MB_2U(SCH_1):PAGE194
 R4461    2      B Q_RES_0402LF-0,5%,1/16W,CHIP,CA    I19 @S9S_MB_2U_LIB.S9S_MB_2U(SCH_1):PAGE194
  U312    1    D1M TUSB211IRWBR-TUSB211IRWBR,SMLFA    I20 @S9S_MB_2U_LIB.S9S_MB_2U(SCH_1):PAGE194
  U312    8    D2M TUSB211IRWBR-TUSB211IRWBR,SMLFA    I20 @S9S_MB_2U_LIB.S9S_MB_2U(SCH_1):PAGE194
 R4468    1      A Q_RES_0402LF-0,5%,1/16W,CHIP,CA    I60 @S9S_MB_2U_LIB.S9S_MB_2U(SCH_1):PAGE194

USB2_HUB_2_BUF_EXT_R_DP @S9S_MB_2U_LIB.S9S_MB_2U(SCH_1):USB2_HUB_2_BUF_EXT_R_DP
 R4454    2      B Q_RES_0402LF-0,5%,1/16W,EMPTY,A    I17 @S9S_MB_2U_LIB.S9S_MB_2U(SCH_1):PAGE194
 R4460    2      B Q_RES_0402LF-0,5%,1/16W,CHIP,CA    I18 @S9S_MB_2U_LIB.S9S_MB_2U(SCH_1):PAGE194
  U312    2    D1P TUSB211IRWBR-TUSB211IRWBR,SMLFA    I20 @S9S_MB_2U_LIB.S9S_MB_2U(SCH_1):PAGE194
  U312    7    D2P TUSB211IRWBR-TUSB211IRWBR,SMLFA    I20 @S9S_MB_2U_LIB.S9S_MB_2U(SCH_1):PAGE194
 R4467    1      A Q_RES_0402LF-0,5%,1/16W,CHIP,CA    I61 @S9S_MB_2U_LIB.S9S_MB_2U(SCH_1):PAGE194

USB2_HUB_2_EXT_DN @S9S_MB_2U_LIB.S9S_MB_2U(SCH_1):USB2_HUB_2_EXT_DN
 R4455    1      A Q_RES_0402LF-0,5%,1/16W,EMPTY,A    I16 @S9S_MB_2U_LIB.S9S_MB_2U(SCH_1):PAGE194
  U313    3    DM1 GL852GOHY60-GL852G-OHY60,SMLF,B    I40 @S9S_MB_2U_LIB.S9S_MB_2U(SCH_1):PAGE194

USB2_HUB_2_EXT_DP @S9S_MB_2U_LIB.S9S_MB_2U(SCH_1):USB2_HUB_2_EXT_DP
 R4454    1      A Q_RES_0402LF-0,5%,1/16W,EMPTY,A    I17 @S9S_MB_2U_LIB.S9S_MB_2U(SCH_1):PAGE194
  U313    4    DP1 GL852GOHY60-GL852G-OHY60,SMLF,B    I40 @S9S_MB_2U_LIB.S9S_MB_2U(SCH_1):PAGE194

USB2_HUB_BUF_SWB_DN @S9S_MB_2U_LIB.S9S_MB_2U(SCH_1):USB2_HUB_BUF_SWB_DN
  J112   R1     R1 CONN160_10131762101LF-CONN160_A    I76 @S9S_MB_2U_LIB.S9S_MB_2U(SCH_1):PAGE149
 R5236    2      B Q_RES_0402LF-0,5%,1/16W,CHIP,CA    I90 @S9S_MB_2U_LIB.S9S_MB_2U(SCH_1):PAGE155

USB2_HUB_BUF_SWB_DP @S9S_MB_2U_LIB.S9S_MB_2U(SCH_1):USB2_HUB_BUF_SWB_DP
  J112   S1     S1 CONN160_10131762101LF-CONN160_A    I76 @S9S_MB_2U_LIB.S9S_MB_2U(SCH_1):PAGE149
 R5234    2      B Q_RES_0402LF-0,5%,1/16W,CHIP,CA    I91 @S9S_MB_2U_LIB.S9S_MB_2U(SCH_1):PAGE155

USB2_HUB_BUF_SWB_R_DN @S9S_MB_2U_LIB.S9S_MB_2U(SCH_1):USB2_HUB_BUF_SWB_R_DN
 R2787    2      B Q_RES_0402LF-0,5%,1/16W,CHIP,CA    I78 @S9S_MB_2U_LIB.S9S_MB_2U(SCH_1):PAGE155
 U5201    1    D1M TUSB211IRWBR-TUSB211IRWBR,SMLFA    I84 @S9S_MB_2U_LIB.S9S_MB_2U(SCH_1):PAGE155
 U5201    8    D2M TUSB211IRWBR-TUSB211IRWBR,SMLFA    I84 @S9S_MB_2U_LIB.S9S_MB_2U(SCH_1):PAGE155
 R5236    1      A Q_RES_0402LF-0,5%,1/16W,CHIP,CA    I90 @S9S_MB_2U_LIB.S9S_MB_2U(SCH_1):PAGE155
 R2789    2      B Q_RES_0402LF-0,5%,1/16W,EMPTY,A    I98 @S9S_MB_2U_LIB.S9S_MB_2U(SCH_1):PAGE155

USB2_HUB_BUF_SWB_R_DP @S9S_MB_2U_LIB.S9S_MB_2U(SCH_1):USB2_HUB_BUF_SWB_R_DP
 R2786    2      B Q_RES_0402LF-0,5%,1/16W,CHIP,CA    I79 @S9S_MB_2U_LIB.S9S_MB_2U(SCH_1):PAGE155
 U5201    2    D1P TUSB211IRWBR-TUSB211IRWBR,SMLFA    I84 @S9S_MB_2U_LIB.S9S_MB_2U(SCH_1):PAGE155
 U5201    7    D2P TUSB211IRWBR-TUSB211IRWBR,SMLFA    I84 @S9S_MB_2U_LIB.S9S_MB_2U(SCH_1):PAGE155
 R5234    1      A Q_RES_0402LF-0,5%,1/16W,CHIP,CA    I91 @S9S_MB_2U_LIB.S9S_MB_2U(SCH_1):PAGE155
 R2788    2      B Q_RES_0402LF-0,5%,1/16W,EMPTY,A    I99 @S9S_MB_2U_LIB.S9S_MB_2U(SCH_1):PAGE155

USB2_HUB_SWB_DN @S9S_MB_2U_LIB.S9S_MB_2U(SCH_1):USB2_HUB_SWB_DN
 R2787    1      A Q_RES_0402LF-0,5%,1/16W,CHIP,CA    I78 @S9S_MB_2U_LIB.S9S_MB_2U(SCH_1):PAGE155
  U268    3    DM1 GL852GOHY60-GL852G-OHY60,SMLF,A   I100 @S9S_MB_2U_LIB.S9S_MB_2U(SCH_1):PAGE155

USB2_HUB_SWB_DP @S9S_MB_2U_LIB.S9S_MB_2U(SCH_1):USB2_HUB_SWB_DP
 R2786    1      A Q_RES_0402LF-0,5%,1/16W,CHIP,CA    I79 @S9S_MB_2U_LIB.S9S_MB_2U(SCH_1):PAGE155
  U268    4    DP1 GL852GOHY60-GL852G-OHY60,SMLF,A   I100 @S9S_MB_2U_LIB.S9S_MB_2U(SCH_1):PAGE155

USB2_P0_R_DN @S9S_MB_2U_LIB.S9S_MB_2U(SCH_1):USB2_P0_R_DN
  U268    1    DM0 GL852GOHY60-GL852G-OHY60,SMLF,A   I100 @S9S_MB_2U_LIB.S9S_MB_2U(SCH_1):PAGE155
 R3652    1      A Q_RES_0402LF-0,5%,1/16W,CHIP,CA   I137 @S9S_MB_2U_LIB.S9S_MB_2U(SCH_1):PAGE155

USB2_P0_R_DP @S9S_MB_2U_LIB.S9S_MB_2U(SCH_1):USB2_P0_R_DP
  U268    2    DP0 GL852GOHY60-GL852G-OHY60,SMLF,A   I100 @S9S_MB_2U_LIB.S9S_MB_2U(SCH_1):PAGE155
 R3651    1      A Q_RES_0402LF-0,5%,1/16W,CHIP,CA   I138 @S9S_MB_2U_LIB.S9S_MB_2U(SCH_1):PAGE155

USB2_PCH_0_R_DN @S9S_MB_2U_LIB.S9S_MB_2U(SCH_1):USB2_PCH_0_R_DN
  U313    1    DM0 GL852GOHY60-GL852G-OHY60,SMLF,B    I40 @S9S_MB_2U_LIB.S9S_MB_2U(SCH_1):PAGE194
 R4472    1      A Q_RES_0402LF-0,5%,1/16W,EMPTY,A    I78 @S9S_MB_2U_LIB.S9S_MB_2U(SCH_1):PAGE194

USB2_PCH_0_R_DP @S9S_MB_2U_LIB.S9S_MB_2U(SCH_1):USB2_PCH_0_R_DP
  U313    2    DP0 GL852GOHY60-GL852G-OHY60,SMLF,B    I40 @S9S_MB_2U_LIB.S9S_MB_2U(SCH_1):PAGE194
 R4471    1      A Q_RES_0402LF-0,5%,1/16W,EMPTY,A    I77 @S9S_MB_2U_LIB.S9S_MB_2U(SCH_1):PAGE194

USB3_PCH_RX_BUF_C_DN<4> @S9S_MB_2U_LIB.S9S_MB_2U(SCH_1):USB3_PCH_RX_BUF_C_DN(4)
  U309   11    BON PI3EQX1002EZREX-PI3EQX1002EZREA    I43 @S9S_MB_2U_LIB.S9S_MB_2U(SCH_1):PAGE162
 C2292    1      A Q_CAP_C0201-0.1UF,6.3V,10%,X6SA    I54 @S9S_MB_2U_LIB.S9S_MB_2U(SCH_1):PAGE162

USB3_PCH_RX_BUF_C_DP<4> @S9S_MB_2U_LIB.S9S_MB_2U(SCH_1):USB3_PCH_RX_BUF_C_DP(4)
  U309   12    BOP PI3EQX1002EZREX-PI3EQX1002EZREA    I43 @S9S_MB_2U_LIB.S9S_MB_2U(SCH_1):PAGE162
 C2291    1      A Q_CAP_C0201-0.1UF,6.3V,10%,X6SA    I55 @S9S_MB_2U_LIB.S9S_MB_2U(SCH_1):PAGE162

USB3_PCH_RX_BUF_DN<4> @S9S_MB_2U_LIB.S9S_MB_2U(SCH_1):USB3_PCH_RX_BUF_DN(4)
 C2292    2      B Q_CAP_C0201-0.1UF,6.3V,10%,X6SA    I54 @S9S_MB_2U_LIB.S9S_MB_2U(SCH_1):PAGE162
    U4  R40 SATA_9_PCIE3_9_USB3_9_RXN EMMITSBURG_REV0P9-GFNOCPU04302A   I110 @S9S_MB_2U_LIB.S9S_MB_2U(SCH_1):PAGE173

USB3_PCH_RX_BUF_DP<4> @S9S_MB_2U_LIB.S9S_MB_2U(SCH_1):USB3_PCH_RX_BUF_DP(4)
 C2291    2      B Q_CAP_C0201-0.1UF,6.3V,10%,X6SA    I55 @S9S_MB_2U_LIB.S9S_MB_2U(SCH_1):PAGE162
    U4  R42 SATA_9_PCIE3_9_USB3_9_RXP EMMITSBURG_REV0P9-GFNOCPU04302A   I110 @S9S_MB_2U_LIB.S9S_MB_2U(SCH_1):PAGE173

USB3_PCH_RX_C_DN<4> @S9S_MB_2U_LIB.S9S_MB_2U(SCH_1):USB3_PCH_RX_C_DN(4)
 C2350    2      2 Q_CAP_DIFFBUS_C0402-DIFF BUS_0A    I25 @S9S_MB_2U_LIB.S9S_MB_2U(SCH_1):PAGE162
  U309   19    BIN PI3EQX1002EZREX-PI3EQX1002EZREA    I43 @S9S_MB_2U_LIB.S9S_MB_2U(SCH_1):PAGE162

USB3_PCH_RX_C_DP<4> @S9S_MB_2U_LIB.S9S_MB_2U(SCH_1):USB3_PCH_RX_C_DP(4)
 C2349    2      2 Q_CAP_DIFFBUS_C0402-DIFF BUS_0A    I26 @S9S_MB_2U_LIB.S9S_MB_2U(SCH_1):PAGE162
  U309   18    BIP PI3EQX1002EZREX-PI3EQX1002EZREA    I43 @S9S_MB_2U_LIB.S9S_MB_2U(SCH_1):PAGE162

USB3_PCH_RX_DN<4> @S9S_MB_2U_LIB.S9S_MB_2U(SCH_1):USB3_PCH_RX_DN(4)
 R4637    1      A Q_RES_0402LF-200K,1%,1/16W,CHIA    I24 @S9S_MB_2U_LIB.S9S_MB_2U(SCH_1):PAGE162
 C2350    1      1 Q_CAP_DIFFBUS_C0402-DIFF BUS_0A    I25 @S9S_MB_2U_LIB.S9S_MB_2U(SCH_1):PAGE162
   J41  A60 PERP13 SCONN168_ME1016810202011-SCONNA   I173 @S9S_MB_2U_LIB.S9S_MB_2U(SCH_1):PAGE227

USB3_PCH_RX_DP<4> @S9S_MB_2U_LIB.S9S_MB_2U(SCH_1):USB3_PCH_RX_DP(4)
 R4636    1      A Q_RES_0402LF-200K,1%,1/16W,CHIA    I23 @S9S_MB_2U_LIB.S9S_MB_2U(SCH_1):PAGE162
 C2349    1      1 Q_CAP_DIFFBUS_C0402-DIFF BUS_0A    I26 @S9S_MB_2U_LIB.S9S_MB_2U(SCH_1):PAGE162
   J41  A59 PERN13 SCONN168_ME1016810202011-SCONNA   I173 @S9S_MB_2U_LIB.S9S_MB_2U(SCH_1):PAGE227

USB3_PCH_TX_BUF_C_DN<4> @S9S_MB_2U_LIB.S9S_MB_2U(SCH_1):USB3_PCH_TX_BUF_C_DN(4)
 C2290    2      B Q_CAP_C0201-0.1UF,6.3V,10%,X6SA    I56 @S9S_MB_2U_LIB.S9S_MB_2U(SCH_1):PAGE162
   J41  B60 PETP13 SCONN168_ME1016810202011-SCONNA   I173 @S9S_MB_2U_LIB.S9S_MB_2U(SCH_1):PAGE227

USB3_PCH_TX_BUF_C_DP<4> @S9S_MB_2U_LIB.S9S_MB_2U(SCH_1):USB3_PCH_TX_BUF_C_DP(4)
 C2289    2      B Q_CAP_C0201-0.1UF,6.3V,10%,X6SA    I57 @S9S_MB_2U_LIB.S9S_MB_2U(SCH_1):PAGE162
   J41  B59 PETN13 SCONN168_ME1016810202011-SCONNA   I173 @S9S_MB_2U_LIB.S9S_MB_2U(SCH_1):PAGE227

USB3_PCH_TX_BUF_DN<4> @S9S_MB_2U_LIB.S9S_MB_2U(SCH_1):USB3_PCH_TX_BUF_DN(4)
  U309   23    AON PI3EQX1002EZREX-PI3EQX1002EZREA    I43 @S9S_MB_2U_LIB.S9S_MB_2U(SCH_1):PAGE162
 C2290    1      A Q_CAP_C0201-0.1UF,6.3V,10%,X6SA    I56 @S9S_MB_2U_LIB.S9S_MB_2U(SCH_1):PAGE162

USB3_PCH_TX_BUF_DP<4> @S9S_MB_2U_LIB.S9S_MB_2U(SCH_1):USB3_PCH_TX_BUF_DP(4)
  U309   24    AOP PI3EQX1002EZREX-PI3EQX1002EZREA    I43 @S9S_MB_2U_LIB.S9S_MB_2U(SCH_1):PAGE162
 C2289    1      A Q_CAP_C0201-0.1UF,6.3V,10%,X6SA    I57 @S9S_MB_2U_LIB.S9S_MB_2U(SCH_1):PAGE162

USB3_PCH_TX_C_DN<4> @S9S_MB_2U_LIB.S9S_MB_2U(SCH_1):USB3_PCH_TX_C_DN(4)
  U309    7    AIN PI3EQX1002EZREX-PI3EQX1002EZREA    I43 @S9S_MB_2U_LIB.S9S_MB_2U(SCH_1):PAGE162
 C1097    2      B Q_CAP_C0201-0.1UF,6.3V,10%,X6SA    I78 @S9S_MB_2U_LIB.S9S_MB_2U(SCH_1):PAGE173

USB3_PCH_TX_C_DP<4> @S9S_MB_2U_LIB.S9S_MB_2U(SCH_1):USB3_PCH_TX_C_DP(4)
  U309    6    AIP PI3EQX1002EZREX-PI3EQX1002EZREA    I43 @S9S_MB_2U_LIB.S9S_MB_2U(SCH_1):PAGE162
 C1096    2      B Q_CAP_C0201-0.1UF,6.3V,10%,X6SA    I80 @S9S_MB_2U_LIB.S9S_MB_2U(SCH_1):PAGE173

USB3_PCH_TX_DN<4> @S9S_MB_2U_LIB.S9S_MB_2U(SCH_1):USB3_PCH_TX_DN(4)
 C1097    1      A Q_CAP_C0201-0.1UF,6.3V,10%,X6SA    I78 @S9S_MB_2U_LIB.S9S_MB_2U(SCH_1):PAGE173
    U4 AE32 SATA_9_PCIE3_9_USB3_9_TXN EMMITSBURG_REV0P9-GFNOCPU04302A   I110 @S9S_MB_2U_LIB.S9S_MB_2U(SCH_1):PAGE173

USB3_PCH_TX_DP<4> @S9S_MB_2U_LIB.S9S_MB_2U(SCH_1):USB3_PCH_TX_DP(4)
 C1096    1      A Q_CAP_C0201-0.1UF,6.3V,10%,X6SA    I80 @S9S_MB_2U_LIB.S9S_MB_2U(SCH_1):PAGE173
    U4 AG32 SATA_9_PCIE3_9_USB3_9_TXP EMMITSBURG_REV0P9-GFNOCPU04302A   I110 @S9S_MB_2U_LIB.S9S_MB_2U(SCH_1):PAGE173

USB_HUB_2_DVDD @S9S_MB_2U_LIB.S9S_MB_2U(SCH_1):USB_HUB_2_DVDD
  U313   21   DVDD GL852GOHY60-GL852G-OHY60,SMLF,B    I40 @S9S_MB_2U_LIB.S9S_MB_2U(SCH_1):PAGE194
 R4462    2      B Q_RES_0402LF-0,5%,1/16W,EMPTY,A    I50 @S9S_MB_2U_LIB.S9S_MB_2U(SCH_1):PAGE194

USB_HUB_2_OVCUR1 @S9S_MB_2U_LIB.S9S_MB_2U(SCH_1):USB_HUB_2_OVCUR1
 R4456    2      B Q_RES_0402LF-10K,1%,1/16W,EMPTA    I25 @S9S_MB_2U_LIB.S9S_MB_2U(SCH_1):PAGE194
  U313   25 OVCUR1#||SMC GL852GOHY60-GL852G-OHY60,SMLF,B    I40 @S9S_MB_2U_LIB.S9S_MB_2U(SCH_1):PAGE194

USB_HUB_2_OVCUR2 @S9S_MB_2U_LIB.S9S_MB_2U(SCH_1):USB_HUB_2_OVCUR2
 R4457    2      B Q_RES_0402LF-10K,1%,1/16W,EMPTA    I24 @S9S_MB_2U_LIB.S9S_MB_2U(SCH_1):PAGE194
  U313   24 OVCUR2#||SMD GL852GOHY60-GL852G-OHY60,SMLF,B    I40 @S9S_MB_2U_LIB.S9S_MB_2U(SCH_1):PAGE194

USB_HUB_2_OVCUR3 @S9S_MB_2U_LIB.S9S_MB_2U(SCH_1):USB_HUB_2_OVCUR3
 R4458    2      B Q_RES_0402LF-10K,1%,1/16W,EMPTA    I23 @S9S_MB_2U_LIB.S9S_MB_2U(SCH_1):PAGE194
  U313   20 OVCUR3# GL852GOHY60-GL852G-OHY60,SMLF,B    I40 @S9S_MB_2U_LIB.S9S_MB_2U(SCH_1):PAGE194

USB_HUB_2_OVCUR4 @S9S_MB_2U_LIB.S9S_MB_2U(SCH_1):USB_HUB_2_OVCUR4
 R4459    2      B Q_RES_0402LF-10K,1%,1/16W,EMPTA    I22 @S9S_MB_2U_LIB.S9S_MB_2U(SCH_1):PAGE194
  U313   19 OVCUR4# GL852GOHY60-GL852G-OHY60,SMLF,B    I40 @S9S_MB_2U_LIB.S9S_MB_2U(SCH_1):PAGE194

USB_HUB_2_PGANG @S9S_MB_2U_LIB.S9S_MB_2U(SCH_1):USB_HUB_2_PGANG
 R4464    1      A Q_RES_0402LF-100K,1%,1/16W,EMPA    I38 @S9S_MB_2U_LIB.S9S_MB_2U(SCH_1):PAGE194
  U313   23  PGANG GL852GOHY60-GL852G-OHY60,SMLF,B    I40 @S9S_MB_2U_LIB.S9S_MB_2U(SCH_1):PAGE194

USB_HUB_2_PSELF @S9S_MB_2U_LIB.S9S_MB_2U(SCH_1):USB_HUB_2_PSELF
 R4449    1      A Q_RES_0402LF-10K,1%,1/16W,EMPTA     I8 @S9S_MB_2U_LIB.S9S_MB_2U(SCH_1):PAGE194
 R4448    2      B Q_RES_0402LF-10K,1%,1/16W,EMPTA     I9 @S9S_MB_2U_LIB.S9S_MB_2U(SCH_1):PAGE194
  U313   22  PSELF GL852GOHY60-GL852G-OHY60,SMLF,B    I40 @S9S_MB_2U_LIB.S9S_MB_2U(SCH_1):PAGE194

USB_HUB_2_RREF @S9S_MB_2U_LIB.S9S_MB_2U(SCH_1):USB_HUB_2_RREF
 R4463    1      A Q_RES_0402LF-680,1%,1/16W,EMPTA    I37 @S9S_MB_2U_LIB.S9S_MB_2U(SCH_1):PAGE194
  U313    8   RREF GL852GOHY60-GL852G-OHY60,SMLF,B    I40 @S9S_MB_2U_LIB.S9S_MB_2U(SCH_1):PAGE194

USB_HUB_2_TEST @S9S_MB_2U_LIB.S9S_MB_2U(SCH_1):USB_HUB_2_TEST
  U313   18 TEST||SCL GL852GOHY60-GL852G-OHY60,SMLF,B    I40 @S9S_MB_2U_LIB.S9S_MB_2U(SCH_1):PAGE194
 R4466    1      A Q_RES_0402LF-0,5%,1/16W,EMPTY,A    I75 @S9S_MB_2U_LIB.S9S_MB_2U(SCH_1):PAGE194

USB_HUB_2_XTAL_IN @S9S_MB_2U_LIB.S9S_MB_2U(SCH_1):USB_HUB_2_XTAL_IN
  U313   10     X1 GL852GOHY60-GL852G-OHY60,SMLF,B    I40 @S9S_MB_2U_LIB.S9S_MB_2U(SCH_1):PAGE194
 C2326    1      A Q_CAP_C0402-12PF,50V,5%,EMPTY,A    I81 @S9S_MB_2U_LIB.S9S_MB_2U(SCH_1):PAGE194
    Y9    1     X1 Q_XTAL_4P_13BI_24GND-12MHZ,SMLB    I83 @S9S_MB_2U_LIB.S9S_MB_2U(SCH_1):PAGE194

USB_HUB_2_XTAL_OUT @S9S_MB_2U_LIB.S9S_MB_2U(SCH_1):USB_HUB_2_XTAL_OUT
  U313   11     X2 GL852GOHY60-GL852G-OHY60,SMLF,B    I40 @S9S_MB_2U_LIB.S9S_MB_2U(SCH_1):PAGE194
    Y9    3     X2 Q_XTAL_4P_13BI_24GND-12MHZ,SMLB    I83 @S9S_MB_2U_LIB.S9S_MB_2U(SCH_1):PAGE194
 C2327    1      A Q_CAP_C0402-12PF,50V,5%,EMPTY,A    I85 @S9S_MB_2U_LIB.S9S_MB_2U(SCH_1):PAGE194

USB_HUB_DVDD @S9S_MB_2U_LIB.S9S_MB_2U(SCH_1):USB_HUB_DVDD
  U268   21   DVDD GL852GOHY60-GL852G-OHY60,SMLF,A   I100 @S9S_MB_2U_LIB.S9S_MB_2U(SCH_1):PAGE155
 R3662    2      B Q_RES_0402LF-0,5%,1/16W,CHIP,CA   I167 @S9S_MB_2U_LIB.S9S_MB_2U(SCH_1):PAGE155

USB_HUB_OVCUR1 @S9S_MB_2U_LIB.S9S_MB_2U(SCH_1):USB_HUB_OVCUR1
  U268   25 OVCUR1#||SMC GL852GOHY60-GL852G-OHY60,SMLF,A   I100 @S9S_MB_2U_LIB.S9S_MB_2U(SCH_1):PAGE155
 R3656    2      B Q_RES_0402LF-10K,1%,1/16W,EMPTA   I194 @S9S_MB_2U_LIB.S9S_MB_2U(SCH_1):PAGE155

USB_HUB_OVCUR2 @S9S_MB_2U_LIB.S9S_MB_2U(SCH_1):USB_HUB_OVCUR2
  U268   24 OVCUR2#||SMD GL852GOHY60-GL852G-OHY60,SMLF,A   I100 @S9S_MB_2U_LIB.S9S_MB_2U(SCH_1):PAGE155
 R3657    2      B Q_RES_0402LF-10K,1%,1/16W,EMPTA   I195 @S9S_MB_2U_LIB.S9S_MB_2U(SCH_1):PAGE155

USB_HUB_OVCUR3 @S9S_MB_2U_LIB.S9S_MB_2U(SCH_1):USB_HUB_OVCUR3
  U268   20 OVCUR3# GL852GOHY60-GL852G-OHY60,SMLF,A   I100 @S9S_MB_2U_LIB.S9S_MB_2U(SCH_1):PAGE155
 R3658    2      B Q_RES_0402LF-10K,1%,1/16W,EMPTA   I196 @S9S_MB_2U_LIB.S9S_MB_2U(SCH_1):PAGE155

USB_HUB_OVCUR4 @S9S_MB_2U_LIB.S9S_MB_2U(SCH_1):USB_HUB_OVCUR4
  U268   19 OVCUR4# GL852GOHY60-GL852G-OHY60,SMLF,A   I100 @S9S_MB_2U_LIB.S9S_MB_2U(SCH_1):PAGE155
 R3659    2      B Q_RES_0402LF-10K,1%,1/16W,EMPTA   I198 @S9S_MB_2U_LIB.S9S_MB_2U(SCH_1):PAGE155

USB_HUB_PGANG @S9S_MB_2U_LIB.S9S_MB_2U(SCH_1):USB_HUB_PGANG
  U268   23  PGANG GL852GOHY60-GL852G-OHY60,SMLF,A   I100 @S9S_MB_2U_LIB.S9S_MB_2U(SCH_1):PAGE155
 R3665    1      A Q_RES_0402LF-100K,1%,1/16W,CHIA   I182 @S9S_MB_2U_LIB.S9S_MB_2U(SCH_1):PAGE155

USB_HUB_PSELF @S9S_MB_2U_LIB.S9S_MB_2U(SCH_1):USB_HUB_PSELF
  U268   22  PSELF GL852GOHY60-GL852G-OHY60,SMLF,A   I100 @S9S_MB_2U_LIB.S9S_MB_2U(SCH_1):PAGE155
 R3663    2      B Q_RES_0402LF-10K,1%,1/16W,CHIPA   I186 @S9S_MB_2U_LIB.S9S_MB_2U(SCH_1):PAGE155
 R3664    1      A Q_RES_0402LF-10K,1%,1/16W,EMPTA   I187 @S9S_MB_2U_LIB.S9S_MB_2U(SCH_1):PAGE155

USB_HUB_RREF @S9S_MB_2U_LIB.S9S_MB_2U(SCH_1):USB_HUB_RREF
  U268    8   RREF GL852GOHY60-GL852G-OHY60,SMLF,A   I100 @S9S_MB_2U_LIB.S9S_MB_2U(SCH_1):PAGE155
 R3653    1      A Q_RES_0402LF-680,1%,1/16W,CHIPA   I139 @S9S_MB_2U_LIB.S9S_MB_2U(SCH_1):PAGE155

USB_HUB_TEST @S9S_MB_2U_LIB.S9S_MB_2U(SCH_1):USB_HUB_TEST
  U268   18 TEST||SCL GL852GOHY60-GL852G-OHY60,SMLF,A   I100 @S9S_MB_2U_LIB.S9S_MB_2U(SCH_1):PAGE155
 R3666    1      A Q_RES_0402LF-0,5%,1/16W,CHIP,CA   I199 @S9S_MB_2U_LIB.S9S_MB_2U(SCH_1):PAGE155

USB_HUB_XTAL_IN @S9S_MB_2U_LIB.S9S_MB_2U(SCH_1):USB_HUB_XTAL_IN
  U268   10     X1 GL852GOHY60-GL852G-OHY60,SMLF,A   I100 @S9S_MB_2U_LIB.S9S_MB_2U(SCH_1):PAGE155
    Y4    1     X1 Q_XTAL_4P_13BI_24GND-12MHZ,SMLA   I200 @S9S_MB_2U_LIB.S9S_MB_2U(SCH_1):PAGE155
 C2029    1      A Q_CAP_0402-18PF,50V,5%,C0G,CH0A   I210 @S9S_MB_2U_LIB.S9S_MB_2U(SCH_1):PAGE155

USB_HUB_XTAL_OUT @S9S_MB_2U_LIB.S9S_MB_2U(SCH_1):USB_HUB_XTAL_OUT
  U268   11     X2 GL852GOHY60-GL852G-OHY60,SMLF,A   I100 @S9S_MB_2U_LIB.S9S_MB_2U(SCH_1):PAGE155
    Y4    3     X2 Q_XTAL_4P_13BI_24GND-12MHZ,SMLA   I200 @S9S_MB_2U_LIB.S9S_MB_2U(SCH_1):PAGE155
 C2030    1      A Q_CAP_0402-18PF,50V,5%,C0G,CH0A   I211 @S9S_MB_2U_LIB.S9S_MB_2U(SCH_1):PAGE155

USB_OC1_REAR_N @S9S_MB_2U_LIB.S9S_MB_2U(SCH_1):USB_OC1_REAR_N
 R1827    2      B Q_RES_0402LF-33.2,1%,1/16W,CHIA   I193 @S9S_MB_2U_LIB.S9S_MB_2U(SCH_1):PAGE175
  U249   W9  PB18D LCMXO3LF9400C5BG484C-LCMXO3LF-A     I1 @S9S_MB_2U_LIB.S9S_MB_2U(SCH_1):PAGE312

USB_OC1_REAR_R_N @S9S_MB_2U_LIB.S9S_MB_2U(SCH_1):USB_OC1_REAR_R_N
    U4 BG32 GPPC_B_6_USB2_OCB_1 EMMITSBURG_REV0P9-GFNOCPU04302A    I93 @S9S_MB_2U_LIB.S9S_MB_2U(SCH_1):PAGE175
 R1828    1      A Q_RES_0402LF-10K,1%,1/16W,CHIPA   I188 @S9S_MB_2U_LIB.S9S_MB_2U(SCH_1):PAGE175
 R1827    1      A Q_RES_0402LF-33.2,1%,1/16W,CHIA   I193 @S9S_MB_2U_LIB.S9S_MB_2U(SCH_1):PAGE175

UV_ADR_P2V5_COMP @S9S_MB_2U_LIB.S9S_MB_2U(SCH_1):UV_ADR_P2V5_COMP
 C2379    1      A Q_CAP_C0402-100NF,50V,10%,EMPTA     I1 @S9S_MB_2U_LIB.S9S_MB_2U(SCH_1):PAGE329
  U337    1     1+ LM4040AIM3X25NOPB-LM4040AIM3X-A     I3 @S9S_MB_2U_LIB.S9S_MB_2U(SCH_1):PAGE329
  U339    1    IN- AP331AWG7-AP331AWG-7,SMLF,EMPTA    I12 @S9S_MB_2U_LIB.S9S_MB_2U(SCH_1):PAGE329
 R4772    2      B Q_RES_0402LF-10K,1%,1/16W,EMPTA    I21 @S9S_MB_2U_LIB.S9S_MB_2U(SCH_1):PAGE329

UV_P2V5_COMP @S9S_MB_2U_LIB.S9S_MB_2U(SCH_1):UV_P2V5_COMP
  U340    1    IN- AP331AWG7-AP331AWG-7,SMLF,EMPTA    I23 @S9S_MB_2U_LIB.S9S_MB_2U(SCH_1):PAGE329
 C2380    1      A Q_CAP_C0402-100NF,50V,10%,EMPTA    I35 @S9S_MB_2U_LIB.S9S_MB_2U(SCH_1):PAGE329
 R4773    2      B Q_RES_0402LF-10K,1%,1/16W,EMPTA    I42 @S9S_MB_2U_LIB.S9S_MB_2U(SCH_1):PAGE329
  U338    1     1+ LM4040AIM3X25NOPB-LM4040AIM3X-A    I43 @S9S_MB_2U_LIB.S9S_MB_2U(SCH_1):PAGE329

VCC_PLD_CORE @S9S_MB_2U_LIB.S9S_MB_2U(SCH_1):VCC_PLD_CORE
 C1154    1      A Q_CAP_C0402-0.01UF,50V,10%,X7RA     I3 @S9S_MB_2U_LIB.S9S_MB_2U(SCH_1):PAGE202
 C1152    1      A Q_CAP_C0402-0.01UF,50V,10%,X7RA     I5 @S9S_MB_2U_LIB.S9S_MB_2U(SCH_1):PAGE202
 C1931    1      A Q_CAP_C0402-0.01UF,50V,10%,X7RA    I21 @S9S_MB_2U_LIB.S9S_MB_2U(SCH_1):PAGE202
 C1928    1      A Q_CAP_C0402-0.01UF,50V,10%,X7RA    I22 @S9S_MB_2U_LIB.S9S_MB_2U(SCH_1):PAGE202
 C1919    1      A Q_CAP_C0402-0.01UF,50V,10%,X7RA    I23 @S9S_MB_2U_LIB.S9S_MB_2U(SCH_1):PAGE202
 C1916    1      A Q_CAP_C0402-0.01UF,50V,10%,X7RA    I24 @S9S_MB_2U_LIB.S9S_MB_2U(SCH_1):PAGE202
 C1907    1      A Q_CAP_0402-0.1UF,25V,10%,X7R,CA    I25 @S9S_MB_2U_LIB.S9S_MB_2U(SCH_1):PAGE202
 C1903    1      A Q_CAP_C0402-0.01UF,50V,10%,X7RA    I26 @S9S_MB_2U_LIB.S9S_MB_2U(SCH_1):PAGE202
 C1897    1      A Q_CAP_C0402-0.01UF,50V,10%,X7RA    I27 @S9S_MB_2U_LIB.S9S_MB_2U(SCH_1):PAGE202
 C1912    1      A Q_CAP_C0402-0.01UF,50V,10%,X7RA    I28 @S9S_MB_2U_LIB.S9S_MB_2U(SCH_1):PAGE202
 C1943    1      A Q_CAP_0402-0.1UF,25V,10%,X7R,CA    I29 @S9S_MB_2U_LIB.S9S_MB_2U(SCH_1):PAGE202
 C1936    1      A Q_CAP_C0402-10UF,6.3V,20%,X6S,A    I30 @S9S_MB_2U_LIB.S9S_MB_2U(SCH_1):PAGE202
  U249  K10   VCC1 LCMXO3LF9400C5BG484C-LCMXO3LF-A   I102 @S9S_MB_2U_LIB.S9S_MB_2U(SCH_1):PAGE202
  U249  K11   VCC2 LCMXO3LF9400C5BG484C-LCMXO3LF-A   I102 @S9S_MB_2U_LIB.S9S_MB_2U(SCH_1):PAGE202
  U249  K12   VCC3 LCMXO3LF9400C5BG484C-LCMXO3LF-A   I102 @S9S_MB_2U_LIB.S9S_MB_2U(SCH_1):PAGE202
  U249  K13   VCC4 LCMXO3LF9400C5BG484C-LCMXO3LF-A   I102 @S9S_MB_2U_LIB.S9S_MB_2U(SCH_1):PAGE202
  U249  L11   VCC5 LCMXO3LF9400C5BG484C-LCMXO3LF-A   I102 @S9S_MB_2U_LIB.S9S_MB_2U(SCH_1):PAGE202
  U249  L12   VCC6 LCMXO3LF9400C5BG484C-LCMXO3LF-A   I102 @S9S_MB_2U_LIB.S9S_MB_2U(SCH_1):PAGE202
  U249  M11   VCC7 LCMXO3LF9400C5BG484C-LCMXO3LF-A   I102 @S9S_MB_2U_LIB.S9S_MB_2U(SCH_1):PAGE202
  U249  M12   VCC8 LCMXO3LF9400C5BG484C-LCMXO3LF-A   I102 @S9S_MB_2U_LIB.S9S_MB_2U(SCH_1):PAGE202
  U249  N10   VCC9 LCMXO3LF9400C5BG484C-LCMXO3LF-A   I102 @S9S_MB_2U_LIB.S9S_MB_2U(SCH_1):PAGE202
  U249  N11  VCC10 LCMXO3LF9400C5BG484C-LCMXO3LF-A   I102 @S9S_MB_2U_LIB.S9S_MB_2U(SCH_1):PAGE202
  U249  N12  VCC11 LCMXO3LF9400C5BG484C-LCMXO3LF-A   I102 @S9S_MB_2U_LIB.S9S_MB_2U(SCH_1):PAGE202
  U249  N13  VCC12 LCMXO3LF9400C5BG484C-LCMXO3LF-A   I102 @S9S_MB_2U_LIB.S9S_MB_2U(SCH_1):PAGE202
 R3458    2      B Q_RES_0603LF-1,1%,1/10W,CHIP,CA   I119 @S9S_MB_2U_LIB.S9S_MB_2U(SCH_1):PAGE202
 C1934    1      A Q_CAP_C0402-0.01UF,50V,10%,X7RA   I120 @S9S_MB_2U_LIB.S9S_MB_2U(SCH_1):PAGE202
 C1150    1      A Q_CAP_0402-0.1UF,25V,10%,X7R,CA   I121 @S9S_MB_2U_LIB.S9S_MB_2U(SCH_1):PAGE202

VFG3P3_CLK_GEN @S9S_MB_2U_LIB.S9S_MB_2U(SCH_1):VFG3P3_CLK_GEN
 C1883    1      A Q_CAP_C0805-10UF,25V,10%,X6S,CA    I16 @S9S_MB_2U_LIB.S9S_MB_2U(SCH_1):PAGE201
 C1886    1      A Q_CAP_0402-0.1UF,25V,10%,X7R,CA    I18 @S9S_MB_2U_LIB.S9S_MB_2U(SCH_1):PAGE201
 C1889    1      A Q_CAP_0402-0.1UF,25V,10%,X7R,CA    I19 @S9S_MB_2U_LIB.S9S_MB_2U(SCH_1):PAGE201
 R4077    1      A Q_RES_0402LF-1,1%,1/16W,CHIP,CA   I102 @S9S_MB_2U_LIB.S9S_MB_2U(SCH_1):PAGE201
 C2257    1      A Q_CAP_0402-0.1UF,25V,10%,X7R,CA   I104 @S9S_MB_2U_LIB.S9S_MB_2U(SCH_1):PAGE201
 C2258    1      A Q_CAP_0402-0.1UF,25V,10%,X7R,CA   I105 @S9S_MB_2U_LIB.S9S_MB_2U(SCH_1):PAGE201
   L17    2      2 Q_INDUCTOR_SMLF-FCM2012KF-601TA   I155 @S9S_MB_2U_LIB.S9S_MB_2U(SCH_1):PAGE201
  U247   11 VDD3.3_11 9FGL0251DKILFT-9FGL0251DKILFT,A   I167 @S9S_MB_2U_LIB.S9S_MB_2U(SCH_1):PAGE201
  U247   20 VDD3.3_20 9FGL0251DKILFT-9FGL0251DKILFT,A   I167 @S9S_MB_2U_LIB.S9S_MB_2U(SCH_1):PAGE201
  U247    7 VDDDIG3.3 9FGL0251DKILFT-9FGL0251DKILFT,A   I167 @S9S_MB_2U_LIB.S9S_MB_2U(SCH_1):PAGE201
  U247    3 VDDXTAL3.3 9FGL0251DKILFT-9FGL0251DKILFT,A   I167 @S9S_MB_2U_LIB.S9S_MB_2U(SCH_1):PAGE201

VFG_3P3A_CLK_GEN @S9S_MB_2U_LIB.S9S_MB_2U(SCH_1):VFG_3P3A_CLK_GEN
 R4077    2      B Q_RES_0402LF-1,1%,1/16W,CHIP,CA   I102 @S9S_MB_2U_LIB.S9S_MB_2U(SCH_1):PAGE201
 C1884    1      A Q_CAP_C0402-1UF,25V,10%,X6S,CHA   I103 @S9S_MB_2U_LIB.S9S_MB_2U(SCH_1):PAGE201
 C2259    1      A Q_CAP_0402-0.1UF,25V,10%,X7R,CA   I106 @S9S_MB_2U_LIB.S9S_MB_2U(SCH_1):PAGE201
  U247   16 VDDA3.3 9FGL0251DKILFT-9FGL0251DKILFT,A   I167 @S9S_MB_2U_LIB.S9S_MB_2U(SCH_1):PAGE201

VIRTUAL_RESEAT @S9S_MB_2U_LIB.S9S_MB_2U(SCH_1):VIRTUAL_RESEAT
  U249 AB16  PB38A LCMXO3LF9400C5BG484C-LCMXO3LF-A     I1 @S9S_MB_2U_LIB.S9S_MB_2U(SCH_1):PAGE312
   J41 OA14 RBT_CLK_IN SCONN168_ME1016810202011-SCONNA   I173 @S9S_MB_2U_LIB.S9S_MB_2U(SCH_1):PAGE227

VIRTUAL_RESEAT_FPGA_N @S9S_MB_2U_LIB.S9S_MB_2U(SCH_1):VIRTUAL_RESEAT_FPGA_N
 R3996    1      A Q_RES_0402LF-0,5%,1/16W,CHIP,CA    I17 @S9S_MB_2U_LIB.S9S_MB_2U(SCH_1):PAGE229
 R1853    2      B Q_RES_0402LF-0,5%,1/16W,CHIP,CA   I138 @S9S_MB_2U_LIB.S9S_MB_2U(SCH_1):PAGE314

VIRTUAL_RESEAT_FPGA_R_N @S9S_MB_2U_LIB.S9S_MB_2U(SCH_1):VIRTUAL_RESEAT_FPGA_R_N
 R1853    1      A Q_RES_0402LF-0,5%,1/16W,CHIP,CA   I138 @S9S_MB_2U_LIB.S9S_MB_2U(SCH_1):PAGE314
  U249   D5  PT12C LCMXO3LF9400C5BG484C-LCMXO3LF-A   I188 @S9S_MB_2U_LIB.S9S_MB_2U(SCH_1):PAGE314

VR_P5V_EN @S9S_MB_2U_LIB.S9S_MB_2U(SCH_1):VR_P5V_EN
 R1640    2      B Q_RES_0402LF-0,5%,1/16W,CHIP,CA     I9 @S9S_MB_2U_LIB.S9S_MB_2U(SCH_1):PAGE246
 R1607    2      B Q_RES_0402LF-0,5%,1/16W,EMPTY,A    I10 @S9S_MB_2U_LIB.S9S_MB_2U(SCH_1):PAGE246
 R1641    1      A Q_RES_0402LF-100K,1%,1/16W,CHIA    I14 @S9S_MB_2U_LIB.S9S_MB_2U(SCH_1):PAGE246
   Q37    2     G1 MOSFET_NCH_DUAL-PJT138K,SMLF,IA    I69 @S9S_MB_2U_LIB.S9S_MB_2U(SCH_1):PAGE246

VR_P5V_EN_D @S9S_MB_2U_LIB.S9S_MB_2U(SCH_1):VR_P5V_EN_D
  U324    D      D MOSFET_NCH_GDS_ESD_PROTECTED-2A    I67 @S9S_MB_2U_LIB.S9S_MB_2U(SCH_1):PAGE246
 R4638    2      B Q_RES_1206LF-243,1%,1/4W,CHIP,A    I77 @S9S_MB_2U_LIB.S9S_MB_2U(SCH_1):PAGE246
 R4639    2      B Q_RES_1206LF-243,1%,1/4W,CHIP,A    I78 @S9S_MB_2U_LIB.S9S_MB_2U(SCH_1):PAGE246
 R4640    2      B Q_RES_1206LF-243,1%,1/4W,CHIP,A    I79 @S9S_MB_2U_LIB.S9S_MB_2U(SCH_1):PAGE246
 R4641    2      B Q_RES_1206LF-243,1%,1/4W,CHIP,A    I80 @S9S_MB_2U_LIB.S9S_MB_2U(SCH_1):PAGE246

VR_P5V_EN_D_R @S9S_MB_2U_LIB.S9S_MB_2U(SCH_1):VR_P5V_EN_D_R
 R1642    2      B Q_RES_0402LF-10K,1%,1/16W,CHIPA    I22 @S9S_MB_2U_LIB.S9S_MB_2U(SCH_1):PAGE246
 R1654    1      A Q_RES_0402LF-1K,1%,1/16W,CHIP,A    I27 @S9S_MB_2U_LIB.S9S_MB_2U(SCH_1):PAGE246
   Q57    4      4 MOSFET_NCH_1D3S-PSMNR58-30YLH,A    I30 @S9S_MB_2U_LIB.S9S_MB_2U(SCH_1):PAGE246
 C1226    1      A Q_CAP_C0402-0.22UF,25V,10%,X7RA    I68 @S9S_MB_2U_LIB.S9S_MB_2U(SCH_1):PAGE246

VR_P5V_EN_D_R1 @S9S_MB_2U_LIB.S9S_MB_2U(SCH_1):VR_P5V_EN_D_R1
 R1654    2      B Q_RES_0402LF-1K,1%,1/16W,CHIP,A    I27 @S9S_MB_2U_LIB.S9S_MB_2U(SCH_1):PAGE246
   Q37    3     D2 MOSFET_NCH_DUAL-PJT138K,SMLF,IA    I76 @S9S_MB_2U_LIB.S9S_MB_2U(SCH_1):PAGE246

VR_P5V_EN_N @S9S_MB_2U_LIB.S9S_MB_2U(SCH_1):VR_P5V_EN_N
 R1643    2      B Q_RES_0402LF-100K,1%,1/16W,CHIA    I17 @S9S_MB_2U_LIB.S9S_MB_2U(SCH_1):PAGE246
  U324    G      G MOSFET_NCH_GDS_ESD_PROTECTED-2A    I67 @S9S_MB_2U_LIB.S9S_MB_2U(SCH_1):PAGE246
   Q37    6     D1 MOSFET_NCH_DUAL-PJT138K,SMLF,IA    I69 @S9S_MB_2U_LIB.S9S_MB_2U(SCH_1):PAGE246
   Q37    5     G2 MOSFET_NCH_DUAL-PJT138K,SMLF,IA    I76 @S9S_MB_2U_LIB.S9S_MB_2U(SCH_1):PAGE246

VSENSE_P12V_INA230_3_INN @S9S_MB_2U_LIB.S9S_MB_2U(SCH_1):VSENSE_P12V_INA230_3_INN
  U263   12    IN- INA230AIRGTR-INA230AIRGTR,SMLFB    I94 @S9S_MB_2U_LIB.S9S_MB_2U(SCH_1):PAGE163
 C2020    2      B Q_CAP_0402-0.1UF,25V,10%,X7R,CA   I108 @S9S_MB_2U_LIB.S9S_MB_2U(SCH_1):PAGE163
 R3571    2      B Q_RES_0402LF-10,1%,1/16W,CHIP,A   I110 @S9S_MB_2U_LIB.S9S_MB_2U(SCH_1):PAGE163

VSENSE_P12V_INA230_3_INP @S9S_MB_2U_LIB.S9S_MB_2U(SCH_1):VSENSE_P12V_INA230_3_INP
  U263   13    IN+ INA230AIRGTR-INA230AIRGTR,SMLFB    I94 @S9S_MB_2U_LIB.S9S_MB_2U(SCH_1):PAGE163
 C2020    1      A Q_CAP_0402-0.1UF,25V,10%,X7R,CA   I108 @S9S_MB_2U_LIB.S9S_MB_2U(SCH_1):PAGE163
 R3570    2      B Q_RES_0402LF-10,1%,1/16W,CHIP,A   I109 @S9S_MB_2U_LIB.S9S_MB_2U(SCH_1):PAGE163

VSENSE_P12V_INA230_4_INN @S9S_MB_2U_LIB.S9S_MB_2U(SCH_1):VSENSE_P12V_INA230_4_INN
 R3575    2      B Q_RES_0402LF-10,1%,1/16W,CHIP,A    I33 @S9S_MB_2U_LIB.S9S_MB_2U(SCH_1):PAGE163
  U264   12    IN- INA230AIRGTR-INA230AIRGTR,SMLFB    I46 @S9S_MB_2U_LIB.S9S_MB_2U(SCH_1):PAGE163
 C2021    2      B Q_CAP_0402-0.1UF,25V,10%,X7R,CA    I71 @S9S_MB_2U_LIB.S9S_MB_2U(SCH_1):PAGE163

VSENSE_P12V_INA230_4_INP @S9S_MB_2U_LIB.S9S_MB_2U(SCH_1):VSENSE_P12V_INA230_4_INP
 R3574    2      B Q_RES_0402LF-10,1%,1/16W,CHIP,A    I35 @S9S_MB_2U_LIB.S9S_MB_2U(SCH_1):PAGE163
  U264   13    IN+ INA230AIRGTR-INA230AIRGTR,SMLFB    I46 @S9S_MB_2U_LIB.S9S_MB_2U(SCH_1):PAGE163
 C2021    1      A Q_CAP_0402-0.1UF,25V,10%,X7R,CA    I71 @S9S_MB_2U_LIB.S9S_MB_2U(SCH_1):PAGE163

VSENSE_P12V_INA230_5_INN @S9S_MB_2U_LIB.S9S_MB_2U(SCH_1):VSENSE_P12V_INA230_5_INN
 R3579    2      B Q_RES_0402LF-10,1%,1/16W,CHIP,A    I56 @S9S_MB_2U_LIB.S9S_MB_2U(SCH_1):PAGE163
  U265   12    IN- INA230AIRGTR-INA230AIRGTR,SMLFB    I69 @S9S_MB_2U_LIB.S9S_MB_2U(SCH_1):PAGE163
 C2022    2      B Q_CAP_0402-0.1UF,25V,10%,X7R,CA    I72 @S9S_MB_2U_LIB.S9S_MB_2U(SCH_1):PAGE163

VSENSE_P12V_INA230_5_INP @S9S_MB_2U_LIB.S9S_MB_2U(SCH_1):VSENSE_P12V_INA230_5_INP
 R3578    2      B Q_RES_0402LF-10,1%,1/16W,CHIP,A    I58 @S9S_MB_2U_LIB.S9S_MB_2U(SCH_1):PAGE163
  U265   13    IN+ INA230AIRGTR-INA230AIRGTR,SMLFB    I69 @S9S_MB_2U_LIB.S9S_MB_2U(SCH_1):PAGE163
 C2022    1      A Q_CAP_0402-0.1UF,25V,10%,X7R,CA    I72 @S9S_MB_2U_LIB.S9S_MB_2U(SCH_1):PAGE163

VSENSE_P3V3_INA230_1_INN @S9S_MB_2U_LIB.S9S_MB_2U(SCH_1):VSENSE_P3V3_INA230_1_INN
  U266   12    IN- INA230AIRGTR-INA230AIRGTR,SMLFB    I30 @S9S_MB_2U_LIB.S9S_MB_2U(SCH_1):PAGE295
 R3603    2      B Q_RES_0402LF-10,1%,1/16W,CHIP,A    I43 @S9S_MB_2U_LIB.S9S_MB_2U(SCH_1):PAGE295
 C2027    2      B Q_CAP_0402-0.1UF,25V,10%,X7R,CA    I77 @S9S_MB_2U_LIB.S9S_MB_2U(SCH_1):PAGE295

VSENSE_P3V3_INA230_1_INP @S9S_MB_2U_LIB.S9S_MB_2U(SCH_1):VSENSE_P3V3_INA230_1_INP
  U266   13    IN+ INA230AIRGTR-INA230AIRGTR,SMLFB    I30 @S9S_MB_2U_LIB.S9S_MB_2U(SCH_1):PAGE295
 R3602    2      B Q_RES_0402LF-10,1%,1/16W,CHIP,A    I41 @S9S_MB_2U_LIB.S9S_MB_2U(SCH_1):PAGE295
 C2027    1      A Q_CAP_0402-0.1UF,25V,10%,X7R,CA    I77 @S9S_MB_2U_LIB.S9S_MB_2U(SCH_1):PAGE295

VSENSE_P3V3_INA230_2_INN @S9S_MB_2U_LIB.S9S_MB_2U(SCH_1):VSENSE_P3V3_INA230_2_INN
  U276   12    IN- INA230AIRGTR-INA230AIRGTR,SMLFB   I129 @S9S_MB_2U_LIB.S9S_MB_2U(SCH_1):PAGE295
 C2071    2      B Q_CAP_0402-0.1UF,25V,10%,X7R,CA   I133 @S9S_MB_2U_LIB.S9S_MB_2U(SCH_1):PAGE295
 R3760    2      B Q_RES_0402LF-10,1%,1/16W,CHIP,A   I134 @S9S_MB_2U_LIB.S9S_MB_2U(SCH_1):PAGE295

VSENSE_P3V3_INA230_2_INP @S9S_MB_2U_LIB.S9S_MB_2U(SCH_1):VSENSE_P3V3_INA230_2_INP
  U276   13    IN+ INA230AIRGTR-INA230AIRGTR,SMLFB   I129 @S9S_MB_2U_LIB.S9S_MB_2U(SCH_1):PAGE295
 R3758    2      B Q_RES_0402LF-10,1%,1/16W,CHIP,A   I132 @S9S_MB_2U_LIB.S9S_MB_2U(SCH_1):PAGE295
 C2071    1      A Q_CAP_0402-0.1UF,25V,10%,X7R,CA   I133 @S9S_MB_2U_LIB.S9S_MB_2U(SCH_1):PAGE295

VSENSE_PVCCD_HV_CPU0_DN @S9S_MB_2U_LIB.S9S_MB_2U(SCH_1):VSENSE_PVCCD_HV_CPU0_DN
    U2 BN11 VSS_VCCD_HV_SENSE SOCKET4677_AZIF0045P001C01CS-SA     I1 @S9S_MB_2U_LIB.S9S_MB_2U(SCH_1):PAGE16
  PU35   22  RGND0 ISL69260IRAZT-ISL69260IRAZ-T,SA    I53 @S9S_MB_2U_LIB.S9S_MB_2U(SCH_1):PAGE264
 PR591    1      A Q_RES_0402LF-100,1%,1/16W,CHIPA    I30 @S9S_MB_2U_LIB.S9S_MB_2U(SCH_1):PAGE264
 PC627    2      B Q_CAP_0402-3300PF,50V,10%,X7R,A    I37 @S9S_MB_2U_LIB.S9S_MB_2U(SCH_1):PAGE264

VSENSE_PVCCD_HV_CPU0_DP @S9S_MB_2U_LIB.S9S_MB_2U(SCH_1):VSENSE_PVCCD_HV_CPU0_DP
    U2 BU11 VCCD_HV_SENSE SOCKET4677_AZIF0045P001C01CS-SA     I1 @S9S_MB_2U_LIB.S9S_MB_2U(SCH_1):PAGE16
  PJ54    1      1 Q_SHORT_SM-EMPTY,SHORT6    I32 @S9S_MB_2U_LIB.S9S_MB_2U(SCH_1):PAGE264
 PR592    1      A Q_RES_0402LF-100,1%,1/16W,CHIPA    I31 @S9S_MB_2U_LIB.S9S_MB_2U(SCH_1):PAGE264

VSENSE_PVCCD_HV_CPU1_DN @S9S_MB_2U_LIB.S9S_MB_2U(SCH_1):VSENSE_PVCCD_HV_CPU1_DN
    U1 BN11 VSS_VCCD_HV_SENSE SOCKET4677_AZIF0045P001C01CS-SA    I16 @S9S_MB_2U_LIB.S9S_MB_2U(SCH_1):PAGE47
  PU18   22  RGND0 ISL69260IRAZT-ISL69260IRAZ-T,SA    I53 @S9S_MB_2U_LIB.S9S_MB_2U(SCH_1):PAGE282
 PR558    1      A Q_RES_0402LF-100,1%,1/16W,CHIPA    I15 @S9S_MB_2U_LIB.S9S_MB_2U(SCH_1):PAGE282
 PC389    2      B Q_CAP_0402-3300PF,50V,10%,X7R,A    I22 @S9S_MB_2U_LIB.S9S_MB_2U(SCH_1):PAGE282

VSENSE_PVCCD_HV_CPU1_DP @S9S_MB_2U_LIB.S9S_MB_2U(SCH_1):VSENSE_PVCCD_HV_CPU1_DP
    U1 BU11 VCCD_HV_SENSE SOCKET4677_AZIF0045P001C01CS-SA    I16 @S9S_MB_2U_LIB.S9S_MB_2U(SCH_1):PAGE47
 PR559    1      A Q_RES_0402LF-100,1%,1/16W,CHIPA    I36 @S9S_MB_2U_LIB.S9S_MB_2U(SCH_1):PAGE282
  PJ48    1      1 Q_SHORT_SM-EMPTY,SHORT6    I16 @S9S_MB_2U_LIB.S9S_MB_2U(SCH_1):PAGE282

VSENSE_PVCCFA_EHV_CPU0_DN @S9S_MB_2U_LIB.S9S_MB_2U(SCH_1):VSENSE_PVCCFA_EHV_CPU0_DN
    U2 BA11 VSS_VCCFA_EHV_SENSE SOCKET4677_AZIF0045P001C01CS-SA     I1 @S9S_MB_2U_LIB.S9S_MB_2U(SCH_1):PAGE16
   PU5   31  RGND1 ISL69260IRAZT-ISL69260IRAZ-T,SA    I65 @S9S_MB_2U_LIB.S9S_MB_2U(SCH_1):PAGE260
 PC216    2      B Q_CAP_0402-3300PF,50V,10%,X7R,A    I48 @S9S_MB_2U_LIB.S9S_MB_2U(SCH_1):PAGE260
 PR520    1      A Q_RES_0402LF-100,1%,1/16W,CHIPA    I38 @S9S_MB_2U_LIB.S9S_MB_2U(SCH_1):PAGE260

VSENSE_PVCCFA_EHV_CPU0_DP @S9S_MB_2U_LIB.S9S_MB_2U(SCH_1):VSENSE_PVCCFA_EHV_CPU0_DP
    U2 AU11 VCCFA_EHV_SENSE SOCKET4677_AZIF0045P001C01CS-SA     I1 @S9S_MB_2U_LIB.S9S_MB_2U(SCH_1):PAGE16
 PR522    1      A Q_RES_0402LF-100,1%,1/16W,CHIPA    I40 @S9S_MB_2U_LIB.S9S_MB_2U(SCH_1):PAGE260
  PJ46    1      1 Q_SHORT_SM-EMPTY,SHORT6    I39 @S9S_MB_2U_LIB.S9S_MB_2U(SCH_1):PAGE260

VSENSE_PVCCFA_EHV_CPU1_DN @S9S_MB_2U_LIB.S9S_MB_2U(SCH_1):VSENSE_PVCCFA_EHV_CPU1_DN
    U1 BA11 VSS_VCCFA_EHV_SENSE SOCKET4677_AZIF0045P001C01CS-SA    I16 @S9S_MB_2U_LIB.S9S_MB_2U(SCH_1):PAGE47
 PC469    2      B Q_CAP_0402-3300PF,50V,10%,X7R,A    I51 @S9S_MB_2U_LIB.S9S_MB_2U(SCH_1):PAGE278
  PU22   31  RGND1 ISL69260IRAZT-ISL69260IRAZ-T,SA    I38 @S9S_MB_2U_LIB.S9S_MB_2U(SCH_1):PAGE278
 PR567    1      A Q_RES_0402LF-100,1%,1/16W,CHIPA    I41 @S9S_MB_2U_LIB.S9S_MB_2U(SCH_1):PAGE278

VSENSE_PVCCFA_EHV_CPU1_DP @S9S_MB_2U_LIB.S9S_MB_2U(SCH_1):VSENSE_PVCCFA_EHV_CPU1_DP
    U1 AU11 VCCFA_EHV_SENSE SOCKET4677_AZIF0045P001C01CS-SA    I16 @S9S_MB_2U_LIB.S9S_MB_2U(SCH_1):PAGE47
  PJ51    1      1 Q_SHORT_SM-EMPTY,SHORT6    I44 @S9S_MB_2U_LIB.S9S_MB_2U(SCH_1):PAGE278
 PR569    1      A Q_RES_0402LF-100,1%,1/16W,CHIPA    I45 @S9S_MB_2U_LIB.S9S_MB_2U(SCH_1):PAGE278

VSENSE_PVCCFA_EHV_FIVRA_CPU0_DN @S9S_MB_2U_LIB.S9S_MB_2U(SCH_1):VSENSE_PVCCFA_EHV_FIVRA_CPU0_DN
    U2 AT85 VSS_VCCFA_EHV_FIVRA_SENSE SOCKET4677_AZIF0045P001C01CS-SA     I1 @S9S_MB_2U_LIB.S9S_MB_2U(SCH_1):PAGE16
 PR586    1      A Q_RES_0402LF-100,1%,1/16W,CHIPA    I15 @S9S_MB_2U_LIB.S9S_MB_2U(SCH_1):PAGE252
  PU14   39  RGND1 RAA229126GNPHA0-RAA229126GNP#HA    I63 @S9S_MB_2U_LIB.S9S_MB_2U(SCH_1):PAGE252
 PC594    2      B Q_CAP_0402-3300PF,50V,10%,X7R,A    I67 @S9S_MB_2U_LIB.S9S_MB_2U(SCH_1):PAGE252

VSENSE_PVCCFA_EHV_FIVRA_CPU0_DP @S9S_MB_2U_LIB.S9S_MB_2U(SCH_1):VSENSE_PVCCFA_EHV_FIVRA_CPU0_DP
    U2 AY85 VCCFA_EHV_FIVRA_SENSE SOCKET4677_AZIF0045P001C01CS-SA     I1 @S9S_MB_2U_LIB.S9S_MB_2U(SCH_1):PAGE16
  PJ53    1      1 Q_SHORT_SM-EMPTY,SHORT6    I24 @S9S_MB_2U_LIB.S9S_MB_2U(SCH_1):PAGE252
 PR587    1      A Q_RES_0402LF-100,1%,1/16W,CHIPA    I25 @S9S_MB_2U_LIB.S9S_MB_2U(SCH_1):PAGE252

VSENSE_PVCCFA_EHV_FIVRA_CPU1_DN @S9S_MB_2U_LIB.S9S_MB_2U(SCH_1):VSENSE_PVCCFA_EHV_FIVRA_CPU1_DN
    U1 AT85 VSS_VCCFA_EHV_FIVRA_SENSE SOCKET4677_AZIF0045P001C01CS-SA    I16 @S9S_MB_2U_LIB.S9S_MB_2U(SCH_1):PAGE47
 PR560    1      A Q_RES_0402LF-100,1%,1/16W,CHIPA    I12 @S9S_MB_2U_LIB.S9S_MB_2U(SCH_1):PAGE270
 PC422    2      B Q_CAP_0402-3300PF,50V,10%,X7R,A    I38 @S9S_MB_2U_LIB.S9S_MB_2U(SCH_1):PAGE270
  PU29   39  RGND1 RAA229126GNPHA0-RAA229126GNP#HA    I33 @S9S_MB_2U_LIB.S9S_MB_2U(SCH_1):PAGE270

VSENSE_PVCCFA_EHV_FIVRA_CPU1_DP @S9S_MB_2U_LIB.S9S_MB_2U(SCH_1):VSENSE_PVCCFA_EHV_FIVRA_CPU1_DP
    U1 AY85 VCCFA_EHV_FIVRA_SENSE SOCKET4677_AZIF0045P001C01CS-SA    I16 @S9S_MB_2U_LIB.S9S_MB_2U(SCH_1):PAGE47
  PJ49    1      1 Q_SHORT_SM-EMPTY,SHORT6    I22 @S9S_MB_2U_LIB.S9S_MB_2U(SCH_1):PAGE270
 PR561    1      A Q_RES_0402LF-100,1%,1/16W,CHIPA    I23 @S9S_MB_2U_LIB.S9S_MB_2U(SCH_1):PAGE270

VSENSE_PVCCINFAON_CPU0_DN @S9S_MB_2U_LIB.S9S_MB_2U(SCH_1):VSENSE_PVCCINFAON_CPU0_DN
    U2 CE11 VSS_VCCINFAON_SENSE SOCKET4677_AZIF0045P001C01CS-SA     I1 @S9S_MB_2U_LIB.S9S_MB_2U(SCH_1):PAGE16
   PU5   22  RGND0 ISL69260IRAZT-ISL69260IRAZ-T,SA    I65 @S9S_MB_2U_LIB.S9S_MB_2U(SCH_1):PAGE260
 PC215    2      B Q_CAP_0402-3300PF,50V,10%,X7R,A    I50 @S9S_MB_2U_LIB.S9S_MB_2U(SCH_1):PAGE260
 PR519    1      A Q_RES_0402LF-100,1%,1/16W,CHIPA    I42 @S9S_MB_2U_LIB.S9S_MB_2U(SCH_1):PAGE260

VSENSE_PVCCINFAON_CPU0_DP @S9S_MB_2U_LIB.S9S_MB_2U(SCH_1):VSENSE_PVCCINFAON_CPU0_DP
    U2 CA11 VCCINFAON_SENSE SOCKET4677_AZIF0045P001C01CS-SA     I1 @S9S_MB_2U_LIB.S9S_MB_2U(SCH_1):PAGE16
 PR521    1      A Q_RES_0402LF-100,1%,1/16W,CHIPA    I44 @S9S_MB_2U_LIB.S9S_MB_2U(SCH_1):PAGE260
  PJ45    1      1 Q_SHORT_SM-EMPTY,SHORT6    I43 @S9S_MB_2U_LIB.S9S_MB_2U(SCH_1):PAGE260

VSENSE_PVCCINFAON_CPU1_DN @S9S_MB_2U_LIB.S9S_MB_2U(SCH_1):VSENSE_PVCCINFAON_CPU1_DN
    U1 CE11 VSS_VCCINFAON_SENSE SOCKET4677_AZIF0045P001C01CS-SA    I16 @S9S_MB_2U_LIB.S9S_MB_2U(SCH_1):PAGE47
 PC468    2      B Q_CAP_0402-3300PF,50V,10%,X7R,A    I53 @S9S_MB_2U_LIB.S9S_MB_2U(SCH_1):PAGE278
  PU22   22  RGND0 ISL69260IRAZT-ISL69260IRAZ-T,SA    I38 @S9S_MB_2U_LIB.S9S_MB_2U(SCH_1):PAGE278
 PR566    1      A Q_RES_0402LF-100,1%,1/16W,CHIPA    I46 @S9S_MB_2U_LIB.S9S_MB_2U(SCH_1):PAGE278

VSENSE_PVCCINFAON_CPU1_DP @S9S_MB_2U_LIB.S9S_MB_2U(SCH_1):VSENSE_PVCCINFAON_CPU1_DP
    U1 CA11 VCCINFAON_SENSE SOCKET4677_AZIF0045P001C01CS-SA    I16 @S9S_MB_2U_LIB.S9S_MB_2U(SCH_1):PAGE47
  PJ50    1      1 Q_SHORT_SM-EMPTY,SHORT6    I54 @S9S_MB_2U_LIB.S9S_MB_2U(SCH_1):PAGE278
 PR568    1      A Q_RES_0402LF-100,1%,1/16W,CHIPA    I55 @S9S_MB_2U_LIB.S9S_MB_2U(SCH_1):PAGE278

VSENSE_PVCCIN_CPU0_DN @S9S_MB_2U_LIB.S9S_MB_2U(SCH_1):VSENSE_PVCCIN_CPU0_DN
    U2 BC90 VSS_VCCIN_SENSE SOCKET4677_AZIF0045P001C01CS-SA     I1 @S9S_MB_2U_LIB.S9S_MB_2U(SCH_1):PAGE16
  PU14   26  RGND0 RAA229126GNPHA0-RAA229126GNP#HA    I63 @S9S_MB_2U_LIB.S9S_MB_2U(SCH_1):PAGE252
 PC331    2      B Q_CAP_0402-3300PF,50V,10%,X7R,A    I79 @S9S_MB_2U_LIB.S9S_MB_2U(SCH_1):PAGE252
 PR527    1      A Q_RES_0402LF-100,1%,1/16W,CHIPA    I26 @S9S_MB_2U_LIB.S9S_MB_2U(SCH_1):PAGE252

VSENSE_PVCCIN_CPU0_DP @S9S_MB_2U_LIB.S9S_MB_2U(SCH_1):VSENSE_PVCCIN_CPU0_DP
    U2 BD87 VCCIN_SENSE SOCKET4677_AZIF0045P001C01CS-SA     I1 @S9S_MB_2U_LIB.S9S_MB_2U(SCH_1):PAGE16
 PR531    1      A Q_RES_0402LF-100,1%,1/16W,CHIPA    I38 @S9S_MB_2U_LIB.S9S_MB_2U(SCH_1):PAGE252
  PJ47    1      1 Q_SHORT_SM-EMPTY,SHORT6    I37 @S9S_MB_2U_LIB.S9S_MB_2U(SCH_1):PAGE252

VSENSE_PVCCIN_CPU1_DN @S9S_MB_2U_LIB.S9S_MB_2U(SCH_1):VSENSE_PVCCIN_CPU1_DN
    U1 BC90 VSS_VCCIN_SENSE SOCKET4677_AZIF0045P001C01CS-SA    I16 @S9S_MB_2U_LIB.S9S_MB_2U(SCH_1):PAGE47
 PC549    2      B Q_CAP_0402-3300PF,50V,10%,X7R,A    I64 @S9S_MB_2U_LIB.S9S_MB_2U(SCH_1):PAGE270
  PU29   26  RGND0 RAA229126GNPHA0-RAA229126GNP#HA    I33 @S9S_MB_2U_LIB.S9S_MB_2U(SCH_1):PAGE270
 PR574    1      A Q_RES_0402LF-100,1%,1/16W,CHIPA    I45 @S9S_MB_2U_LIB.S9S_MB_2U(SCH_1):PAGE270

VSENSE_PVCCIN_CPU1_DP @S9S_MB_2U_LIB.S9S_MB_2U(SCH_1):VSENSE_PVCCIN_CPU1_DP
    U1 BD87 VCCIN_SENSE SOCKET4677_AZIF0045P001C01CS-SA    I16 @S9S_MB_2U_LIB.S9S_MB_2U(SCH_1):PAGE47
 PR578    1      A Q_RES_0402LF-100,1%,1/16W,CHIPA    I49 @S9S_MB_2U_LIB.S9S_MB_2U(SCH_1):PAGE270
  PJ52    1      1 Q_SHORT_SM-EMPTY,SHORT6    I46 @S9S_MB_2U_LIB.S9S_MB_2U(SCH_1):PAGE270

XTAL_CLK_GEN1_25M_X1 @S9S_MB_2U_LIB.S9S_MB_2U(SCH_1):XTAL_CLK_GEN1_25M_X1
   U13  A13 XIN_CLKIN 9SQ440NQQI8-9SQ440NQQI8,SMLF,IA   I180 @S9S_MB_2U_LIB.S9S_MB_2U(SCH_1):PAGE197
 R1724    2      B Q_RES_0402LF-0,5%,1/16W,CHIP,CA   I392 @S9S_MB_2U_LIB.S9S_MB_2U(SCH_1):PAGE197

XTAL_CLK_GEN1_25M_X1_R @S9S_MB_2U_LIB.S9S_MB_2U(SCH_1):XTAL_CLK_GEN1_25M_X1_R
    Y2    1     X1 Q_XTAL_4P_13BI_24GND-25MHZ,SMLB   I391 @S9S_MB_2U_LIB.S9S_MB_2U(SCH_1):PAGE197
 R1724    1      A Q_RES_0402LF-0,5%,1/16W,CHIP,CA   I392 @S9S_MB_2U_LIB.S9S_MB_2U(SCH_1):PAGE197
 C2036    1      A Q_CAP_C0402-8.2PF,50V,0.1P,NP0A   I393 @S9S_MB_2U_LIB.S9S_MB_2U(SCH_1):PAGE197

XTAL_CLK_GEN1_25M_X2 @S9S_MB_2U_LIB.S9S_MB_2U(SCH_1):XTAL_CLK_GEN1_25M_X2
   U13  B11   XOUT 9SQ440NQQI8-9SQ440NQQI8,SMLF,IA   I180 @S9S_MB_2U_LIB.S9S_MB_2U(SCH_1):PAGE197
    Y2    3     X2 Q_XTAL_4P_13BI_24GND-25MHZ,SMLB   I391 @S9S_MB_2U_LIB.S9S_MB_2U(SCH_1):PAGE197
 C2037    1      A Q_CAP_C0402-8.2PF,50V,0.1P,NP0A   I394 @S9S_MB_2U_LIB.S9S_MB_2U(SCH_1):PAGE197

XTAL_PCH_25M_IN @S9S_MB_2U_LIB.S9S_MB_2U(SCH_1):XTAL_PCH_25M_IN
    U4  B23 XTAL_IN EMMITSBURG_REV0P9-GFNOCPU04302A    I78 @S9S_MB_2U_LIB.S9S_MB_2U(SCH_1):PAGE171
 R1720    2      B Q_RES_0402LF-0,5%,1/16W,EMPTY,A   I103 @S9S_MB_2U_LIB.S9S_MB_2U(SCH_1):PAGE171

XTAL_PCH_25M_IN_R @S9S_MB_2U_LIB.S9S_MB_2U(SCH_1):XTAL_PCH_25M_IN_R
    Y7    1     X1 Q_XTAL_4P_13BI_24GND-25MHZ,SMLA    I75 @S9S_MB_2U_LIB.S9S_MB_2U(SCH_1):PAGE171
  C103    1      A Q_CAP_0402-27PF  ,50V ,5% ,EMPA    I77 @S9S_MB_2U_LIB.S9S_MB_2U(SCH_1):PAGE171
 R1316    1      A Q_RES_0603LF-200K,0.1%,1/10W,EA    I92 @S9S_MB_2U_LIB.S9S_MB_2U(SCH_1):PAGE171
 R1720    1      A Q_RES_0402LF-0,5%,1/16W,EMPTY,A   I103 @S9S_MB_2U_LIB.S9S_MB_2U(SCH_1):PAGE171

XTAL_PCH_25M_OUT @S9S_MB_2U_LIB.S9S_MB_2U(SCH_1):XTAL_PCH_25M_OUT
    Y7    3     X2 Q_XTAL_4P_13BI_24GND-25MHZ,SMLA    I75 @S9S_MB_2U_LIB.S9S_MB_2U(SCH_1):PAGE171
  C104    1      A Q_CAP_0402-27PF  ,50V ,5% ,EMPA    I76 @S9S_MB_2U_LIB.S9S_MB_2U(SCH_1):PAGE171
    U4  D23 XTAL_OUT EMMITSBURG_REV0P9-GFNOCPU04302A    I78 @S9S_MB_2U_LIB.S9S_MB_2U(SCH_1):PAGE171
 R1316    2      B Q_RES_0603LF-200K,0.1%,1/10W,EA    I92 @S9S_MB_2U_LIB.S9S_MB_2U(SCH_1):PAGE171

XTAL_PCH_RTC1 @S9S_MB_2U_LIB.S9S_MB_2U(SCH_1):XTAL_PCH_RTC1
    Y1    2      2 Q_CRYSTAL_SMLF-32.768KHZ,IC,BGA    I11 @S9S_MB_2U_LIB.S9S_MB_2U(SCH_1):PAGE171
 C1508    1      A Q_CAP_0402-18PF,50V,5%,C0G,CH0A    I17 @S9S_MB_2U_LIB.S9S_MB_2U(SCH_1):PAGE171
  R120    2      B Q_RES_0603LF-10M,1%,1/10W,CHIPA    I74 @S9S_MB_2U_LIB.S9S_MB_2U(SCH_1):PAGE171
    U4  BE6  RTCX1 EMMITSBURG_REV0P9-GFNOCPU04302A    I78 @S9S_MB_2U_LIB.S9S_MB_2U(SCH_1):PAGE171

XTAL_PCH_RTC2 @S9S_MB_2U_LIB.S9S_MB_2U(SCH_1):XTAL_PCH_RTC2
    U4  BF7  RTCX2 EMMITSBURG_REV0P9-GFNOCPU04302A    I78 @S9S_MB_2U_LIB.S9S_MB_2U(SCH_1):PAGE171
 R1721    2      B Q_RES_0402LF-0,5%,1/16W,CHIP,CA   I104 @S9S_MB_2U_LIB.S9S_MB_2U(SCH_1):PAGE171

XTAL_PCH_RTC2_R @S9S_MB_2U_LIB.S9S_MB_2U(SCH_1):XTAL_PCH_RTC2_R
 C1507    1      A Q_CAP_0402-18PF,50V,5%,C0G,CH0A    I10 @S9S_MB_2U_LIB.S9S_MB_2U(SCH_1):PAGE171
    Y1    1      1 Q_CRYSTAL_SMLF-32.768KHZ,IC,BGA    I11 @S9S_MB_2U_LIB.S9S_MB_2U(SCH_1):PAGE171
  R120    1      A Q_RES_0603LF-10M,1%,1/10W,CHIPA    I74 @S9S_MB_2U_LIB.S9S_MB_2U(SCH_1):PAGE171
 R1721    1      A Q_RES_0402LF-0,5%,1/16W,CHIP,CA   I104 @S9S_MB_2U_LIB.S9S_MB_2U(SCH_1):PAGE171

END GLOBAL SIGNAL CROSS REFERENCE
GLOBAL PART CROSS REFERENCE - 24-Aug-2023 AT 15:36:33

 BT1 CONN2_AAABAT029Y19-CONN2_AAA-BA
     1 P3V_BAT @S9S_MB_2U_LIB.S9S_MB_2U(SCH_1):P3V_BAT    I63 @S9S_MB_2U_LIB.S9S_MB_2U(SCH_1):PAGE177
     2    GND @S9S_MB_2U_LIB.S9S_MB_2U(SCH_1):GND    I63 @S9S_MB_2U_LIB.S9S_MB_2U(SCH_1):PAGE177

  C1 Q_CAP_C0402-10UF,6.3V,20%,X6S,A
     1 P3V3_AUX @S9S_MB_2U_LIB.S9S_MB_2U(SCH_1):P3V3_AUX    I15 @S9S_MB_2U_LIB.S9S_MB_2U(SCH_1):PAGE37
     2    GND @S9S_MB_2U_LIB.S9S_MB_2U(SCH_1):GND    I15 @S9S_MB_2U_LIB.S9S_MB_2U(SCH_1):PAGE37

  C2 Q_CAP_C0402-2.2UF,6.3V,20%,X6SA
     1 P3V3_AUX @S9S_MB_2U_LIB.S9S_MB_2U(SCH_1):P3V3_AUX   I192 @S9S_MB_2U_LIB.S9S_MB_2U(SCH_1):PAGE82
     2    GND @S9S_MB_2U_LIB.S9S_MB_2U(SCH_1):GND   I192 @S9S_MB_2U_LIB.S9S_MB_2U(SCH_1):PAGE82

  C3 Q_CAP_C0805-10UF,16V,10%,X6S,CA
     1 P12V_S3_AUX_CPU0_NVDIMM @S9S_MB_2U_LIB.S9S_MB_2U(SCH_1):P12V_S3_AUX_CPU0_NVDIMM   I188 @S9S_MB_2U_LIB.S9S_MB_2U(SCH_1):PAGE82
     2    GND @S9S_MB_2U_LIB.S9S_MB_2U(SCH_1):GND   I188 @S9S_MB_2U_LIB.S9S_MB_2U(SCH_1):PAGE82

  C4 Q_CAP_C0805-10UF,16V,10%,X6S,CA
     1 P12V_S3_AUX_CPU0_NVDIMM @S9S_MB_2U_LIB.S9S_MB_2U(SCH_1):P12V_S3_AUX_CPU0_NVDIMM   I190 @S9S_MB_2U_LIB.S9S_MB_2U(SCH_1):PAGE82
     2    GND @S9S_MB_2U_LIB.S9S_MB_2U(SCH_1):GND   I190 @S9S_MB_2U_LIB.S9S_MB_2U(SCH_1):PAGE82

  C5 Q_CAP_C0402-2.2UF,6.3V,20%,X6SA
     1 P3V3_AUX @S9S_MB_2U_LIB.S9S_MB_2U(SCH_1):P3V3_AUX   I120 @S9S_MB_2U_LIB.S9S_MB_2U(SCH_1):PAGE83
     2    GND @S9S_MB_2U_LIB.S9S_MB_2U(SCH_1):GND   I120 @S9S_MB_2U_LIB.S9S_MB_2U(SCH_1):PAGE83

  C6 Q_CAP_C0805-10UF,16V,10%,X6S,CA
     1 P12V_S3_AUX_CPU0_NVDIMM @S9S_MB_2U_LIB.S9S_MB_2U(SCH_1):P12V_S3_AUX_CPU0_NVDIMM   I122 @S9S_MB_2U_LIB.S9S_MB_2U(SCH_1):PAGE83
     2    GND @S9S_MB_2U_LIB.S9S_MB_2U(SCH_1):GND   I122 @S9S_MB_2U_LIB.S9S_MB_2U(SCH_1):PAGE83

  C7 Q_CAP_C0805-10UF,16V,10%,X6S,CA
     1 P12V_S3_AUX_CPU0_NVDIMM @S9S_MB_2U_LIB.S9S_MB_2U(SCH_1):P12V_S3_AUX_CPU0_NVDIMM   I144 @S9S_MB_2U_LIB.S9S_MB_2U(SCH_1):PAGE83
     2    GND @S9S_MB_2U_LIB.S9S_MB_2U(SCH_1):GND   I144 @S9S_MB_2U_LIB.S9S_MB_2U(SCH_1):PAGE83

  C8 Q_CAP_C0402-2.2UF,6.3V,20%,X6SA
     1 P3V3_AUX @S9S_MB_2U_LIB.S9S_MB_2U(SCH_1):P3V3_AUX   I121 @S9S_MB_2U_LIB.S9S_MB_2U(SCH_1):PAGE84
     2    GND @S9S_MB_2U_LIB.S9S_MB_2U(SCH_1):GND   I121 @S9S_MB_2U_LIB.S9S_MB_2U(SCH_1):PAGE84

  C9 Q_CAP_C0805-10UF,16V,10%,X6S,CA
     1 P12V_S3_AUX_CPU0_NVDIMM @S9S_MB_2U_LIB.S9S_MB_2U(SCH_1):P12V_S3_AUX_CPU0_NVDIMM   I122 @S9S_MB_2U_LIB.S9S_MB_2U(SCH_1):PAGE84
     2    GND @S9S_MB_2U_LIB.S9S_MB_2U(SCH_1):GND   I122 @S9S_MB_2U_LIB.S9S_MB_2U(SCH_1):PAGE84

 C10 Q_CAP_C0805-10UF,16V,10%,X6S,CA
     1 P12V_S3_AUX_CPU0_NVDIMM @S9S_MB_2U_LIB.S9S_MB_2U(SCH_1):P12V_S3_AUX_CPU0_NVDIMM   I144 @S9S_MB_2U_LIB.S9S_MB_2U(SCH_1):PAGE84
     2    GND @S9S_MB_2U_LIB.S9S_MB_2U(SCH_1):GND   I144 @S9S_MB_2U_LIB.S9S_MB_2U(SCH_1):PAGE84

 C11 Q_CAP_C0402-2.2UF,6.3V,20%,X6SA
     1 P3V3_AUX @S9S_MB_2U_LIB.S9S_MB_2U(SCH_1):P3V3_AUX   I121 @S9S_MB_2U_LIB.S9S_MB_2U(SCH_1):PAGE85
     2    GND @S9S_MB_2U_LIB.S9S_MB_2U(SCH_1):GND   I121 @S9S_MB_2U_LIB.S9S_MB_2U(SCH_1):PAGE85

 C12 Q_CAP_C0805-10UF,16V,10%,X6S,CA
     1 P12V_S3_AUX_CPU0_NVDIMM @S9S_MB_2U_LIB.S9S_MB_2U(SCH_1):P12V_S3_AUX_CPU0_NVDIMM   I125 @S9S_MB_2U_LIB.S9S_MB_2U(SCH_1):PAGE85
     2    GND @S9S_MB_2U_LIB.S9S_MB_2U(SCH_1):GND   I125 @S9S_MB_2U_LIB.S9S_MB_2U(SCH_1):PAGE85

 C13 Q_CAP_C0805-10UF,16V,10%,X6S,CA
     1 P12V_S3_AUX_CPU0_NVDIMM @S9S_MB_2U_LIB.S9S_MB_2U(SCH_1):P12V_S3_AUX_CPU0_NVDIMM   I127 @S9S_MB_2U_LIB.S9S_MB_2U(SCH_1):PAGE85
     2    GND @S9S_MB_2U_LIB.S9S_MB_2U(SCH_1):GND   I127 @S9S_MB_2U_LIB.S9S_MB_2U(SCH_1):PAGE85

 C14 Q_CAP_C0402-2.2UF,6.3V,20%,X6SA
     1 P3V3_AUX @S9S_MB_2U_LIB.S9S_MB_2U(SCH_1):P3V3_AUX   I120 @S9S_MB_2U_LIB.S9S_MB_2U(SCH_1):PAGE86
     2    GND @S9S_MB_2U_LIB.S9S_MB_2U(SCH_1):GND   I120 @S9S_MB_2U_LIB.S9S_MB_2U(SCH_1):PAGE86

 C15 Q_CAP_C0805-10UF,16V,10%,X6S,CA
     1 P12V_S3_AUX_CPU0_NVDIMM @S9S_MB_2U_LIB.S9S_MB_2U(SCH_1):P12V_S3_AUX_CPU0_NVDIMM   I121 @S9S_MB_2U_LIB.S9S_MB_2U(SCH_1):PAGE86
     2    GND @S9S_MB_2U_LIB.S9S_MB_2U(SCH_1):GND   I121 @S9S_MB_2U_LIB.S9S_MB_2U(SCH_1):PAGE86

 C16 Q_CAP_C0805-10UF,16V,10%,X6S,CA
     1 P12V_S3_AUX_CPU0_NVDIMM @S9S_MB_2U_LIB.S9S_MB_2U(SCH_1):P12V_S3_AUX_CPU0_NVDIMM   I123 @S9S_MB_2U_LIB.S9S_MB_2U(SCH_1):PAGE86
     2    GND @S9S_MB_2U_LIB.S9S_MB_2U(SCH_1):GND   I123 @S9S_MB_2U_LIB.S9S_MB_2U(SCH_1):PAGE86

 C17 Q_CAP_C0402-2.2UF,6.3V,20%,X6SA
     1 P3V3_AUX @S9S_MB_2U_LIB.S9S_MB_2U(SCH_1):P3V3_AUX   I120 @S9S_MB_2U_LIB.S9S_MB_2U(SCH_1):PAGE87
     2    GND @S9S_MB_2U_LIB.S9S_MB_2U(SCH_1):GND   I120 @S9S_MB_2U_LIB.S9S_MB_2U(SCH_1):PAGE87

 C18 Q_CAP_C0805-10UF,16V,10%,X6S,CA
     1 P12V_S3_AUX_CPU0_NVDIMM @S9S_MB_2U_LIB.S9S_MB_2U(SCH_1):P12V_S3_AUX_CPU0_NVDIMM   I124 @S9S_MB_2U_LIB.S9S_MB_2U(SCH_1):PAGE87
     2    GND @S9S_MB_2U_LIB.S9S_MB_2U(SCH_1):GND   I124 @S9S_MB_2U_LIB.S9S_MB_2U(SCH_1):PAGE87

 C19 Q_CAP_C0805-10UF,16V,10%,X6S,CA
     1 P12V_S3_AUX_CPU0_NVDIMM @S9S_MB_2U_LIB.S9S_MB_2U(SCH_1):P12V_S3_AUX_CPU0_NVDIMM   I127 @S9S_MB_2U_LIB.S9S_MB_2U(SCH_1):PAGE87
     2    GND @S9S_MB_2U_LIB.S9S_MB_2U(SCH_1):GND   I127 @S9S_MB_2U_LIB.S9S_MB_2U(SCH_1):PAGE87

 C20 Q_CAP_C0402-2.2UF,6.3V,20%,X6SA
     1 P3V3_AUX @S9S_MB_2U_LIB.S9S_MB_2U(SCH_1):P3V3_AUX   I123 @S9S_MB_2U_LIB.S9S_MB_2U(SCH_1):PAGE88
     2    GND @S9S_MB_2U_LIB.S9S_MB_2U(SCH_1):GND   I123 @S9S_MB_2U_LIB.S9S_MB_2U(SCH_1):PAGE88

 C21 Q_CAP_C0805-10UF,16V,10%,X6S,CA
     1 P12V_S3_AUX_CPU0_NVDIMM @S9S_MB_2U_LIB.S9S_MB_2U(SCH_1):P12V_S3_AUX_CPU0_NVDIMM   I126 @S9S_MB_2U_LIB.S9S_MB_2U(SCH_1):PAGE88
     2    GND @S9S_MB_2U_LIB.S9S_MB_2U(SCH_1):GND   I126 @S9S_MB_2U_LIB.S9S_MB_2U(SCH_1):PAGE88

 C22 Q_CAP_C0805-10UF,16V,10%,X6S,CA
     1 P12V_S3_AUX_CPU0_NVDIMM @S9S_MB_2U_LIB.S9S_MB_2U(SCH_1):P12V_S3_AUX_CPU0_NVDIMM   I166 @S9S_MB_2U_LIB.S9S_MB_2U(SCH_1):PAGE88
     2    GND @S9S_MB_2U_LIB.S9S_MB_2U(SCH_1):GND   I166 @S9S_MB_2U_LIB.S9S_MB_2U(SCH_1):PAGE88

 C23 Q_CAP_C0402-2.2UF,6.3V,20%,X6SA
     1 P3V3_AUX @S9S_MB_2U_LIB.S9S_MB_2U(SCH_1):P3V3_AUX   I121 @S9S_MB_2U_LIB.S9S_MB_2U(SCH_1):PAGE89
     2    GND @S9S_MB_2U_LIB.S9S_MB_2U(SCH_1):GND   I121 @S9S_MB_2U_LIB.S9S_MB_2U(SCH_1):PAGE89

 C24 Q_CAP_C0805-10UF,16V,10%,X6S,CA
     1 P12V_S3_AUX_CPU0_NVDIMM @S9S_MB_2U_LIB.S9S_MB_2U(SCH_1):P12V_S3_AUX_CPU0_NVDIMM   I125 @S9S_MB_2U_LIB.S9S_MB_2U(SCH_1):PAGE89
     2    GND @S9S_MB_2U_LIB.S9S_MB_2U(SCH_1):GND   I125 @S9S_MB_2U_LIB.S9S_MB_2U(SCH_1):PAGE89

 C25 Q_CAP_C0805-10UF,16V,10%,X6S,CA
     1 P12V_S3_AUX_CPU0_NVDIMM @S9S_MB_2U_LIB.S9S_MB_2U(SCH_1):P12V_S3_AUX_CPU0_NVDIMM   I127 @S9S_MB_2U_LIB.S9S_MB_2U(SCH_1):PAGE89
     2    GND @S9S_MB_2U_LIB.S9S_MB_2U(SCH_1):GND   I127 @S9S_MB_2U_LIB.S9S_MB_2U(SCH_1):PAGE89

 C26 Q_CAP_C0402-2.2UF,6.3V,20%,X6SA
     1 P3V3_AUX @S9S_MB_2U_LIB.S9S_MB_2U(SCH_1):P3V3_AUX   I122 @S9S_MB_2U_LIB.S9S_MB_2U(SCH_1):PAGE90
     2    GND @S9S_MB_2U_LIB.S9S_MB_2U(SCH_1):GND   I122 @S9S_MB_2U_LIB.S9S_MB_2U(SCH_1):PAGE90

 C27 Q_CAP_C0805-10UF,16V,10%,X6S,CA
     1 P12V_S3_AUX_CPU0_NVDIMM @S9S_MB_2U_LIB.S9S_MB_2U(SCH_1):P12V_S3_AUX_CPU0_NVDIMM   I123 @S9S_MB_2U_LIB.S9S_MB_2U(SCH_1):PAGE90
     2    GND @S9S_MB_2U_LIB.S9S_MB_2U(SCH_1):GND   I123 @S9S_MB_2U_LIB.S9S_MB_2U(SCH_1):PAGE90

 C28 Q_CAP_C0805-10UF,16V,10%,X6S,CA
     1 P12V_S3_AUX_CPU0_NVDIMM @S9S_MB_2U_LIB.S9S_MB_2U(SCH_1):P12V_S3_AUX_CPU0_NVDIMM   I145 @S9S_MB_2U_LIB.S9S_MB_2U(SCH_1):PAGE90
     2    GND @S9S_MB_2U_LIB.S9S_MB_2U(SCH_1):GND   I145 @S9S_MB_2U_LIB.S9S_MB_2U(SCH_1):PAGE90

 C29 Q_CAP_C0402-2.2UF,6.3V,20%,X6SA
     1 P3V3_AUX @S9S_MB_2U_LIB.S9S_MB_2U(SCH_1):P3V3_AUX   I123 @S9S_MB_2U_LIB.S9S_MB_2U(SCH_1):PAGE91
     2    GND @S9S_MB_2U_LIB.S9S_MB_2U(SCH_1):GND   I123 @S9S_MB_2U_LIB.S9S_MB_2U(SCH_1):PAGE91

 C30 Q_CAP_C0805-10UF,16V,10%,X6S,CA
     1 P12V_S3_AUX_CPU0_NVDIMM @S9S_MB_2U_LIB.S9S_MB_2U(SCH_1):P12V_S3_AUX_CPU0_NVDIMM   I124 @S9S_MB_2U_LIB.S9S_MB_2U(SCH_1):PAGE91
     2    GND @S9S_MB_2U_LIB.S9S_MB_2U(SCH_1):GND   I124 @S9S_MB_2U_LIB.S9S_MB_2U(SCH_1):PAGE91

 C31 Q_CAP_C0805-10UF,16V,10%,X6S,CA
     1 P12V_S3_AUX_CPU0_NVDIMM @S9S_MB_2U_LIB.S9S_MB_2U(SCH_1):P12V_S3_AUX_CPU0_NVDIMM   I146 @S9S_MB_2U_LIB.S9S_MB_2U(SCH_1):PAGE91
     2    GND @S9S_MB_2U_LIB.S9S_MB_2U(SCH_1):GND   I146 @S9S_MB_2U_LIB.S9S_MB_2U(SCH_1):PAGE91

 C32 Q_CAP_C0402-2.2UF,6.3V,20%,X6SA
     1 P3V3_AUX @S9S_MB_2U_LIB.S9S_MB_2U(SCH_1):P3V3_AUX   I122 @S9S_MB_2U_LIB.S9S_MB_2U(SCH_1):PAGE92
     2    GND @S9S_MB_2U_LIB.S9S_MB_2U(SCH_1):GND   I122 @S9S_MB_2U_LIB.S9S_MB_2U(SCH_1):PAGE92

 C33 Q_CAP_C0805-10UF,16V,10%,X6S,CA
     1 P12V_S3_AUX_CPU0_NVDIMM @S9S_MB_2U_LIB.S9S_MB_2U(SCH_1):P12V_S3_AUX_CPU0_NVDIMM   I127 @S9S_MB_2U_LIB.S9S_MB_2U(SCH_1):PAGE92
     2    GND @S9S_MB_2U_LIB.S9S_MB_2U(SCH_1):GND   I127 @S9S_MB_2U_LIB.S9S_MB_2U(SCH_1):PAGE92

 C34 Q_CAP_C0805-10UF,16V,10%,X6S,CA
     1 P12V_S3_AUX_CPU0_NVDIMM @S9S_MB_2U_LIB.S9S_MB_2U(SCH_1):P12V_S3_AUX_CPU0_NVDIMM   I130 @S9S_MB_2U_LIB.S9S_MB_2U(SCH_1):PAGE92
     2    GND @S9S_MB_2U_LIB.S9S_MB_2U(SCH_1):GND   I130 @S9S_MB_2U_LIB.S9S_MB_2U(SCH_1):PAGE92

 C35 Q_CAP_C0402-2.2UF,6.3V,20%,X6SA
     1 P3V3_AUX @S9S_MB_2U_LIB.S9S_MB_2U(SCH_1):P3V3_AUX   I122 @S9S_MB_2U_LIB.S9S_MB_2U(SCH_1):PAGE93
     2    GND @S9S_MB_2U_LIB.S9S_MB_2U(SCH_1):GND   I122 @S9S_MB_2U_LIB.S9S_MB_2U(SCH_1):PAGE93

 C36 Q_CAP_C0805-10UF,16V,10%,X6S,CA
     1 P12V_S3_AUX_CPU0_NVDIMM @S9S_MB_2U_LIB.S9S_MB_2U(SCH_1):P12V_S3_AUX_CPU0_NVDIMM   I126 @S9S_MB_2U_LIB.S9S_MB_2U(SCH_1):PAGE93
     2    GND @S9S_MB_2U_LIB.S9S_MB_2U(SCH_1):GND   I126 @S9S_MB_2U_LIB.S9S_MB_2U(SCH_1):PAGE93

 C37 Q_CAP_C0805-10UF,16V,10%,X6S,CA
     1 P12V_S3_AUX_CPU0_NVDIMM @S9S_MB_2U_LIB.S9S_MB_2U(SCH_1):P12V_S3_AUX_CPU0_NVDIMM   I128 @S9S_MB_2U_LIB.S9S_MB_2U(SCH_1):PAGE93
     2    GND @S9S_MB_2U_LIB.S9S_MB_2U(SCH_1):GND   I128 @S9S_MB_2U_LIB.S9S_MB_2U(SCH_1):PAGE93

 C38 Q_CAP_C0402-2.2UF,6.3V,20%,X6SA
     1 P3V3_AUX @S9S_MB_2U_LIB.S9S_MB_2U(SCH_1):P3V3_AUX   I123 @S9S_MB_2U_LIB.S9S_MB_2U(SCH_1):PAGE94
     2    GND @S9S_MB_2U_LIB.S9S_MB_2U(SCH_1):GND   I123 @S9S_MB_2U_LIB.S9S_MB_2U(SCH_1):PAGE94

 C39 Q_CAP_C0805-10UF,16V,10%,X6S,CA
     1 P12V_S3_AUX_CPU0_NVDIMM @S9S_MB_2U_LIB.S9S_MB_2U(SCH_1):P12V_S3_AUX_CPU0_NVDIMM   I125 @S9S_MB_2U_LIB.S9S_MB_2U(SCH_1):PAGE94
     2    GND @S9S_MB_2U_LIB.S9S_MB_2U(SCH_1):GND   I125 @S9S_MB_2U_LIB.S9S_MB_2U(SCH_1):PAGE94

 C40 Q_CAP_C0805-10UF,16V,10%,X6S,CA
     1 P12V_S3_AUX_CPU0_NVDIMM @S9S_MB_2U_LIB.S9S_MB_2U(SCH_1):P12V_S3_AUX_CPU0_NVDIMM   I162 @S9S_MB_2U_LIB.S9S_MB_2U(SCH_1):PAGE94
     2    GND @S9S_MB_2U_LIB.S9S_MB_2U(SCH_1):GND   I162 @S9S_MB_2U_LIB.S9S_MB_2U(SCH_1):PAGE94

 C41 Q_CAP_C0402-2.2UF,6.3V,20%,X6SA
     1 P3V3_AUX @S9S_MB_2U_LIB.S9S_MB_2U(SCH_1):P3V3_AUX   I121 @S9S_MB_2U_LIB.S9S_MB_2U(SCH_1):PAGE95
     2    GND @S9S_MB_2U_LIB.S9S_MB_2U(SCH_1):GND   I121 @S9S_MB_2U_LIB.S9S_MB_2U(SCH_1):PAGE95

 C42 Q_CAP_C0805-10UF,16V,10%,X6S,CA
     1 P12V_S3_AUX_CPU0_NVDIMM @S9S_MB_2U_LIB.S9S_MB_2U(SCH_1):P12V_S3_AUX_CPU0_NVDIMM   I125 @S9S_MB_2U_LIB.S9S_MB_2U(SCH_1):PAGE95
     2    GND @S9S_MB_2U_LIB.S9S_MB_2U(SCH_1):GND   I125 @S9S_MB_2U_LIB.S9S_MB_2U(SCH_1):PAGE95

 C43 Q_CAP_C0805-10UF,16V,10%,X6S,CA
     1 P12V_S3_AUX_CPU0_NVDIMM @S9S_MB_2U_LIB.S9S_MB_2U(SCH_1):P12V_S3_AUX_CPU0_NVDIMM   I128 @S9S_MB_2U_LIB.S9S_MB_2U(SCH_1):PAGE95
     2    GND @S9S_MB_2U_LIB.S9S_MB_2U(SCH_1):GND   I128 @S9S_MB_2U_LIB.S9S_MB_2U(SCH_1):PAGE95

 C44 Q_CAP_C0402-2.2UF,6.3V,20%,X6SA
     1 P3V3_AUX @S9S_MB_2U_LIB.S9S_MB_2U(SCH_1):P3V3_AUX   I121 @S9S_MB_2U_LIB.S9S_MB_2U(SCH_1):PAGE96
     2    GND @S9S_MB_2U_LIB.S9S_MB_2U(SCH_1):GND   I121 @S9S_MB_2U_LIB.S9S_MB_2U(SCH_1):PAGE96

 C45 Q_CAP_C0805-10UF,16V,10%,X6S,CA
     1 P12V_S3_AUX_CPU0_NVDIMM @S9S_MB_2U_LIB.S9S_MB_2U(SCH_1):P12V_S3_AUX_CPU0_NVDIMM   I125 @S9S_MB_2U_LIB.S9S_MB_2U(SCH_1):PAGE96
     2    GND @S9S_MB_2U_LIB.S9S_MB_2U(SCH_1):GND   I125 @S9S_MB_2U_LIB.S9S_MB_2U(SCH_1):PAGE96

 C46 Q_CAP_C0805-10UF,16V,10%,X6S,CA
     1 P12V_S3_AUX_CPU0_NVDIMM @S9S_MB_2U_LIB.S9S_MB_2U(SCH_1):P12V_S3_AUX_CPU0_NVDIMM   I127 @S9S_MB_2U_LIB.S9S_MB_2U(SCH_1):PAGE96
     2    GND @S9S_MB_2U_LIB.S9S_MB_2U(SCH_1):GND   I127 @S9S_MB_2U_LIB.S9S_MB_2U(SCH_1):PAGE96

 C47 Q_CAP_C0402-2.2UF,6.3V,20%,X6SA
     1 P3V3_AUX @S9S_MB_2U_LIB.S9S_MB_2U(SCH_1):P3V3_AUX    I56 @S9S_MB_2U_LIB.S9S_MB_2U(SCH_1):PAGE97
     2    GND @S9S_MB_2U_LIB.S9S_MB_2U(SCH_1):GND    I56 @S9S_MB_2U_LIB.S9S_MB_2U(SCH_1):PAGE97

 C48 Q_CAP_C0805-10UF,16V,10%,X6S,CA
     1 P12V_S3_AUX_CPU0_NVDIMM @S9S_MB_2U_LIB.S9S_MB_2U(SCH_1):P12V_S3_AUX_CPU0_NVDIMM    I59 @S9S_MB_2U_LIB.S9S_MB_2U(SCH_1):PAGE97
     2    GND @S9S_MB_2U_LIB.S9S_MB_2U(SCH_1):GND    I59 @S9S_MB_2U_LIB.S9S_MB_2U(SCH_1):PAGE97

 C49 Q_CAP_C0805-10UF,16V,10%,X6S,CA
     1 P12V_S3_AUX_CPU0_NVDIMM @S9S_MB_2U_LIB.S9S_MB_2U(SCH_1):P12V_S3_AUX_CPU0_NVDIMM    I62 @S9S_MB_2U_LIB.S9S_MB_2U(SCH_1):PAGE97
     2    GND @S9S_MB_2U_LIB.S9S_MB_2U(SCH_1):GND    I62 @S9S_MB_2U_LIB.S9S_MB_2U(SCH_1):PAGE97

 C50 Q_CAP_C0402-2.2UF,6.3V,20%,X6SA
     1 P3V3_AUX @S9S_MB_2U_LIB.S9S_MB_2U(SCH_1):P3V3_AUX   I122 @S9S_MB_2U_LIB.S9S_MB_2U(SCH_1):PAGE98
     2    GND @S9S_MB_2U_LIB.S9S_MB_2U(SCH_1):GND   I122 @S9S_MB_2U_LIB.S9S_MB_2U(SCH_1):PAGE98

 C51 Q_CAP_C0805-10UF,16V,10%,X6S,CA
     1 P12V_S3_AUX_CPU1_NVDIMM @S9S_MB_2U_LIB.S9S_MB_2U(SCH_1):P12V_S3_AUX_CPU1_NVDIMM   I123 @S9S_MB_2U_LIB.S9S_MB_2U(SCH_1):PAGE98
     2    GND @S9S_MB_2U_LIB.S9S_MB_2U(SCH_1):GND   I123 @S9S_MB_2U_LIB.S9S_MB_2U(SCH_1):PAGE98

 C52 Q_CAP_C0805-10UF,16V,10%,X6S,CA
     1 P12V_S3_AUX_CPU1_NVDIMM @S9S_MB_2U_LIB.S9S_MB_2U(SCH_1):P12V_S3_AUX_CPU1_NVDIMM   I145 @S9S_MB_2U_LIB.S9S_MB_2U(SCH_1):PAGE98
     2    GND @S9S_MB_2U_LIB.S9S_MB_2U(SCH_1):GND   I145 @S9S_MB_2U_LIB.S9S_MB_2U(SCH_1):PAGE98

 C53 Q_CAP_C0402-2.2UF,6.3V,20%,X6SA
     1 P3V3_AUX @S9S_MB_2U_LIB.S9S_MB_2U(SCH_1):P3V3_AUX   I122 @S9S_MB_2U_LIB.S9S_MB_2U(SCH_1):PAGE99
     2    GND @S9S_MB_2U_LIB.S9S_MB_2U(SCH_1):GND   I122 @S9S_MB_2U_LIB.S9S_MB_2U(SCH_1):PAGE99

 C54 Q_CAP_C0805-10UF,16V,10%,X6S,CA
     1 P12V_S3_AUX_CPU1_NVDIMM @S9S_MB_2U_LIB.S9S_MB_2U(SCH_1):P12V_S3_AUX_CPU1_NVDIMM   I126 @S9S_MB_2U_LIB.S9S_MB_2U(SCH_1):PAGE99
     2    GND @S9S_MB_2U_LIB.S9S_MB_2U(SCH_1):GND   I126 @S9S_MB_2U_LIB.S9S_MB_2U(SCH_1):PAGE99

 C55 Q_CAP_C0805-10UF,16V,10%,X6S,CA
     1 P12V_S3_AUX_CPU1_NVDIMM @S9S_MB_2U_LIB.S9S_MB_2U(SCH_1):P12V_S3_AUX_CPU1_NVDIMM   I128 @S9S_MB_2U_LIB.S9S_MB_2U(SCH_1):PAGE99
     2    GND @S9S_MB_2U_LIB.S9S_MB_2U(SCH_1):GND   I128 @S9S_MB_2U_LIB.S9S_MB_2U(SCH_1):PAGE99

 C56 Q_CAP_C0402-2.2UF,6.3V,20%,X6SA
     1 P3V3_AUX @S9S_MB_2U_LIB.S9S_MB_2U(SCH_1):P3V3_AUX   I121 @S9S_MB_2U_LIB.S9S_MB_2U(SCH_1):PAGE100
     2    GND @S9S_MB_2U_LIB.S9S_MB_2U(SCH_1):GND   I121 @S9S_MB_2U_LIB.S9S_MB_2U(SCH_1):PAGE100

 C57 Q_CAP_C0805-10UF,16V,10%,X6S,CA
     1 P12V_S3_AUX_CPU1_NVDIMM @S9S_MB_2U_LIB.S9S_MB_2U(SCH_1):P12V_S3_AUX_CPU1_NVDIMM   I122 @S9S_MB_2U_LIB.S9S_MB_2U(SCH_1):PAGE100
     2    GND @S9S_MB_2U_LIB.S9S_MB_2U(SCH_1):GND   I122 @S9S_MB_2U_LIB.S9S_MB_2U(SCH_1):PAGE100

 C58 Q_CAP_C0805-10UF,16V,10%,X6S,CA
     1 P12V_S3_AUX_CPU1_NVDIMM @S9S_MB_2U_LIB.S9S_MB_2U(SCH_1):P12V_S3_AUX_CPU1_NVDIMM   I124 @S9S_MB_2U_LIB.S9S_MB_2U(SCH_1):PAGE100
     2    GND @S9S_MB_2U_LIB.S9S_MB_2U(SCH_1):GND   I124 @S9S_MB_2U_LIB.S9S_MB_2U(SCH_1):PAGE100

 C59 Q_CAP_C0402-2.2UF,6.3V,20%,X6SA
     1 P3V3_AUX @S9S_MB_2U_LIB.S9S_MB_2U(SCH_1):P3V3_AUX   I121 @S9S_MB_2U_LIB.S9S_MB_2U(SCH_1):PAGE101
     2    GND @S9S_MB_2U_LIB.S9S_MB_2U(SCH_1):GND   I121 @S9S_MB_2U_LIB.S9S_MB_2U(SCH_1):PAGE101

 C60 Q_CAP_C0805-10UF,16V,10%,X6S,CA
     1 P12V_S3_AUX_CPU1_NVDIMM @S9S_MB_2U_LIB.S9S_MB_2U(SCH_1):P12V_S3_AUX_CPU1_NVDIMM   I125 @S9S_MB_2U_LIB.S9S_MB_2U(SCH_1):PAGE101
     2    GND @S9S_MB_2U_LIB.S9S_MB_2U(SCH_1):GND   I125 @S9S_MB_2U_LIB.S9S_MB_2U(SCH_1):PAGE101

 C61 Q_CAP_C0805-10UF,16V,10%,X6S,CA
     1 P12V_S3_AUX_CPU1_NVDIMM @S9S_MB_2U_LIB.S9S_MB_2U(SCH_1):P12V_S3_AUX_CPU1_NVDIMM   I127 @S9S_MB_2U_LIB.S9S_MB_2U(SCH_1):PAGE101
     2    GND @S9S_MB_2U_LIB.S9S_MB_2U(SCH_1):GND   I127 @S9S_MB_2U_LIB.S9S_MB_2U(SCH_1):PAGE101

 C62 Q_CAP_C0402-2.2UF,6.3V,20%,X6SA
     1 P3V3_AUX @S9S_MB_2U_LIB.S9S_MB_2U(SCH_1):P3V3_AUX   I124 @S9S_MB_2U_LIB.S9S_MB_2U(SCH_1):PAGE102
     2    GND @S9S_MB_2U_LIB.S9S_MB_2U(SCH_1):GND   I124 @S9S_MB_2U_LIB.S9S_MB_2U(SCH_1):PAGE102

 C63 Q_CAP_C0805-10UF,16V,10%,X6S,CA
     1 P12V_S3_AUX_CPU1_NVDIMM @S9S_MB_2U_LIB.S9S_MB_2U(SCH_1):P12V_S3_AUX_CPU1_NVDIMM   I127 @S9S_MB_2U_LIB.S9S_MB_2U(SCH_1):PAGE102
     2    GND @S9S_MB_2U_LIB.S9S_MB_2U(SCH_1):GND   I127 @S9S_MB_2U_LIB.S9S_MB_2U(SCH_1):PAGE102

 C64 Q_CAP_C0805-10UF,16V,10%,X6S,CA
     1 P12V_S3_AUX_CPU1_NVDIMM @S9S_MB_2U_LIB.S9S_MB_2U(SCH_1):P12V_S3_AUX_CPU1_NVDIMM   I167 @S9S_MB_2U_LIB.S9S_MB_2U(SCH_1):PAGE102
     2    GND @S9S_MB_2U_LIB.S9S_MB_2U(SCH_1):GND   I167 @S9S_MB_2U_LIB.S9S_MB_2U(SCH_1):PAGE102

 C65 Q_CAP_C0402-2.2UF,6.3V,20%,X6SA
     1 P3V3_AUX @S9S_MB_2U_LIB.S9S_MB_2U(SCH_1):P3V3_AUX   I122 @S9S_MB_2U_LIB.S9S_MB_2U(SCH_1):PAGE103
     2    GND @S9S_MB_2U_LIB.S9S_MB_2U(SCH_1):GND   I122 @S9S_MB_2U_LIB.S9S_MB_2U(SCH_1):PAGE103

 C66 Q_CAP_C0805-10UF,16V,10%,X6S,CA
     1 P12V_S3_AUX_CPU1_NVDIMM @S9S_MB_2U_LIB.S9S_MB_2U(SCH_1):P12V_S3_AUX_CPU1_NVDIMM   I126 @S9S_MB_2U_LIB.S9S_MB_2U(SCH_1):PAGE103
     2    GND @S9S_MB_2U_LIB.S9S_MB_2U(SCH_1):GND   I126 @S9S_MB_2U_LIB.S9S_MB_2U(SCH_1):PAGE103

 C67 Q_CAP_C0805-10UF,16V,10%,X6S,CA
     1 P12V_S3_AUX_CPU1_NVDIMM @S9S_MB_2U_LIB.S9S_MB_2U(SCH_1):P12V_S3_AUX_CPU1_NVDIMM   I128 @S9S_MB_2U_LIB.S9S_MB_2U(SCH_1):PAGE103
     2    GND @S9S_MB_2U_LIB.S9S_MB_2U(SCH_1):GND   I128 @S9S_MB_2U_LIB.S9S_MB_2U(SCH_1):PAGE103

 C68 Q_CAP_C0402-2.2UF,6.3V,20%,X6SA
     1 P3V3_AUX @S9S_MB_2U_LIB.S9S_MB_2U(SCH_1):P3V3_AUX   I122 @S9S_MB_2U_LIB.S9S_MB_2U(SCH_1):PAGE104
     2    GND @S9S_MB_2U_LIB.S9S_MB_2U(SCH_1):GND   I122 @S9S_MB_2U_LIB.S9S_MB_2U(SCH_1):PAGE104

 C69 Q_CAP_C0805-10UF,16V,10%,X6S,CA
     1 P12V_S3_AUX_CPU1_NVDIMM @S9S_MB_2U_LIB.S9S_MB_2U(SCH_1):P12V_S3_AUX_CPU1_NVDIMM   I127 @S9S_MB_2U_LIB.S9S_MB_2U(SCH_1):PAGE104
     2    GND @S9S_MB_2U_LIB.S9S_MB_2U(SCH_1):GND   I127 @S9S_MB_2U_LIB.S9S_MB_2U(SCH_1):PAGE104

 C70 Q_CAP_C0805-10UF,16V,10%,X6S,CA
     1 P12V_S3_AUX_CPU1_NVDIMM @S9S_MB_2U_LIB.S9S_MB_2U(SCH_1):P12V_S3_AUX_CPU1_NVDIMM   I129 @S9S_MB_2U_LIB.S9S_MB_2U(SCH_1):PAGE104
     2    GND @S9S_MB_2U_LIB.S9S_MB_2U(SCH_1):GND   I129 @S9S_MB_2U_LIB.S9S_MB_2U(SCH_1):PAGE104

 C71 Q_CAP_C0402-10UF,6.3V,20%,X6S,A
     1 P3V3_AUX @S9S_MB_2U_LIB.S9S_MB_2U(SCH_1):P3V3_AUX     I4 @S9S_MB_2U_LIB.S9S_MB_2U(SCH_1):PAGE68
     2    GND @S9S_MB_2U_LIB.S9S_MB_2U(SCH_1):GND     I4 @S9S_MB_2U_LIB.S9S_MB_2U(SCH_1):PAGE68

 C72 Q_CAP_C0402-2.2UF,6.3V,20%,X6SA
     1 P3V3_AUX @S9S_MB_2U_LIB.S9S_MB_2U(SCH_1):P3V3_AUX   I116 @S9S_MB_2U_LIB.S9S_MB_2U(SCH_1):PAGE113
     2    GND @S9S_MB_2U_LIB.S9S_MB_2U(SCH_1):GND   I116 @S9S_MB_2U_LIB.S9S_MB_2U(SCH_1):PAGE113

 C73 Q_CAP_C0805-10UF,16V,10%,X6S,CA
     1 P12V_S3_AUX_CPU1_NVDIMM @S9S_MB_2U_LIB.S9S_MB_2U(SCH_1):P12V_S3_AUX_CPU1_NVDIMM   I120 @S9S_MB_2U_LIB.S9S_MB_2U(SCH_1):PAGE113
     2    GND @S9S_MB_2U_LIB.S9S_MB_2U(SCH_1):GND   I120 @S9S_MB_2U_LIB.S9S_MB_2U(SCH_1):PAGE113

 C74 Q_CAP_C0805-10UF,16V,10%,X6S,CA
     1 P12V_S3_AUX_CPU1_NVDIMM @S9S_MB_2U_LIB.S9S_MB_2U(SCH_1):P12V_S3_AUX_CPU1_NVDIMM   I122 @S9S_MB_2U_LIB.S9S_MB_2U(SCH_1):PAGE113
     2    GND @S9S_MB_2U_LIB.S9S_MB_2U(SCH_1):GND   I122 @S9S_MB_2U_LIB.S9S_MB_2U(SCH_1):PAGE113

 C75 Q_CAP_C0402-2.2UF,6.3V,20%,X6SA
     1 P3V3_AUX @S9S_MB_2U_LIB.S9S_MB_2U(SCH_1):P3V3_AUX   I124 @S9S_MB_2U_LIB.S9S_MB_2U(SCH_1):PAGE112
     2    GND @S9S_MB_2U_LIB.S9S_MB_2U(SCH_1):GND   I124 @S9S_MB_2U_LIB.S9S_MB_2U(SCH_1):PAGE112

 C76 Q_CAP_C0805-10UF,16V,10%,X6S,CA
     1 P12V_S3_AUX_CPU1_NVDIMM @S9S_MB_2U_LIB.S9S_MB_2U(SCH_1):P12V_S3_AUX_CPU1_NVDIMM   I125 @S9S_MB_2U_LIB.S9S_MB_2U(SCH_1):PAGE112
     2    GND @S9S_MB_2U_LIB.S9S_MB_2U(SCH_1):GND   I125 @S9S_MB_2U_LIB.S9S_MB_2U(SCH_1):PAGE112

 C77 Q_CAP_C0805-10UF,16V,10%,X6S,CA
     1 P12V_S3_AUX_CPU1_NVDIMM @S9S_MB_2U_LIB.S9S_MB_2U(SCH_1):P12V_S3_AUX_CPU1_NVDIMM   I126 @S9S_MB_2U_LIB.S9S_MB_2U(SCH_1):PAGE112
     2    GND @S9S_MB_2U_LIB.S9S_MB_2U(SCH_1):GND   I126 @S9S_MB_2U_LIB.S9S_MB_2U(SCH_1):PAGE112

 C78 Q_CAP_C0402-2.2UF,6.3V,20%,X6SA
     1 P3V3_AUX @S9S_MB_2U_LIB.S9S_MB_2U(SCH_1):P3V3_AUX    I54 @S9S_MB_2U_LIB.S9S_MB_2U(SCH_1):PAGE111
     2    GND @S9S_MB_2U_LIB.S9S_MB_2U(SCH_1):GND    I54 @S9S_MB_2U_LIB.S9S_MB_2U(SCH_1):PAGE111

 C79 Q_CAP_C0805-10UF,16V,10%,X6S,CA
     1 P12V_S3_AUX_CPU1_NVDIMM @S9S_MB_2U_LIB.S9S_MB_2U(SCH_1):P12V_S3_AUX_CPU1_NVDIMM    I56 @S9S_MB_2U_LIB.S9S_MB_2U(SCH_1):PAGE111
     2    GND @S9S_MB_2U_LIB.S9S_MB_2U(SCH_1):GND    I56 @S9S_MB_2U_LIB.S9S_MB_2U(SCH_1):PAGE111

 C80 Q_CAP_C0805-10UF,16V,10%,X6S,CA
     1 P12V_S3_AUX_CPU1_NVDIMM @S9S_MB_2U_LIB.S9S_MB_2U(SCH_1):P12V_S3_AUX_CPU1_NVDIMM    I59 @S9S_MB_2U_LIB.S9S_MB_2U(SCH_1):PAGE111
     2    GND @S9S_MB_2U_LIB.S9S_MB_2U(SCH_1):GND    I59 @S9S_MB_2U_LIB.S9S_MB_2U(SCH_1):PAGE111

 C81 Q_CAP_C0402-2.2UF,6.3V,20%,X6SA
     1 P3V3_AUX @S9S_MB_2U_LIB.S9S_MB_2U(SCH_1):P3V3_AUX   I120 @S9S_MB_2U_LIB.S9S_MB_2U(SCH_1):PAGE110
     2    GND @S9S_MB_2U_LIB.S9S_MB_2U(SCH_1):GND   I120 @S9S_MB_2U_LIB.S9S_MB_2U(SCH_1):PAGE110

 C82 Q_CAP_C0805-10UF,16V,10%,X6S,CA
     1 P12V_S3_AUX_CPU1_NVDIMM @S9S_MB_2U_LIB.S9S_MB_2U(SCH_1):P12V_S3_AUX_CPU1_NVDIMM   I124 @S9S_MB_2U_LIB.S9S_MB_2U(SCH_1):PAGE110
     2    GND @S9S_MB_2U_LIB.S9S_MB_2U(SCH_1):GND   I124 @S9S_MB_2U_LIB.S9S_MB_2U(SCH_1):PAGE110

 C83 Q_CAP_C0805-10UF,16V,10%,X6S,CA
     1 P12V_S3_AUX_CPU1_NVDIMM @S9S_MB_2U_LIB.S9S_MB_2U(SCH_1):P12V_S3_AUX_CPU1_NVDIMM   I126 @S9S_MB_2U_LIB.S9S_MB_2U(SCH_1):PAGE110
     2    GND @S9S_MB_2U_LIB.S9S_MB_2U(SCH_1):GND   I126 @S9S_MB_2U_LIB.S9S_MB_2U(SCH_1):PAGE110

 C84 Q_CAP_C0402-2.2UF,6.3V,20%,X6SA
     1 P3V3_AUX @S9S_MB_2U_LIB.S9S_MB_2U(SCH_1):P3V3_AUX   I121 @S9S_MB_2U_LIB.S9S_MB_2U(SCH_1):PAGE109
     2    GND @S9S_MB_2U_LIB.S9S_MB_2U(SCH_1):GND   I121 @S9S_MB_2U_LIB.S9S_MB_2U(SCH_1):PAGE109

 C85 Q_CAP_C0805-10UF,16V,10%,X6S,CA
     1 P12V_S3_AUX_CPU1_NVDIMM @S9S_MB_2U_LIB.S9S_MB_2U(SCH_1):P12V_S3_AUX_CPU1_NVDIMM   I125 @S9S_MB_2U_LIB.S9S_MB_2U(SCH_1):PAGE109
     2    GND @S9S_MB_2U_LIB.S9S_MB_2U(SCH_1):GND   I125 @S9S_MB_2U_LIB.S9S_MB_2U(SCH_1):PAGE109

 C86 Q_CAP_C0805-10UF,16V,10%,X6S,CA
     1 P12V_S3_AUX_CPU1_NVDIMM @S9S_MB_2U_LIB.S9S_MB_2U(SCH_1):P12V_S3_AUX_CPU1_NVDIMM   I128 @S9S_MB_2U_LIB.S9S_MB_2U(SCH_1):PAGE109
     2    GND @S9S_MB_2U_LIB.S9S_MB_2U(SCH_1):GND   I128 @S9S_MB_2U_LIB.S9S_MB_2U(SCH_1):PAGE109

 C87 Q_CAP_C0402-2.2UF,6.3V,20%,X6SA
     1 P3V3_AUX @S9S_MB_2U_LIB.S9S_MB_2U(SCH_1):P3V3_AUX   I121 @S9S_MB_2U_LIB.S9S_MB_2U(SCH_1):PAGE108
     2    GND @S9S_MB_2U_LIB.S9S_MB_2U(SCH_1):GND   I121 @S9S_MB_2U_LIB.S9S_MB_2U(SCH_1):PAGE108

 C88 Q_CAP_C0805-10UF,16V,10%,X6S,CA
     1 P12V_S3_AUX_CPU1_NVDIMM @S9S_MB_2U_LIB.S9S_MB_2U(SCH_1):P12V_S3_AUX_CPU1_NVDIMM   I123 @S9S_MB_2U_LIB.S9S_MB_2U(SCH_1):PAGE108
     2    GND @S9S_MB_2U_LIB.S9S_MB_2U(SCH_1):GND   I123 @S9S_MB_2U_LIB.S9S_MB_2U(SCH_1):PAGE108

 C89 Q_CAP_C0805-10UF,16V,10%,X6S,CA
     1 P12V_S3_AUX_CPU1_NVDIMM @S9S_MB_2U_LIB.S9S_MB_2U(SCH_1):P12V_S3_AUX_CPU1_NVDIMM   I160 @S9S_MB_2U_LIB.S9S_MB_2U(SCH_1):PAGE108
     2    GND @S9S_MB_2U_LIB.S9S_MB_2U(SCH_1):GND   I160 @S9S_MB_2U_LIB.S9S_MB_2U(SCH_1):PAGE108

 C90 Q_CAP_C0402-2.2UF,6.3V,20%,X6SA
     1 P3V3_AUX @S9S_MB_2U_LIB.S9S_MB_2U(SCH_1):P3V3_AUX   I122 @S9S_MB_2U_LIB.S9S_MB_2U(SCH_1):PAGE107
     2    GND @S9S_MB_2U_LIB.S9S_MB_2U(SCH_1):GND   I122 @S9S_MB_2U_LIB.S9S_MB_2U(SCH_1):PAGE107

 C91 Q_CAP_C0805-10UF,16V,10%,X6S,CA
     1 P12V_S3_AUX_CPU1_NVDIMM @S9S_MB_2U_LIB.S9S_MB_2U(SCH_1):P12V_S3_AUX_CPU1_NVDIMM   I126 @S9S_MB_2U_LIB.S9S_MB_2U(SCH_1):PAGE107
     2    GND @S9S_MB_2U_LIB.S9S_MB_2U(SCH_1):GND   I126 @S9S_MB_2U_LIB.S9S_MB_2U(SCH_1):PAGE107

 C92 Q_CAP_C0805-10UF,16V,10%,X6S,CA
     1 P12V_S3_AUX_CPU1_NVDIMM @S9S_MB_2U_LIB.S9S_MB_2U(SCH_1):P12V_S3_AUX_CPU1_NVDIMM   I128 @S9S_MB_2U_LIB.S9S_MB_2U(SCH_1):PAGE107
     2    GND @S9S_MB_2U_LIB.S9S_MB_2U(SCH_1):GND   I128 @S9S_MB_2U_LIB.S9S_MB_2U(SCH_1):PAGE107

 C93 Q_CAP_C0402-2.2UF,6.3V,20%,X6SA
     1 P3V3_AUX @S9S_MB_2U_LIB.S9S_MB_2U(SCH_1):P3V3_AUX   I122 @S9S_MB_2U_LIB.S9S_MB_2U(SCH_1):PAGE106
     2    GND @S9S_MB_2U_LIB.S9S_MB_2U(SCH_1):GND   I122 @S9S_MB_2U_LIB.S9S_MB_2U(SCH_1):PAGE106

 C94 Q_CAP_C0805-10UF,16V,10%,X6S,CA
     1 P12V_S3_AUX_CPU1_NVDIMM @S9S_MB_2U_LIB.S9S_MB_2U(SCH_1):P12V_S3_AUX_CPU1_NVDIMM   I127 @S9S_MB_2U_LIB.S9S_MB_2U(SCH_1):PAGE106
     2    GND @S9S_MB_2U_LIB.S9S_MB_2U(SCH_1):GND   I127 @S9S_MB_2U_LIB.S9S_MB_2U(SCH_1):PAGE106

 C95 Q_CAP_C0805-10UF,16V,10%,X6S,CA
     1 P12V_S3_AUX_CPU1_NVDIMM @S9S_MB_2U_LIB.S9S_MB_2U(SCH_1):P12V_S3_AUX_CPU1_NVDIMM   I130 @S9S_MB_2U_LIB.S9S_MB_2U(SCH_1):PAGE106
     2    GND @S9S_MB_2U_LIB.S9S_MB_2U(SCH_1):GND   I130 @S9S_MB_2U_LIB.S9S_MB_2U(SCH_1):PAGE106

 C96 Q_CAP_C0402-2.2UF,6.3V,20%,X6SA
     1 P3V3_AUX @S9S_MB_2U_LIB.S9S_MB_2U(SCH_1):P3V3_AUX   I123 @S9S_MB_2U_LIB.S9S_MB_2U(SCH_1):PAGE105
     2    GND @S9S_MB_2U_LIB.S9S_MB_2U(SCH_1):GND   I123 @S9S_MB_2U_LIB.S9S_MB_2U(SCH_1):PAGE105

 C97 Q_CAP_C0805-10UF,16V,10%,X6S,CA
     1 P12V_S3_AUX_CPU1_NVDIMM @S9S_MB_2U_LIB.S9S_MB_2U(SCH_1):P12V_S3_AUX_CPU1_NVDIMM   I124 @S9S_MB_2U_LIB.S9S_MB_2U(SCH_1):PAGE105
     2    GND @S9S_MB_2U_LIB.S9S_MB_2U(SCH_1):GND   I124 @S9S_MB_2U_LIB.S9S_MB_2U(SCH_1):PAGE105

 C98 Q_CAP_C0805-10UF,16V,10%,X6S,CA
     1 P12V_S3_AUX_CPU1_NVDIMM @S9S_MB_2U_LIB.S9S_MB_2U(SCH_1):P12V_S3_AUX_CPU1_NVDIMM   I146 @S9S_MB_2U_LIB.S9S_MB_2U(SCH_1):PAGE105
     2    GND @S9S_MB_2U_LIB.S9S_MB_2U(SCH_1):GND   I146 @S9S_MB_2U_LIB.S9S_MB_2U(SCH_1):PAGE105

C101 Q_CAP_C0805-47UF,4V,20%,X6S,CHA
     1 PVCCIN_CPU0 @S9S_MB_2U_LIB.S9S_MB_2U(SCH_1):PVCCIN_CPU0    I13 @S9S_MB_2U_LIB.S9S_MB_2U(SCH_1):PAGE74
     2    GND @S9S_MB_2U_LIB.S9S_MB_2U(SCH_1):GND    I13 @S9S_MB_2U_LIB.S9S_MB_2U(SCH_1):PAGE74

C103 Q_CAP_0402-27PF  ,50V ,5% ,EMPA
     1 XTAL_PCH_25M_IN_R @S9S_MB_2U_LIB.S9S_MB_2U(SCH_1):XTAL_PCH_25M_IN_R    I77 @S9S_MB_2U_LIB.S9S_MB_2U(SCH_1):PAGE171
     2    GND @S9S_MB_2U_LIB.S9S_MB_2U(SCH_1):GND    I77 @S9S_MB_2U_LIB.S9S_MB_2U(SCH_1):PAGE171

C104 Q_CAP_0402-27PF  ,50V ,5% ,EMPA
     1 XTAL_PCH_25M_OUT @S9S_MB_2U_LIB.S9S_MB_2U(SCH_1):XTAL_PCH_25M_OUT    I76 @S9S_MB_2U_LIB.S9S_MB_2U(SCH_1):PAGE171
     2    GND @S9S_MB_2U_LIB.S9S_MB_2U(SCH_1):GND    I76 @S9S_MB_2U_LIB.S9S_MB_2U(SCH_1):PAGE171

C107 Q_CAP_C0402-1UF,25V,10%,X6S,CHA
     1 P3V3_AUX_CLK_GEN_VDD_CK440 @S9S_MB_2U_LIB.S9S_MB_2U(SCH_1):P3V3_AUX_CLK_GEN_VDD_CK440    I82 @S9S_MB_2U_LIB.S9S_MB_2U(SCH_1):PAGE199
     2    GND @S9S_MB_2U_LIB.S9S_MB_2U(SCH_1):GND    I82 @S9S_MB_2U_LIB.S9S_MB_2U(SCH_1):PAGE199

C108 Q_CAP_C0603-10UF,6.3V,20%,X6S,A
     1 P3V3_AUX_CLK_GEN_VDD_CK440 @S9S_MB_2U_LIB.S9S_MB_2U(SCH_1):P3V3_AUX_CLK_GEN_VDD_CK440    I19 @S9S_MB_2U_LIB.S9S_MB_2U(SCH_1):PAGE199
     2    GND @S9S_MB_2U_LIB.S9S_MB_2U(SCH_1):GND    I19 @S9S_MB_2U_LIB.S9S_MB_2U(SCH_1):PAGE199

C110 Q_CAP_C0402-0.047UF,25V,10%,X7A
     1 P3V3_AUX_CLK_GEN_VDD_CK440 @S9S_MB_2U_LIB.S9S_MB_2U(SCH_1):P3V3_AUX_CLK_GEN_VDD_CK440    I76 @S9S_MB_2U_LIB.S9S_MB_2U(SCH_1):PAGE199
     2    GND @S9S_MB_2U_LIB.S9S_MB_2U(SCH_1):GND    I76 @S9S_MB_2U_LIB.S9S_MB_2U(SCH_1):PAGE199

C111 Q_CAP_C0402-0.047UF,25V,10%,X7A
     1 P3V3_AUX_CLK_GEN_VDDXTAL_CK440 @S9S_MB_2U_LIB.S9S_MB_2U(SCH_1):P3V3_AUX_CLK_GEN_VDDXTAL_CK440    I81 @S9S_MB_2U_LIB.S9S_MB_2U(SCH_1):PAGE199
     2    GND @S9S_MB_2U_LIB.S9S_MB_2U(SCH_1):GND    I81 @S9S_MB_2U_LIB.S9S_MB_2U(SCH_1):PAGE199

C112 Q_CAP_C0402-0.047UF,25V,10%,X7A
     1 P3V3_AUX_CLK_GEN_VDDXTAL_CK440 @S9S_MB_2U_LIB.S9S_MB_2U(SCH_1):P3V3_AUX_CLK_GEN_VDDXTAL_CK440    I80 @S9S_MB_2U_LIB.S9S_MB_2U(SCH_1):PAGE199
     2    GND @S9S_MB_2U_LIB.S9S_MB_2U(SCH_1):GND    I80 @S9S_MB_2U_LIB.S9S_MB_2U(SCH_1):PAGE199

C114 Q_CAP_C0402-0.047UF,25V,10%,X7A
     1 P3V3_AUX_CLK_GEN_VDDA25M_CK440 @S9S_MB_2U_LIB.S9S_MB_2U(SCH_1):P3V3_AUX_CLK_GEN_VDDA25M_CK440    I79 @S9S_MB_2U_LIB.S9S_MB_2U(SCH_1):PAGE199
     2    GND @S9S_MB_2U_LIB.S9S_MB_2U(SCH_1):GND    I79 @S9S_MB_2U_LIB.S9S_MB_2U(SCH_1):PAGE199

C115 Q_CAP_C0402-0.047UF,25V,10%,X7A
     1 P3V3_AUX_CLK_GEN_VDDMXCK_CK440 @S9S_MB_2U_LIB.S9S_MB_2U(SCH_1):P3V3_AUX_CLK_GEN_VDDMXCK_CK440    I89 @S9S_MB_2U_LIB.S9S_MB_2U(SCH_1):PAGE199
     2    GND @S9S_MB_2U_LIB.S9S_MB_2U(SCH_1):GND    I89 @S9S_MB_2U_LIB.S9S_MB_2U(SCH_1):PAGE199

C116 Q_CAP_C0402-0.047UF,25V,10%,X7A
     1 P3V3_AUX_CLK_GEN_VDDMXCK_CK440 @S9S_MB_2U_LIB.S9S_MB_2U(SCH_1):P3V3_AUX_CLK_GEN_VDDMXCK_CK440    I88 @S9S_MB_2U_LIB.S9S_MB_2U(SCH_1):PAGE199
     2    GND @S9S_MB_2U_LIB.S9S_MB_2U(SCH_1):GND    I88 @S9S_MB_2U_LIB.S9S_MB_2U(SCH_1):PAGE199

C117 Q_CAP_C0402-0.047UF,25V,10%,X7A
     1 P3V3_AUX_CLK_GEN_VDDMXCK_CK440 @S9S_MB_2U_LIB.S9S_MB_2U(SCH_1):P3V3_AUX_CLK_GEN_VDDMXCK_CK440    I87 @S9S_MB_2U_LIB.S9S_MB_2U(SCH_1):PAGE199
     2    GND @S9S_MB_2U_LIB.S9S_MB_2U(SCH_1):GND    I87 @S9S_MB_2U_LIB.S9S_MB_2U(SCH_1):PAGE199

C119 Q_CAP_C0402-0.047UF,25V,10%,X7A
     1 P3V3_AUX_CLK_GEN_VDDMXCK_CK440 @S9S_MB_2U_LIB.S9S_MB_2U(SCH_1):P3V3_AUX_CLK_GEN_VDDMXCK_CK440    I86 @S9S_MB_2U_LIB.S9S_MB_2U(SCH_1):PAGE199
     2    GND @S9S_MB_2U_LIB.S9S_MB_2U(SCH_1):GND    I86 @S9S_MB_2U_LIB.S9S_MB_2U(SCH_1):PAGE199

C120 Q_CAP_C0402-0.047UF,25V,10%,X7A
     1 P3V3_AUX_CLK_GEN_VDDPT_CK440 @S9S_MB_2U_LIB.S9S_MB_2U(SCH_1):P3V3_AUX_CLK_GEN_VDDPT_CK440    I85 @S9S_MB_2U_LIB.S9S_MB_2U(SCH_1):PAGE199
     2    GND @S9S_MB_2U_LIB.S9S_MB_2U(SCH_1):GND    I85 @S9S_MB_2U_LIB.S9S_MB_2U(SCH_1):PAGE199

C139 Q_CAP_DIFFBUS_C0201-DIFF BUS_0A
     1 DMI_CPU0_PCH_TX_C_DN<7> @S9S_MB_2U_LIB.S9S_MB_2U(SCH_1):DMI_CPU0_PCH_TX_C_DN(7)    I35 @S9S_MB_2U_LIB.S9S_MB_2U(SCH_1):PAGE169
     2 DMI_CPU0_PCH_TX_DN<7> @S9S_MB_2U_LIB.S9S_MB_2U(SCH_1):DMI_CPU0_PCH_TX_DN(7)    I35 @S9S_MB_2U_LIB.S9S_MB_2U(SCH_1):PAGE169

C141 Q_CAP_DIFFBUS_C0201-DIFF BUS_0A
     1 DMI_CPU0_PCH_TX_C_DN<6> @S9S_MB_2U_LIB.S9S_MB_2U(SCH_1):DMI_CPU0_PCH_TX_C_DN(6)    I34 @S9S_MB_2U_LIB.S9S_MB_2U(SCH_1):PAGE169
     2 DMI_CPU0_PCH_TX_DN<6> @S9S_MB_2U_LIB.S9S_MB_2U(SCH_1):DMI_CPU0_PCH_TX_DN(6)    I34 @S9S_MB_2U_LIB.S9S_MB_2U(SCH_1):PAGE169

C142 Q_CAP_DIFFBUS_C0201-DIFF BUS_0A
     1 DMI_CPU0_PCH_TX_C_DP<6> @S9S_MB_2U_LIB.S9S_MB_2U(SCH_1):DMI_CPU0_PCH_TX_C_DP(6)    I33 @S9S_MB_2U_LIB.S9S_MB_2U(SCH_1):PAGE169
     2 DMI_CPU0_PCH_TX_DP<6> @S9S_MB_2U_LIB.S9S_MB_2U(SCH_1):DMI_CPU0_PCH_TX_DP(6)    I33 @S9S_MB_2U_LIB.S9S_MB_2U(SCH_1):PAGE169

C143 Q_CAP_DIFFBUS_C0201-DIFF BUS_0A
     1 DMI_CPU0_PCH_TX_C_DN<5> @S9S_MB_2U_LIB.S9S_MB_2U(SCH_1):DMI_CPU0_PCH_TX_C_DN(5)    I32 @S9S_MB_2U_LIB.S9S_MB_2U(SCH_1):PAGE169
     2 DMI_CPU0_PCH_TX_DN<5> @S9S_MB_2U_LIB.S9S_MB_2U(SCH_1):DMI_CPU0_PCH_TX_DN(5)    I32 @S9S_MB_2U_LIB.S9S_MB_2U(SCH_1):PAGE169

C144 Q_CAP_DIFFBUS_C0201-DIFF BUS_0A
     1 DMI_CPU0_PCH_TX_C_DP<5> @S9S_MB_2U_LIB.S9S_MB_2U(SCH_1):DMI_CPU0_PCH_TX_C_DP(5)    I31 @S9S_MB_2U_LIB.S9S_MB_2U(SCH_1):PAGE169
     2 DMI_CPU0_PCH_TX_DP<5> @S9S_MB_2U_LIB.S9S_MB_2U(SCH_1):DMI_CPU0_PCH_TX_DP(5)    I31 @S9S_MB_2U_LIB.S9S_MB_2U(SCH_1):PAGE169

C145 Q_CAP_DIFFBUS_C0201-DIFF BUS_0A
     1 DMI_CPU0_PCH_TX_C_DN<4> @S9S_MB_2U_LIB.S9S_MB_2U(SCH_1):DMI_CPU0_PCH_TX_C_DN(4)    I30 @S9S_MB_2U_LIB.S9S_MB_2U(SCH_1):PAGE169
     2 DMI_CPU0_PCH_TX_DN<4> @S9S_MB_2U_LIB.S9S_MB_2U(SCH_1):DMI_CPU0_PCH_TX_DN(4)    I30 @S9S_MB_2U_LIB.S9S_MB_2U(SCH_1):PAGE169

C146 Q_CAP_DIFFBUS_C0201-DIFF BUS_0A
     1 DMI_CPU0_PCH_TX_C_DP<4> @S9S_MB_2U_LIB.S9S_MB_2U(SCH_1):DMI_CPU0_PCH_TX_C_DP(4)    I29 @S9S_MB_2U_LIB.S9S_MB_2U(SCH_1):PAGE169
     2 DMI_CPU0_PCH_TX_DP<4> @S9S_MB_2U_LIB.S9S_MB_2U(SCH_1):DMI_CPU0_PCH_TX_DP(4)    I29 @S9S_MB_2U_LIB.S9S_MB_2U(SCH_1):PAGE169

C147 Q_CAP_DIFFBUS_C0201-DIFF BUS_0A
     1 DMI_CPU0_PCH_TX_C_DN<3> @S9S_MB_2U_LIB.S9S_MB_2U(SCH_1):DMI_CPU0_PCH_TX_C_DN(3)    I28 @S9S_MB_2U_LIB.S9S_MB_2U(SCH_1):PAGE169
     2 DMI_CPU0_PCH_TX_DN<3> @S9S_MB_2U_LIB.S9S_MB_2U(SCH_1):DMI_CPU0_PCH_TX_DN(3)    I28 @S9S_MB_2U_LIB.S9S_MB_2U(SCH_1):PAGE169

C148 Q_CAP_DIFFBUS_C0201-DIFF BUS_0A
     1 DMI_CPU0_PCH_TX_C_DP<3> @S9S_MB_2U_LIB.S9S_MB_2U(SCH_1):DMI_CPU0_PCH_TX_C_DP(3)    I27 @S9S_MB_2U_LIB.S9S_MB_2U(SCH_1):PAGE169
     2 DMI_CPU0_PCH_TX_DP<3> @S9S_MB_2U_LIB.S9S_MB_2U(SCH_1):DMI_CPU0_PCH_TX_DP(3)    I27 @S9S_MB_2U_LIB.S9S_MB_2U(SCH_1):PAGE169

C149 Q_CAP_DIFFBUS_C0201-DIFF BUS_0A
     1 DMI_CPU0_PCH_TX_C_DN<2> @S9S_MB_2U_LIB.S9S_MB_2U(SCH_1):DMI_CPU0_PCH_TX_C_DN(2)    I25 @S9S_MB_2U_LIB.S9S_MB_2U(SCH_1):PAGE169
     2 DMI_CPU0_PCH_TX_DN<2> @S9S_MB_2U_LIB.S9S_MB_2U(SCH_1):DMI_CPU0_PCH_TX_DN(2)    I25 @S9S_MB_2U_LIB.S9S_MB_2U(SCH_1):PAGE169

C150 Q_CAP_DIFFBUS_C0201-DIFF BUS_0A
     1 DMI_CPU0_PCH_TX_C_DP<2> @S9S_MB_2U_LIB.S9S_MB_2U(SCH_1):DMI_CPU0_PCH_TX_C_DP(2)    I26 @S9S_MB_2U_LIB.S9S_MB_2U(SCH_1):PAGE169
     2 DMI_CPU0_PCH_TX_DP<2> @S9S_MB_2U_LIB.S9S_MB_2U(SCH_1):DMI_CPU0_PCH_TX_DP(2)    I26 @S9S_MB_2U_LIB.S9S_MB_2U(SCH_1):PAGE169

C151 Q_CAP_DIFFBUS_C0201-DIFF BUS_0A
     1 DMI_CPU0_PCH_TX_C_DN<1> @S9S_MB_2U_LIB.S9S_MB_2U(SCH_1):DMI_CPU0_PCH_TX_C_DN(1)    I24 @S9S_MB_2U_LIB.S9S_MB_2U(SCH_1):PAGE169
     2 DMI_CPU0_PCH_TX_DN<1> @S9S_MB_2U_LIB.S9S_MB_2U(SCH_1):DMI_CPU0_PCH_TX_DN(1)    I24 @S9S_MB_2U_LIB.S9S_MB_2U(SCH_1):PAGE169

C152 Q_CAP_DIFFBUS_C0201-DIFF BUS_0A
     1 DMI_CPU0_PCH_TX_C_DP<1> @S9S_MB_2U_LIB.S9S_MB_2U(SCH_1):DMI_CPU0_PCH_TX_C_DP(1)    I23 @S9S_MB_2U_LIB.S9S_MB_2U(SCH_1):PAGE169
     2 DMI_CPU0_PCH_TX_DP<1> @S9S_MB_2U_LIB.S9S_MB_2U(SCH_1):DMI_CPU0_PCH_TX_DP(1)    I23 @S9S_MB_2U_LIB.S9S_MB_2U(SCH_1):PAGE169

C153 Q_CAP_DIFFBUS_C0201-DIFF BUS_0A
     1 DMI_CPU0_PCH_TX_C_DN<0> @S9S_MB_2U_LIB.S9S_MB_2U(SCH_1):DMI_CPU0_PCH_TX_C_DN(0)    I21 @S9S_MB_2U_LIB.S9S_MB_2U(SCH_1):PAGE169
     2 DMI_CPU0_PCH_TX_DN<0> @S9S_MB_2U_LIB.S9S_MB_2U(SCH_1):DMI_CPU0_PCH_TX_DN(0)    I21 @S9S_MB_2U_LIB.S9S_MB_2U(SCH_1):PAGE169

C154 Q_CAP_DIFFBUS_C0201-DIFF BUS_0A
     1 DMI_CPU0_PCH_TX_C_DP<0> @S9S_MB_2U_LIB.S9S_MB_2U(SCH_1):DMI_CPU0_PCH_TX_C_DP(0)    I22 @S9S_MB_2U_LIB.S9S_MB_2U(SCH_1):PAGE169
     2 DMI_CPU0_PCH_TX_DP<0> @S9S_MB_2U_LIB.S9S_MB_2U(SCH_1):DMI_CPU0_PCH_TX_DP(0)    I22 @S9S_MB_2U_LIB.S9S_MB_2U(SCH_1):PAGE169

C155 Q_CAP_DIFFBUS_C0201-DIFF BUS_0A
     1 DMI_CPU0_PCH_RX_C_DN<7> @S9S_MB_2U_LIB.S9S_MB_2U(SCH_1):DMI_CPU0_PCH_RX_C_DN(7)   I113 @S9S_MB_2U_LIB.S9S_MB_2U(SCH_1):PAGE169
     2 DMI_CPU0_PCH_RX_DN<7> @S9S_MB_2U_LIB.S9S_MB_2U(SCH_1):DMI_CPU0_PCH_RX_DN(7)   I113 @S9S_MB_2U_LIB.S9S_MB_2U(SCH_1):PAGE169

C156 Q_CAP_DIFFBUS_C0201-DIFF BUS_0A
     1 DMI_CPU0_PCH_RX_C_DP<7> @S9S_MB_2U_LIB.S9S_MB_2U(SCH_1):DMI_CPU0_PCH_RX_C_DP(7)   I114 @S9S_MB_2U_LIB.S9S_MB_2U(SCH_1):PAGE169
     2 DMI_CPU0_PCH_RX_DP<7> @S9S_MB_2U_LIB.S9S_MB_2U(SCH_1):DMI_CPU0_PCH_RX_DP(7)   I114 @S9S_MB_2U_LIB.S9S_MB_2U(SCH_1):PAGE169

C157 Q_CAP_DIFFBUS_C0201-DIFF BUS_0A
     1 DMI_CPU0_PCH_RX_C_DN<6> @S9S_MB_2U_LIB.S9S_MB_2U(SCH_1):DMI_CPU0_PCH_RX_C_DN(6)   I115 @S9S_MB_2U_LIB.S9S_MB_2U(SCH_1):PAGE169
     2 DMI_CPU0_PCH_RX_DN<6> @S9S_MB_2U_LIB.S9S_MB_2U(SCH_1):DMI_CPU0_PCH_RX_DN(6)   I115 @S9S_MB_2U_LIB.S9S_MB_2U(SCH_1):PAGE169

C158 Q_CAP_DIFFBUS_C0201-DIFF BUS_0A
     1 DMI_CPU0_PCH_RX_C_DP<6> @S9S_MB_2U_LIB.S9S_MB_2U(SCH_1):DMI_CPU0_PCH_RX_C_DP(6)   I116 @S9S_MB_2U_LIB.S9S_MB_2U(SCH_1):PAGE169
     2 DMI_CPU0_PCH_RX_DP<6> @S9S_MB_2U_LIB.S9S_MB_2U(SCH_1):DMI_CPU0_PCH_RX_DP(6)   I116 @S9S_MB_2U_LIB.S9S_MB_2U(SCH_1):PAGE169

C159 Q_CAP_DIFFBUS_C0201-DIFF BUS_0A
     1 DMI_CPU0_PCH_RX_C_DN<5> @S9S_MB_2U_LIB.S9S_MB_2U(SCH_1):DMI_CPU0_PCH_RX_C_DN(5)   I117 @S9S_MB_2U_LIB.S9S_MB_2U(SCH_1):PAGE169
     2 DMI_CPU0_PCH_RX_DN<5> @S9S_MB_2U_LIB.S9S_MB_2U(SCH_1):DMI_CPU0_PCH_RX_DN(5)   I117 @S9S_MB_2U_LIB.S9S_MB_2U(SCH_1):PAGE169

C160 Q_CAP_DIFFBUS_C0201-DIFF BUS_0A
     1 DMI_CPU0_PCH_RX_C_DP<5> @S9S_MB_2U_LIB.S9S_MB_2U(SCH_1):DMI_CPU0_PCH_RX_C_DP(5)   I118 @S9S_MB_2U_LIB.S9S_MB_2U(SCH_1):PAGE169
     2 DMI_CPU0_PCH_RX_DP<5> @S9S_MB_2U_LIB.S9S_MB_2U(SCH_1):DMI_CPU0_PCH_RX_DP(5)   I118 @S9S_MB_2U_LIB.S9S_MB_2U(SCH_1):PAGE169

C161 Q_CAP_DIFFBUS_C0201-DIFF BUS_0A
     1 DMI_CPU0_PCH_RX_C_DN<4> @S9S_MB_2U_LIB.S9S_MB_2U(SCH_1):DMI_CPU0_PCH_RX_C_DN(4)   I119 @S9S_MB_2U_LIB.S9S_MB_2U(SCH_1):PAGE169
     2 DMI_CPU0_PCH_RX_DN<4> @S9S_MB_2U_LIB.S9S_MB_2U(SCH_1):DMI_CPU0_PCH_RX_DN(4)   I119 @S9S_MB_2U_LIB.S9S_MB_2U(SCH_1):PAGE169

C162 Q_CAP_DIFFBUS_C0201-DIFF BUS_0A
     1 DMI_CPU0_PCH_RX_C_DP<4> @S9S_MB_2U_LIB.S9S_MB_2U(SCH_1):DMI_CPU0_PCH_RX_C_DP(4)   I120 @S9S_MB_2U_LIB.S9S_MB_2U(SCH_1):PAGE169
     2 DMI_CPU0_PCH_RX_DP<4> @S9S_MB_2U_LIB.S9S_MB_2U(SCH_1):DMI_CPU0_PCH_RX_DP(4)   I120 @S9S_MB_2U_LIB.S9S_MB_2U(SCH_1):PAGE169

C163 Q_CAP_DIFFBUS_C0201-DIFF BUS_0A
     1 DMI_CPU0_PCH_RX_C_DN<3> @S9S_MB_2U_LIB.S9S_MB_2U(SCH_1):DMI_CPU0_PCH_RX_C_DN(3)   I121 @S9S_MB_2U_LIB.S9S_MB_2U(SCH_1):PAGE169
     2 DMI_CPU0_PCH_RX_DN<3> @S9S_MB_2U_LIB.S9S_MB_2U(SCH_1):DMI_CPU0_PCH_RX_DN(3)   I121 @S9S_MB_2U_LIB.S9S_MB_2U(SCH_1):PAGE169

C164 Q_CAP_DIFFBUS_C0201-DIFF BUS_0A
     1 DMI_CPU0_PCH_RX_C_DP<3> @S9S_MB_2U_LIB.S9S_MB_2U(SCH_1):DMI_CPU0_PCH_RX_C_DP(3)   I122 @S9S_MB_2U_LIB.S9S_MB_2U(SCH_1):PAGE169
     2 DMI_CPU0_PCH_RX_DP<3> @S9S_MB_2U_LIB.S9S_MB_2U(SCH_1):DMI_CPU0_PCH_RX_DP(3)   I122 @S9S_MB_2U_LIB.S9S_MB_2U(SCH_1):PAGE169

C165 Q_CAP_DIFFBUS_C0201-DIFF BUS_0A
     1 DMI_CPU0_PCH_RX_C_DN<2> @S9S_MB_2U_LIB.S9S_MB_2U(SCH_1):DMI_CPU0_PCH_RX_C_DN(2)   I123 @S9S_MB_2U_LIB.S9S_MB_2U(SCH_1):PAGE169
     2 DMI_CPU0_PCH_RX_DN<2> @S9S_MB_2U_LIB.S9S_MB_2U(SCH_1):DMI_CPU0_PCH_RX_DN(2)   I123 @S9S_MB_2U_LIB.S9S_MB_2U(SCH_1):PAGE169

C166 Q_CAP_DIFFBUS_C0201-DIFF BUS_0A
     1 DMI_CPU0_PCH_RX_C_DP<2> @S9S_MB_2U_LIB.S9S_MB_2U(SCH_1):DMI_CPU0_PCH_RX_C_DP(2)   I124 @S9S_MB_2U_LIB.S9S_MB_2U(SCH_1):PAGE169
     2 DMI_CPU0_PCH_RX_DP<2> @S9S_MB_2U_LIB.S9S_MB_2U(SCH_1):DMI_CPU0_PCH_RX_DP(2)   I124 @S9S_MB_2U_LIB.S9S_MB_2U(SCH_1):PAGE169

C167 Q_CAP_DIFFBUS_C0201-DIFF BUS_0A
     1 DMI_CPU0_PCH_RX_C_DN<1> @S9S_MB_2U_LIB.S9S_MB_2U(SCH_1):DMI_CPU0_PCH_RX_C_DN(1)   I126 @S9S_MB_2U_LIB.S9S_MB_2U(SCH_1):PAGE169
     2 DMI_CPU0_PCH_RX_DN<1> @S9S_MB_2U_LIB.S9S_MB_2U(SCH_1):DMI_CPU0_PCH_RX_DN(1)   I126 @S9S_MB_2U_LIB.S9S_MB_2U(SCH_1):PAGE169

C168 Q_CAP_DIFFBUS_C0201-DIFF BUS_0A
     1 DMI_CPU0_PCH_RX_C_DP<1> @S9S_MB_2U_LIB.S9S_MB_2U(SCH_1):DMI_CPU0_PCH_RX_C_DP(1)   I125 @S9S_MB_2U_LIB.S9S_MB_2U(SCH_1):PAGE169
     2 DMI_CPU0_PCH_RX_DP<1> @S9S_MB_2U_LIB.S9S_MB_2U(SCH_1):DMI_CPU0_PCH_RX_DP(1)   I125 @S9S_MB_2U_LIB.S9S_MB_2U(SCH_1):PAGE169

C169 Q_CAP_DIFFBUS_C0201-DIFF BUS_0A
     1 DMI_CPU0_PCH_RX_C_DN<0> @S9S_MB_2U_LIB.S9S_MB_2U(SCH_1):DMI_CPU0_PCH_RX_C_DN(0)   I127 @S9S_MB_2U_LIB.S9S_MB_2U(SCH_1):PAGE169
     2 DMI_CPU0_PCH_RX_DN<0> @S9S_MB_2U_LIB.S9S_MB_2U(SCH_1):DMI_CPU0_PCH_RX_DN(0)   I127 @S9S_MB_2U_LIB.S9S_MB_2U(SCH_1):PAGE169

C170 Q_CAP_DIFFBUS_C0201-DIFF BUS_0A
     1 DMI_CPU0_PCH_RX_C_DP<0> @S9S_MB_2U_LIB.S9S_MB_2U(SCH_1):DMI_CPU0_PCH_RX_C_DP(0)   I128 @S9S_MB_2U_LIB.S9S_MB_2U(SCH_1):PAGE169
     2 DMI_CPU0_PCH_RX_DP<0> @S9S_MB_2U_LIB.S9S_MB_2U(SCH_1):DMI_CPU0_PCH_RX_DP(0)   I128 @S9S_MB_2U_LIB.S9S_MB_2U(SCH_1):PAGE169

C171 Q_CAP_C0402-0.047UF,25V,10%,X7A
     1 P3V3_AUX_CLK_GEN_VDD_CK440 @S9S_MB_2U_LIB.S9S_MB_2U(SCH_1):P3V3_AUX_CLK_GEN_VDD_CK440    I77 @S9S_MB_2U_LIB.S9S_MB_2U(SCH_1):PAGE199
     2    GND @S9S_MB_2U_LIB.S9S_MB_2U(SCH_1):GND    I77 @S9S_MB_2U_LIB.S9S_MB_2U(SCH_1):PAGE199

C172 Q_CAP_C0603-10UF,6.3V,20%,X6S,A
     1 P3V3_AUX_CLK_GEN_VDDA100M_CK440 @S9S_MB_2U_LIB.S9S_MB_2U(SCH_1):P3V3_AUX_CLK_GEN_VDDA100M_CK440     I6 @S9S_MB_2U_LIB.S9S_MB_2U(SCH_1):PAGE199
     2    GND @S9S_MB_2U_LIB.S9S_MB_2U(SCH_1):GND     I6 @S9S_MB_2U_LIB.S9S_MB_2U(SCH_1):PAGE199

C173 Q_CAP_C0402-0.047UF,25V,10%,X7A
     1 P3V3_AUX_CLK_GEN_VDDA100M_CK440 @S9S_MB_2U_LIB.S9S_MB_2U(SCH_1):P3V3_AUX_CLK_GEN_VDDA100M_CK440    I78 @S9S_MB_2U_LIB.S9S_MB_2U(SCH_1):PAGE199
     2    GND @S9S_MB_2U_LIB.S9S_MB_2U(SCH_1):GND    I78 @S9S_MB_2U_LIB.S9S_MB_2U(SCH_1):PAGE199

C174 Q_CAP_0402-0.1UF,25V,10%,X7R,CA
     1 P3V3_AUX @S9S_MB_2U_LIB.S9S_MB_2U(SCH_1):P3V3_AUX    I47 @S9S_MB_2U_LIB.S9S_MB_2U(SCH_1):PAGE219
     2    GND @S9S_MB_2U_LIB.S9S_MB_2U(SCH_1):GND    I47 @S9S_MB_2U_LIB.S9S_MB_2U(SCH_1):PAGE219

C188 Q_CAP_0402-0.1UF,25V,10%,X7R,CA
     1 P3V3_AUX @S9S_MB_2U_LIB.S9S_MB_2U(SCH_1):P3V3_AUX    I44 @S9S_MB_2U_LIB.S9S_MB_2U(SCH_1):PAGE152
     2    GND @S9S_MB_2U_LIB.S9S_MB_2U(SCH_1):GND    I44 @S9S_MB_2U_LIB.S9S_MB_2U(SCH_1):PAGE152

C204 Q_CAP_0402-0.1UF,25V,10%,X7R,CA
     1 P3V3_DB2000_VDD @S9S_MB_2U_LIB.S9S_MB_2U(SCH_1):P3V3_DB2000_VDD   I171 @S9S_MB_2U_LIB.S9S_MB_2U(SCH_1):PAGE195
     2    GND @S9S_MB_2U_LIB.S9S_MB_2U(SCH_1):GND   I171 @S9S_MB_2U_LIB.S9S_MB_2U(SCH_1):PAGE195

C205 Q_CAP_0402-0.1UF,25V,10%,X7R,CA
     1 P3V3_DB2000_VDD @S9S_MB_2U_LIB.S9S_MB_2U(SCH_1):P3V3_DB2000_VDD   I172 @S9S_MB_2U_LIB.S9S_MB_2U(SCH_1):PAGE195
     2    GND @S9S_MB_2U_LIB.S9S_MB_2U(SCH_1):GND   I172 @S9S_MB_2U_LIB.S9S_MB_2U(SCH_1):PAGE195

C206 Q_CAP_0402-0.1UF,25V,10%,X7R,CA
     1 P3V3_DB2000_VDD @S9S_MB_2U_LIB.S9S_MB_2U(SCH_1):P3V3_DB2000_VDD   I173 @S9S_MB_2U_LIB.S9S_MB_2U(SCH_1):PAGE195
     2    GND @S9S_MB_2U_LIB.S9S_MB_2U(SCH_1):GND   I173 @S9S_MB_2U_LIB.S9S_MB_2U(SCH_1):PAGE195

C207 Q_CAP_0402-0.1UF,25V,10%,X7R,CA
     1 P3V3_DB2000_VDD @S9S_MB_2U_LIB.S9S_MB_2U(SCH_1):P3V3_DB2000_VDD   I174 @S9S_MB_2U_LIB.S9S_MB_2U(SCH_1):PAGE195
     2    GND @S9S_MB_2U_LIB.S9S_MB_2U(SCH_1):GND   I174 @S9S_MB_2U_LIB.S9S_MB_2U(SCH_1):PAGE195

C208 Q_CAP_C0603-10UF,6.3V,20%,X6S,A
     1 P3V3_DB2000_VDDR @S9S_MB_2U_LIB.S9S_MB_2U(SCH_1):P3V3_DB2000_VDDR   I167 @S9S_MB_2U_LIB.S9S_MB_2U(SCH_1):PAGE195
     2    GND @S9S_MB_2U_LIB.S9S_MB_2U(SCH_1):GND   I167 @S9S_MB_2U_LIB.S9S_MB_2U(SCH_1):PAGE195

C209 Q_CAP_C0603-10UF,6.3V,20%,X6S,A
     1 P3V3_DB2000_VDDA @S9S_MB_2U_LIB.S9S_MB_2U(SCH_1):P3V3_DB2000_VDDA   I164 @S9S_MB_2U_LIB.S9S_MB_2U(SCH_1):PAGE195
     2    GND @S9S_MB_2U_LIB.S9S_MB_2U(SCH_1):GND   I164 @S9S_MB_2U_LIB.S9S_MB_2U(SCH_1):PAGE195

C210 Q_CAP_0402-0.1UF,25V,10%,X7R,CA
     1 P3V3_DB2000_VDDR @S9S_MB_2U_LIB.S9S_MB_2U(SCH_1):P3V3_DB2000_VDDR   I168 @S9S_MB_2U_LIB.S9S_MB_2U(SCH_1):PAGE195
     2    GND @S9S_MB_2U_LIB.S9S_MB_2U(SCH_1):GND   I168 @S9S_MB_2U_LIB.S9S_MB_2U(SCH_1):PAGE195

C211 Q_CAP_0402-0.1UF,25V,10%,X7R,CA
     1 P3V3_DB2000_VDDA @S9S_MB_2U_LIB.S9S_MB_2U(SCH_1):P3V3_DB2000_VDDA   I165 @S9S_MB_2U_LIB.S9S_MB_2U(SCH_1):PAGE195
     2    GND @S9S_MB_2U_LIB.S9S_MB_2U(SCH_1):GND   I165 @S9S_MB_2U_LIB.S9S_MB_2U(SCH_1):PAGE195

C212 Q_CAP_C0805-47UF,4V,20%,X6S,CHA
     1 PVCCIN_CPU0 @S9S_MB_2U_LIB.S9S_MB_2U(SCH_1):PVCCIN_CPU0    I18 @S9S_MB_2U_LIB.S9S_MB_2U(SCH_1):PAGE74
     2    GND @S9S_MB_2U_LIB.S9S_MB_2U(SCH_1):GND    I18 @S9S_MB_2U_LIB.S9S_MB_2U(SCH_1):PAGE74

C213 Q_CAP_C0805-47UF,4V,20%,X6S,CHA
     1 PVCCIN_CPU0 @S9S_MB_2U_LIB.S9S_MB_2U(SCH_1):PVCCIN_CPU0    I20 @S9S_MB_2U_LIB.S9S_MB_2U(SCH_1):PAGE74
     2    GND @S9S_MB_2U_LIB.S9S_MB_2U(SCH_1):GND    I20 @S9S_MB_2U_LIB.S9S_MB_2U(SCH_1):PAGE74

C214 Q_CAP_C0805-47UF,4V,20%,X6S,CHA
     1 PVCCIN_CPU0 @S9S_MB_2U_LIB.S9S_MB_2U(SCH_1):PVCCIN_CPU0    I35 @S9S_MB_2U_LIB.S9S_MB_2U(SCH_1):PAGE74
     2    GND @S9S_MB_2U_LIB.S9S_MB_2U(SCH_1):GND    I35 @S9S_MB_2U_LIB.S9S_MB_2U(SCH_1):PAGE74

C215 Q_CAP_C0805-47UF,4V,20%,X6S,CHA
     1 PVCCIN_CPU0 @S9S_MB_2U_LIB.S9S_MB_2U(SCH_1):PVCCIN_CPU0    I36 @S9S_MB_2U_LIB.S9S_MB_2U(SCH_1):PAGE74
     2    GND @S9S_MB_2U_LIB.S9S_MB_2U(SCH_1):GND    I36 @S9S_MB_2U_LIB.S9S_MB_2U(SCH_1):PAGE74

C216 Q_CAP_C0805-47UF,4V,20%,X6S,CHA
     1 PVCCIN_CPU0 @S9S_MB_2U_LIB.S9S_MB_2U(SCH_1):PVCCIN_CPU0    I40 @S9S_MB_2U_LIB.S9S_MB_2U(SCH_1):PAGE74
     2    GND @S9S_MB_2U_LIB.S9S_MB_2U(SCH_1):GND    I40 @S9S_MB_2U_LIB.S9S_MB_2U(SCH_1):PAGE74

C217 Q_CAP_C0805-47UF,4V,20%,X6S,CHA
     1 PVCCIN_CPU0 @S9S_MB_2U_LIB.S9S_MB_2U(SCH_1):PVCCIN_CPU0    I43 @S9S_MB_2U_LIB.S9S_MB_2U(SCH_1):PAGE74
     2    GND @S9S_MB_2U_LIB.S9S_MB_2U(SCH_1):GND    I43 @S9S_MB_2U_LIB.S9S_MB_2U(SCH_1):PAGE74

C218 Q_CAP_C0805-47UF,4V,20%,X6S,CHA
     1 PVCCIN_CPU0 @S9S_MB_2U_LIB.S9S_MB_2U(SCH_1):PVCCIN_CPU0    I44 @S9S_MB_2U_LIB.S9S_MB_2U(SCH_1):PAGE74
     2    GND @S9S_MB_2U_LIB.S9S_MB_2U(SCH_1):GND    I44 @S9S_MB_2U_LIB.S9S_MB_2U(SCH_1):PAGE74

C219 Q_CAP_C0805-47UF,4V,20%,X6S,CHA
     1 PVCCIN_CPU0 @S9S_MB_2U_LIB.S9S_MB_2U(SCH_1):PVCCIN_CPU0    I71 @S9S_MB_2U_LIB.S9S_MB_2U(SCH_1):PAGE74
     2    GND @S9S_MB_2U_LIB.S9S_MB_2U(SCH_1):GND    I71 @S9S_MB_2U_LIB.S9S_MB_2U(SCH_1):PAGE74

C220 Q_CAP_C0805-47UF,4V,20%,X6S,CHA
     1 PVCCIN_CPU0 @S9S_MB_2U_LIB.S9S_MB_2U(SCH_1):PVCCIN_CPU0    I74 @S9S_MB_2U_LIB.S9S_MB_2U(SCH_1):PAGE74
     2    GND @S9S_MB_2U_LIB.S9S_MB_2U(SCH_1):GND    I74 @S9S_MB_2U_LIB.S9S_MB_2U(SCH_1):PAGE74

C221 Q_CAP_C0402-10UF,6.3V,20%,X6S,B
     1 PVCCIN_CPU1 @S9S_MB_2U_LIB.S9S_MB_2U(SCH_1):PVCCIN_CPU1    I28 @S9S_MB_2U_LIB.S9S_MB_2U(SCH_1):PAGE77
     2    GND @S9S_MB_2U_LIB.S9S_MB_2U(SCH_1):GND    I28 @S9S_MB_2U_LIB.S9S_MB_2U(SCH_1):PAGE77

C222 Q_CAP_C0402-10UF,6.3V,20%,X6S,B
     1 PVCCIN_CPU1 @S9S_MB_2U_LIB.S9S_MB_2U(SCH_1):PVCCIN_CPU1    I25 @S9S_MB_2U_LIB.S9S_MB_2U(SCH_1):PAGE77
     2    GND @S9S_MB_2U_LIB.S9S_MB_2U(SCH_1):GND    I25 @S9S_MB_2U_LIB.S9S_MB_2U(SCH_1):PAGE77

C223 Q_CAP_C0402-10UF,6.3V,20%,X6S,B
     1 PVCCIN_CPU1 @S9S_MB_2U_LIB.S9S_MB_2U(SCH_1):PVCCIN_CPU1    I22 @S9S_MB_2U_LIB.S9S_MB_2U(SCH_1):PAGE77
     2    GND @S9S_MB_2U_LIB.S9S_MB_2U(SCH_1):GND    I22 @S9S_MB_2U_LIB.S9S_MB_2U(SCH_1):PAGE77

C224 Q_CAP_C0402-10UF,6.3V,20%,X6S,B
     1 PVCCIN_CPU1 @S9S_MB_2U_LIB.S9S_MB_2U(SCH_1):PVCCIN_CPU1    I13 @S9S_MB_2U_LIB.S9S_MB_2U(SCH_1):PAGE77
     2    GND @S9S_MB_2U_LIB.S9S_MB_2U(SCH_1):GND    I13 @S9S_MB_2U_LIB.S9S_MB_2U(SCH_1):PAGE77

C225 Q_CAP_C0805-47UF,4V,20%,X6S,CHA
     1 PVCCIN_CPU1 @S9S_MB_2U_LIB.S9S_MB_2U(SCH_1):PVCCIN_CPU1    I10 @S9S_MB_2U_LIB.S9S_MB_2U(SCH_1):PAGE77
     2    GND @S9S_MB_2U_LIB.S9S_MB_2U(SCH_1):GND    I10 @S9S_MB_2U_LIB.S9S_MB_2U(SCH_1):PAGE77

C226 Q_CAP_C0402-10UF,6.3V,20%,X6S,B
     1 PVCCIN_CPU1 @S9S_MB_2U_LIB.S9S_MB_2U(SCH_1):PVCCIN_CPU1    I29 @S9S_MB_2U_LIB.S9S_MB_2U(SCH_1):PAGE77
     2    GND @S9S_MB_2U_LIB.S9S_MB_2U(SCH_1):GND    I29 @S9S_MB_2U_LIB.S9S_MB_2U(SCH_1):PAGE77

C227 Q_CAP_C0402-10UF,6.3V,20%,X6S,B
     1 PVCCIN_CPU1 @S9S_MB_2U_LIB.S9S_MB_2U(SCH_1):PVCCIN_CPU1    I26 @S9S_MB_2U_LIB.S9S_MB_2U(SCH_1):PAGE77
     2    GND @S9S_MB_2U_LIB.S9S_MB_2U(SCH_1):GND    I26 @S9S_MB_2U_LIB.S9S_MB_2U(SCH_1):PAGE77

C228 Q_CAP_C0402-10UF,6.3V,20%,X6S,B
     1 PVCCIN_CPU1 @S9S_MB_2U_LIB.S9S_MB_2U(SCH_1):PVCCIN_CPU1    I23 @S9S_MB_2U_LIB.S9S_MB_2U(SCH_1):PAGE77
     2    GND @S9S_MB_2U_LIB.S9S_MB_2U(SCH_1):GND    I23 @S9S_MB_2U_LIB.S9S_MB_2U(SCH_1):PAGE77

C229 Q_CAP_C0402-10UF,6.3V,20%,X6S,B
     1 PVCCIN_CPU1 @S9S_MB_2U_LIB.S9S_MB_2U(SCH_1):PVCCIN_CPU1    I14 @S9S_MB_2U_LIB.S9S_MB_2U(SCH_1):PAGE77
     2    GND @S9S_MB_2U_LIB.S9S_MB_2U(SCH_1):GND    I14 @S9S_MB_2U_LIB.S9S_MB_2U(SCH_1):PAGE77

C230 Q_CAP_C0805-47UF,4V,20%,X6S,CHA
     1 PVCCIN_CPU1 @S9S_MB_2U_LIB.S9S_MB_2U(SCH_1):PVCCIN_CPU1    I11 @S9S_MB_2U_LIB.S9S_MB_2U(SCH_1):PAGE77
     2    GND @S9S_MB_2U_LIB.S9S_MB_2U(SCH_1):GND    I11 @S9S_MB_2U_LIB.S9S_MB_2U(SCH_1):PAGE77

C231 Q_CAP_C0402-10UF,6.3V,20%,X6S,B
     1 PVCCIN_CPU1 @S9S_MB_2U_LIB.S9S_MB_2U(SCH_1):PVCCIN_CPU1    I33 @S9S_MB_2U_LIB.S9S_MB_2U(SCH_1):PAGE77
     2    GND @S9S_MB_2U_LIB.S9S_MB_2U(SCH_1):GND    I33 @S9S_MB_2U_LIB.S9S_MB_2U(SCH_1):PAGE77

C232 Q_CAP_C0402-10UF,6.3V,20%,X6S,B
     1 PVCCIN_CPU1 @S9S_MB_2U_LIB.S9S_MB_2U(SCH_1):PVCCIN_CPU1    I32 @S9S_MB_2U_LIB.S9S_MB_2U(SCH_1):PAGE77
     2    GND @S9S_MB_2U_LIB.S9S_MB_2U(SCH_1):GND    I32 @S9S_MB_2U_LIB.S9S_MB_2U(SCH_1):PAGE77

C233 Q_CAP_C0402-10UF,6.3V,20%,X6S,B
     1 PVCCIN_CPU1 @S9S_MB_2U_LIB.S9S_MB_2U(SCH_1):PVCCIN_CPU1    I30 @S9S_MB_2U_LIB.S9S_MB_2U(SCH_1):PAGE77
     2    GND @S9S_MB_2U_LIB.S9S_MB_2U(SCH_1):GND    I30 @S9S_MB_2U_LIB.S9S_MB_2U(SCH_1):PAGE77

C234 Q_CAP_C0402-10UF,6.3V,20%,X6S,B
     1 PVCCIN_CPU1 @S9S_MB_2U_LIB.S9S_MB_2U(SCH_1):PVCCIN_CPU1    I19 @S9S_MB_2U_LIB.S9S_MB_2U(SCH_1):PAGE77
     2    GND @S9S_MB_2U_LIB.S9S_MB_2U(SCH_1):GND    I19 @S9S_MB_2U_LIB.S9S_MB_2U(SCH_1):PAGE77

C235 Q_CAP_C0805-47UF,4V,20%,X6S,CHA
     1 PVCCIN_CPU1 @S9S_MB_2U_LIB.S9S_MB_2U(SCH_1):PVCCIN_CPU1    I16 @S9S_MB_2U_LIB.S9S_MB_2U(SCH_1):PAGE77
     2    GND @S9S_MB_2U_LIB.S9S_MB_2U(SCH_1):GND    I16 @S9S_MB_2U_LIB.S9S_MB_2U(SCH_1):PAGE77

C236 Q_CAP_C0402-10UF,6.3V,20%,X6S,B
     1 PVCCIN_CPU1 @S9S_MB_2U_LIB.S9S_MB_2U(SCH_1):PVCCIN_CPU1    I35 @S9S_MB_2U_LIB.S9S_MB_2U(SCH_1):PAGE77
     2    GND @S9S_MB_2U_LIB.S9S_MB_2U(SCH_1):GND    I35 @S9S_MB_2U_LIB.S9S_MB_2U(SCH_1):PAGE77

C237 Q_CAP_C0402-10UF,6.3V,20%,X6S,B
     1 PVCCIN_CPU1 @S9S_MB_2U_LIB.S9S_MB_2U(SCH_1):PVCCIN_CPU1    I34 @S9S_MB_2U_LIB.S9S_MB_2U(SCH_1):PAGE77
     2    GND @S9S_MB_2U_LIB.S9S_MB_2U(SCH_1):GND    I34 @S9S_MB_2U_LIB.S9S_MB_2U(SCH_1):PAGE77

C238 Q_CAP_C0402-10UF,6.3V,20%,X6S,B
     1 PVCCIN_CPU1 @S9S_MB_2U_LIB.S9S_MB_2U(SCH_1):PVCCIN_CPU1    I31 @S9S_MB_2U_LIB.S9S_MB_2U(SCH_1):PAGE77
     2    GND @S9S_MB_2U_LIB.S9S_MB_2U(SCH_1):GND    I31 @S9S_MB_2U_LIB.S9S_MB_2U(SCH_1):PAGE77

C239 Q_CAP_C0402-10UF,6.3V,20%,X6S,B
     1 PVCCIN_CPU1 @S9S_MB_2U_LIB.S9S_MB_2U(SCH_1):PVCCIN_CPU1    I20 @S9S_MB_2U_LIB.S9S_MB_2U(SCH_1):PAGE77
     2    GND @S9S_MB_2U_LIB.S9S_MB_2U(SCH_1):GND    I20 @S9S_MB_2U_LIB.S9S_MB_2U(SCH_1):PAGE77

C240 Q_CAP_C0805-47UF,4V,20%,X6S,CHA
     1 PVCCIN_CPU1 @S9S_MB_2U_LIB.S9S_MB_2U(SCH_1):PVCCIN_CPU1    I18 @S9S_MB_2U_LIB.S9S_MB_2U(SCH_1):PAGE77
     2    GND @S9S_MB_2U_LIB.S9S_MB_2U(SCH_1):GND    I18 @S9S_MB_2U_LIB.S9S_MB_2U(SCH_1):PAGE77

C241 Q_CAP_C0402-10UF,6.3V,20%,X6S,B
     1 PVCCIN_CPU1 @S9S_MB_2U_LIB.S9S_MB_2U(SCH_1):PVCCIN_CPU1    I77 @S9S_MB_2U_LIB.S9S_MB_2U(SCH_1):PAGE77
     2    GND @S9S_MB_2U_LIB.S9S_MB_2U(SCH_1):GND    I77 @S9S_MB_2U_LIB.S9S_MB_2U(SCH_1):PAGE77

C242 Q_CAP_C0402-10UF,6.3V,20%,X6S,B
     1 PVCCIN_CPU1 @S9S_MB_2U_LIB.S9S_MB_2U(SCH_1):PVCCIN_CPU1    I76 @S9S_MB_2U_LIB.S9S_MB_2U(SCH_1):PAGE77
     2    GND @S9S_MB_2U_LIB.S9S_MB_2U(SCH_1):GND    I76 @S9S_MB_2U_LIB.S9S_MB_2U(SCH_1):PAGE77

C243 Q_CAP_C0402-10UF,6.3V,20%,X6S,B
     1 PVCCIN_CPU1 @S9S_MB_2U_LIB.S9S_MB_2U(SCH_1):PVCCIN_CPU1    I74 @S9S_MB_2U_LIB.S9S_MB_2U(SCH_1):PAGE77
     2    GND @S9S_MB_2U_LIB.S9S_MB_2U(SCH_1):GND    I74 @S9S_MB_2U_LIB.S9S_MB_2U(SCH_1):PAGE77

C244 Q_CAP_C0402-10UF,6.3V,20%,X6S,B
     1 PVCCIN_CPU1 @S9S_MB_2U_LIB.S9S_MB_2U(SCH_1):PVCCIN_CPU1    I45 @S9S_MB_2U_LIB.S9S_MB_2U(SCH_1):PAGE77
     2    GND @S9S_MB_2U_LIB.S9S_MB_2U(SCH_1):GND    I45 @S9S_MB_2U_LIB.S9S_MB_2U(SCH_1):PAGE77

C245 Q_CAP_C0805-47UF,4V,20%,X6S,CHA
     1 PVCCIN_CPU1 @S9S_MB_2U_LIB.S9S_MB_2U(SCH_1):PVCCIN_CPU1    I41 @S9S_MB_2U_LIB.S9S_MB_2U(SCH_1):PAGE77
     2    GND @S9S_MB_2U_LIB.S9S_MB_2U(SCH_1):GND    I41 @S9S_MB_2U_LIB.S9S_MB_2U(SCH_1):PAGE77

C246 Q_CAP_C0402-10UF,6.3V,20%,X6S,B
     1 PVCCIN_CPU1 @S9S_MB_2U_LIB.S9S_MB_2U(SCH_1):PVCCIN_CPU1    I79 @S9S_MB_2U_LIB.S9S_MB_2U(SCH_1):PAGE77
     2    GND @S9S_MB_2U_LIB.S9S_MB_2U(SCH_1):GND    I79 @S9S_MB_2U_LIB.S9S_MB_2U(SCH_1):PAGE77

C247 Q_CAP_C0402-10UF,6.3V,20%,X6S,B
     1 PVCCIN_CPU1 @S9S_MB_2U_LIB.S9S_MB_2U(SCH_1):PVCCIN_CPU1    I78 @S9S_MB_2U_LIB.S9S_MB_2U(SCH_1):PAGE77
     2    GND @S9S_MB_2U_LIB.S9S_MB_2U(SCH_1):GND    I78 @S9S_MB_2U_LIB.S9S_MB_2U(SCH_1):PAGE77

C248 Q_CAP_C0402-10UF,6.3V,20%,X6S,B
     1 PVCCIN_CPU1 @S9S_MB_2U_LIB.S9S_MB_2U(SCH_1):PVCCIN_CPU1    I75 @S9S_MB_2U_LIB.S9S_MB_2U(SCH_1):PAGE77
     2    GND @S9S_MB_2U_LIB.S9S_MB_2U(SCH_1):GND    I75 @S9S_MB_2U_LIB.S9S_MB_2U(SCH_1):PAGE77

C249 Q_CAP_C0402-10UF,6.3V,20%,X6S,B
     1 PVCCIN_CPU1 @S9S_MB_2U_LIB.S9S_MB_2U(SCH_1):PVCCIN_CPU1    I46 @S9S_MB_2U_LIB.S9S_MB_2U(SCH_1):PAGE77
     2    GND @S9S_MB_2U_LIB.S9S_MB_2U(SCH_1):GND    I46 @S9S_MB_2U_LIB.S9S_MB_2U(SCH_1):PAGE77

C250 Q_CAP_C0805-47UF,4V,20%,X6S,CHA
     1 PVCCIN_CPU1 @S9S_MB_2U_LIB.S9S_MB_2U(SCH_1):PVCCIN_CPU1    I44 @S9S_MB_2U_LIB.S9S_MB_2U(SCH_1):PAGE77
     2    GND @S9S_MB_2U_LIB.S9S_MB_2U(SCH_1):GND    I44 @S9S_MB_2U_LIB.S9S_MB_2U(SCH_1):PAGE77

C251 Q_CAP_C0402-10UF,6.3V,20%,X6S,B
     1 PVCCIN_CPU1 @S9S_MB_2U_LIB.S9S_MB_2U(SCH_1):PVCCIN_CPU1    I83 @S9S_MB_2U_LIB.S9S_MB_2U(SCH_1):PAGE77
     2    GND @S9S_MB_2U_LIB.S9S_MB_2U(SCH_1):GND    I83 @S9S_MB_2U_LIB.S9S_MB_2U(SCH_1):PAGE77

C252 Q_CAP_C0402-10UF,6.3V,20%,X6S,B
     1 PVCCIN_CPU1 @S9S_MB_2U_LIB.S9S_MB_2U(SCH_1):PVCCIN_CPU1    I82 @S9S_MB_2U_LIB.S9S_MB_2U(SCH_1):PAGE77
     2    GND @S9S_MB_2U_LIB.S9S_MB_2U(SCH_1):GND    I82 @S9S_MB_2U_LIB.S9S_MB_2U(SCH_1):PAGE77

C253 Q_CAP_C0402-10UF,6.3V,20%,X6S,B
     1 PVCCIN_CPU1 @S9S_MB_2U_LIB.S9S_MB_2U(SCH_1):PVCCIN_CPU1    I80 @S9S_MB_2U_LIB.S9S_MB_2U(SCH_1):PAGE77
     2    GND @S9S_MB_2U_LIB.S9S_MB_2U(SCH_1):GND    I80 @S9S_MB_2U_LIB.S9S_MB_2U(SCH_1):PAGE77

C254 Q_CAP_C0402-10UF,6.3V,20%,X6S,B
     1 PVCCIN_CPU1 @S9S_MB_2U_LIB.S9S_MB_2U(SCH_1):PVCCIN_CPU1    I51 @S9S_MB_2U_LIB.S9S_MB_2U(SCH_1):PAGE77
     2    GND @S9S_MB_2U_LIB.S9S_MB_2U(SCH_1):GND    I51 @S9S_MB_2U_LIB.S9S_MB_2U(SCH_1):PAGE77

C255 Q_CAP_C0805-47UF,4V,20%,X6S,CHA
     1 PVCCIN_CPU1 @S9S_MB_2U_LIB.S9S_MB_2U(SCH_1):PVCCIN_CPU1    I48 @S9S_MB_2U_LIB.S9S_MB_2U(SCH_1):PAGE77
     2    GND @S9S_MB_2U_LIB.S9S_MB_2U(SCH_1):GND    I48 @S9S_MB_2U_LIB.S9S_MB_2U(SCH_1):PAGE77

C256 Q_CAP_C0402-10UF,6.3V,20%,X6S,B
     1 PVCCIN_CPU1 @S9S_MB_2U_LIB.S9S_MB_2U(SCH_1):PVCCIN_CPU1    I85 @S9S_MB_2U_LIB.S9S_MB_2U(SCH_1):PAGE77
     2    GND @S9S_MB_2U_LIB.S9S_MB_2U(SCH_1):GND    I85 @S9S_MB_2U_LIB.S9S_MB_2U(SCH_1):PAGE77

C257 Q_CAP_C0402-10UF,6.3V,20%,X6S,B
     1 PVCCIN_CPU1 @S9S_MB_2U_LIB.S9S_MB_2U(SCH_1):PVCCIN_CPU1    I84 @S9S_MB_2U_LIB.S9S_MB_2U(SCH_1):PAGE77
     2    GND @S9S_MB_2U_LIB.S9S_MB_2U(SCH_1):GND    I84 @S9S_MB_2U_LIB.S9S_MB_2U(SCH_1):PAGE77

C258 Q_CAP_C0402-10UF,6.3V,20%,X6S,B
     1 PVCCIN_CPU1 @S9S_MB_2U_LIB.S9S_MB_2U(SCH_1):PVCCIN_CPU1    I81 @S9S_MB_2U_LIB.S9S_MB_2U(SCH_1):PAGE77
     2    GND @S9S_MB_2U_LIB.S9S_MB_2U(SCH_1):GND    I81 @S9S_MB_2U_LIB.S9S_MB_2U(SCH_1):PAGE77

C259 Q_CAP_C0402-10UF,6.3V,20%,X6S,B
     1 PVCCIN_CPU1 @S9S_MB_2U_LIB.S9S_MB_2U(SCH_1):PVCCIN_CPU1    I52 @S9S_MB_2U_LIB.S9S_MB_2U(SCH_1):PAGE77
     2    GND @S9S_MB_2U_LIB.S9S_MB_2U(SCH_1):GND    I52 @S9S_MB_2U_LIB.S9S_MB_2U(SCH_1):PAGE77

C260 Q_CAP_C0805-47UF,4V,20%,X6S,CHA
     1 PVCCIN_CPU1 @S9S_MB_2U_LIB.S9S_MB_2U(SCH_1):PVCCIN_CPU1    I50 @S9S_MB_2U_LIB.S9S_MB_2U(SCH_1):PAGE77
     2    GND @S9S_MB_2U_LIB.S9S_MB_2U(SCH_1):GND    I50 @S9S_MB_2U_LIB.S9S_MB_2U(SCH_1):PAGE77

C261 Q_CAP_C0402-10UF,6.3V,20%,X6S,B
     1 PVCCIN_CPU1 @S9S_MB_2U_LIB.S9S_MB_2U(SCH_1):PVCCIN_CPU1    I95 @S9S_MB_2U_LIB.S9S_MB_2U(SCH_1):PAGE77
     2    GND @S9S_MB_2U_LIB.S9S_MB_2U(SCH_1):GND    I95 @S9S_MB_2U_LIB.S9S_MB_2U(SCH_1):PAGE77

C262 Q_CAP_C0402-10UF,6.3V,20%,X6S,B
     1 PVCCIN_CPU1 @S9S_MB_2U_LIB.S9S_MB_2U(SCH_1):PVCCIN_CPU1    I93 @S9S_MB_2U_LIB.S9S_MB_2U(SCH_1):PAGE77
     2    GND @S9S_MB_2U_LIB.S9S_MB_2U(SCH_1):GND    I93 @S9S_MB_2U_LIB.S9S_MB_2U(SCH_1):PAGE77

C263 Q_CAP_C0402-10UF,6.3V,20%,X6S,B
     1 PVCCIN_CPU1 @S9S_MB_2U_LIB.S9S_MB_2U(SCH_1):PVCCIN_CPU1    I86 @S9S_MB_2U_LIB.S9S_MB_2U(SCH_1):PAGE77
     2    GND @S9S_MB_2U_LIB.S9S_MB_2U(SCH_1):GND    I86 @S9S_MB_2U_LIB.S9S_MB_2U(SCH_1):PAGE77

C264 Q_CAP_C0402-10UF,6.3V,20%,X6S,B
     1 PVCCIN_CPU1 @S9S_MB_2U_LIB.S9S_MB_2U(SCH_1):PVCCIN_CPU1    I63 @S9S_MB_2U_LIB.S9S_MB_2U(SCH_1):PAGE77
     2    GND @S9S_MB_2U_LIB.S9S_MB_2U(SCH_1):GND    I63 @S9S_MB_2U_LIB.S9S_MB_2U(SCH_1):PAGE77

C265 Q_CAP_C0805-47UF,4V,20%,X6S,CHA
     1 PVCCIN_CPU1 @S9S_MB_2U_LIB.S9S_MB_2U(SCH_1):PVCCIN_CPU1    I59 @S9S_MB_2U_LIB.S9S_MB_2U(SCH_1):PAGE77
     2    GND @S9S_MB_2U_LIB.S9S_MB_2U(SCH_1):GND    I59 @S9S_MB_2U_LIB.S9S_MB_2U(SCH_1):PAGE77

C266 Q_CAP_C0402-10UF,6.3V,20%,X6S,B
     1 PVCCIN_CPU1 @S9S_MB_2U_LIB.S9S_MB_2U(SCH_1):PVCCIN_CPU1    I97 @S9S_MB_2U_LIB.S9S_MB_2U(SCH_1):PAGE77
     2    GND @S9S_MB_2U_LIB.S9S_MB_2U(SCH_1):GND    I97 @S9S_MB_2U_LIB.S9S_MB_2U(SCH_1):PAGE77

C267 Q_CAP_C0402-10UF,6.3V,20%,X6S,B
     1 PVCCIN_CPU1 @S9S_MB_2U_LIB.S9S_MB_2U(SCH_1):PVCCIN_CPU1    I94 @S9S_MB_2U_LIB.S9S_MB_2U(SCH_1):PAGE77
     2    GND @S9S_MB_2U_LIB.S9S_MB_2U(SCH_1):GND    I94 @S9S_MB_2U_LIB.S9S_MB_2U(SCH_1):PAGE77

C268 Q_CAP_C0402-10UF,6.3V,20%,X6S,B
     1 PVCCIN_CPU1 @S9S_MB_2U_LIB.S9S_MB_2U(SCH_1):PVCCIN_CPU1    I88 @S9S_MB_2U_LIB.S9S_MB_2U(SCH_1):PAGE77
     2    GND @S9S_MB_2U_LIB.S9S_MB_2U(SCH_1):GND    I88 @S9S_MB_2U_LIB.S9S_MB_2U(SCH_1):PAGE77

C269 Q_CAP_C0402-10UF,6.3V,20%,X6S,B
     1 PVCCIN_CPU1 @S9S_MB_2U_LIB.S9S_MB_2U(SCH_1):PVCCIN_CPU1    I64 @S9S_MB_2U_LIB.S9S_MB_2U(SCH_1):PAGE77
     2    GND @S9S_MB_2U_LIB.S9S_MB_2U(SCH_1):GND    I64 @S9S_MB_2U_LIB.S9S_MB_2U(SCH_1):PAGE77

C270 Q_CAP_C0805-47UF,4V,20%,X6S,CHA
     1 PVCCIN_CPU1 @S9S_MB_2U_LIB.S9S_MB_2U(SCH_1):PVCCIN_CPU1    I62 @S9S_MB_2U_LIB.S9S_MB_2U(SCH_1):PAGE77
     2    GND @S9S_MB_2U_LIB.S9S_MB_2U(SCH_1):GND    I62 @S9S_MB_2U_LIB.S9S_MB_2U(SCH_1):PAGE77

C271 Q_CAP_C0402-22UF,4V,20%,X6S,CHA
     1 PVCCIN_CPU1 @S9S_MB_2U_LIB.S9S_MB_2U(SCH_1):PVCCIN_CPU1   I100 @S9S_MB_2U_LIB.S9S_MB_2U(SCH_1):PAGE77
     2    GND @S9S_MB_2U_LIB.S9S_MB_2U(SCH_1):GND   I100 @S9S_MB_2U_LIB.S9S_MB_2U(SCH_1):PAGE77

C272 Q_CAP_C0402-22UF,4V,20%,X6S,CHA
     1 PVCCIN_CPU1 @S9S_MB_2U_LIB.S9S_MB_2U(SCH_1):PVCCIN_CPU1    I98 @S9S_MB_2U_LIB.S9S_MB_2U(SCH_1):PAGE77
     2    GND @S9S_MB_2U_LIB.S9S_MB_2U(SCH_1):GND    I98 @S9S_MB_2U_LIB.S9S_MB_2U(SCH_1):PAGE77

C273 Q_CAP_C0402-22UF,4V,20%,X6S,CHA
     1 PVCCIN_CPU1 @S9S_MB_2U_LIB.S9S_MB_2U(SCH_1):PVCCIN_CPU1    I91 @S9S_MB_2U_LIB.S9S_MB_2U(SCH_1):PAGE77
     2    GND @S9S_MB_2U_LIB.S9S_MB_2U(SCH_1):GND    I91 @S9S_MB_2U_LIB.S9S_MB_2U(SCH_1):PAGE77

C274 Q_CAP_C0402-22UF,4V,20%,X6S,CHA
     1 PVCCIN_CPU1 @S9S_MB_2U_LIB.S9S_MB_2U(SCH_1):PVCCIN_CPU1    I66 @S9S_MB_2U_LIB.S9S_MB_2U(SCH_1):PAGE77
     2    GND @S9S_MB_2U_LIB.S9S_MB_2U(SCH_1):GND    I66 @S9S_MB_2U_LIB.S9S_MB_2U(SCH_1):PAGE77

C275 Q_CAP_C0402-22UF,4V,20%,X6S,CHA
     1 PVCCIN_CPU1 @S9S_MB_2U_LIB.S9S_MB_2U(SCH_1):PVCCIN_CPU1   I104 @S9S_MB_2U_LIB.S9S_MB_2U(SCH_1):PAGE77
     2    GND @S9S_MB_2U_LIB.S9S_MB_2U(SCH_1):GND   I104 @S9S_MB_2U_LIB.S9S_MB_2U(SCH_1):PAGE77

C276 Q_CAP_C0402-22UF,4V,20%,X6S,CHA
     1 PVCCIN_CPU1 @S9S_MB_2U_LIB.S9S_MB_2U(SCH_1):PVCCIN_CPU1   I103 @S9S_MB_2U_LIB.S9S_MB_2U(SCH_1):PAGE77
     2    GND @S9S_MB_2U_LIB.S9S_MB_2U(SCH_1):GND   I103 @S9S_MB_2U_LIB.S9S_MB_2U(SCH_1):PAGE77

C277 Q_CAP_C0402-22UF,4V,20%,X6S,CHA
     1 PVCCIN_CPU1 @S9S_MB_2U_LIB.S9S_MB_2U(SCH_1):PVCCIN_CPU1   I101 @S9S_MB_2U_LIB.S9S_MB_2U(SCH_1):PAGE77
     2    GND @S9S_MB_2U_LIB.S9S_MB_2U(SCH_1):GND   I101 @S9S_MB_2U_LIB.S9S_MB_2U(SCH_1):PAGE77

C278 Q_CAP_C0402-22UF,4V,20%,X6S,CHA
     1 PVCCIN_CPU1 @S9S_MB_2U_LIB.S9S_MB_2U(SCH_1):PVCCIN_CPU1    I71 @S9S_MB_2U_LIB.S9S_MB_2U(SCH_1):PAGE77
     2    GND @S9S_MB_2U_LIB.S9S_MB_2U(SCH_1):GND    I71 @S9S_MB_2U_LIB.S9S_MB_2U(SCH_1):PAGE77

C279 Q_CAP_C0402-22UF,4V,20%,X6S,CHA
     1 PVCCIN_CPU1 @S9S_MB_2U_LIB.S9S_MB_2U(SCH_1):PVCCIN_CPU1   I106 @S9S_MB_2U_LIB.S9S_MB_2U(SCH_1):PAGE77
     2    GND @S9S_MB_2U_LIB.S9S_MB_2U(SCH_1):GND   I106 @S9S_MB_2U_LIB.S9S_MB_2U(SCH_1):PAGE77

C280 Q_CAP_C0402-22UF,4V,20%,X6S,CHA
     1 PVCCIN_CPU1 @S9S_MB_2U_LIB.S9S_MB_2U(SCH_1):PVCCIN_CPU1   I105 @S9S_MB_2U_LIB.S9S_MB_2U(SCH_1):PAGE77
     2    GND @S9S_MB_2U_LIB.S9S_MB_2U(SCH_1):GND   I105 @S9S_MB_2U_LIB.S9S_MB_2U(SCH_1):PAGE77

C281 Q_CAP_C0402-22UF,4V,20%,X6S,CHA
     1 PVCCIN_CPU1 @S9S_MB_2U_LIB.S9S_MB_2U(SCH_1):PVCCIN_CPU1   I102 @S9S_MB_2U_LIB.S9S_MB_2U(SCH_1):PAGE77
     2    GND @S9S_MB_2U_LIB.S9S_MB_2U(SCH_1):GND   I102 @S9S_MB_2U_LIB.S9S_MB_2U(SCH_1):PAGE77

C282 Q_CAP_C0402-22UF,4V,20%,X6S,CHA
     1 PVCCIN_CPU1 @S9S_MB_2U_LIB.S9S_MB_2U(SCH_1):PVCCIN_CPU1    I73 @S9S_MB_2U_LIB.S9S_MB_2U(SCH_1):PAGE77
     2    GND @S9S_MB_2U_LIB.S9S_MB_2U(SCH_1):GND    I73 @S9S_MB_2U_LIB.S9S_MB_2U(SCH_1):PAGE77

C283 Q_CAP_C0402-22UF,4V,20%,X6S,CHA
     1 PVCCIN_CPU1 @S9S_MB_2U_LIB.S9S_MB_2U(SCH_1):PVCCIN_CPU1   I122 @S9S_MB_2U_LIB.S9S_MB_2U(SCH_1):PAGE77
     2    GND @S9S_MB_2U_LIB.S9S_MB_2U(SCH_1):GND   I122 @S9S_MB_2U_LIB.S9S_MB_2U(SCH_1):PAGE77

C284 Q_CAP_C0402-22UF,4V,20%,X6S,CHA
     1 PVCCIN_CPU1 @S9S_MB_2U_LIB.S9S_MB_2U(SCH_1):PVCCIN_CPU1   I121 @S9S_MB_2U_LIB.S9S_MB_2U(SCH_1):PAGE77
     2    GND @S9S_MB_2U_LIB.S9S_MB_2U(SCH_1):GND   I121 @S9S_MB_2U_LIB.S9S_MB_2U(SCH_1):PAGE77

C285 Q_CAP_C0402-22UF,4V,20%,X6S,CHA
     1 PVCCIN_CPU1 @S9S_MB_2U_LIB.S9S_MB_2U(SCH_1):PVCCIN_CPU1   I119 @S9S_MB_2U_LIB.S9S_MB_2U(SCH_1):PAGE77
     2    GND @S9S_MB_2U_LIB.S9S_MB_2U(SCH_1):GND   I119 @S9S_MB_2U_LIB.S9S_MB_2U(SCH_1):PAGE77

C286 Q_CAP_C0402-22UF,4V,20%,X6S,CHA
     1 PVCCIN_CPU1 @S9S_MB_2U_LIB.S9S_MB_2U(SCH_1):PVCCIN_CPU1   I111 @S9S_MB_2U_LIB.S9S_MB_2U(SCH_1):PAGE77
     2    GND @S9S_MB_2U_LIB.S9S_MB_2U(SCH_1):GND   I111 @S9S_MB_2U_LIB.S9S_MB_2U(SCH_1):PAGE77

C287 Q_CAP_C0402-22UF,4V,20%,X6S,CHA
     1 PVCCIN_CPU1 @S9S_MB_2U_LIB.S9S_MB_2U(SCH_1):PVCCIN_CPU1   I124 @S9S_MB_2U_LIB.S9S_MB_2U(SCH_1):PAGE77
     2    GND @S9S_MB_2U_LIB.S9S_MB_2U(SCH_1):GND   I124 @S9S_MB_2U_LIB.S9S_MB_2U(SCH_1):PAGE77

C288 Q_CAP_C0402-22UF,4V,20%,X6S,CHA
     1 PVCCIN_CPU1 @S9S_MB_2U_LIB.S9S_MB_2U(SCH_1):PVCCIN_CPU1   I123 @S9S_MB_2U_LIB.S9S_MB_2U(SCH_1):PAGE77
     2    GND @S9S_MB_2U_LIB.S9S_MB_2U(SCH_1):GND   I123 @S9S_MB_2U_LIB.S9S_MB_2U(SCH_1):PAGE77

C289 Q_CAP_C0402-22UF,4V,20%,X6S,CHA
     1 PVCCIN_CPU1 @S9S_MB_2U_LIB.S9S_MB_2U(SCH_1):PVCCIN_CPU1   I120 @S9S_MB_2U_LIB.S9S_MB_2U(SCH_1):PAGE77
     2    GND @S9S_MB_2U_LIB.S9S_MB_2U(SCH_1):GND   I120 @S9S_MB_2U_LIB.S9S_MB_2U(SCH_1):PAGE77

C290 Q_CAP_C0402-22UF,4V,20%,X6S,CHA
     1 PVCCIN_CPU1 @S9S_MB_2U_LIB.S9S_MB_2U(SCH_1):PVCCIN_CPU1   I112 @S9S_MB_2U_LIB.S9S_MB_2U(SCH_1):PAGE77
     2    GND @S9S_MB_2U_LIB.S9S_MB_2U(SCH_1):GND   I112 @S9S_MB_2U_LIB.S9S_MB_2U(SCH_1):PAGE77

C291 Q_CAP_C0402-22UF,4V,20%,X6S,CHA
     1 PVCCIN_CPU1 @S9S_MB_2U_LIB.S9S_MB_2U(SCH_1):PVCCIN_CPU1   I128 @S9S_MB_2U_LIB.S9S_MB_2U(SCH_1):PAGE77
     2    GND @S9S_MB_2U_LIB.S9S_MB_2U(SCH_1):GND   I128 @S9S_MB_2U_LIB.S9S_MB_2U(SCH_1):PAGE77

C292 Q_CAP_C0402-22UF,4V,20%,X6S,CHA
     1 PVCCIN_CPU1 @S9S_MB_2U_LIB.S9S_MB_2U(SCH_1):PVCCIN_CPU1   I127 @S9S_MB_2U_LIB.S9S_MB_2U(SCH_1):PAGE77
     2    GND @S9S_MB_2U_LIB.S9S_MB_2U(SCH_1):GND   I127 @S9S_MB_2U_LIB.S9S_MB_2U(SCH_1):PAGE77

C293 Q_CAP_C0402-22UF,4V,20%,X6S,CHA
     1 PVCCIN_CPU1 @S9S_MB_2U_LIB.S9S_MB_2U(SCH_1):PVCCIN_CPU1   I125 @S9S_MB_2U_LIB.S9S_MB_2U(SCH_1):PAGE77
     2    GND @S9S_MB_2U_LIB.S9S_MB_2U(SCH_1):GND   I125 @S9S_MB_2U_LIB.S9S_MB_2U(SCH_1):PAGE77

C294 Q_CAP_C0402-22UF,4V,20%,X6S,CHA
     1 PVCCIN_CPU1 @S9S_MB_2U_LIB.S9S_MB_2U(SCH_1):PVCCIN_CPU1   I114 @S9S_MB_2U_LIB.S9S_MB_2U(SCH_1):PAGE77
     2    GND @S9S_MB_2U_LIB.S9S_MB_2U(SCH_1):GND   I114 @S9S_MB_2U_LIB.S9S_MB_2U(SCH_1):PAGE77

C295 Q_CAP_C0402-22UF,4V,20%,X6S,CHA
     1 PVCCIN_CPU1 @S9S_MB_2U_LIB.S9S_MB_2U(SCH_1):PVCCIN_CPU1   I130 @S9S_MB_2U_LIB.S9S_MB_2U(SCH_1):PAGE77
     2    GND @S9S_MB_2U_LIB.S9S_MB_2U(SCH_1):GND   I130 @S9S_MB_2U_LIB.S9S_MB_2U(SCH_1):PAGE77

C296 Q_CAP_C0402-22UF,4V,20%,X6S,CHA
     1 PVCCIN_CPU1 @S9S_MB_2U_LIB.S9S_MB_2U(SCH_1):PVCCIN_CPU1   I129 @S9S_MB_2U_LIB.S9S_MB_2U(SCH_1):PAGE77
     2    GND @S9S_MB_2U_LIB.S9S_MB_2U(SCH_1):GND   I129 @S9S_MB_2U_LIB.S9S_MB_2U(SCH_1):PAGE77

C297 Q_CAP_C0402-22UF,4V,20%,X6S,CHA
     1 PVCCIN_CPU1 @S9S_MB_2U_LIB.S9S_MB_2U(SCH_1):PVCCIN_CPU1   I126 @S9S_MB_2U_LIB.S9S_MB_2U(SCH_1):PAGE77
     2    GND @S9S_MB_2U_LIB.S9S_MB_2U(SCH_1):GND   I126 @S9S_MB_2U_LIB.S9S_MB_2U(SCH_1):PAGE77

C298 Q_CAP_C0402-22UF,4V,20%,X6S,CHA
     1 PVCCIN_CPU1 @S9S_MB_2U_LIB.S9S_MB_2U(SCH_1):PVCCIN_CPU1   I115 @S9S_MB_2U_LIB.S9S_MB_2U(SCH_1):PAGE77
     2    GND @S9S_MB_2U_LIB.S9S_MB_2U(SCH_1):GND   I115 @S9S_MB_2U_LIB.S9S_MB_2U(SCH_1):PAGE77

C299 Q_CAP_C0402-22UF,4V,20%,X6S,CHA
     1 PVCCIN_CPU1 @S9S_MB_2U_LIB.S9S_MB_2U(SCH_1):PVCCIN_CPU1   I131 @S9S_MB_2U_LIB.S9S_MB_2U(SCH_1):PAGE77
     2    GND @S9S_MB_2U_LIB.S9S_MB_2U(SCH_1):GND   I131 @S9S_MB_2U_LIB.S9S_MB_2U(SCH_1):PAGE77

C300 Q_CAP_C0402-22UF,4V,20%,X6S,CHA
     1 PVCCIN_CPU1 @S9S_MB_2U_LIB.S9S_MB_2U(SCH_1):PVCCIN_CPU1   I132 @S9S_MB_2U_LIB.S9S_MB_2U(SCH_1):PAGE77
     2    GND @S9S_MB_2U_LIB.S9S_MB_2U(SCH_1):GND   I132 @S9S_MB_2U_LIB.S9S_MB_2U(SCH_1):PAGE77

C301 Q_CAP_C0402-22UF,4V,20%,X6S,CHA
     1 PVCCIN_CPU1 @S9S_MB_2U_LIB.S9S_MB_2U(SCH_1):PVCCIN_CPU1   I133 @S9S_MB_2U_LIB.S9S_MB_2U(SCH_1):PAGE77
     2    GND @S9S_MB_2U_LIB.S9S_MB_2U(SCH_1):GND   I133 @S9S_MB_2U_LIB.S9S_MB_2U(SCH_1):PAGE77

C302 Q_CAP_C0402-22UF,4V,20%,X6S,CHA
     1 PVCCIN_CPU1 @S9S_MB_2U_LIB.S9S_MB_2U(SCH_1):PVCCIN_CPU1   I117 @S9S_MB_2U_LIB.S9S_MB_2U(SCH_1):PAGE77
     2    GND @S9S_MB_2U_LIB.S9S_MB_2U(SCH_1):GND   I117 @S9S_MB_2U_LIB.S9S_MB_2U(SCH_1):PAGE77

C303 Q_CAP_C0402-22UF,4V,20%,X6S,CHA
     1 PVCCIN_CPU1 @S9S_MB_2U_LIB.S9S_MB_2U(SCH_1):PVCCIN_CPU1   I139 @S9S_MB_2U_LIB.S9S_MB_2U(SCH_1):PAGE77
     2    GND @S9S_MB_2U_LIB.S9S_MB_2U(SCH_1):GND   I139 @S9S_MB_2U_LIB.S9S_MB_2U(SCH_1):PAGE77

C304 Q_CAP_C0402-22UF,4V,20%,X6S,CHA
     1 PVCCIN_CPU1 @S9S_MB_2U_LIB.S9S_MB_2U(SCH_1):PVCCIN_CPU1   I138 @S9S_MB_2U_LIB.S9S_MB_2U(SCH_1):PAGE77
     2    GND @S9S_MB_2U_LIB.S9S_MB_2U(SCH_1):GND   I138 @S9S_MB_2U_LIB.S9S_MB_2U(SCH_1):PAGE77

C305 Q_CAP_C0402-22UF,4V,20%,X6S,CHA
     1 PVCCIN_CPU1 @S9S_MB_2U_LIB.S9S_MB_2U(SCH_1):PVCCIN_CPU1   I134 @S9S_MB_2U_LIB.S9S_MB_2U(SCH_1):PAGE77
     2    GND @S9S_MB_2U_LIB.S9S_MB_2U(SCH_1):GND   I134 @S9S_MB_2U_LIB.S9S_MB_2U(SCH_1):PAGE77

C306 Q_CAP_C0402-22UF,4V,20%,X6S,CHA
     1 PVCCIN_CPU1 @S9S_MB_2U_LIB.S9S_MB_2U(SCH_1):PVCCIN_CPU1   I118 @S9S_MB_2U_LIB.S9S_MB_2U(SCH_1):PAGE77
     2    GND @S9S_MB_2U_LIB.S9S_MB_2U(SCH_1):GND   I118 @S9S_MB_2U_LIB.S9S_MB_2U(SCH_1):PAGE77

C307 Q_CAP_C0402-22UF,4V,20%,X6S,CHA
     1 PVCCIN_CPU1 @S9S_MB_2U_LIB.S9S_MB_2U(SCH_1):PVCCIN_CPU1   I142 @S9S_MB_2U_LIB.S9S_MB_2U(SCH_1):PAGE77
     2    GND @S9S_MB_2U_LIB.S9S_MB_2U(SCH_1):GND   I142 @S9S_MB_2U_LIB.S9S_MB_2U(SCH_1):PAGE77

C308 Q_CAP_C0402-22UF,4V,20%,X6S,CHA
     1 PVCCIN_CPU1 @S9S_MB_2U_LIB.S9S_MB_2U(SCH_1):PVCCIN_CPU1   I140 @S9S_MB_2U_LIB.S9S_MB_2U(SCH_1):PAGE77
     2    GND @S9S_MB_2U_LIB.S9S_MB_2U(SCH_1):GND   I140 @S9S_MB_2U_LIB.S9S_MB_2U(SCH_1):PAGE77

C309 Q_CAP_C0402-22UF,4V,20%,X6S,CHA
     1 PVCCIN_CPU1 @S9S_MB_2U_LIB.S9S_MB_2U(SCH_1):PVCCIN_CPU1   I136 @S9S_MB_2U_LIB.S9S_MB_2U(SCH_1):PAGE77
     2    GND @S9S_MB_2U_LIB.S9S_MB_2U(SCH_1):GND   I136 @S9S_MB_2U_LIB.S9S_MB_2U(SCH_1):PAGE77

C310 Q_CAP_C0402-22UF,4V,20%,X6S,CHA
     1 PVNN_MAIN_CPU1 @S9S_MB_2U_LIB.S9S_MB_2U(SCH_1):PVNN_MAIN_CPU1    I70 @S9S_MB_2U_LIB.S9S_MB_2U(SCH_1):PAGE77
     2    GND @S9S_MB_2U_LIB.S9S_MB_2U(SCH_1):GND    I70 @S9S_MB_2U_LIB.S9S_MB_2U(SCH_1):PAGE77

C311 Q_CAP_C0805-47UF,4V,20%,X6S,CHA
     1 PVCCIN_CPU1 @S9S_MB_2U_LIB.S9S_MB_2U(SCH_1):PVCCIN_CPU1    I16 @S9S_MB_2U_LIB.S9S_MB_2U(SCH_1):PAGE78
     2    GND @S9S_MB_2U_LIB.S9S_MB_2U(SCH_1):GND    I16 @S9S_MB_2U_LIB.S9S_MB_2U(SCH_1):PAGE78

C312 Q_CAP_C0805-47UF,4V,20%,X6S,CHA
     1 PVCCIN_CPU1 @S9S_MB_2U_LIB.S9S_MB_2U(SCH_1):PVCCIN_CPU1    I14 @S9S_MB_2U_LIB.S9S_MB_2U(SCH_1):PAGE78
     2    GND @S9S_MB_2U_LIB.S9S_MB_2U(SCH_1):GND    I14 @S9S_MB_2U_LIB.S9S_MB_2U(SCH_1):PAGE78

C313 Q_CAP_C0805-47UF,4V,20%,X6S,CHA
     1 PVCCIN_CPU1 @S9S_MB_2U_LIB.S9S_MB_2U(SCH_1):PVCCIN_CPU1    I58 @S9S_MB_2U_LIB.S9S_MB_2U(SCH_1):PAGE78
     2    GND @S9S_MB_2U_LIB.S9S_MB_2U(SCH_1):GND    I58 @S9S_MB_2U_LIB.S9S_MB_2U(SCH_1):PAGE78

C314 Q_CAP_C0805-47UF,4V,20%,X6S,CHA
     1 PVCCIN_CPU1 @S9S_MB_2U_LIB.S9S_MB_2U(SCH_1):PVCCIN_CPU1    I37 @S9S_MB_2U_LIB.S9S_MB_2U(SCH_1):PAGE78
     2    GND @S9S_MB_2U_LIB.S9S_MB_2U(SCH_1):GND    I37 @S9S_MB_2U_LIB.S9S_MB_2U(SCH_1):PAGE78

C315 Q_CAP_C0805-47UF,4V,20%,X6S,CHA
     1 PVCCIN_CPU1 @S9S_MB_2U_LIB.S9S_MB_2U(SCH_1):PVCCIN_CPU1    I26 @S9S_MB_2U_LIB.S9S_MB_2U(SCH_1):PAGE78
     2    GND @S9S_MB_2U_LIB.S9S_MB_2U(SCH_1):GND    I26 @S9S_MB_2U_LIB.S9S_MB_2U(SCH_1):PAGE78

C316 Q_CAP_C0805-47UF,4V,20%,X6S,CHA
     1 PVCCIN_CPU1 @S9S_MB_2U_LIB.S9S_MB_2U(SCH_1):PVCCIN_CPU1    I60 @S9S_MB_2U_LIB.S9S_MB_2U(SCH_1):PAGE78
     2    GND @S9S_MB_2U_LIB.S9S_MB_2U(SCH_1):GND    I60 @S9S_MB_2U_LIB.S9S_MB_2U(SCH_1):PAGE78

C317 Q_CAP_C0805-47UF,4V,20%,X6S,CHA
     1 PVCCIN_CPU1 @S9S_MB_2U_LIB.S9S_MB_2U(SCH_1):PVCCIN_CPU1    I38 @S9S_MB_2U_LIB.S9S_MB_2U(SCH_1):PAGE78
     2    GND @S9S_MB_2U_LIB.S9S_MB_2U(SCH_1):GND    I38 @S9S_MB_2U_LIB.S9S_MB_2U(SCH_1):PAGE78

C318 Q_CAP_C0805-47UF,4V,20%,X6S,CHA
     1 PVCCIN_CPU1 @S9S_MB_2U_LIB.S9S_MB_2U(SCH_1):PVCCIN_CPU1    I27 @S9S_MB_2U_LIB.S9S_MB_2U(SCH_1):PAGE78
     2    GND @S9S_MB_2U_LIB.S9S_MB_2U(SCH_1):GND    I27 @S9S_MB_2U_LIB.S9S_MB_2U(SCH_1):PAGE78

C320 Q_CAP_C0805-47UF,4V,20%,X6S,CHA
     1 PVCCIN_CPU1 @S9S_MB_2U_LIB.S9S_MB_2U(SCH_1):PVCCIN_CPU1    I39 @S9S_MB_2U_LIB.S9S_MB_2U(SCH_1):PAGE78
     2    GND @S9S_MB_2U_LIB.S9S_MB_2U(SCH_1):GND    I39 @S9S_MB_2U_LIB.S9S_MB_2U(SCH_1):PAGE78

C321 Q_CAP_C0805-47UF,4V,20%,X6S,CHA
     1 PVCCIN_CPU1 @S9S_MB_2U_LIB.S9S_MB_2U(SCH_1):PVCCIN_CPU1    I30 @S9S_MB_2U_LIB.S9S_MB_2U(SCH_1):PAGE78
     2    GND @S9S_MB_2U_LIB.S9S_MB_2U(SCH_1):GND    I30 @S9S_MB_2U_LIB.S9S_MB_2U(SCH_1):PAGE78

C322 Q_CAP_C0805-47UF,4V,20%,X6S,CHA
     1 PVCCIN_CPU1 @S9S_MB_2U_LIB.S9S_MB_2U(SCH_1):PVCCIN_CPU1    I46 @S9S_MB_2U_LIB.S9S_MB_2U(SCH_1):PAGE79
     2    GND @S9S_MB_2U_LIB.S9S_MB_2U(SCH_1):GND    I46 @S9S_MB_2U_LIB.S9S_MB_2U(SCH_1):PAGE79

C323 Q_CAP_C0805-47UF,4V,20%,X6S,CHA
     1 PVCCIN_CPU1 @S9S_MB_2U_LIB.S9S_MB_2U(SCH_1):PVCCIN_CPU1    I40 @S9S_MB_2U_LIB.S9S_MB_2U(SCH_1):PAGE78
     2    GND @S9S_MB_2U_LIB.S9S_MB_2U(SCH_1):GND    I40 @S9S_MB_2U_LIB.S9S_MB_2U(SCH_1):PAGE78

C324 Q_CAP_C0805-47UF,4V,20%,X6S,CHA
     1 PVCCIN_CPU1 @S9S_MB_2U_LIB.S9S_MB_2U(SCH_1):PVCCIN_CPU1    I31 @S9S_MB_2U_LIB.S9S_MB_2U(SCH_1):PAGE78
     2    GND @S9S_MB_2U_LIB.S9S_MB_2U(SCH_1):GND    I31 @S9S_MB_2U_LIB.S9S_MB_2U(SCH_1):PAGE78

C325 Q_CAP_C0805-47UF,4V,20%,X6S,CHA
     1 PVCCIN_CPU1 @S9S_MB_2U_LIB.S9S_MB_2U(SCH_1):PVCCIN_CPU1    I47 @S9S_MB_2U_LIB.S9S_MB_2U(SCH_1):PAGE79
     2    GND @S9S_MB_2U_LIB.S9S_MB_2U(SCH_1):GND    I47 @S9S_MB_2U_LIB.S9S_MB_2U(SCH_1):PAGE79

C326 Q_CAP_C0805-47UF,4V,20%,X6S,CHA
     1 PVCCIN_CPU1 @S9S_MB_2U_LIB.S9S_MB_2U(SCH_1):PVCCIN_CPU1    I41 @S9S_MB_2U_LIB.S9S_MB_2U(SCH_1):PAGE78
     2    GND @S9S_MB_2U_LIB.S9S_MB_2U(SCH_1):GND    I41 @S9S_MB_2U_LIB.S9S_MB_2U(SCH_1):PAGE78

C327 Q_CAP_C0805-47UF,4V,20%,X6S,CHA
     1 PVCCIN_CPU1 @S9S_MB_2U_LIB.S9S_MB_2U(SCH_1):PVCCIN_CPU1    I32 @S9S_MB_2U_LIB.S9S_MB_2U(SCH_1):PAGE78
     2    GND @S9S_MB_2U_LIB.S9S_MB_2U(SCH_1):GND    I32 @S9S_MB_2U_LIB.S9S_MB_2U(SCH_1):PAGE78

C328 Q_CAP_C0805-47UF,4V,20%,X6S,CHA
     1 PVCCIN_CPU1 @S9S_MB_2U_LIB.S9S_MB_2U(SCH_1):PVCCIN_CPU1    I50 @S9S_MB_2U_LIB.S9S_MB_2U(SCH_1):PAGE79
     2    GND @S9S_MB_2U_LIB.S9S_MB_2U(SCH_1):GND    I50 @S9S_MB_2U_LIB.S9S_MB_2U(SCH_1):PAGE79

C329 Q_CAP_C0805-47UF,4V,20%,X6S,CHA
     1 PVCCIN_CPU1 @S9S_MB_2U_LIB.S9S_MB_2U(SCH_1):PVCCIN_CPU1    I42 @S9S_MB_2U_LIB.S9S_MB_2U(SCH_1):PAGE78
     2    GND @S9S_MB_2U_LIB.S9S_MB_2U(SCH_1):GND    I42 @S9S_MB_2U_LIB.S9S_MB_2U(SCH_1):PAGE78

C330 Q_CAP_C0805-47UF,4V,20%,X6S,CHA
     1 PVCCIN_CPU1 @S9S_MB_2U_LIB.S9S_MB_2U(SCH_1):PVCCIN_CPU1    I33 @S9S_MB_2U_LIB.S9S_MB_2U(SCH_1):PAGE78
     2    GND @S9S_MB_2U_LIB.S9S_MB_2U(SCH_1):GND    I33 @S9S_MB_2U_LIB.S9S_MB_2U(SCH_1):PAGE78

C332 Q_CAP_C0805-47UF,4V,20%,X6S,CHA
     1 PVCCIN_CPU1 @S9S_MB_2U_LIB.S9S_MB_2U(SCH_1):PVCCIN_CPU1    I43 @S9S_MB_2U_LIB.S9S_MB_2U(SCH_1):PAGE78
     2    GND @S9S_MB_2U_LIB.S9S_MB_2U(SCH_1):GND    I43 @S9S_MB_2U_LIB.S9S_MB_2U(SCH_1):PAGE78

C333 Q_CAP_C0805-47UF,4V,20%,X6S,CHA
     1 PVCCIN_CPU1 @S9S_MB_2U_LIB.S9S_MB_2U(SCH_1):PVCCIN_CPU1    I34 @S9S_MB_2U_LIB.S9S_MB_2U(SCH_1):PAGE78
     2    GND @S9S_MB_2U_LIB.S9S_MB_2U(SCH_1):GND    I34 @S9S_MB_2U_LIB.S9S_MB_2U(SCH_1):PAGE78

C335 Q_CAP_C0805-47UF,4V,20%,X6S,CHA
     1 PVCCIN_CPU1 @S9S_MB_2U_LIB.S9S_MB_2U(SCH_1):PVCCIN_CPU1    I44 @S9S_MB_2U_LIB.S9S_MB_2U(SCH_1):PAGE78
     2    GND @S9S_MB_2U_LIB.S9S_MB_2U(SCH_1):GND    I44 @S9S_MB_2U_LIB.S9S_MB_2U(SCH_1):PAGE78

C336 Q_CAP_C0805-47UF,4V,20%,X6S,CHA
     1 PVCCIN_CPU1 @S9S_MB_2U_LIB.S9S_MB_2U(SCH_1):PVCCIN_CPU1    I35 @S9S_MB_2U_LIB.S9S_MB_2U(SCH_1):PAGE78
     2    GND @S9S_MB_2U_LIB.S9S_MB_2U(SCH_1):GND    I35 @S9S_MB_2U_LIB.S9S_MB_2U(SCH_1):PAGE78

C337 Q_CAP_C0805-47UF,4V,20%,X6S,CHA
     1 PVCCIN_CPU1 @S9S_MB_2U_LIB.S9S_MB_2U(SCH_1):PVCCIN_CPU1    I66 @S9S_MB_2U_LIB.S9S_MB_2U(SCH_1):PAGE78
     2    GND @S9S_MB_2U_LIB.S9S_MB_2U(SCH_1):GND    I66 @S9S_MB_2U_LIB.S9S_MB_2U(SCH_1):PAGE78

C338 Q_CAP_C0805-47UF,4V,20%,X6S,CHA
     1 PVCCIN_CPU1 @S9S_MB_2U_LIB.S9S_MB_2U(SCH_1):PVCCIN_CPU1    I45 @S9S_MB_2U_LIB.S9S_MB_2U(SCH_1):PAGE78
     2    GND @S9S_MB_2U_LIB.S9S_MB_2U(SCH_1):GND    I45 @S9S_MB_2U_LIB.S9S_MB_2U(SCH_1):PAGE78

C339 Q_CAP_C0805-47UF,4V,20%,X6S,CHA
     1 PVCCIN_CPU1 @S9S_MB_2U_LIB.S9S_MB_2U(SCH_1):PVCCIN_CPU1    I36 @S9S_MB_2U_LIB.S9S_MB_2U(SCH_1):PAGE78
     2    GND @S9S_MB_2U_LIB.S9S_MB_2U(SCH_1):GND    I36 @S9S_MB_2U_LIB.S9S_MB_2U(SCH_1):PAGE78

C341 Q_CAP_C0805-47UF,4V,20%,X6S,CHA
     1 PVCCIN_CPU1 @S9S_MB_2U_LIB.S9S_MB_2U(SCH_1):PVCCIN_CPU1    I51 @S9S_MB_2U_LIB.S9S_MB_2U(SCH_1):PAGE79
     2    GND @S9S_MB_2U_LIB.S9S_MB_2U(SCH_1):GND    I51 @S9S_MB_2U_LIB.S9S_MB_2U(SCH_1):PAGE79

C342 Q_CAP_C0805-47UF,4V,20%,X6S,CHA
     1 PVCCIN_CPU1 @S9S_MB_2U_LIB.S9S_MB_2U(SCH_1):PVCCIN_CPU1    I23 @S9S_MB_2U_LIB.S9S_MB_2U(SCH_1):PAGE79
     2    GND @S9S_MB_2U_LIB.S9S_MB_2U(SCH_1):GND    I23 @S9S_MB_2U_LIB.S9S_MB_2U(SCH_1):PAGE79

C343 Q_CAP_C0805-47UF,4V,20%,X6S,CHA
     1 PVCCIN_CPU1 @S9S_MB_2U_LIB.S9S_MB_2U(SCH_1):PVCCIN_CPU1    I52 @S9S_MB_2U_LIB.S9S_MB_2U(SCH_1):PAGE79
     2    GND @S9S_MB_2U_LIB.S9S_MB_2U(SCH_1):GND    I52 @S9S_MB_2U_LIB.S9S_MB_2U(SCH_1):PAGE79

C344 Q_CAP_C0805-47UF,4V,20%,X6S,CHA
     1 PVCCIN_CPU1 @S9S_MB_2U_LIB.S9S_MB_2U(SCH_1):PVCCIN_CPU1    I24 @S9S_MB_2U_LIB.S9S_MB_2U(SCH_1):PAGE79
     2    GND @S9S_MB_2U_LIB.S9S_MB_2U(SCH_1):GND    I24 @S9S_MB_2U_LIB.S9S_MB_2U(SCH_1):PAGE79

C345 Q_CAP_C0805-47UF,4V,20%,X6S,CHA
     1 PVCCIN_CPU1 @S9S_MB_2U_LIB.S9S_MB_2U(SCH_1):PVCCIN_CPU1    I53 @S9S_MB_2U_LIB.S9S_MB_2U(SCH_1):PAGE79
     2    GND @S9S_MB_2U_LIB.S9S_MB_2U(SCH_1):GND    I53 @S9S_MB_2U_LIB.S9S_MB_2U(SCH_1):PAGE79

C346 Q_CAP_C0805-47UF,4V,20%,X6S,CHA
     1 PVCCIN_CPU1 @S9S_MB_2U_LIB.S9S_MB_2U(SCH_1):PVCCIN_CPU1    I25 @S9S_MB_2U_LIB.S9S_MB_2U(SCH_1):PAGE79
     2    GND @S9S_MB_2U_LIB.S9S_MB_2U(SCH_1):GND    I25 @S9S_MB_2U_LIB.S9S_MB_2U(SCH_1):PAGE79

C347 Q_CAP_C0805-47UF,4V,20%,X6S,CHA
     1 PVCCIN_CPU1 @S9S_MB_2U_LIB.S9S_MB_2U(SCH_1):PVCCIN_CPU1    I55 @S9S_MB_2U_LIB.S9S_MB_2U(SCH_1):PAGE79
     2    GND @S9S_MB_2U_LIB.S9S_MB_2U(SCH_1):GND    I55 @S9S_MB_2U_LIB.S9S_MB_2U(SCH_1):PAGE79

C348 Q_CAP_C0805-47UF,4V,20%,X6S,CHA
     1 PVCCIN_CPU1 @S9S_MB_2U_LIB.S9S_MB_2U(SCH_1):PVCCIN_CPU1    I32 @S9S_MB_2U_LIB.S9S_MB_2U(SCH_1):PAGE79
     2    GND @S9S_MB_2U_LIB.S9S_MB_2U(SCH_1):GND    I32 @S9S_MB_2U_LIB.S9S_MB_2U(SCH_1):PAGE79

C349 Q_CAP_C0805-47UF,4V,20%,X6S,CHA
     1 PVCCIN_CPU1 @S9S_MB_2U_LIB.S9S_MB_2U(SCH_1):PVCCIN_CPU1    I63 @S9S_MB_2U_LIB.S9S_MB_2U(SCH_1):PAGE78
     2    GND @S9S_MB_2U_LIB.S9S_MB_2U(SCH_1):GND    I63 @S9S_MB_2U_LIB.S9S_MB_2U(SCH_1):PAGE78

C350 Q_CAP_C0805-47UF,4V,20%,X6S,CHA
     1 PVCCIN_CPU1 @S9S_MB_2U_LIB.S9S_MB_2U(SCH_1):PVCCIN_CPU1    I33 @S9S_MB_2U_LIB.S9S_MB_2U(SCH_1):PAGE79
     2    GND @S9S_MB_2U_LIB.S9S_MB_2U(SCH_1):GND    I33 @S9S_MB_2U_LIB.S9S_MB_2U(SCH_1):PAGE79

C351 Q_CAP_C0805-47UF,4V,20%,X6S,CHA
     1 PVCCIN_CPU1 @S9S_MB_2U_LIB.S9S_MB_2U(SCH_1):PVCCIN_CPU1    I64 @S9S_MB_2U_LIB.S9S_MB_2U(SCH_1):PAGE78
     2    GND @S9S_MB_2U_LIB.S9S_MB_2U(SCH_1):GND    I64 @S9S_MB_2U_LIB.S9S_MB_2U(SCH_1):PAGE78

C352 Q_CAP_C0805-47UF,4V,20%,X6S,CHA
     1 PVCCIN_CPU1 @S9S_MB_2U_LIB.S9S_MB_2U(SCH_1):PVCCIN_CPU1    I34 @S9S_MB_2U_LIB.S9S_MB_2U(SCH_1):PAGE79
     2    GND @S9S_MB_2U_LIB.S9S_MB_2U(SCH_1):GND    I34 @S9S_MB_2U_LIB.S9S_MB_2U(SCH_1):PAGE79

C353 Q_CAP_C0805-47UF,4V,20%,X6S,CHA
     1 PVCCIN_CPU1 @S9S_MB_2U_LIB.S9S_MB_2U(SCH_1):PVCCIN_CPU1    I65 @S9S_MB_2U_LIB.S9S_MB_2U(SCH_1):PAGE78
     2    GND @S9S_MB_2U_LIB.S9S_MB_2U(SCH_1):GND    I65 @S9S_MB_2U_LIB.S9S_MB_2U(SCH_1):PAGE78

C354 Q_CAP_C0805-47UF,4V,20%,X6S,CHA
     1 PVCCIN_CPU1 @S9S_MB_2U_LIB.S9S_MB_2U(SCH_1):PVCCIN_CPU1    I35 @S9S_MB_2U_LIB.S9S_MB_2U(SCH_1):PAGE79
     2    GND @S9S_MB_2U_LIB.S9S_MB_2U(SCH_1):GND    I35 @S9S_MB_2U_LIB.S9S_MB_2U(SCH_1):PAGE79

C355 Q_CAP_C0805-47UF,4V,20%,X6S,CHA
     1 PVCCIN_CPU0 @S9S_MB_2U_LIB.S9S_MB_2U(SCH_1):PVCCIN_CPU0    I23 @S9S_MB_2U_LIB.S9S_MB_2U(SCH_1):PAGE75
     2    GND @S9S_MB_2U_LIB.S9S_MB_2U(SCH_1):GND    I23 @S9S_MB_2U_LIB.S9S_MB_2U(SCH_1):PAGE75

C356 Q_CAP_C0805-47UF,4V,20%,X6S,CHA
     1 PVCCIN_CPU0 @S9S_MB_2U_LIB.S9S_MB_2U(SCH_1):PVCCIN_CPU0    I21 @S9S_MB_2U_LIB.S9S_MB_2U(SCH_1):PAGE75
     2    GND @S9S_MB_2U_LIB.S9S_MB_2U(SCH_1):GND    I21 @S9S_MB_2U_LIB.S9S_MB_2U(SCH_1):PAGE75

C357 Q_CAP_C0805-47UF,4V,20%,X6S,CHA
     1 PVCCIN_CPU0 @S9S_MB_2U_LIB.S9S_MB_2U(SCH_1):PVCCIN_CPU0    I38 @S9S_MB_2U_LIB.S9S_MB_2U(SCH_1):PAGE75
     2    GND @S9S_MB_2U_LIB.S9S_MB_2U(SCH_1):GND    I38 @S9S_MB_2U_LIB.S9S_MB_2U(SCH_1):PAGE75

C358 Q_CAP_C0805-47UF,4V,20%,X6S,CHA
     1 PVCCIN_CPU0 @S9S_MB_2U_LIB.S9S_MB_2U(SCH_1):PVCCIN_CPU0    I27 @S9S_MB_2U_LIB.S9S_MB_2U(SCH_1):PAGE75
     2    GND @S9S_MB_2U_LIB.S9S_MB_2U(SCH_1):GND    I27 @S9S_MB_2U_LIB.S9S_MB_2U(SCH_1):PAGE75

C359 Q_CAP_C0805-47UF,4V,20%,X6S,CHA
     1 PVCCIN_CPU0 @S9S_MB_2U_LIB.S9S_MB_2U(SCH_1):PVCCIN_CPU0    I25 @S9S_MB_2U_LIB.S9S_MB_2U(SCH_1):PAGE75
     2    GND @S9S_MB_2U_LIB.S9S_MB_2U(SCH_1):GND    I25 @S9S_MB_2U_LIB.S9S_MB_2U(SCH_1):PAGE75

C360 Q_CAP_C0805-47UF,4V,20%,X6S,CHA
     1 PVCCIN_CPU0 @S9S_MB_2U_LIB.S9S_MB_2U(SCH_1):PVCCIN_CPU0    I54 @S9S_MB_2U_LIB.S9S_MB_2U(SCH_1):PAGE75
     2    GND @S9S_MB_2U_LIB.S9S_MB_2U(SCH_1):GND    I54 @S9S_MB_2U_LIB.S9S_MB_2U(SCH_1):PAGE75

C361 Q_CAP_C0805-47UF,4V,20%,X6S,CHA
     1 PVCCIN_CPU0 @S9S_MB_2U_LIB.S9S_MB_2U(SCH_1):PVCCIN_CPU0    I28 @S9S_MB_2U_LIB.S9S_MB_2U(SCH_1):PAGE75
     2    GND @S9S_MB_2U_LIB.S9S_MB_2U(SCH_1):GND    I28 @S9S_MB_2U_LIB.S9S_MB_2U(SCH_1):PAGE75

C362 Q_CAP_C0805-47UF,4V,20%,X6S,CHA
     1 PVCCIN_CPU0 @S9S_MB_2U_LIB.S9S_MB_2U(SCH_1):PVCCIN_CPU0    I26 @S9S_MB_2U_LIB.S9S_MB_2U(SCH_1):PAGE75
     2    GND @S9S_MB_2U_LIB.S9S_MB_2U(SCH_1):GND    I26 @S9S_MB_2U_LIB.S9S_MB_2U(SCH_1):PAGE75

C363 Q_CAP_C0805-47UF,4V,20%,X6S,CHA
     1 PVCCIN_CPU0 @S9S_MB_2U_LIB.S9S_MB_2U(SCH_1):PVCCIN_CPU0    I64 @S9S_MB_2U_LIB.S9S_MB_2U(SCH_1):PAGE75
     2    GND @S9S_MB_2U_LIB.S9S_MB_2U(SCH_1):GND    I64 @S9S_MB_2U_LIB.S9S_MB_2U(SCH_1):PAGE75

C364 Q_CAP_C0805-47UF,4V,20%,X6S,CHA
     1 PVCCIN_CPU0 @S9S_MB_2U_LIB.S9S_MB_2U(SCH_1):PVCCIN_CPU0    I34 @S9S_MB_2U_LIB.S9S_MB_2U(SCH_1):PAGE75
     2    GND @S9S_MB_2U_LIB.S9S_MB_2U(SCH_1):GND    I34 @S9S_MB_2U_LIB.S9S_MB_2U(SCH_1):PAGE75

C365 Q_CAP_C0805-47UF,4V,20%,X6S,CHA
     1 PVCCIN_CPU0 @S9S_MB_2U_LIB.S9S_MB_2U(SCH_1):PVCCIN_CPU0    I32 @S9S_MB_2U_LIB.S9S_MB_2U(SCH_1):PAGE75
     2    GND @S9S_MB_2U_LIB.S9S_MB_2U(SCH_1):GND    I32 @S9S_MB_2U_LIB.S9S_MB_2U(SCH_1):PAGE75

C366 Q_CAP_C0805-47UF,4V,20%,X6S,CHA
     1 PVCCIN_CPU0 @S9S_MB_2U_LIB.S9S_MB_2U(SCH_1):PVCCIN_CPU0    I48 @S9S_MB_2U_LIB.S9S_MB_2U(SCH_1):PAGE76
     2    GND @S9S_MB_2U_LIB.S9S_MB_2U(SCH_1):GND    I48 @S9S_MB_2U_LIB.S9S_MB_2U(SCH_1):PAGE76

C367 Q_CAP_C0805-47UF,4V,20%,X6S,CHA
     1 PVCCIN_CPU0 @S9S_MB_2U_LIB.S9S_MB_2U(SCH_1):PVCCIN_CPU0    I35 @S9S_MB_2U_LIB.S9S_MB_2U(SCH_1):PAGE75
     2    GND @S9S_MB_2U_LIB.S9S_MB_2U(SCH_1):GND    I35 @S9S_MB_2U_LIB.S9S_MB_2U(SCH_1):PAGE75

C368 Q_CAP_C0805-47UF,4V,20%,X6S,CHA
     1 PVCCIN_CPU0 @S9S_MB_2U_LIB.S9S_MB_2U(SCH_1):PVCCIN_CPU0    I33 @S9S_MB_2U_LIB.S9S_MB_2U(SCH_1):PAGE75
     2    GND @S9S_MB_2U_LIB.S9S_MB_2U(SCH_1):GND    I33 @S9S_MB_2U_LIB.S9S_MB_2U(SCH_1):PAGE75

C369 Q_CAP_C0805-47UF,4V,20%,X6S,CHA
     1 PVCCIN_CPU0 @S9S_MB_2U_LIB.S9S_MB_2U(SCH_1):PVCCIN_CPU0    I49 @S9S_MB_2U_LIB.S9S_MB_2U(SCH_1):PAGE76
     2    GND @S9S_MB_2U_LIB.S9S_MB_2U(SCH_1):GND    I49 @S9S_MB_2U_LIB.S9S_MB_2U(SCH_1):PAGE76

C370 Q_CAP_C0805-47UF,4V,20%,X6S,CHA
     1 PVCCIN_CPU0 @S9S_MB_2U_LIB.S9S_MB_2U(SCH_1):PVCCIN_CPU0    I39 @S9S_MB_2U_LIB.S9S_MB_2U(SCH_1):PAGE75
     2    GND @S9S_MB_2U_LIB.S9S_MB_2U(SCH_1):GND    I39 @S9S_MB_2U_LIB.S9S_MB_2U(SCH_1):PAGE75

C371 Q_CAP_C0805-47UF,4V,20%,X6S,CHA
     1 PVCCIN_CPU0 @S9S_MB_2U_LIB.S9S_MB_2U(SCH_1):PVCCIN_CPU0    I36 @S9S_MB_2U_LIB.S9S_MB_2U(SCH_1):PAGE75
     2    GND @S9S_MB_2U_LIB.S9S_MB_2U(SCH_1):GND    I36 @S9S_MB_2U_LIB.S9S_MB_2U(SCH_1):PAGE75

C372 Q_CAP_C0805-47UF,4V,20%,X6S,CHA
     1 PVCCIN_CPU0 @S9S_MB_2U_LIB.S9S_MB_2U(SCH_1):PVCCIN_CPU0    I50 @S9S_MB_2U_LIB.S9S_MB_2U(SCH_1):PAGE76
     2    GND @S9S_MB_2U_LIB.S9S_MB_2U(SCH_1):GND    I50 @S9S_MB_2U_LIB.S9S_MB_2U(SCH_1):PAGE76

C373 Q_CAP_C0805-47UF,4V,20%,X6S,CHA
     1 PVCCIN_CPU0 @S9S_MB_2U_LIB.S9S_MB_2U(SCH_1):PVCCIN_CPU0    I40 @S9S_MB_2U_LIB.S9S_MB_2U(SCH_1):PAGE75
     2    GND @S9S_MB_2U_LIB.S9S_MB_2U(SCH_1):GND    I40 @S9S_MB_2U_LIB.S9S_MB_2U(SCH_1):PAGE75

C374 Q_CAP_C0805-47UF,4V,20%,X6S,CHA
     1 PVCCIN_CPU0 @S9S_MB_2U_LIB.S9S_MB_2U(SCH_1):PVCCIN_CPU0    I51 @S9S_MB_2U_LIB.S9S_MB_2U(SCH_1):PAGE76
     2    GND @S9S_MB_2U_LIB.S9S_MB_2U(SCH_1):GND    I51 @S9S_MB_2U_LIB.S9S_MB_2U(SCH_1):PAGE76

C376 Q_CAP_C0805-47UF,4V,20%,X6S,CHA
     1 PVCCIN_CPU0 @S9S_MB_2U_LIB.S9S_MB_2U(SCH_1):PVCCIN_CPU0    I41 @S9S_MB_2U_LIB.S9S_MB_2U(SCH_1):PAGE75
     2    GND @S9S_MB_2U_LIB.S9S_MB_2U(SCH_1):GND    I41 @S9S_MB_2U_LIB.S9S_MB_2U(SCH_1):PAGE75

C377 Q_CAP_C0805-47UF,4V,20%,X6S,CHA
     1 PVCCIN_CPU0 @S9S_MB_2U_LIB.S9S_MB_2U(SCH_1):PVCCIN_CPU0    I52 @S9S_MB_2U_LIB.S9S_MB_2U(SCH_1):PAGE76
     2    GND @S9S_MB_2U_LIB.S9S_MB_2U(SCH_1):GND    I52 @S9S_MB_2U_LIB.S9S_MB_2U(SCH_1):PAGE76

C379 Q_CAP_C0805-47UF,4V,20%,X6S,CHA
     1 PVCCIN_CPU0 @S9S_MB_2U_LIB.S9S_MB_2U(SCH_1):PVCCIN_CPU0    I50 @S9S_MB_2U_LIB.S9S_MB_2U(SCH_1):PAGE75
     2    GND @S9S_MB_2U_LIB.S9S_MB_2U(SCH_1):GND    I50 @S9S_MB_2U_LIB.S9S_MB_2U(SCH_1):PAGE75

C380 Q_CAP_C0805-47UF,4V,20%,X6S,CHA
     1 PVCCIN_CPU0 @S9S_MB_2U_LIB.S9S_MB_2U(SCH_1):PVCCIN_CPU0    I53 @S9S_MB_2U_LIB.S9S_MB_2U(SCH_1):PAGE76
     2    GND @S9S_MB_2U_LIB.S9S_MB_2U(SCH_1):GND    I53 @S9S_MB_2U_LIB.S9S_MB_2U(SCH_1):PAGE76

C381 Q_CAP_C0805-47UF,4V,20%,X6S,CHA
     1 PVCCIN_CPU0 @S9S_MB_2U_LIB.S9S_MB_2U(SCH_1):PVCCIN_CPU0    I67 @S9S_MB_2U_LIB.S9S_MB_2U(SCH_1):PAGE75
     2    GND @S9S_MB_2U_LIB.S9S_MB_2U(SCH_1):GND    I67 @S9S_MB_2U_LIB.S9S_MB_2U(SCH_1):PAGE75

C382 Q_CAP_C0805-47UF,4V,20%,X6S,CHA
     1 PVCCIN_CPU0 @S9S_MB_2U_LIB.S9S_MB_2U(SCH_1):PVCCIN_CPU0    I51 @S9S_MB_2U_LIB.S9S_MB_2U(SCH_1):PAGE75
     2    GND @S9S_MB_2U_LIB.S9S_MB_2U(SCH_1):GND    I51 @S9S_MB_2U_LIB.S9S_MB_2U(SCH_1):PAGE75

C383 Q_CAP_C0805-47UF,4V,20%,X6S,CHA
     1 PVCCIN_CPU0 @S9S_MB_2U_LIB.S9S_MB_2U(SCH_1):PVCCIN_CPU0    I54 @S9S_MB_2U_LIB.S9S_MB_2U(SCH_1):PAGE76
     2    GND @S9S_MB_2U_LIB.S9S_MB_2U(SCH_1):GND    I54 @S9S_MB_2U_LIB.S9S_MB_2U(SCH_1):PAGE76

C385 Q_CAP_C0805-47UF,4V,20%,X6S,CHA
     1 PVCCIN_CPU0 @S9S_MB_2U_LIB.S9S_MB_2U(SCH_1):PVCCIN_CPU0    I55 @S9S_MB_2U_LIB.S9S_MB_2U(SCH_1):PAGE75
     2    GND @S9S_MB_2U_LIB.S9S_MB_2U(SCH_1):GND    I55 @S9S_MB_2U_LIB.S9S_MB_2U(SCH_1):PAGE75

C386 Q_CAP_C0805-47UF,4V,20%,X6S,CHA
     1 PVCCIN_CPU0 @S9S_MB_2U_LIB.S9S_MB_2U(SCH_1):PVCCIN_CPU0    I22 @S9S_MB_2U_LIB.S9S_MB_2U(SCH_1):PAGE76
     2    GND @S9S_MB_2U_LIB.S9S_MB_2U(SCH_1):GND    I22 @S9S_MB_2U_LIB.S9S_MB_2U(SCH_1):PAGE76

C387 Q_CAP_C0805-47UF,4V,20%,X6S,CHA
     1 PVCCIN_CPU0 @S9S_MB_2U_LIB.S9S_MB_2U(SCH_1):PVCCIN_CPU0    I56 @S9S_MB_2U_LIB.S9S_MB_2U(SCH_1):PAGE75
     2    GND @S9S_MB_2U_LIB.S9S_MB_2U(SCH_1):GND    I56 @S9S_MB_2U_LIB.S9S_MB_2U(SCH_1):PAGE75

C388 Q_CAP_C0805-47UF,4V,20%,X6S,CHA
     1 PVCCIN_CPU0 @S9S_MB_2U_LIB.S9S_MB_2U(SCH_1):PVCCIN_CPU0    I23 @S9S_MB_2U_LIB.S9S_MB_2U(SCH_1):PAGE76
     2    GND @S9S_MB_2U_LIB.S9S_MB_2U(SCH_1):GND    I23 @S9S_MB_2U_LIB.S9S_MB_2U(SCH_1):PAGE76

C389 Q_CAP_C0805-47UF,4V,20%,X6S,CHA
     1 PVCCIN_CPU0 @S9S_MB_2U_LIB.S9S_MB_2U(SCH_1):PVCCIN_CPU0    I48 @S9S_MB_2U_LIB.S9S_MB_2U(SCH_1):PAGE75
     2    GND @S9S_MB_2U_LIB.S9S_MB_2U(SCH_1):GND    I48 @S9S_MB_2U_LIB.S9S_MB_2U(SCH_1):PAGE75

C390 Q_CAP_C0805-47UF,4V,20%,X6S,CHA
     1 PVCCIN_CPU0 @S9S_MB_2U_LIB.S9S_MB_2U(SCH_1):PVCCIN_CPU0    I25 @S9S_MB_2U_LIB.S9S_MB_2U(SCH_1):PAGE76
     2    GND @S9S_MB_2U_LIB.S9S_MB_2U(SCH_1):GND    I25 @S9S_MB_2U_LIB.S9S_MB_2U(SCH_1):PAGE76

C391 Q_CAP_C0805-47UF,4V,20%,X6S,CHA
     1 PVCCIN_CPU0 @S9S_MB_2U_LIB.S9S_MB_2U(SCH_1):PVCCIN_CPU0    I49 @S9S_MB_2U_LIB.S9S_MB_2U(SCH_1):PAGE75
     2    GND @S9S_MB_2U_LIB.S9S_MB_2U(SCH_1):GND    I49 @S9S_MB_2U_LIB.S9S_MB_2U(SCH_1):PAGE75

C392 Q_CAP_C0805-47UF,4V,20%,X6S,CHA
     1 PVCCIN_CPU0 @S9S_MB_2U_LIB.S9S_MB_2U(SCH_1):PVCCIN_CPU0    I44 @S9S_MB_2U_LIB.S9S_MB_2U(SCH_1):PAGE76
     2    GND @S9S_MB_2U_LIB.S9S_MB_2U(SCH_1):GND    I44 @S9S_MB_2U_LIB.S9S_MB_2U(SCH_1):PAGE76

C393 Q_CAP_C0805-47UF,4V,20%,X6S,CHA
     1 PVCCIN_CPU0 @S9S_MB_2U_LIB.S9S_MB_2U(SCH_1):PVCCIN_CPU0    I52 @S9S_MB_2U_LIB.S9S_MB_2U(SCH_1):PAGE75
     2    GND @S9S_MB_2U_LIB.S9S_MB_2U(SCH_1):GND    I52 @S9S_MB_2U_LIB.S9S_MB_2U(SCH_1):PAGE75

C394 Q_CAP_C0805-47UF,4V,20%,X6S,CHA
     1 PVCCIN_CPU0 @S9S_MB_2U_LIB.S9S_MB_2U(SCH_1):PVCCIN_CPU0    I45 @S9S_MB_2U_LIB.S9S_MB_2U(SCH_1):PAGE76
     2    GND @S9S_MB_2U_LIB.S9S_MB_2U(SCH_1):GND    I45 @S9S_MB_2U_LIB.S9S_MB_2U(SCH_1):PAGE76

C395 Q_CAP_C0805-47UF,4V,20%,X6S,CHA
     1 PVNN_MAIN_CPU0 @S9S_MB_2U_LIB.S9S_MB_2U(SCH_1):PVNN_MAIN_CPU0    I46 @S9S_MB_2U_LIB.S9S_MB_2U(SCH_1):PAGE75
     2    GND @S9S_MB_2U_LIB.S9S_MB_2U(SCH_1):GND    I46 @S9S_MB_2U_LIB.S9S_MB_2U(SCH_1):PAGE75

C396 Q_CAP_C0805-47UF,4V,20%,X6S,CHA
     1 PVCCIN_CPU0 @S9S_MB_2U_LIB.S9S_MB_2U(SCH_1):PVCCIN_CPU0    I46 @S9S_MB_2U_LIB.S9S_MB_2U(SCH_1):PAGE76
     2    GND @S9S_MB_2U_LIB.S9S_MB_2U(SCH_1):GND    I46 @S9S_MB_2U_LIB.S9S_MB_2U(SCH_1):PAGE76

C397 Q_CAP_C0805-47UF,4V,20%,X6S,CHA
     1 PVCCIN_CPU0 @S9S_MB_2U_LIB.S9S_MB_2U(SCH_1):PVCCIN_CPU0    I37 @S9S_MB_2U_LIB.S9S_MB_2U(SCH_1):PAGE75
     2    GND @S9S_MB_2U_LIB.S9S_MB_2U(SCH_1):GND    I37 @S9S_MB_2U_LIB.S9S_MB_2U(SCH_1):PAGE75

C398 Q_CAP_C0805-47UF,4V,20%,X6S,CHA
     1 PVCCIN_CPU0 @S9S_MB_2U_LIB.S9S_MB_2U(SCH_1):PVCCIN_CPU0    I47 @S9S_MB_2U_LIB.S9S_MB_2U(SCH_1):PAGE76
     2    GND @S9S_MB_2U_LIB.S9S_MB_2U(SCH_1):GND    I47 @S9S_MB_2U_LIB.S9S_MB_2U(SCH_1):PAGE76

C399 Q_CAP_C0402-22UF,4V,20%,X6S,CHA
     1 PVCCD_HV_CPU0 @S9S_MB_2U_LIB.S9S_MB_2U(SCH_1):PVCCD_HV_CPU0    I11 @S9S_MB_2U_LIB.S9S_MB_2U(SCH_1):PAGE74
     2    GND @S9S_MB_2U_LIB.S9S_MB_2U(SCH_1):GND    I11 @S9S_MB_2U_LIB.S9S_MB_2U(SCH_1):PAGE74

C400 Q_CAP_C0402-22UF,4V,20%,X6S,CHA
     1 PVCCFA_EHV_FIVRA_CPU0 @S9S_MB_2U_LIB.S9S_MB_2U(SCH_1):PVCCFA_EHV_FIVRA_CPU0     I1 @S9S_MB_2U_LIB.S9S_MB_2U(SCH_1):PAGE74
     2    GND @S9S_MB_2U_LIB.S9S_MB_2U(SCH_1):GND     I1 @S9S_MB_2U_LIB.S9S_MB_2U(SCH_1):PAGE74

C401 Q_CAP_C0402-22UF,4V,20%,X6S,CHA
     1 PVCCD_HV_CPU0 @S9S_MB_2U_LIB.S9S_MB_2U(SCH_1):PVCCD_HV_CPU0    I17 @S9S_MB_2U_LIB.S9S_MB_2U(SCH_1):PAGE74
     2    GND @S9S_MB_2U_LIB.S9S_MB_2U(SCH_1):GND    I17 @S9S_MB_2U_LIB.S9S_MB_2U(SCH_1):PAGE74

C402 Q_CAP_C0402-22UF,4V,20%,X6S,CHA
     1 PVCCFA_EHV_FIVRA_CPU0 @S9S_MB_2U_LIB.S9S_MB_2U(SCH_1):PVCCFA_EHV_FIVRA_CPU0     I3 @S9S_MB_2U_LIB.S9S_MB_2U(SCH_1):PAGE74
     2    GND @S9S_MB_2U_LIB.S9S_MB_2U(SCH_1):GND     I3 @S9S_MB_2U_LIB.S9S_MB_2U(SCH_1):PAGE74

C403 Q_CAP_C0402-22UF,4V,20%,X6S,CHA
     1 PVCCD_HV_CPU0 @S9S_MB_2U_LIB.S9S_MB_2U(SCH_1):PVCCD_HV_CPU0    I19 @S9S_MB_2U_LIB.S9S_MB_2U(SCH_1):PAGE74
     2    GND @S9S_MB_2U_LIB.S9S_MB_2U(SCH_1):GND    I19 @S9S_MB_2U_LIB.S9S_MB_2U(SCH_1):PAGE74

C404 Q_CAP_C0402-22UF,4V,20%,X6S,CHA
     1 PVCCFA_EHV_FIVRA_CPU0 @S9S_MB_2U_LIB.S9S_MB_2U(SCH_1):PVCCFA_EHV_FIVRA_CPU0     I4 @S9S_MB_2U_LIB.S9S_MB_2U(SCH_1):PAGE74
     2    GND @S9S_MB_2U_LIB.S9S_MB_2U(SCH_1):GND     I4 @S9S_MB_2U_LIB.S9S_MB_2U(SCH_1):PAGE74

C405 Q_CAP_C0402-22UF,4V,20%,X6S,CHA
     1 PVCCD_HV_CPU0 @S9S_MB_2U_LIB.S9S_MB_2U(SCH_1):PVCCD_HV_CPU0    I34 @S9S_MB_2U_LIB.S9S_MB_2U(SCH_1):PAGE74
     2    GND @S9S_MB_2U_LIB.S9S_MB_2U(SCH_1):GND    I34 @S9S_MB_2U_LIB.S9S_MB_2U(SCH_1):PAGE74

C406 Q_CAP_C0402-22UF,4V,20%,X6S,CHA
     1 PVCCFA_EHV_FIVRA_CPU0 @S9S_MB_2U_LIB.S9S_MB_2U(SCH_1):PVCCFA_EHV_FIVRA_CPU0     I5 @S9S_MB_2U_LIB.S9S_MB_2U(SCH_1):PAGE74
     2    GND @S9S_MB_2U_LIB.S9S_MB_2U(SCH_1):GND     I5 @S9S_MB_2U_LIB.S9S_MB_2U(SCH_1):PAGE74

C407 Q_CAP_C0402-22UF,4V,20%,X6S,CHA
     1 PVCCFA_EHV_FIVRA_CPU0 @S9S_MB_2U_LIB.S9S_MB_2U(SCH_1):PVCCFA_EHV_FIVRA_CPU0     I7 @S9S_MB_2U_LIB.S9S_MB_2U(SCH_1):PAGE74
     2    GND @S9S_MB_2U_LIB.S9S_MB_2U(SCH_1):GND     I7 @S9S_MB_2U_LIB.S9S_MB_2U(SCH_1):PAGE74

C408 Q_CAP_C0402-22UF,4V,20%,X6S,CHA
     1 PVCCINFAON_CPU0 @S9S_MB_2U_LIB.S9S_MB_2U(SCH_1):PVCCINFAON_CPU0   I142 @S9S_MB_2U_LIB.S9S_MB_2U(SCH_1):PAGE74
     2    GND @S9S_MB_2U_LIB.S9S_MB_2U(SCH_1):GND   I142 @S9S_MB_2U_LIB.S9S_MB_2U(SCH_1):PAGE74

C409 Q_CAP_C0402-22UF,4V,20%,X6S,CHA
     1 PVCCFA_EHV_FIVRA_CPU0 @S9S_MB_2U_LIB.S9S_MB_2U(SCH_1):PVCCFA_EHV_FIVRA_CPU0     I8 @S9S_MB_2U_LIB.S9S_MB_2U(SCH_1):PAGE74
     2    GND @S9S_MB_2U_LIB.S9S_MB_2U(SCH_1):GND     I8 @S9S_MB_2U_LIB.S9S_MB_2U(SCH_1):PAGE74

C410 Q_CAP_C0402-22UF,4V,20%,X6S,CHA
     1 PVCCINFAON_CPU0 @S9S_MB_2U_LIB.S9S_MB_2U(SCH_1):PVCCINFAON_CPU0    I41 @S9S_MB_2U_LIB.S9S_MB_2U(SCH_1):PAGE74
     2    GND @S9S_MB_2U_LIB.S9S_MB_2U(SCH_1):GND    I41 @S9S_MB_2U_LIB.S9S_MB_2U(SCH_1):PAGE74

C411 Q_CAP_C0402-22UF,4V,20%,X6S,CHA
     1 PVCCFA_EHV_FIVRA_CPU0 @S9S_MB_2U_LIB.S9S_MB_2U(SCH_1):PVCCFA_EHV_FIVRA_CPU0     I9 @S9S_MB_2U_LIB.S9S_MB_2U(SCH_1):PAGE74
     2    GND @S9S_MB_2U_LIB.S9S_MB_2U(SCH_1):GND     I9 @S9S_MB_2U_LIB.S9S_MB_2U(SCH_1):PAGE74

C412 Q_CAP_C0402-22UF,4V,20%,X6S,CHA
     1 PVCCINFAON_CPU0 @S9S_MB_2U_LIB.S9S_MB_2U(SCH_1):PVCCINFAON_CPU0    I42 @S9S_MB_2U_LIB.S9S_MB_2U(SCH_1):PAGE74
     2    GND @S9S_MB_2U_LIB.S9S_MB_2U(SCH_1):GND    I42 @S9S_MB_2U_LIB.S9S_MB_2U(SCH_1):PAGE74

C413 Q_CAP_C0402-22UF,4V,20%,X6S,CHA
     1 PVCCFA_EHV_FIVRA_CPU0 @S9S_MB_2U_LIB.S9S_MB_2U(SCH_1):PVCCFA_EHV_FIVRA_CPU0    I10 @S9S_MB_2U_LIB.S9S_MB_2U(SCH_1):PAGE74
     2    GND @S9S_MB_2U_LIB.S9S_MB_2U(SCH_1):GND    I10 @S9S_MB_2U_LIB.S9S_MB_2U(SCH_1):PAGE74

C414 Q_CAP_C0402-22UF,4V,20%,X6S,CHA
     1 PVCCINFAON_CPU0 @S9S_MB_2U_LIB.S9S_MB_2U(SCH_1):PVCCINFAON_CPU0    I70 @S9S_MB_2U_LIB.S9S_MB_2U(SCH_1):PAGE74
     2    GND @S9S_MB_2U_LIB.S9S_MB_2U(SCH_1):GND    I70 @S9S_MB_2U_LIB.S9S_MB_2U(SCH_1):PAGE74

C415 Q_CAP_C0402-22UF,4V,20%,X6S,CHA
     1 PVCCFA_EHV_FIVRA_CPU0 @S9S_MB_2U_LIB.S9S_MB_2U(SCH_1):PVCCFA_EHV_FIVRA_CPU0    I64 @S9S_MB_2U_LIB.S9S_MB_2U(SCH_1):PAGE74
     2    GND @S9S_MB_2U_LIB.S9S_MB_2U(SCH_1):GND    I64 @S9S_MB_2U_LIB.S9S_MB_2U(SCH_1):PAGE74

C416 Q_CAP_C0402-22UF,4V,20%,X6S,CHA
     1 PVCCINFAON_CPU0 @S9S_MB_2U_LIB.S9S_MB_2U(SCH_1):PVCCINFAON_CPU0    I72 @S9S_MB_2U_LIB.S9S_MB_2U(SCH_1):PAGE74
     2    GND @S9S_MB_2U_LIB.S9S_MB_2U(SCH_1):GND    I72 @S9S_MB_2U_LIB.S9S_MB_2U(SCH_1):PAGE74

C417 Q_CAP_C0402-22UF,4V,20%,X6S,CHA
     1 PVCCFA_EHV_FIVRA_CPU0 @S9S_MB_2U_LIB.S9S_MB_2U(SCH_1):PVCCFA_EHV_FIVRA_CPU0    I65 @S9S_MB_2U_LIB.S9S_MB_2U(SCH_1):PAGE74
     2    GND @S9S_MB_2U_LIB.S9S_MB_2U(SCH_1):GND    I65 @S9S_MB_2U_LIB.S9S_MB_2U(SCH_1):PAGE74

C418 Q_CAP_C0402-22UF,4V,20%,X6S,CHA
     1 PVCCFA_EHV_FIVRA_CPU0 @S9S_MB_2U_LIB.S9S_MB_2U(SCH_1):PVCCFA_EHV_FIVRA_CPU0    I68 @S9S_MB_2U_LIB.S9S_MB_2U(SCH_1):PAGE74
     2    GND @S9S_MB_2U_LIB.S9S_MB_2U(SCH_1):GND    I68 @S9S_MB_2U_LIB.S9S_MB_2U(SCH_1):PAGE74

C419 Q_CAP_C0402-22UF,4V,20%,X6S,CHA
     1 PVCCFA_EHV_CPU0 @S9S_MB_2U_LIB.S9S_MB_2U(SCH_1):PVCCFA_EHV_CPU0    I98 @S9S_MB_2U_LIB.S9S_MB_2U(SCH_1):PAGE74
     2    GND @S9S_MB_2U_LIB.S9S_MB_2U(SCH_1):GND    I98 @S9S_MB_2U_LIB.S9S_MB_2U(SCH_1):PAGE74

C420 Q_CAP_C0402-22UF,4V,20%,X6S,CHA
     1 PVCCFA_EHV_CPU0 @S9S_MB_2U_LIB.S9S_MB_2U(SCH_1):PVCCFA_EHV_CPU0   I100 @S9S_MB_2U_LIB.S9S_MB_2U(SCH_1):PAGE74
     2    GND @S9S_MB_2U_LIB.S9S_MB_2U(SCH_1):GND   I100 @S9S_MB_2U_LIB.S9S_MB_2U(SCH_1):PAGE74

C421 Q_CAP_C0402-22UF,4V,20%,X6S,CHA
     1 PVCCFA_EHV_CPU0 @S9S_MB_2U_LIB.S9S_MB_2U(SCH_1):PVCCFA_EHV_CPU0   I103 @S9S_MB_2U_LIB.S9S_MB_2U(SCH_1):PAGE74
     2    GND @S9S_MB_2U_LIB.S9S_MB_2U(SCH_1):GND   I103 @S9S_MB_2U_LIB.S9S_MB_2U(SCH_1):PAGE74

C422 Q_CAP_C0402-22UF,4V,20%,X6S,CHA
     1 PVCCFA_EHV_CPU0 @S9S_MB_2U_LIB.S9S_MB_2U(SCH_1):PVCCFA_EHV_CPU0   I107 @S9S_MB_2U_LIB.S9S_MB_2U(SCH_1):PAGE74
     2    GND @S9S_MB_2U_LIB.S9S_MB_2U(SCH_1):GND   I107 @S9S_MB_2U_LIB.S9S_MB_2U(SCH_1):PAGE74

C423 Q_CAP_C0402-22UF,4V,20%,X6S,CHA
     1 PVCCD_HV_CPU1 @S9S_MB_2U_LIB.S9S_MB_2U(SCH_1):PVCCD_HV_CPU1     I7 @S9S_MB_2U_LIB.S9S_MB_2U(SCH_1):PAGE77
     2    GND @S9S_MB_2U_LIB.S9S_MB_2U(SCH_1):GND     I7 @S9S_MB_2U_LIB.S9S_MB_2U(SCH_1):PAGE77

C424 Q_CAP_C0402-22UF,4V,20%,X6S,CHA
     1 PVCCFA_EHV_FIVRA_CPU1 @S9S_MB_2U_LIB.S9S_MB_2U(SCH_1):PVCCFA_EHV_FIVRA_CPU1     I1 @S9S_MB_2U_LIB.S9S_MB_2U(SCH_1):PAGE77
     2    GND @S9S_MB_2U_LIB.S9S_MB_2U(SCH_1):GND     I1 @S9S_MB_2U_LIB.S9S_MB_2U(SCH_1):PAGE77

C425 Q_CAP_C0402-22UF,4V,20%,X6S,CHA
     1 PVCCD_HV_CPU1 @S9S_MB_2U_LIB.S9S_MB_2U(SCH_1):PVCCD_HV_CPU1     I8 @S9S_MB_2U_LIB.S9S_MB_2U(SCH_1):PAGE77
     2    GND @S9S_MB_2U_LIB.S9S_MB_2U(SCH_1):GND     I8 @S9S_MB_2U_LIB.S9S_MB_2U(SCH_1):PAGE77

C426 Q_CAP_C0402-22UF,4V,20%,X6S,CHA
     1 PVCCFA_EHV_FIVRA_CPU1 @S9S_MB_2U_LIB.S9S_MB_2U(SCH_1):PVCCFA_EHV_FIVRA_CPU1     I2 @S9S_MB_2U_LIB.S9S_MB_2U(SCH_1):PAGE77
     2    GND @S9S_MB_2U_LIB.S9S_MB_2U(SCH_1):GND     I2 @S9S_MB_2U_LIB.S9S_MB_2U(SCH_1):PAGE77

C427 Q_CAP_C0402-22UF,4V,20%,X6S,CHA
     1 PVCCD_HV_CPU1 @S9S_MB_2U_LIB.S9S_MB_2U(SCH_1):PVCCD_HV_CPU1    I15 @S9S_MB_2U_LIB.S9S_MB_2U(SCH_1):PAGE77
     2    GND @S9S_MB_2U_LIB.S9S_MB_2U(SCH_1):GND    I15 @S9S_MB_2U_LIB.S9S_MB_2U(SCH_1):PAGE77

C428 Q_CAP_C0402-22UF,4V,20%,X6S,CHA
     1 PVCCFA_EHV_FIVRA_CPU1 @S9S_MB_2U_LIB.S9S_MB_2U(SCH_1):PVCCFA_EHV_FIVRA_CPU1     I4 @S9S_MB_2U_LIB.S9S_MB_2U(SCH_1):PAGE77
     2    GND @S9S_MB_2U_LIB.S9S_MB_2U(SCH_1):GND     I4 @S9S_MB_2U_LIB.S9S_MB_2U(SCH_1):PAGE77

C429 Q_CAP_C0402-22UF,4V,20%,X6S,CHA
     1 PVCCD_HV_CPU1 @S9S_MB_2U_LIB.S9S_MB_2U(SCH_1):PVCCD_HV_CPU1    I17 @S9S_MB_2U_LIB.S9S_MB_2U(SCH_1):PAGE77
     2    GND @S9S_MB_2U_LIB.S9S_MB_2U(SCH_1):GND    I17 @S9S_MB_2U_LIB.S9S_MB_2U(SCH_1):PAGE77

C430 Q_CAP_C0402-22UF,4V,20%,X6S,CHA
     1 PVCCFA_EHV_FIVRA_CPU1 @S9S_MB_2U_LIB.S9S_MB_2U(SCH_1):PVCCFA_EHV_FIVRA_CPU1     I5 @S9S_MB_2U_LIB.S9S_MB_2U(SCH_1):PAGE77
     2    GND @S9S_MB_2U_LIB.S9S_MB_2U(SCH_1):GND     I5 @S9S_MB_2U_LIB.S9S_MB_2U(SCH_1):PAGE77

C431 Q_CAP_C0402-22UF,4V,20%,X6S,CHA
     1 PVCCFA_EHV_FIVRA_CPU1 @S9S_MB_2U_LIB.S9S_MB_2U(SCH_1):PVCCFA_EHV_FIVRA_CPU1    I37 @S9S_MB_2U_LIB.S9S_MB_2U(SCH_1):PAGE77
     2    GND @S9S_MB_2U_LIB.S9S_MB_2U(SCH_1):GND    I37 @S9S_MB_2U_LIB.S9S_MB_2U(SCH_1):PAGE77

C432 Q_CAP_C0402-22UF,4V,20%,X6S,CHA
     1 PVCCINFAON_CPU1 @S9S_MB_2U_LIB.S9S_MB_2U(SCH_1):PVCCINFAON_CPU1    I42 @S9S_MB_2U_LIB.S9S_MB_2U(SCH_1):PAGE77
     2    GND @S9S_MB_2U_LIB.S9S_MB_2U(SCH_1):GND    I42 @S9S_MB_2U_LIB.S9S_MB_2U(SCH_1):PAGE77

C433 Q_CAP_C0402-22UF,4V,20%,X6S,CHA
     1 PVCCFA_EHV_FIVRA_CPU1 @S9S_MB_2U_LIB.S9S_MB_2U(SCH_1):PVCCFA_EHV_FIVRA_CPU1    I38 @S9S_MB_2U_LIB.S9S_MB_2U(SCH_1):PAGE77
     2    GND @S9S_MB_2U_LIB.S9S_MB_2U(SCH_1):GND    I38 @S9S_MB_2U_LIB.S9S_MB_2U(SCH_1):PAGE77

C434 Q_CAP_C0402-22UF,4V,20%,X6S,CHA
     1 PVCCINFAON_CPU1 @S9S_MB_2U_LIB.S9S_MB_2U(SCH_1):PVCCINFAON_CPU1    I47 @S9S_MB_2U_LIB.S9S_MB_2U(SCH_1):PAGE77
     2    GND @S9S_MB_2U_LIB.S9S_MB_2U(SCH_1):GND    I47 @S9S_MB_2U_LIB.S9S_MB_2U(SCH_1):PAGE77

C435 Q_CAP_C0402-22UF,4V,20%,X6S,CHA
     1 PVCCFA_EHV_FIVRA_CPU1 @S9S_MB_2U_LIB.S9S_MB_2U(SCH_1):PVCCFA_EHV_FIVRA_CPU1    I39 @S9S_MB_2U_LIB.S9S_MB_2U(SCH_1):PAGE77
     2    GND @S9S_MB_2U_LIB.S9S_MB_2U(SCH_1):GND    I39 @S9S_MB_2U_LIB.S9S_MB_2U(SCH_1):PAGE77

C436 Q_CAP_C0402-22UF,4V,20%,X6S,CHA
     1 PVCCINFAON_CPU1 @S9S_MB_2U_LIB.S9S_MB_2U(SCH_1):PVCCINFAON_CPU1    I49 @S9S_MB_2U_LIB.S9S_MB_2U(SCH_1):PAGE77
     2    GND @S9S_MB_2U_LIB.S9S_MB_2U(SCH_1):GND    I49 @S9S_MB_2U_LIB.S9S_MB_2U(SCH_1):PAGE77

C437 Q_CAP_C0402-22UF,4V,20%,X6S,CHA
     1 PVCCFA_EHV_FIVRA_CPU1 @S9S_MB_2U_LIB.S9S_MB_2U(SCH_1):PVCCFA_EHV_FIVRA_CPU1    I40 @S9S_MB_2U_LIB.S9S_MB_2U(SCH_1):PAGE77
     2    GND @S9S_MB_2U_LIB.S9S_MB_2U(SCH_1):GND    I40 @S9S_MB_2U_LIB.S9S_MB_2U(SCH_1):PAGE77

C438 Q_CAP_C0402-22UF,4V,20%,X6S,CHA
     1 PVCCINFAON_CPU1 @S9S_MB_2U_LIB.S9S_MB_2U(SCH_1):PVCCINFAON_CPU1    I58 @S9S_MB_2U_LIB.S9S_MB_2U(SCH_1):PAGE77
     2    GND @S9S_MB_2U_LIB.S9S_MB_2U(SCH_1):GND    I58 @S9S_MB_2U_LIB.S9S_MB_2U(SCH_1):PAGE77

C439 Q_CAP_C0402-22UF,4V,20%,X6S,CHA
     1 PVCCFA_EHV_FIVRA_CPU1 @S9S_MB_2U_LIB.S9S_MB_2U(SCH_1):PVCCFA_EHV_FIVRA_CPU1    I53 @S9S_MB_2U_LIB.S9S_MB_2U(SCH_1):PAGE77
     2    GND @S9S_MB_2U_LIB.S9S_MB_2U(SCH_1):GND    I53 @S9S_MB_2U_LIB.S9S_MB_2U(SCH_1):PAGE77

C440 Q_CAP_C0402-22UF,4V,20%,X6S,CHA
     1 PVCCINFAON_CPU1 @S9S_MB_2U_LIB.S9S_MB_2U(SCH_1):PVCCINFAON_CPU1    I61 @S9S_MB_2U_LIB.S9S_MB_2U(SCH_1):PAGE77
     2    GND @S9S_MB_2U_LIB.S9S_MB_2U(SCH_1):GND    I61 @S9S_MB_2U_LIB.S9S_MB_2U(SCH_1):PAGE77

C441 Q_CAP_C0402-22UF,4V,20%,X6S,CHA
     1 PVCCFA_EHV_FIVRA_CPU1 @S9S_MB_2U_LIB.S9S_MB_2U(SCH_1):PVCCFA_EHV_FIVRA_CPU1    I55 @S9S_MB_2U_LIB.S9S_MB_2U(SCH_1):PAGE77
     2    GND @S9S_MB_2U_LIB.S9S_MB_2U(SCH_1):GND    I55 @S9S_MB_2U_LIB.S9S_MB_2U(SCH_1):PAGE77

C442 Q_CAP_C0402-22UF,4V,20%,X6S,CHA
     1 PVCCFA_EHV_FIVRA_CPU1 @S9S_MB_2U_LIB.S9S_MB_2U(SCH_1):PVCCFA_EHV_FIVRA_CPU1    I57 @S9S_MB_2U_LIB.S9S_MB_2U(SCH_1):PAGE77
     2    GND @S9S_MB_2U_LIB.S9S_MB_2U(SCH_1):GND    I57 @S9S_MB_2U_LIB.S9S_MB_2U(SCH_1):PAGE77

C443 Q_CAP_C0402-22UF,4V,20%,X6S,CHA
     1 PVCCFA_EHV_CPU1 @S9S_MB_2U_LIB.S9S_MB_2U(SCH_1):PVCCFA_EHV_CPU1    I67 @S9S_MB_2U_LIB.S9S_MB_2U(SCH_1):PAGE77
     2    GND @S9S_MB_2U_LIB.S9S_MB_2U(SCH_1):GND    I67 @S9S_MB_2U_LIB.S9S_MB_2U(SCH_1):PAGE77

C444 Q_CAP_C0402-22UF,4V,20%,X6S,CHA
     1 PVCCFA_EHV_CPU1 @S9S_MB_2U_LIB.S9S_MB_2U(SCH_1):PVCCFA_EHV_CPU1   I109 @S9S_MB_2U_LIB.S9S_MB_2U(SCH_1):PAGE77
     2    GND @S9S_MB_2U_LIB.S9S_MB_2U(SCH_1):GND   I109 @S9S_MB_2U_LIB.S9S_MB_2U(SCH_1):PAGE77

C445 Q_CAP_C0402-22UF,4V,20%,X6S,CHA
     1 PVCCFA_EHV_CPU1 @S9S_MB_2U_LIB.S9S_MB_2U(SCH_1):PVCCFA_EHV_CPU1   I110 @S9S_MB_2U_LIB.S9S_MB_2U(SCH_1):PAGE77
     2    GND @S9S_MB_2U_LIB.S9S_MB_2U(SCH_1):GND   I110 @S9S_MB_2U_LIB.S9S_MB_2U(SCH_1):PAGE77

C446 Q_CAP_C0402-22UF,4V,20%,X6S,CHA
     1 PVCCFA_EHV_CPU1 @S9S_MB_2U_LIB.S9S_MB_2U(SCH_1):PVCCFA_EHV_CPU1   I113 @S9S_MB_2U_LIB.S9S_MB_2U(SCH_1):PAGE77
     2    GND @S9S_MB_2U_LIB.S9S_MB_2U(SCH_1):GND   I113 @S9S_MB_2U_LIB.S9S_MB_2U(SCH_1):PAGE77

C447 Q_CAP_C0805-47UF,4V,20%,X6S,CHA
     1 PVCCD_HV_CPU1 @S9S_MB_2U_LIB.S9S_MB_2U(SCH_1):PVCCD_HV_CPU1    I12 @S9S_MB_2U_LIB.S9S_MB_2U(SCH_1):PAGE78
     2    GND @S9S_MB_2U_LIB.S9S_MB_2U(SCH_1):GND    I12 @S9S_MB_2U_LIB.S9S_MB_2U(SCH_1):PAGE78

C448 Q_CAP_C0805-47UF,4V,20%,X6S,CHA
     1 PVCCFA_EHV_CPU1 @S9S_MB_2U_LIB.S9S_MB_2U(SCH_1):PVCCFA_EHV_CPU1    I10 @S9S_MB_2U_LIB.S9S_MB_2U(SCH_1):PAGE78
     2    GND @S9S_MB_2U_LIB.S9S_MB_2U(SCH_1):GND    I10 @S9S_MB_2U_LIB.S9S_MB_2U(SCH_1):PAGE78

C449 Q_CAP_C0805-47UF,4V,20%,X6S,CHA
     1 PVCCFA_EHV_FIVRA_CPU1 @S9S_MB_2U_LIB.S9S_MB_2U(SCH_1):PVCCFA_EHV_FIVRA_CPU1     I1 @S9S_MB_2U_LIB.S9S_MB_2U(SCH_1):PAGE78
     2    GND @S9S_MB_2U_LIB.S9S_MB_2U(SCH_1):GND     I1 @S9S_MB_2U_LIB.S9S_MB_2U(SCH_1):PAGE78

C450 Q_CAP_C0805-47UF,4V,20%,X6S,CHA
     1 PVCCFA_EHV_FIVRA_CPU1 @S9S_MB_2U_LIB.S9S_MB_2U(SCH_1):PVCCFA_EHV_FIVRA_CPU1     I1 @S9S_MB_2U_LIB.S9S_MB_2U(SCH_1):PAGE79
     2    GND @S9S_MB_2U_LIB.S9S_MB_2U(SCH_1):GND     I1 @S9S_MB_2U_LIB.S9S_MB_2U(SCH_1):PAGE79

C451 Q_CAP_C0805-47UF,4V,20%,X6S,CHA
     1 PVCCD_HV_CPU1 @S9S_MB_2U_LIB.S9S_MB_2U(SCH_1):PVCCD_HV_CPU1    I24 @S9S_MB_2U_LIB.S9S_MB_2U(SCH_1):PAGE78
     2    GND @S9S_MB_2U_LIB.S9S_MB_2U(SCH_1):GND    I24 @S9S_MB_2U_LIB.S9S_MB_2U(SCH_1):PAGE78

C452 Q_CAP_C0805-47UF,4V,20%,X6S,CHA
     1 PVCCFA_EHV_CPU1 @S9S_MB_2U_LIB.S9S_MB_2U(SCH_1):PVCCFA_EHV_CPU1    I21 @S9S_MB_2U_LIB.S9S_MB_2U(SCH_1):PAGE78
     2    GND @S9S_MB_2U_LIB.S9S_MB_2U(SCH_1):GND    I21 @S9S_MB_2U_LIB.S9S_MB_2U(SCH_1):PAGE78

C453 Q_CAP_C0805-47UF,4V,20%,X6S,CHA
     1 PVCCFA_EHV_FIVRA_CPU1 @S9S_MB_2U_LIB.S9S_MB_2U(SCH_1):PVCCFA_EHV_FIVRA_CPU1     I3 @S9S_MB_2U_LIB.S9S_MB_2U(SCH_1):PAGE78
     2    GND @S9S_MB_2U_LIB.S9S_MB_2U(SCH_1):GND     I3 @S9S_MB_2U_LIB.S9S_MB_2U(SCH_1):PAGE78

C454 Q_CAP_C0805-47UF,4V,20%,X6S,CHA
     1 PVCCFA_EHV_FIVRA_CPU1 @S9S_MB_2U_LIB.S9S_MB_2U(SCH_1):PVCCFA_EHV_FIVRA_CPU1     I3 @S9S_MB_2U_LIB.S9S_MB_2U(SCH_1):PAGE79
     2    GND @S9S_MB_2U_LIB.S9S_MB_2U(SCH_1):GND     I3 @S9S_MB_2U_LIB.S9S_MB_2U(SCH_1):PAGE79

C455 Q_CAP_C0805-47UF,4V,20%,X6S,CHA
     1 PVCCD_HV_CPU1 @S9S_MB_2U_LIB.S9S_MB_2U(SCH_1):PVCCD_HV_CPU1    I19 @S9S_MB_2U_LIB.S9S_MB_2U(SCH_1):PAGE79
     2    GND @S9S_MB_2U_LIB.S9S_MB_2U(SCH_1):GND    I19 @S9S_MB_2U_LIB.S9S_MB_2U(SCH_1):PAGE79

C456 Q_CAP_C0805-47UF,4V,20%,X6S,CHA
     1 PVCCFA_EHV_CPU1 @S9S_MB_2U_LIB.S9S_MB_2U(SCH_1):PVCCFA_EHV_CPU1    I15 @S9S_MB_2U_LIB.S9S_MB_2U(SCH_1):PAGE79
     2    GND @S9S_MB_2U_LIB.S9S_MB_2U(SCH_1):GND    I15 @S9S_MB_2U_LIB.S9S_MB_2U(SCH_1):PAGE79

C457 Q_CAP_C0805-47UF,4V,20%,X6S,CHA
     1 PVCCFA_EHV_FIVRA_CPU1 @S9S_MB_2U_LIB.S9S_MB_2U(SCH_1):PVCCFA_EHV_FIVRA_CPU1     I4 @S9S_MB_2U_LIB.S9S_MB_2U(SCH_1):PAGE78
     2    GND @S9S_MB_2U_LIB.S9S_MB_2U(SCH_1):GND     I4 @S9S_MB_2U_LIB.S9S_MB_2U(SCH_1):PAGE78

C458 Q_CAP_C0805-47UF,4V,20%,X6S,CHA
     1 PVCCFA_EHV_FIVRA_CPU1 @S9S_MB_2U_LIB.S9S_MB_2U(SCH_1):PVCCFA_EHV_FIVRA_CPU1     I4 @S9S_MB_2U_LIB.S9S_MB_2U(SCH_1):PAGE79
     2    GND @S9S_MB_2U_LIB.S9S_MB_2U(SCH_1):GND     I4 @S9S_MB_2U_LIB.S9S_MB_2U(SCH_1):PAGE79

C459 Q_CAP_C0805-47UF,4V,20%,X6S,CHA
     1 PVCCD_HV_CPU1 @S9S_MB_2U_LIB.S9S_MB_2U(SCH_1):PVCCD_HV_CPU1    I20 @S9S_MB_2U_LIB.S9S_MB_2U(SCH_1):PAGE79
     2    GND @S9S_MB_2U_LIB.S9S_MB_2U(SCH_1):GND    I20 @S9S_MB_2U_LIB.S9S_MB_2U(SCH_1):PAGE79

C460 Q_CAP_C0805-47UF,4V,20%,X6S,CHA
     1 PVCCFA_EHV_CPU1 @S9S_MB_2U_LIB.S9S_MB_2U(SCH_1):PVCCFA_EHV_CPU1    I16 @S9S_MB_2U_LIB.S9S_MB_2U(SCH_1):PAGE79
     2    GND @S9S_MB_2U_LIB.S9S_MB_2U(SCH_1):GND    I16 @S9S_MB_2U_LIB.S9S_MB_2U(SCH_1):PAGE79

C461 Q_CAP_C0805-47UF,4V,20%,X6S,CHA
     1 PVCCFA_EHV_FIVRA_CPU1 @S9S_MB_2U_LIB.S9S_MB_2U(SCH_1):PVCCFA_EHV_FIVRA_CPU1     I5 @S9S_MB_2U_LIB.S9S_MB_2U(SCH_1):PAGE78
     2    GND @S9S_MB_2U_LIB.S9S_MB_2U(SCH_1):GND     I5 @S9S_MB_2U_LIB.S9S_MB_2U(SCH_1):PAGE78

C462 Q_CAP_C0805-47UF,4V,20%,X6S,CHA
     1 PVCCFA_EHV_FIVRA_CPU1 @S9S_MB_2U_LIB.S9S_MB_2U(SCH_1):PVCCFA_EHV_FIVRA_CPU1     I5 @S9S_MB_2U_LIB.S9S_MB_2U(SCH_1):PAGE79
     2    GND @S9S_MB_2U_LIB.S9S_MB_2U(SCH_1):GND     I5 @S9S_MB_2U_LIB.S9S_MB_2U(SCH_1):PAGE79

C463 Q_CAP_C0805-47UF,4V,20%,X6S,CHA
     1 PVCCD_HV_CPU1 @S9S_MB_2U_LIB.S9S_MB_2U(SCH_1):PVCCD_HV_CPU1    I21 @S9S_MB_2U_LIB.S9S_MB_2U(SCH_1):PAGE79
     2    GND @S9S_MB_2U_LIB.S9S_MB_2U(SCH_1):GND    I21 @S9S_MB_2U_LIB.S9S_MB_2U(SCH_1):PAGE79

C464 Q_CAP_C0805-47UF,4V,20%,X6S,CHA
     1 PVCCFA_EHV_CPU1 @S9S_MB_2U_LIB.S9S_MB_2U(SCH_1):PVCCFA_EHV_CPU1    I17 @S9S_MB_2U_LIB.S9S_MB_2U(SCH_1):PAGE79
     2    GND @S9S_MB_2U_LIB.S9S_MB_2U(SCH_1):GND    I17 @S9S_MB_2U_LIB.S9S_MB_2U(SCH_1):PAGE79

C465 Q_CAP_C0603-47UF,2.5V,20%,X6S,A
     1 PVCCFA_EHV_FIVRA_CPU1 @S9S_MB_2U_LIB.S9S_MB_2U(SCH_1):PVCCFA_EHV_FIVRA_CPU1     I7 @S9S_MB_2U_LIB.S9S_MB_2U(SCH_1):PAGE78
     2    GND @S9S_MB_2U_LIB.S9S_MB_2U(SCH_1):GND     I7 @S9S_MB_2U_LIB.S9S_MB_2U(SCH_1):PAGE78

C466 Q_CAP_C0805-47UF,4V,20%,X6S,CHA
     1 PVCCFA_EHV_FIVRA_CPU1 @S9S_MB_2U_LIB.S9S_MB_2U(SCH_1):PVCCFA_EHV_FIVRA_CPU1     I7 @S9S_MB_2U_LIB.S9S_MB_2U(SCH_1):PAGE79
     2    GND @S9S_MB_2U_LIB.S9S_MB_2U(SCH_1):GND     I7 @S9S_MB_2U_LIB.S9S_MB_2U(SCH_1):PAGE79

C467 Q_CAP_C0805-47UF,4V,20%,X6S,CHA
     1 PVCCD_HV_CPU1 @S9S_MB_2U_LIB.S9S_MB_2U(SCH_1):PVCCD_HV_CPU1    I31 @S9S_MB_2U_LIB.S9S_MB_2U(SCH_1):PAGE79
     2    GND @S9S_MB_2U_LIB.S9S_MB_2U(SCH_1):GND    I31 @S9S_MB_2U_LIB.S9S_MB_2U(SCH_1):PAGE79

C468 Q_CAP_C0805-47UF,4V,20%,X6S,CHA
     1 PVCCFA_EHV_CPU1 @S9S_MB_2U_LIB.S9S_MB_2U(SCH_1):PVCCFA_EHV_CPU1    I26 @S9S_MB_2U_LIB.S9S_MB_2U(SCH_1):PAGE79
     2    GND @S9S_MB_2U_LIB.S9S_MB_2U(SCH_1):GND    I26 @S9S_MB_2U_LIB.S9S_MB_2U(SCH_1):PAGE79

C470 Q_CAP_C0805-47UF,4V,20%,X6S,CHA
     1 PVCCFA_EHV_FIVRA_CPU1 @S9S_MB_2U_LIB.S9S_MB_2U(SCH_1):PVCCFA_EHV_FIVRA_CPU1     I8 @S9S_MB_2U_LIB.S9S_MB_2U(SCH_1):PAGE79
     2    GND @S9S_MB_2U_LIB.S9S_MB_2U(SCH_1):GND     I8 @S9S_MB_2U_LIB.S9S_MB_2U(SCH_1):PAGE79

C471 Q_CAP_C0805-47UF,4V,20%,X6S,CHA
     1 PVCCD_HV_CPU1 @S9S_MB_2U_LIB.S9S_MB_2U(SCH_1):PVCCD_HV_CPU1    I25 @S9S_MB_2U_LIB.S9S_MB_2U(SCH_1):PAGE78
     2    GND @S9S_MB_2U_LIB.S9S_MB_2U(SCH_1):GND    I25 @S9S_MB_2U_LIB.S9S_MB_2U(SCH_1):PAGE78

C472 Q_CAP_C0603-47UF,2.5V,20%,X6S,A
     1 PVCCFA_EHV_CPU1 @S9S_MB_2U_LIB.S9S_MB_2U(SCH_1):PVCCFA_EHV_CPU1    I27 @S9S_MB_2U_LIB.S9S_MB_2U(SCH_1):PAGE79
     2    GND @S9S_MB_2U_LIB.S9S_MB_2U(SCH_1):GND    I27 @S9S_MB_2U_LIB.S9S_MB_2U(SCH_1):PAGE79

C473 Q_CAP_C0805-47UF,4V,20%,X6S,CHA
     1 PVCCFA_EHV_FIVRA_CPU1 @S9S_MB_2U_LIB.S9S_MB_2U(SCH_1):PVCCFA_EHV_FIVRA_CPU1     I9 @S9S_MB_2U_LIB.S9S_MB_2U(SCH_1):PAGE79
     2    GND @S9S_MB_2U_LIB.S9S_MB_2U(SCH_1):GND     I9 @S9S_MB_2U_LIB.S9S_MB_2U(SCH_1):PAGE79

C474 Q_CAP_C0805-47UF,4V,20%,X6S,CHA
     1 PVCCD_HV_CPU1 @S9S_MB_2U_LIB.S9S_MB_2U(SCH_1):PVCCD_HV_CPU1    I29 @S9S_MB_2U_LIB.S9S_MB_2U(SCH_1):PAGE78
     2    GND @S9S_MB_2U_LIB.S9S_MB_2U(SCH_1):GND    I29 @S9S_MB_2U_LIB.S9S_MB_2U(SCH_1):PAGE78

C475 Q_CAP_C0603-47UF,2.5V,20%,X6S,A
     1 PVCCFA_EHV_CPU1 @S9S_MB_2U_LIB.S9S_MB_2U(SCH_1):PVCCFA_EHV_CPU1    I29 @S9S_MB_2U_LIB.S9S_MB_2U(SCH_1):PAGE79
     2    GND @S9S_MB_2U_LIB.S9S_MB_2U(SCH_1):GND    I29 @S9S_MB_2U_LIB.S9S_MB_2U(SCH_1):PAGE79

C476 Q_CAP_C0805-47UF,4V,20%,X6S,CHA
     1 PVCCFA_EHV_FIVRA_CPU1 @S9S_MB_2U_LIB.S9S_MB_2U(SCH_1):PVCCFA_EHV_FIVRA_CPU1    I37 @S9S_MB_2U_LIB.S9S_MB_2U(SCH_1):PAGE79
     2    GND @S9S_MB_2U_LIB.S9S_MB_2U(SCH_1):GND    I37 @S9S_MB_2U_LIB.S9S_MB_2U(SCH_1):PAGE79

C477 Q_CAP_C0805-47UF,4V,20%,X6S,CHA
     1 PVCCFA_EHV_FIVRA_CPU1 @S9S_MB_2U_LIB.S9S_MB_2U(SCH_1):PVCCFA_EHV_FIVRA_CPU1    I38 @S9S_MB_2U_LIB.S9S_MB_2U(SCH_1):PAGE79
     2    GND @S9S_MB_2U_LIB.S9S_MB_2U(SCH_1):GND    I38 @S9S_MB_2U_LIB.S9S_MB_2U(SCH_1):PAGE79

C478 Q_CAP_C0805-47UF,4V,20%,X6S,CHA
     1 PVCCINFAON_CPU1 @S9S_MB_2U_LIB.S9S_MB_2U(SCH_1):PVCCINFAON_CPU1     I8 @S9S_MB_2U_LIB.S9S_MB_2U(SCH_1):PAGE78
     2    GND @S9S_MB_2U_LIB.S9S_MB_2U(SCH_1):GND     I8 @S9S_MB_2U_LIB.S9S_MB_2U(SCH_1):PAGE78

C479 Q_CAP_C0805-47UF,4V,20%,X6S,CHA
     1 PVCCFA_EHV_FIVRA_CPU1 @S9S_MB_2U_LIB.S9S_MB_2U(SCH_1):PVCCFA_EHV_FIVRA_CPU1    I39 @S9S_MB_2U_LIB.S9S_MB_2U(SCH_1):PAGE79
     2    GND @S9S_MB_2U_LIB.S9S_MB_2U(SCH_1):GND    I39 @S9S_MB_2U_LIB.S9S_MB_2U(SCH_1):PAGE79

C481 Q_CAP_C0805-47UF,4V,20%,X6S,CHA
     1 PVCCINFAON_CPU1 @S9S_MB_2U_LIB.S9S_MB_2U(SCH_1):PVCCINFAON_CPU1    I13 @S9S_MB_2U_LIB.S9S_MB_2U(SCH_1):PAGE79
     2    GND @S9S_MB_2U_LIB.S9S_MB_2U(SCH_1):GND    I13 @S9S_MB_2U_LIB.S9S_MB_2U(SCH_1):PAGE79

C482 Q_CAP_C0805-47UF,4V,20%,X6S,CHA
     1 PVCCFA_EHV_FIVRA_CPU1 @S9S_MB_2U_LIB.S9S_MB_2U(SCH_1):PVCCFA_EHV_FIVRA_CPU1    I41 @S9S_MB_2U_LIB.S9S_MB_2U(SCH_1):PAGE79
     2    GND @S9S_MB_2U_LIB.S9S_MB_2U(SCH_1):GND    I41 @S9S_MB_2U_LIB.S9S_MB_2U(SCH_1):PAGE79

C483 Q_CAP_C0805-47UF,4V,20%,X6S,CHA
     1 PVCCIN_CPU1 @S9S_MB_2U_LIB.S9S_MB_2U(SCH_1):PVCCIN_CPU1    I68 @S9S_MB_2U_LIB.S9S_MB_2U(SCH_1):PAGE78
     2    GND @S9S_MB_2U_LIB.S9S_MB_2U(SCH_1):GND    I68 @S9S_MB_2U_LIB.S9S_MB_2U(SCH_1):PAGE78

C484 Q_CAP_C0805-47UF,4V,20%,X6S,CHA
     1 PVCCINFAON_CPU1 @S9S_MB_2U_LIB.S9S_MB_2U(SCH_1):PVCCINFAON_CPU1    I12 @S9S_MB_2U_LIB.S9S_MB_2U(SCH_1):PAGE79
     2    GND @S9S_MB_2U_LIB.S9S_MB_2U(SCH_1):GND    I12 @S9S_MB_2U_LIB.S9S_MB_2U(SCH_1):PAGE79

C485 Q_CAP_C0805-47UF,4V,20%,X6S,CHA
     1 PVCCFA_EHV_FIVRA_CPU1 @S9S_MB_2U_LIB.S9S_MB_2U(SCH_1):PVCCFA_EHV_FIVRA_CPU1    I42 @S9S_MB_2U_LIB.S9S_MB_2U(SCH_1):PAGE79
     2    GND @S9S_MB_2U_LIB.S9S_MB_2U(SCH_1):GND    I42 @S9S_MB_2U_LIB.S9S_MB_2U(SCH_1):PAGE79

C486 Q_CAP_C0805-47UF,4V,20%,X6S,CHA
     1 PVCCINFAON_CPU1 @S9S_MB_2U_LIB.S9S_MB_2U(SCH_1):PVCCINFAON_CPU1    I11 @S9S_MB_2U_LIB.S9S_MB_2U(SCH_1):PAGE79
     2    GND @S9S_MB_2U_LIB.S9S_MB_2U(SCH_1):GND    I11 @S9S_MB_2U_LIB.S9S_MB_2U(SCH_1):PAGE79

C487 Q_CAP_C0805-47UF,4V,20%,X6S,CHA
     1 PVCCINFAON_CPU1 @S9S_MB_2U_LIB.S9S_MB_2U(SCH_1):PVCCINFAON_CPU1    I10 @S9S_MB_2U_LIB.S9S_MB_2U(SCH_1):PAGE79
     2    GND @S9S_MB_2U_LIB.S9S_MB_2U(SCH_1):GND    I10 @S9S_MB_2U_LIB.S9S_MB_2U(SCH_1):PAGE79

C488 Q_CAP_C0603-47UF,2.5V,20%,X6S,A
     1 PVCCINFAON_CPU1 @S9S_MB_2U_LIB.S9S_MB_2U(SCH_1):PVCCINFAON_CPU1    I18 @S9S_MB_2U_LIB.S9S_MB_2U(SCH_1):PAGE78
     2    GND @S9S_MB_2U_LIB.S9S_MB_2U(SCH_1):GND    I18 @S9S_MB_2U_LIB.S9S_MB_2U(SCH_1):PAGE78

C489 Q_CAP_C0603-47UF,2.5V,20%,X6S,A
     1 PVCCINFAON_CPU1 @S9S_MB_2U_LIB.S9S_MB_2U(SCH_1):PVCCINFAON_CPU1    I19 @S9S_MB_2U_LIB.S9S_MB_2U(SCH_1):PAGE78
     2    GND @S9S_MB_2U_LIB.S9S_MB_2U(SCH_1):GND    I19 @S9S_MB_2U_LIB.S9S_MB_2U(SCH_1):PAGE78

C490 Q_CAP_C0402-22UF,4V,20%,X6S,CHA
     1 PVCCINFAON_CPU1 @S9S_MB_2U_LIB.S9S_MB_2U(SCH_1):PVCCINFAON_CPU1    I23 @S9S_MB_2U_LIB.S9S_MB_2U(SCH_1):PAGE78
     2    GND @S9S_MB_2U_LIB.S9S_MB_2U(SCH_1):GND    I23 @S9S_MB_2U_LIB.S9S_MB_2U(SCH_1):PAGE78

C491 Q_CAP_C0805-47UF,4V,20%,X6S,CHA
     1 PVCCD_HV_CPU0 @S9S_MB_2U_LIB.S9S_MB_2U(SCH_1):PVCCD_HV_CPU0    I13 @S9S_MB_2U_LIB.S9S_MB_2U(SCH_1):PAGE75
     2    GND @S9S_MB_2U_LIB.S9S_MB_2U(SCH_1):GND    I13 @S9S_MB_2U_LIB.S9S_MB_2U(SCH_1):PAGE75

C492 Q_CAP_C0805-47UF,4V,20%,X6S,CHA
     1 PVCCFA_EHV_CPU0 @S9S_MB_2U_LIB.S9S_MB_2U(SCH_1):PVCCFA_EHV_CPU0    I11 @S9S_MB_2U_LIB.S9S_MB_2U(SCH_1):PAGE75
     2    GND @S9S_MB_2U_LIB.S9S_MB_2U(SCH_1):GND    I11 @S9S_MB_2U_LIB.S9S_MB_2U(SCH_1):PAGE75

C493 Q_CAP_C0805-47UF,4V,20%,X6S,CHA
     1 PVCCFA_EHV_FIVRA_CPU0 @S9S_MB_2U_LIB.S9S_MB_2U(SCH_1):PVCCFA_EHV_FIVRA_CPU0     I1 @S9S_MB_2U_LIB.S9S_MB_2U(SCH_1):PAGE75
     2    GND @S9S_MB_2U_LIB.S9S_MB_2U(SCH_1):GND     I1 @S9S_MB_2U_LIB.S9S_MB_2U(SCH_1):PAGE75

C494 Q_CAP_C0805-47UF,4V,20%,X6S,CHA
     1 PVCCFA_EHV_FIVRA_CPU0 @S9S_MB_2U_LIB.S9S_MB_2U(SCH_1):PVCCFA_EHV_FIVRA_CPU0     I1 @S9S_MB_2U_LIB.S9S_MB_2U(SCH_1):PAGE76
     2    GND @S9S_MB_2U_LIB.S9S_MB_2U(SCH_1):GND     I1 @S9S_MB_2U_LIB.S9S_MB_2U(SCH_1):PAGE76

C495 Q_CAP_C0805-47UF,4V,20%,X6S,CHA
     1 PVCCD_HV_CPU0 @S9S_MB_2U_LIB.S9S_MB_2U(SCH_1):PVCCD_HV_CPU0    I18 @S9S_MB_2U_LIB.S9S_MB_2U(SCH_1):PAGE75
     2    GND @S9S_MB_2U_LIB.S9S_MB_2U(SCH_1):GND    I18 @S9S_MB_2U_LIB.S9S_MB_2U(SCH_1):PAGE75

C496 Q_CAP_C0805-47UF,4V,20%,X6S,CHA
     1 PVCCFA_EHV_CPU0 @S9S_MB_2U_LIB.S9S_MB_2U(SCH_1):PVCCFA_EHV_CPU0    I16 @S9S_MB_2U_LIB.S9S_MB_2U(SCH_1):PAGE75
     2    GND @S9S_MB_2U_LIB.S9S_MB_2U(SCH_1):GND    I16 @S9S_MB_2U_LIB.S9S_MB_2U(SCH_1):PAGE75

C497 Q_CAP_C0805-47UF,4V,20%,X6S,CHA
     1 PVCCFA_EHV_FIVRA_CPU0 @S9S_MB_2U_LIB.S9S_MB_2U(SCH_1):PVCCFA_EHV_FIVRA_CPU0     I3 @S9S_MB_2U_LIB.S9S_MB_2U(SCH_1):PAGE75
     2    GND @S9S_MB_2U_LIB.S9S_MB_2U(SCH_1):GND     I3 @S9S_MB_2U_LIB.S9S_MB_2U(SCH_1):PAGE75

C498 Q_CAP_C0805-47UF,4V,20%,X6S,CHA
     1 PVCCFA_EHV_FIVRA_CPU0 @S9S_MB_2U_LIB.S9S_MB_2U(SCH_1):PVCCFA_EHV_FIVRA_CPU0     I2 @S9S_MB_2U_LIB.S9S_MB_2U(SCH_1):PAGE76
     2    GND @S9S_MB_2U_LIB.S9S_MB_2U(SCH_1):GND     I2 @S9S_MB_2U_LIB.S9S_MB_2U(SCH_1):PAGE76

C499 Q_CAP_C0805-47UF,4V,20%,X6S,CHA
     1 PVCCD_HV_CPU0 @S9S_MB_2U_LIB.S9S_MB_2U(SCH_1):PVCCD_HV_CPU0    I18 @S9S_MB_2U_LIB.S9S_MB_2U(SCH_1):PAGE76
     2    GND @S9S_MB_2U_LIB.S9S_MB_2U(SCH_1):GND    I18 @S9S_MB_2U_LIB.S9S_MB_2U(SCH_1):PAGE76

C500 Q_CAP_C0805-47UF,4V,20%,X6S,CHA
     1 PVCCFA_EHV_CPU0 @S9S_MB_2U_LIB.S9S_MB_2U(SCH_1):PVCCFA_EHV_CPU0     I9 @S9S_MB_2U_LIB.S9S_MB_2U(SCH_1):PAGE76
     2    GND @S9S_MB_2U_LIB.S9S_MB_2U(SCH_1):GND     I9 @S9S_MB_2U_LIB.S9S_MB_2U(SCH_1):PAGE76

C501 Q_CAP_C0805-47UF,4V,20%,X6S,CHA
     1 PVCCFA_EHV_FIVRA_CPU0 @S9S_MB_2U_LIB.S9S_MB_2U(SCH_1):PVCCFA_EHV_FIVRA_CPU0     I4 @S9S_MB_2U_LIB.S9S_MB_2U(SCH_1):PAGE75
     2    GND @S9S_MB_2U_LIB.S9S_MB_2U(SCH_1):GND     I4 @S9S_MB_2U_LIB.S9S_MB_2U(SCH_1):PAGE75

C502 Q_CAP_C0805-47UF,4V,20%,X6S,CHA
     1 PVCCFA_EHV_FIVRA_CPU0 @S9S_MB_2U_LIB.S9S_MB_2U(SCH_1):PVCCFA_EHV_FIVRA_CPU0     I3 @S9S_MB_2U_LIB.S9S_MB_2U(SCH_1):PAGE76
     2    GND @S9S_MB_2U_LIB.S9S_MB_2U(SCH_1):GND     I3 @S9S_MB_2U_LIB.S9S_MB_2U(SCH_1):PAGE76

C503 Q_CAP_C0805-47UF,4V,20%,X6S,CHA
     1 PVCCD_HV_CPU0 @S9S_MB_2U_LIB.S9S_MB_2U(SCH_1):PVCCD_HV_CPU0    I20 @S9S_MB_2U_LIB.S9S_MB_2U(SCH_1):PAGE76
     2    GND @S9S_MB_2U_LIB.S9S_MB_2U(SCH_1):GND    I20 @S9S_MB_2U_LIB.S9S_MB_2U(SCH_1):PAGE76

C504 Q_CAP_C0805-47UF,4V,20%,X6S,CHA
     1 PVCCFA_EHV_CPU0 @S9S_MB_2U_LIB.S9S_MB_2U(SCH_1):PVCCFA_EHV_CPU0    I10 @S9S_MB_2U_LIB.S9S_MB_2U(SCH_1):PAGE76
     2    GND @S9S_MB_2U_LIB.S9S_MB_2U(SCH_1):GND    I10 @S9S_MB_2U_LIB.S9S_MB_2U(SCH_1):PAGE76

C505 Q_CAP_C0805-47UF,4V,20%,X6S,CHA
     1 PVCCFA_EHV_FIVRA_CPU0 @S9S_MB_2U_LIB.S9S_MB_2U(SCH_1):PVCCFA_EHV_FIVRA_CPU0     I6 @S9S_MB_2U_LIB.S9S_MB_2U(SCH_1):PAGE75
     2    GND @S9S_MB_2U_LIB.S9S_MB_2U(SCH_1):GND     I6 @S9S_MB_2U_LIB.S9S_MB_2U(SCH_1):PAGE75

C506 Q_CAP_C0805-47UF,4V,20%,X6S,CHA
     1 PVCCFA_EHV_FIVRA_CPU0 @S9S_MB_2U_LIB.S9S_MB_2U(SCH_1):PVCCFA_EHV_FIVRA_CPU0    I26 @S9S_MB_2U_LIB.S9S_MB_2U(SCH_1):PAGE76
     2    GND @S9S_MB_2U_LIB.S9S_MB_2U(SCH_1):GND    I26 @S9S_MB_2U_LIB.S9S_MB_2U(SCH_1):PAGE76

C507 Q_CAP_C0805-47UF,4V,20%,X6S,CHA
     1 PVCCD_HV_CPU0 @S9S_MB_2U_LIB.S9S_MB_2U(SCH_1):PVCCD_HV_CPU0    I21 @S9S_MB_2U_LIB.S9S_MB_2U(SCH_1):PAGE76
     2    GND @S9S_MB_2U_LIB.S9S_MB_2U(SCH_1):GND    I21 @S9S_MB_2U_LIB.S9S_MB_2U(SCH_1):PAGE76

C508 Q_CAP_C0805-47UF,4V,20%,X6S,CHA
     1 PVCCFA_EHV_CPU0 @S9S_MB_2U_LIB.S9S_MB_2U(SCH_1):PVCCFA_EHV_CPU0    I11 @S9S_MB_2U_LIB.S9S_MB_2U(SCH_1):PAGE76
     2    GND @S9S_MB_2U_LIB.S9S_MB_2U(SCH_1):GND    I11 @S9S_MB_2U_LIB.S9S_MB_2U(SCH_1):PAGE76

C509 Q_CAP_C0603-47UF,2.5V,20%,X6S,A
     1 PVCCFA_EHV_FIVRA_CPU0 @S9S_MB_2U_LIB.S9S_MB_2U(SCH_1):PVCCFA_EHV_FIVRA_CPU0     I8 @S9S_MB_2U_LIB.S9S_MB_2U(SCH_1):PAGE75
     2    GND @S9S_MB_2U_LIB.S9S_MB_2U(SCH_1):GND     I8 @S9S_MB_2U_LIB.S9S_MB_2U(SCH_1):PAGE75

C510 Q_CAP_C0805-47UF,4V,20%,X6S,CHA
     1 PVCCFA_EHV_FIVRA_CPU0 @S9S_MB_2U_LIB.S9S_MB_2U(SCH_1):PVCCFA_EHV_FIVRA_CPU0    I27 @S9S_MB_2U_LIB.S9S_MB_2U(SCH_1):PAGE76
     2    GND @S9S_MB_2U_LIB.S9S_MB_2U(SCH_1):GND    I27 @S9S_MB_2U_LIB.S9S_MB_2U(SCH_1):PAGE76

C511 Q_CAP_C0805-47UF,4V,20%,X6S,CHA
     1 PVCCD_HV_CPU0 @S9S_MB_2U_LIB.S9S_MB_2U(SCH_1):PVCCD_HV_CPU0    I43 @S9S_MB_2U_LIB.S9S_MB_2U(SCH_1):PAGE76
     2    GND @S9S_MB_2U_LIB.S9S_MB_2U(SCH_1):GND    I43 @S9S_MB_2U_LIB.S9S_MB_2U(SCH_1):PAGE76

C512 Q_CAP_C0805-47UF,4V,20%,X6S,CHA
     1 PVCCFA_EHV_CPU0 @S9S_MB_2U_LIB.S9S_MB_2U(SCH_1):PVCCFA_EHV_CPU0    I32 @S9S_MB_2U_LIB.S9S_MB_2U(SCH_1):PAGE76
     2    GND @S9S_MB_2U_LIB.S9S_MB_2U(SCH_1):GND    I32 @S9S_MB_2U_LIB.S9S_MB_2U(SCH_1):PAGE76

C513 Q_CAP_C0805-22UF,16V,20%,X6S,CA
     1 PGPPA_AUX @S9S_MB_2U_LIB.S9S_MB_2U(SCH_1):PGPPA_AUX     I5 @S9S_MB_2U_LIB.S9S_MB_2U(SCH_1):PAGE243
     2    GND @S9S_MB_2U_LIB.S9S_MB_2U(SCH_1):GND     I5 @S9S_MB_2U_LIB.S9S_MB_2U(SCH_1):PAGE243

C514 Q_CAP_C0805-47UF,4V,20%,X6S,CHA
     1 PVCCFA_EHV_FIVRA_CPU0 @S9S_MB_2U_LIB.S9S_MB_2U(SCH_1):PVCCFA_EHV_FIVRA_CPU0    I28 @S9S_MB_2U_LIB.S9S_MB_2U(SCH_1):PAGE76
     2    GND @S9S_MB_2U_LIB.S9S_MB_2U(SCH_1):GND    I28 @S9S_MB_2U_LIB.S9S_MB_2U(SCH_1):PAGE76

C515 Q_CAP_C0805-47UF,4V,20%,X6S,CHA
     1 PVCCD_HV_CPU0 @S9S_MB_2U_LIB.S9S_MB_2U(SCH_1):PVCCD_HV_CPU0    I19 @S9S_MB_2U_LIB.S9S_MB_2U(SCH_1):PAGE75
     2    GND @S9S_MB_2U_LIB.S9S_MB_2U(SCH_1):GND    I19 @S9S_MB_2U_LIB.S9S_MB_2U(SCH_1):PAGE75

C516 Q_CAP_C0603-47UF,2.5V,20%,X6S,A
     1 PVCCFA_EHV_CPU0 @S9S_MB_2U_LIB.S9S_MB_2U(SCH_1):PVCCFA_EHV_CPU0    I33 @S9S_MB_2U_LIB.S9S_MB_2U(SCH_1):PAGE76
     2    GND @S9S_MB_2U_LIB.S9S_MB_2U(SCH_1):GND    I33 @S9S_MB_2U_LIB.S9S_MB_2U(SCH_1):PAGE76

C517 Q_CAP_C0805-47UF,4V,20%,X6S,CHA
     1 PVCCFA_EHV_FIVRA_CPU0 @S9S_MB_2U_LIB.S9S_MB_2U(SCH_1):PVCCFA_EHV_FIVRA_CPU0    I29 @S9S_MB_2U_LIB.S9S_MB_2U(SCH_1):PAGE76
     2    GND @S9S_MB_2U_LIB.S9S_MB_2U(SCH_1):GND    I29 @S9S_MB_2U_LIB.S9S_MB_2U(SCH_1):PAGE76

C518 Q_CAP_C0805-47UF,4V,20%,X6S,CHA
     1 PVCCD_HV_CPU0 @S9S_MB_2U_LIB.S9S_MB_2U(SCH_1):PVCCD_HV_CPU0    I31 @S9S_MB_2U_LIB.S9S_MB_2U(SCH_1):PAGE75
     2    GND @S9S_MB_2U_LIB.S9S_MB_2U(SCH_1):GND    I31 @S9S_MB_2U_LIB.S9S_MB_2U(SCH_1):PAGE75

C519 Q_CAP_C0603-47UF,2.5V,20%,X6S,A
     1 PVCCFA_EHV_CPU0 @S9S_MB_2U_LIB.S9S_MB_2U(SCH_1):PVCCFA_EHV_CPU0    I35 @S9S_MB_2U_LIB.S9S_MB_2U(SCH_1):PAGE76
     2    GND @S9S_MB_2U_LIB.S9S_MB_2U(SCH_1):GND    I35 @S9S_MB_2U_LIB.S9S_MB_2U(SCH_1):PAGE76

C520 Q_CAP_C0805-47UF,4V,20%,X6S,CHA
     1 PVCCFA_EHV_FIVRA_CPU0 @S9S_MB_2U_LIB.S9S_MB_2U(SCH_1):PVCCFA_EHV_FIVRA_CPU0    I36 @S9S_MB_2U_LIB.S9S_MB_2U(SCH_1):PAGE76
     2    GND @S9S_MB_2U_LIB.S9S_MB_2U(SCH_1):GND    I36 @S9S_MB_2U_LIB.S9S_MB_2U(SCH_1):PAGE76

C521 Q_CAP_C0805-47UF,4V,20%,X6S,CHA
     1 PVCCFA_EHV_FIVRA_CPU0 @S9S_MB_2U_LIB.S9S_MB_2U(SCH_1):PVCCFA_EHV_FIVRA_CPU0    I37 @S9S_MB_2U_LIB.S9S_MB_2U(SCH_1):PAGE76
     2    GND @S9S_MB_2U_LIB.S9S_MB_2U(SCH_1):GND    I37 @S9S_MB_2U_LIB.S9S_MB_2U(SCH_1):PAGE76

C522 Q_CAP_C0805-47UF,4V,20%,X6S,CHA
     1 PVCCINFAON_CPU0 @S9S_MB_2U_LIB.S9S_MB_2U(SCH_1):PVCCINFAON_CPU0     I9 @S9S_MB_2U_LIB.S9S_MB_2U(SCH_1):PAGE75
     2    GND @S9S_MB_2U_LIB.S9S_MB_2U(SCH_1):GND     I9 @S9S_MB_2U_LIB.S9S_MB_2U(SCH_1):PAGE75

C523 Q_CAP_C0805-47UF,4V,20%,X6S,CHA
     1 PVCCFA_EHV_FIVRA_CPU0 @S9S_MB_2U_LIB.S9S_MB_2U(SCH_1):PVCCFA_EHV_FIVRA_CPU0    I38 @S9S_MB_2U_LIB.S9S_MB_2U(SCH_1):PAGE76
     2    GND @S9S_MB_2U_LIB.S9S_MB_2U(SCH_1):GND    I38 @S9S_MB_2U_LIB.S9S_MB_2U(SCH_1):PAGE76

C525 Q_CAP_C0805-47UF,4V,20%,X6S,CHA
     1 PVCCINFAON_CPU0 @S9S_MB_2U_LIB.S9S_MB_2U(SCH_1):PVCCINFAON_CPU0     I5 @S9S_MB_2U_LIB.S9S_MB_2U(SCH_1):PAGE76
     2    GND @S9S_MB_2U_LIB.S9S_MB_2U(SCH_1):GND     I5 @S9S_MB_2U_LIB.S9S_MB_2U(SCH_1):PAGE76

C526 Q_CAP_C0805-47UF,4V,20%,X6S,CHA
     1 PVCCFA_EHV_FIVRA_CPU0 @S9S_MB_2U_LIB.S9S_MB_2U(SCH_1):PVCCFA_EHV_FIVRA_CPU0    I39 @S9S_MB_2U_LIB.S9S_MB_2U(SCH_1):PAGE76
     2    GND @S9S_MB_2U_LIB.S9S_MB_2U(SCH_1):GND    I39 @S9S_MB_2U_LIB.S9S_MB_2U(SCH_1):PAGE76

C527 Q_CAP_C0805-47UF,4V,20%,X6S,CHA
     1 PVCCIN_CPU0 @S9S_MB_2U_LIB.S9S_MB_2U(SCH_1):PVCCIN_CPU0    I68 @S9S_MB_2U_LIB.S9S_MB_2U(SCH_1):PAGE75
     2    GND @S9S_MB_2U_LIB.S9S_MB_2U(SCH_1):GND    I68 @S9S_MB_2U_LIB.S9S_MB_2U(SCH_1):PAGE75

C528 Q_CAP_C0805-47UF,4V,20%,X6S,CHA
     1 PVCCINFAON_CPU0 @S9S_MB_2U_LIB.S9S_MB_2U(SCH_1):PVCCINFAON_CPU0     I6 @S9S_MB_2U_LIB.S9S_MB_2U(SCH_1):PAGE76
     2    GND @S9S_MB_2U_LIB.S9S_MB_2U(SCH_1):GND     I6 @S9S_MB_2U_LIB.S9S_MB_2U(SCH_1):PAGE76

C529 Q_CAP_C0805-47UF,4V,20%,X6S,CHA
     1 PVCCFA_EHV_FIVRA_CPU0 @S9S_MB_2U_LIB.S9S_MB_2U(SCH_1):PVCCFA_EHV_FIVRA_CPU0    I41 @S9S_MB_2U_LIB.S9S_MB_2U(SCH_1):PAGE76
     2    GND @S9S_MB_2U_LIB.S9S_MB_2U(SCH_1):GND    I41 @S9S_MB_2U_LIB.S9S_MB_2U(SCH_1):PAGE76

C530 Q_CAP_C0805-47UF,4V,20%,X6S,CHA
     1 PVCCINFAON_CPU0 @S9S_MB_2U_LIB.S9S_MB_2U(SCH_1):PVCCINFAON_CPU0     I7 @S9S_MB_2U_LIB.S9S_MB_2U(SCH_1):PAGE76
     2    GND @S9S_MB_2U_LIB.S9S_MB_2U(SCH_1):GND     I7 @S9S_MB_2U_LIB.S9S_MB_2U(SCH_1):PAGE76

C531 Q_CAP_C0805-47UF,4V,20%,X6S,CHA
     1 PVCCINFAON_CPU0 @S9S_MB_2U_LIB.S9S_MB_2U(SCH_1):PVCCINFAON_CPU0    I31 @S9S_MB_2U_LIB.S9S_MB_2U(SCH_1):PAGE76
     2    GND @S9S_MB_2U_LIB.S9S_MB_2U(SCH_1):GND    I31 @S9S_MB_2U_LIB.S9S_MB_2U(SCH_1):PAGE76

C532 Q_CAP_C0603-47UF,2.5V,20%,X6S,A
     1 PVCCINFAON_CPU0 @S9S_MB_2U_LIB.S9S_MB_2U(SCH_1):PVCCINFAON_CPU0    I14 @S9S_MB_2U_LIB.S9S_MB_2U(SCH_1):PAGE75
     2    GND @S9S_MB_2U_LIB.S9S_MB_2U(SCH_1):GND    I14 @S9S_MB_2U_LIB.S9S_MB_2U(SCH_1):PAGE75

C533 Q_CAP_C0603-47UF,2.5V,20%,X6S,A
     1 PVCCINFAON_CPU0 @S9S_MB_2U_LIB.S9S_MB_2U(SCH_1):PVCCINFAON_CPU0    I17 @S9S_MB_2U_LIB.S9S_MB_2U(SCH_1):PAGE75
     2    GND @S9S_MB_2U_LIB.S9S_MB_2U(SCH_1):GND    I17 @S9S_MB_2U_LIB.S9S_MB_2U(SCH_1):PAGE75

C534 Q_CAP_C0402-22UF,4V,20%,X6S,CHA
     1 PVCCINFAON_CPU0 @S9S_MB_2U_LIB.S9S_MB_2U(SCH_1):PVCCINFAON_CPU0    I29 @S9S_MB_2U_LIB.S9S_MB_2U(SCH_1):PAGE75
     2    GND @S9S_MB_2U_LIB.S9S_MB_2U(SCH_1):GND    I29 @S9S_MB_2U_LIB.S9S_MB_2U(SCH_1):PAGE75

C535 Q_CAP_C0805-22UF,16V,20%,X6S,CA
     1 PGPPA_AUX @S9S_MB_2U_LIB.S9S_MB_2U(SCH_1):PGPPA_AUX     I4 @S9S_MB_2U_LIB.S9S_MB_2U(SCH_1):PAGE243
     2    GND @S9S_MB_2U_LIB.S9S_MB_2U(SCH_1):GND     I4 @S9S_MB_2U_LIB.S9S_MB_2U(SCH_1):PAGE243

C537 Q_CAP_0402-0.1UF,25V,10%,X7R,CA
     1 P3V3_AUX @S9S_MB_2U_LIB.S9S_MB_2U(SCH_1):P3V3_AUX    I25 @S9S_MB_2U_LIB.S9S_MB_2U(SCH_1):PAGE218
     2    GND @S9S_MB_2U_LIB.S9S_MB_2U(SCH_1):GND    I25 @S9S_MB_2U_LIB.S9S_MB_2U(SCH_1):PAGE218

C538 Q_CAP_0402-0.1UF,25V,10%,X7R,CA
     1 P3V3_AUX @S9S_MB_2U_LIB.S9S_MB_2U(SCH_1):P3V3_AUX    I24 @S9S_MB_2U_LIB.S9S_MB_2U(SCH_1):PAGE217
     2    GND @S9S_MB_2U_LIB.S9S_MB_2U(SCH_1):GND    I24 @S9S_MB_2U_LIB.S9S_MB_2U(SCH_1):PAGE217

C539 Q_CAP_0402-0.1UF,25V,10%,X7R,CA
     1 P3V3_AUX @S9S_MB_2U_LIB.S9S_MB_2U(SCH_1):P3V3_AUX    I70 @S9S_MB_2U_LIB.S9S_MB_2U(SCH_1):PAGE135
     2    GND @S9S_MB_2U_LIB.S9S_MB_2U(SCH_1):GND    I70 @S9S_MB_2U_LIB.S9S_MB_2U(SCH_1):PAGE135

C540 Q_CAP_0402-0.1UF,25V,10%,X7R,CA
     1 P3V3_AUX @S9S_MB_2U_LIB.S9S_MB_2U(SCH_1):P3V3_AUX    I81 @S9S_MB_2U_LIB.S9S_MB_2U(SCH_1):PAGE135
     2    GND @S9S_MB_2U_LIB.S9S_MB_2U(SCH_1):GND    I81 @S9S_MB_2U_LIB.S9S_MB_2U(SCH_1):PAGE135

C541 Q_CAP_C0402-1UF,25V,10%,X6S,CHA
     1 P3V3_AUX @S9S_MB_2U_LIB.S9S_MB_2U(SCH_1):P3V3_AUX    I61 @S9S_MB_2U_LIB.S9S_MB_2U(SCH_1):PAGE135
     2    GND @S9S_MB_2U_LIB.S9S_MB_2U(SCH_1):GND    I61 @S9S_MB_2U_LIB.S9S_MB_2U(SCH_1):PAGE135

C542 Q_CAP_C0402-1UF,25V,10%,X6S,CHA
     1 P3V3_AUX @S9S_MB_2U_LIB.S9S_MB_2U(SCH_1):P3V3_AUX    I80 @S9S_MB_2U_LIB.S9S_MB_2U(SCH_1):PAGE135
     2    GND @S9S_MB_2U_LIB.S9S_MB_2U(SCH_1):GND    I80 @S9S_MB_2U_LIB.S9S_MB_2U(SCH_1):PAGE135

C543 Q_CAP_0402-0.1UF,25V,10%,X7R,CA
     1 P3V3_AUX @S9S_MB_2U_LIB.S9S_MB_2U(SCH_1):P3V3_AUX   I100 @S9S_MB_2U_LIB.S9S_MB_2U(SCH_1):PAGE135
     2    GND @S9S_MB_2U_LIB.S9S_MB_2U(SCH_1):GND   I100 @S9S_MB_2U_LIB.S9S_MB_2U(SCH_1):PAGE135

C544 Q_CAP_0402-0.1UF,25V,10%,X7R,CA
     1 P3V3_AUX @S9S_MB_2U_LIB.S9S_MB_2U(SCH_1):P3V3_AUX    I94 @S9S_MB_2U_LIB.S9S_MB_2U(SCH_1):PAGE135
     2    GND @S9S_MB_2U_LIB.S9S_MB_2U(SCH_1):GND    I94 @S9S_MB_2U_LIB.S9S_MB_2U(SCH_1):PAGE135

C545 Q_CAP_C0402-1UF,25V,10%,X6S,CHA
     1 P3V3_AUX @S9S_MB_2U_LIB.S9S_MB_2U(SCH_1):P3V3_AUX    I93 @S9S_MB_2U_LIB.S9S_MB_2U(SCH_1):PAGE134
     2    GND @S9S_MB_2U_LIB.S9S_MB_2U(SCH_1):GND    I93 @S9S_MB_2U_LIB.S9S_MB_2U(SCH_1):PAGE134

C546 Q_CAP_C0402-1UF,25V,10%,X6S,CHA
     1 P3V3_AUX @S9S_MB_2U_LIB.S9S_MB_2U(SCH_1):P3V3_AUX   I135 @S9S_MB_2U_LIB.S9S_MB_2U(SCH_1):PAGE134
     2    GND @S9S_MB_2U_LIB.S9S_MB_2U(SCH_1):GND   I135 @S9S_MB_2U_LIB.S9S_MB_2U(SCH_1):PAGE134

C547 Q_CAP_C0402-1UF,25V,10%,X6S,CHA
     1 P1V05_PCH_AUX @S9S_MB_2U_LIB.S9S_MB_2U(SCH_1):P1V05_PCH_AUX   I100 @S9S_MB_2U_LIB.S9S_MB_2U(SCH_1):PAGE133
     2    GND @S9S_MB_2U_LIB.S9S_MB_2U(SCH_1):GND   I100 @S9S_MB_2U_LIB.S9S_MB_2U(SCH_1):PAGE133

C548 Q_CAP_0402-0.1UF,25V,10%,X7R,CA
     1 JTAG_DBP_POWER_BTN_N @S9S_MB_2U_LIB.S9S_MB_2U(SCH_1):JTAG_DBP_POWER_BTN_N   I130 @S9S_MB_2U_LIB.S9S_MB_2U(SCH_1):PAGE133
     2    GND @S9S_MB_2U_LIB.S9S_MB_2U(SCH_1):GND   I130 @S9S_MB_2U_LIB.S9S_MB_2U(SCH_1):PAGE133

C549 Q_CAP_0402-0.1UF,25V,10%,X7R,CA
     1 JTAG_RST_DBP_RST_CO_N @S9S_MB_2U_LIB.S9S_MB_2U(SCH_1):JTAG_RST_DBP_RST_CO_N   I129 @S9S_MB_2U_LIB.S9S_MB_2U(SCH_1):PAGE133
     2    GND @S9S_MB_2U_LIB.S9S_MB_2U(SCH_1):GND   I129 @S9S_MB_2U_LIB.S9S_MB_2U(SCH_1):PAGE133

C550 Q_CAP_C0402-1UF,25V,10%,X6S,CHA
     1 P1V8_PCH_AUX @S9S_MB_2U_LIB.S9S_MB_2U(SCH_1):P1V8_PCH_AUX    I99 @S9S_MB_2U_LIB.S9S_MB_2U(SCH_1):PAGE133
     2    GND @S9S_MB_2U_LIB.S9S_MB_2U(SCH_1):GND    I99 @S9S_MB_2U_LIB.S9S_MB_2U(SCH_1):PAGE133

C551 Q_CAP_C0402-1UF,25V,10%,X6S,CHA
     1 P3V3_AUX @S9S_MB_2U_LIB.S9S_MB_2U(SCH_1):P3V3_AUX   I105 @S9S_MB_2U_LIB.S9S_MB_2U(SCH_1):PAGE133
     2    GND @S9S_MB_2U_LIB.S9S_MB_2U(SCH_1):GND   I105 @S9S_MB_2U_LIB.S9S_MB_2U(SCH_1):PAGE133

C552 Q_CAP_0402-0.1UF,25V,10%,X7R,CA
     1 FM_CPU_FBRK_DEBUG_N @S9S_MB_2U_LIB.S9S_MB_2U(SCH_1):FM_CPU_FBRK_DEBUG_N    I96 @S9S_MB_2U_LIB.S9S_MB_2U(SCH_1):PAGE133
     2    GND @S9S_MB_2U_LIB.S9S_MB_2U(SCH_1):GND    I96 @S9S_MB_2U_LIB.S9S_MB_2U(SCH_1):PAGE133

C554 Q_CAP_0402-0.1UF,25V,10%,X7R,CA
     1 P3V3_AUX_BMC_D @S9S_MB_2U_LIB.S9S_MB_2U(SCH_1):P3V3_AUX_BMC_D    I86 @S9S_MB_2U_LIB.S9S_MB_2U(SCH_1):PAGE210
     2    GND @S9S_MB_2U_LIB.S9S_MB_2U(SCH_1):GND    I86 @S9S_MB_2U_LIB.S9S_MB_2U(SCH_1):PAGE210

C559 Q_CAP_0402-0.1UF,25V,10%,X7R,CA
     1 PVNN_TERM_CPU0 @S9S_MB_2U_LIB.S9S_MB_2U(SCH_1):PVNN_TERM_CPU0    I20 @S9S_MB_2U_LIB.S9S_MB_2U(SCH_1):PAGE223
     2    GND @S9S_MB_2U_LIB.S9S_MB_2U(SCH_1):GND    I20 @S9S_MB_2U_LIB.S9S_MB_2U(SCH_1):PAGE223

C560 Q_CAP_0402-0.1UF,25V,10%,X7R,CA
     1 PVNN_TERM_CPU1 @S9S_MB_2U_LIB.S9S_MB_2U(SCH_1):PVNN_TERM_CPU1    I42 @S9S_MB_2U_LIB.S9S_MB_2U(SCH_1):PAGE223
     2    GND @S9S_MB_2U_LIB.S9S_MB_2U(SCH_1):GND    I42 @S9S_MB_2U_LIB.S9S_MB_2U(SCH_1):PAGE223

C561 Q_CAP_0402-0.1UF,25V,10%,X7R,CA
     1 P3V3_AUX @S9S_MB_2U_LIB.S9S_MB_2U(SCH_1):P3V3_AUX    I18 @S9S_MB_2U_LIB.S9S_MB_2U(SCH_1):PAGE223
     2    GND @S9S_MB_2U_LIB.S9S_MB_2U(SCH_1):GND    I18 @S9S_MB_2U_LIB.S9S_MB_2U(SCH_1):PAGE223

C562 Q_CAP_0402-0.1UF,25V,10%,X7R,CA
     1 P3V3_AUX @S9S_MB_2U_LIB.S9S_MB_2U(SCH_1):P3V3_AUX    I31 @S9S_MB_2U_LIB.S9S_MB_2U(SCH_1):PAGE223
     2    GND @S9S_MB_2U_LIB.S9S_MB_2U(SCH_1):GND    I31 @S9S_MB_2U_LIB.S9S_MB_2U(SCH_1):PAGE223

C563 Q_CAP_C0805-10UF,25V,10%,X6S,CA
     1 P3V3_AUX_BMC_D @S9S_MB_2U_LIB.S9S_MB_2U(SCH_1):P3V3_AUX_BMC_D    I88 @S9S_MB_2U_LIB.S9S_MB_2U(SCH_1):PAGE210
     2    GND @S9S_MB_2U_LIB.S9S_MB_2U(SCH_1):GND    I88 @S9S_MB_2U_LIB.S9S_MB_2U(SCH_1):PAGE210

C567 Q_CAP_0402-0.1UF,25V,10%,X7R,CA
     1 PVNN_TERM_CPU0 @S9S_MB_2U_LIB.S9S_MB_2U(SCH_1):PVNN_TERM_CPU0    I25 @S9S_MB_2U_LIB.S9S_MB_2U(SCH_1):PAGE224
     2    GND @S9S_MB_2U_LIB.S9S_MB_2U(SCH_1):GND    I25 @S9S_MB_2U_LIB.S9S_MB_2U(SCH_1):PAGE224

C568 Q_CAP_0402-0.1UF,25V,10%,X7R,CA
     1 PVNN_TERM_CPU1 @S9S_MB_2U_LIB.S9S_MB_2U(SCH_1):PVNN_TERM_CPU1    I35 @S9S_MB_2U_LIB.S9S_MB_2U(SCH_1):PAGE224
     2    GND @S9S_MB_2U_LIB.S9S_MB_2U(SCH_1):GND    I35 @S9S_MB_2U_LIB.S9S_MB_2U(SCH_1):PAGE224

C569 Q_CAP_0402-0.1UF,25V,10%,X7R,CA
     1 P3V3_AUX @S9S_MB_2U_LIB.S9S_MB_2U(SCH_1):P3V3_AUX    I22 @S9S_MB_2U_LIB.S9S_MB_2U(SCH_1):PAGE224
     2    GND @S9S_MB_2U_LIB.S9S_MB_2U(SCH_1):GND    I22 @S9S_MB_2U_LIB.S9S_MB_2U(SCH_1):PAGE224

C570 Q_CAP_0402-0.1UF,25V,10%,X7R,CA
     1 P3V3_AUX @S9S_MB_2U_LIB.S9S_MB_2U(SCH_1):P3V3_AUX    I33 @S9S_MB_2U_LIB.S9S_MB_2U(SCH_1):PAGE224
     2    GND @S9S_MB_2U_LIB.S9S_MB_2U(SCH_1):GND    I33 @S9S_MB_2U_LIB.S9S_MB_2U(SCH_1):PAGE224

C578 Q_CAP_0402-0.1UF,25V,10%,X7R,CA
     1 P3V3_AUX @S9S_MB_2U_LIB.S9S_MB_2U(SCH_1):P3V3_AUX   I169 @S9S_MB_2U_LIB.S9S_MB_2U(SCH_1):PAGE154
     2    GND @S9S_MB_2U_LIB.S9S_MB_2U(SCH_1):GND   I169 @S9S_MB_2U_LIB.S9S_MB_2U(SCH_1):PAGE154

C579 Q_CAP_0402-0.1UF,25V,10%,X7R,CA
     1 P3V3_AUX @S9S_MB_2U_LIB.S9S_MB_2U(SCH_1):P3V3_AUX   I192 @S9S_MB_2U_LIB.S9S_MB_2U(SCH_1):PAGE154
     2    GND @S9S_MB_2U_LIB.S9S_MB_2U(SCH_1):GND   I192 @S9S_MB_2U_LIB.S9S_MB_2U(SCH_1):PAGE154

C580 Q_CAP_0402-0.1UF,25V,10%,X7R,CA
     1 P3V3_OCP_SFF @S9S_MB_2U_LIB.S9S_MB_2U(SCH_1):P3V3_OCP_SFF   I229 @S9S_MB_2U_LIB.S9S_MB_2U(SCH_1):PAGE154
     2    GND @S9S_MB_2U_LIB.S9S_MB_2U(SCH_1):GND   I229 @S9S_MB_2U_LIB.S9S_MB_2U(SCH_1):PAGE154

C581 Q_CAP_0402-0.1UF,25V,10%,X7R,CA
     1 P3V3_AUX @S9S_MB_2U_LIB.S9S_MB_2U(SCH_1):P3V3_AUX   I148 @S9S_MB_2U_LIB.S9S_MB_2U(SCH_1):PAGE154
     2    GND @S9S_MB_2U_LIB.S9S_MB_2U(SCH_1):GND   I148 @S9S_MB_2U_LIB.S9S_MB_2U(SCH_1):PAGE154

C590 Q_CAP_C0402-22UF,4V,20%,X6S,CHA
     1 PVNN_MAIN_CPU0 @S9S_MB_2U_LIB.S9S_MB_2U(SCH_1):PVNN_MAIN_CPU0   I102 @S9S_MB_2U_LIB.S9S_MB_2U(SCH_1):PAGE74
     2    GND @S9S_MB_2U_LIB.S9S_MB_2U(SCH_1):GND   I102 @S9S_MB_2U_LIB.S9S_MB_2U(SCH_1):PAGE74

C592 Q_CAP_0402-0.1UF,25V,10%,X7R,CA
     1 P3V3_AUX @S9S_MB_2U_LIB.S9S_MB_2U(SCH_1):P3V3_AUX    I30 @S9S_MB_2U_LIB.S9S_MB_2U(SCH_1):PAGE153
     2    GND @S9S_MB_2U_LIB.S9S_MB_2U(SCH_1):GND    I30 @S9S_MB_2U_LIB.S9S_MB_2U(SCH_1):PAGE153

C593 Q_CAP_0402-0.1UF,25V,10%,X7R,CA
     1 P3V3_AUX @S9S_MB_2U_LIB.S9S_MB_2U(SCH_1):P3V3_AUX    I27 @S9S_MB_2U_LIB.S9S_MB_2U(SCH_1):PAGE153
     2    GND @S9S_MB_2U_LIB.S9S_MB_2U(SCH_1):GND    I27 @S9S_MB_2U_LIB.S9S_MB_2U(SCH_1):PAGE153

C605 Q_CAP_C0402-1UF,25V,10%,X6S,CHA
     1 PGPPA_AUX @S9S_MB_2U_LIB.S9S_MB_2U(SCH_1):PGPPA_AUX    I37 @S9S_MB_2U_LIB.S9S_MB_2U(SCH_1):PAGE190
     2    GND @S9S_MB_2U_LIB.S9S_MB_2U(SCH_1):GND    I37 @S9S_MB_2U_LIB.S9S_MB_2U(SCH_1):PAGE190

C606 Q_CAP_C0402-1UF,25V,10%,X6S,CHA
     1 PGPPA_AUX @S9S_MB_2U_LIB.S9S_MB_2U(SCH_1):PGPPA_AUX    I45 @S9S_MB_2U_LIB.S9S_MB_2U(SCH_1):PAGE190
     2    GND @S9S_MB_2U_LIB.S9S_MB_2U(SCH_1):GND    I45 @S9S_MB_2U_LIB.S9S_MB_2U(SCH_1):PAGE190

C607 Q_CAP_0402-0.1UF,25V,10%,X7R,CA
     1 PGPPA_AUX @S9S_MB_2U_LIB.S9S_MB_2U(SCH_1):PGPPA_AUX    I36 @S9S_MB_2U_LIB.S9S_MB_2U(SCH_1):PAGE190
     2    GND @S9S_MB_2U_LIB.S9S_MB_2U(SCH_1):GND    I36 @S9S_MB_2U_LIB.S9S_MB_2U(SCH_1):PAGE190

C608 Q_CAP_0402-0.1UF,25V,10%,X7R,CA
     1 PGPPA_AUX @S9S_MB_2U_LIB.S9S_MB_2U(SCH_1):PGPPA_AUX    I43 @S9S_MB_2U_LIB.S9S_MB_2U(SCH_1):PAGE190
     2    GND @S9S_MB_2U_LIB.S9S_MB_2U(SCH_1):GND    I43 @S9S_MB_2U_LIB.S9S_MB_2U(SCH_1):PAGE190

C609 Q_CAP_0402-0.1UF,25V,10%,X7R,CA
     1 RTC_EXT_CAP @S9S_MB_2U_LIB.S9S_MB_2U(SCH_1):RTC_EXT_CAP    I89 @S9S_MB_2U_LIB.S9S_MB_2U(SCH_1):PAGE171
     2    GND @S9S_MB_2U_LIB.S9S_MB_2U(SCH_1):GND    I89 @S9S_MB_2U_LIB.S9S_MB_2U(SCH_1):PAGE171

C610 Q_CAP_C0402-1UF,25V,10%,X6S,CHA
     1 RST_SRTCRST_N @S9S_MB_2U_LIB.S9S_MB_2U(SCH_1):RST_SRTCRST_N    I68 @S9S_MB_2U_LIB.S9S_MB_2U(SCH_1):PAGE177
     2    GND @S9S_MB_2U_LIB.S9S_MB_2U(SCH_1):GND    I68 @S9S_MB_2U_LIB.S9S_MB_2U(SCH_1):PAGE177

C611 Q_CAP_C0402-1UF,25V,10%,X6S,CHA
     1 P3V3_RTC_AUX @S9S_MB_2U_LIB.S9S_MB_2U(SCH_1):P3V3_RTC_AUX    I65 @S9S_MB_2U_LIB.S9S_MB_2U(SCH_1):PAGE177
     2    GND @S9S_MB_2U_LIB.S9S_MB_2U(SCH_1):GND    I65 @S9S_MB_2U_LIB.S9S_MB_2U(SCH_1):PAGE177

C613 Q_CAP_C0402-1UF,25V,10%,EMPTY,A
     1 RST_PLD_CPU1_DRAM_GH_N @S9S_MB_2U_LIB.S9S_MB_2U(SCH_1):RST_PLD_CPU1_DRAM_GH_N    I68 @S9S_MB_2U_LIB.S9S_MB_2U(SCH_1):PAGE130
     2    GND @S9S_MB_2U_LIB.S9S_MB_2U(SCH_1):GND    I68 @S9S_MB_2U_LIB.S9S_MB_2U(SCH_1):PAGE130

C614 Q_CAP_C0402-1UF,25V,10%,EMPTY,A
     1 RST_PLD_CPU1_DRAM_AB_N @S9S_MB_2U_LIB.S9S_MB_2U(SCH_1):RST_PLD_CPU1_DRAM_AB_N    I65 @S9S_MB_2U_LIB.S9S_MB_2U(SCH_1):PAGE130
     2    GND @S9S_MB_2U_LIB.S9S_MB_2U(SCH_1):GND    I65 @S9S_MB_2U_LIB.S9S_MB_2U(SCH_1):PAGE130

C615 Q_CAP_C0402-1UF,25V,10%,EMPTY,A
     1 RST_PLD_CPU1_DRAM_CD_N @S9S_MB_2U_LIB.S9S_MB_2U(SCH_1):RST_PLD_CPU1_DRAM_CD_N    I62 @S9S_MB_2U_LIB.S9S_MB_2U(SCH_1):PAGE130
     2    GND @S9S_MB_2U_LIB.S9S_MB_2U(SCH_1):GND    I62 @S9S_MB_2U_LIB.S9S_MB_2U(SCH_1):PAGE130

C616 Q_CAP_C0402-1UF,25V,10%,EMPTY,A
     1 RST_PLD_CPU1_DRAM_EF_N @S9S_MB_2U_LIB.S9S_MB_2U(SCH_1):RST_PLD_CPU1_DRAM_EF_N    I59 @S9S_MB_2U_LIB.S9S_MB_2U(SCH_1):PAGE130
     2    GND @S9S_MB_2U_LIB.S9S_MB_2U(SCH_1):GND    I59 @S9S_MB_2U_LIB.S9S_MB_2U(SCH_1):PAGE130

C621 Q_CAP_C0402-1UF,25V,10%,EMPTY,A
     1 RST_PLD_CPU0_DRAM_GH_N @S9S_MB_2U_LIB.S9S_MB_2U(SCH_1):RST_PLD_CPU0_DRAM_GH_N   I102 @S9S_MB_2U_LIB.S9S_MB_2U(SCH_1):PAGE129
     2    GND @S9S_MB_2U_LIB.S9S_MB_2U(SCH_1):GND   I102 @S9S_MB_2U_LIB.S9S_MB_2U(SCH_1):PAGE129

C622 Q_CAP_C0402-1UF,25V,10%,EMPTY,A
     1 RST_PLD_CPU0_DRAM_AB_N @S9S_MB_2U_LIB.S9S_MB_2U(SCH_1):RST_PLD_CPU0_DRAM_AB_N    I91 @S9S_MB_2U_LIB.S9S_MB_2U(SCH_1):PAGE129
     2    GND @S9S_MB_2U_LIB.S9S_MB_2U(SCH_1):GND    I91 @S9S_MB_2U_LIB.S9S_MB_2U(SCH_1):PAGE129

C623 Q_CAP_C0402-1UF,25V,10%,EMPTY,A
     1 RST_PLD_CPU0_DRAM_CD_N @S9S_MB_2U_LIB.S9S_MB_2U(SCH_1):RST_PLD_CPU0_DRAM_CD_N    I94 @S9S_MB_2U_LIB.S9S_MB_2U(SCH_1):PAGE129
     2    GND @S9S_MB_2U_LIB.S9S_MB_2U(SCH_1):GND    I94 @S9S_MB_2U_LIB.S9S_MB_2U(SCH_1):PAGE129

C624 Q_CAP_C0402-1UF,25V,10%,EMPTY,A
     1 RST_PLD_CPU0_DRAM_EF_N @S9S_MB_2U_LIB.S9S_MB_2U(SCH_1):RST_PLD_CPU0_DRAM_EF_N    I99 @S9S_MB_2U_LIB.S9S_MB_2U(SCH_1):PAGE129
     2    GND @S9S_MB_2U_LIB.S9S_MB_2U(SCH_1):GND    I99 @S9S_MB_2U_LIB.S9S_MB_2U(SCH_1):PAGE129

C626 Q_CAP_0402-1000PF,50V,5%,EMPTYA
     1 PWRGD_PVCCD_HV_CPU0_R @S9S_MB_2U_LIB.S9S_MB_2U(SCH_1):PWRGD_PVCCD_HV_CPU0_R    I47 @S9S_MB_2U_LIB.S9S_MB_2U(SCH_1):PAGE264
     2    GND @S9S_MB_2U_LIB.S9S_MB_2U(SCH_1):GND    I47 @S9S_MB_2U_LIB.S9S_MB_2U(SCH_1):PAGE264

C629 Q_CAP_0402-0.1UF,25V,10%,X7R,CA
     1 P3V3_AUX @S9S_MB_2U_LIB.S9S_MB_2U(SCH_1):P3V3_AUX    I55 @S9S_MB_2U_LIB.S9S_MB_2U(SCH_1):PAGE231
     2    GND @S9S_MB_2U_LIB.S9S_MB_2U(SCH_1):GND    I55 @S9S_MB_2U_LIB.S9S_MB_2U(SCH_1):PAGE231

C639 Q_CAP_0402-0.1UF,25V,10%,X7R,CA
     1 P3V3_AUX @S9S_MB_2U_LIB.S9S_MB_2U(SCH_1):P3V3_AUX    I22 @S9S_MB_2U_LIB.S9S_MB_2U(SCH_1):PAGE151
     2    GND @S9S_MB_2U_LIB.S9S_MB_2U(SCH_1):GND    I22 @S9S_MB_2U_LIB.S9S_MB_2U(SCH_1):PAGE151

C640 Q_CAP_0402-0.1UF,25V,10%,X7R,CA
     1 P3V3_AUX @S9S_MB_2U_LIB.S9S_MB_2U(SCH_1):P3V3_AUX    I40 @S9S_MB_2U_LIB.S9S_MB_2U(SCH_1):PAGE151
     2    GND @S9S_MB_2U_LIB.S9S_MB_2U(SCH_1):GND    I40 @S9S_MB_2U_LIB.S9S_MB_2U(SCH_1):PAGE151

C641 Q_CAP_0402-0.1UF,25V,10%,X7R,CA
     1 P3V3_AUX @S9S_MB_2U_LIB.S9S_MB_2U(SCH_1):P3V3_AUX    I32 @S9S_MB_2U_LIB.S9S_MB_2U(SCH_1):PAGE151
     2    GND @S9S_MB_2U_LIB.S9S_MB_2U(SCH_1):GND    I32 @S9S_MB_2U_LIB.S9S_MB_2U(SCH_1):PAGE151

C678 Q_CAP_DIFFBUS_C0201-DIFF BUS_0A
     1 P5E_CPU1_PE4_TX_C_DN<15> @S9S_MB_2U_LIB.S9S_MB_2U(SCH_1):P5E_CPU1_PE4_TX_C_DN(15)   I172 @S9S_MB_2U_LIB.S9S_MB_2U(SCH_1):PAGE168
     2 P5E_CPU1_PE4_TX_DN<15> @S9S_MB_2U_LIB.S9S_MB_2U(SCH_1):P5E_CPU1_PE4_TX_DN(15)   I172 @S9S_MB_2U_LIB.S9S_MB_2U(SCH_1):PAGE168

C679 Q_CAP_DIFFBUS_C0201-DIFF BUS_0A
     1 P5E_CPU1_PE4_TX_C_DP<15> @S9S_MB_2U_LIB.S9S_MB_2U(SCH_1):P5E_CPU1_PE4_TX_C_DP(15)   I169 @S9S_MB_2U_LIB.S9S_MB_2U(SCH_1):PAGE168
     2 P5E_CPU1_PE4_TX_DP<15> @S9S_MB_2U_LIB.S9S_MB_2U(SCH_1):P5E_CPU1_PE4_TX_DP(15)   I169 @S9S_MB_2U_LIB.S9S_MB_2U(SCH_1):PAGE168

C680 Q_CAP_DIFFBUS_C0201-DIFF BUS_0A
     1 P5E_CPU1_PE4_TX_C_DN<14> @S9S_MB_2U_LIB.S9S_MB_2U(SCH_1):P5E_CPU1_PE4_TX_C_DN(14)   I170 @S9S_MB_2U_LIB.S9S_MB_2U(SCH_1):PAGE168
     2 P5E_CPU1_PE4_TX_DN<14> @S9S_MB_2U_LIB.S9S_MB_2U(SCH_1):P5E_CPU1_PE4_TX_DN(14)   I170 @S9S_MB_2U_LIB.S9S_MB_2U(SCH_1):PAGE168

C681 Q_CAP_DIFFBUS_C0201-DIFF BUS_0A
     1 P5E_CPU1_PE4_TX_C_DP<14> @S9S_MB_2U_LIB.S9S_MB_2U(SCH_1):P5E_CPU1_PE4_TX_C_DP(14)   I171 @S9S_MB_2U_LIB.S9S_MB_2U(SCH_1):PAGE168
     2 P5E_CPU1_PE4_TX_DP<14> @S9S_MB_2U_LIB.S9S_MB_2U(SCH_1):P5E_CPU1_PE4_TX_DP(14)   I171 @S9S_MB_2U_LIB.S9S_MB_2U(SCH_1):PAGE168

C682 Q_CAP_DIFFBUS_C0201-DIFF BUS_0A
     1 P5E_CPU1_PE4_TX_C_DN<13> @S9S_MB_2U_LIB.S9S_MB_2U(SCH_1):P5E_CPU1_PE4_TX_C_DN(13)   I167 @S9S_MB_2U_LIB.S9S_MB_2U(SCH_1):PAGE168
     2 P5E_CPU1_PE4_TX_DN<13> @S9S_MB_2U_LIB.S9S_MB_2U(SCH_1):P5E_CPU1_PE4_TX_DN(13)   I167 @S9S_MB_2U_LIB.S9S_MB_2U(SCH_1):PAGE168

C683 Q_CAP_DIFFBUS_C0201-DIFF BUS_0A
     1 P5E_CPU1_PE4_TX_C_DP<13> @S9S_MB_2U_LIB.S9S_MB_2U(SCH_1):P5E_CPU1_PE4_TX_C_DP(13)   I168 @S9S_MB_2U_LIB.S9S_MB_2U(SCH_1):PAGE168
     2 P5E_CPU1_PE4_TX_DP<13> @S9S_MB_2U_LIB.S9S_MB_2U(SCH_1):P5E_CPU1_PE4_TX_DP(13)   I168 @S9S_MB_2U_LIB.S9S_MB_2U(SCH_1):PAGE168

C684 Q_CAP_DIFFBUS_C0201-DIFF BUS_0A
     1 P5E_CPU1_PE4_TX_C_DN<12> @S9S_MB_2U_LIB.S9S_MB_2U(SCH_1):P5E_CPU1_PE4_TX_C_DN(12)   I166 @S9S_MB_2U_LIB.S9S_MB_2U(SCH_1):PAGE168
     2 P5E_CPU1_PE4_TX_DN<12> @S9S_MB_2U_LIB.S9S_MB_2U(SCH_1):P5E_CPU1_PE4_TX_DN(12)   I166 @S9S_MB_2U_LIB.S9S_MB_2U(SCH_1):PAGE168

C685 Q_CAP_DIFFBUS_C0201-DIFF BUS_0A
     1 P5E_CPU1_PE4_TX_C_DP<12> @S9S_MB_2U_LIB.S9S_MB_2U(SCH_1):P5E_CPU1_PE4_TX_C_DP(12)   I165 @S9S_MB_2U_LIB.S9S_MB_2U(SCH_1):PAGE168
     2 P5E_CPU1_PE4_TX_DP<12> @S9S_MB_2U_LIB.S9S_MB_2U(SCH_1):P5E_CPU1_PE4_TX_DP(12)   I165 @S9S_MB_2U_LIB.S9S_MB_2U(SCH_1):PAGE168

C686 Q_CAP_DIFFBUS_C0201-DIFF BUS_0A
     1 P5E_CPU1_PE4_TX_C_DN<11> @S9S_MB_2U_LIB.S9S_MB_2U(SCH_1):P5E_CPU1_PE4_TX_C_DN(11)   I164 @S9S_MB_2U_LIB.S9S_MB_2U(SCH_1):PAGE168
     2 P5E_CPU1_PE4_TX_DN<11> @S9S_MB_2U_LIB.S9S_MB_2U(SCH_1):P5E_CPU1_PE4_TX_DN(11)   I164 @S9S_MB_2U_LIB.S9S_MB_2U(SCH_1):PAGE168

C687 Q_CAP_DIFFBUS_C0201-DIFF BUS_0A
     1 P5E_CPU1_PE4_TX_C_DP<11> @S9S_MB_2U_LIB.S9S_MB_2U(SCH_1):P5E_CPU1_PE4_TX_C_DP(11)   I161 @S9S_MB_2U_LIB.S9S_MB_2U(SCH_1):PAGE168
     2 P5E_CPU1_PE4_TX_DP<11> @S9S_MB_2U_LIB.S9S_MB_2U(SCH_1):P5E_CPU1_PE4_TX_DP(11)   I161 @S9S_MB_2U_LIB.S9S_MB_2U(SCH_1):PAGE168

C688 Q_CAP_DIFFBUS_C0201-DIFF BUS_0A
     1 P5E_CPU1_PE4_TX_C_DN<10> @S9S_MB_2U_LIB.S9S_MB_2U(SCH_1):P5E_CPU1_PE4_TX_C_DN(10)   I162 @S9S_MB_2U_LIB.S9S_MB_2U(SCH_1):PAGE168
     2 P5E_CPU1_PE4_TX_DN<10> @S9S_MB_2U_LIB.S9S_MB_2U(SCH_1):P5E_CPU1_PE4_TX_DN(10)   I162 @S9S_MB_2U_LIB.S9S_MB_2U(SCH_1):PAGE168

C689 Q_CAP_DIFFBUS_C0201-DIFF BUS_0A
     1 P5E_CPU1_PE4_TX_C_DP<10> @S9S_MB_2U_LIB.S9S_MB_2U(SCH_1):P5E_CPU1_PE4_TX_C_DP(10)   I163 @S9S_MB_2U_LIB.S9S_MB_2U(SCH_1):PAGE168
     2 P5E_CPU1_PE4_TX_DP<10> @S9S_MB_2U_LIB.S9S_MB_2U(SCH_1):P5E_CPU1_PE4_TX_DP(10)   I163 @S9S_MB_2U_LIB.S9S_MB_2U(SCH_1):PAGE168

C690 Q_CAP_DIFFBUS_C0201-DIFF BUS_0A
     1 P5E_CPU1_PE4_TX_C_DN<9> @S9S_MB_2U_LIB.S9S_MB_2U(SCH_1):P5E_CPU1_PE4_TX_C_DN(9)   I159 @S9S_MB_2U_LIB.S9S_MB_2U(SCH_1):PAGE168
     2 P5E_CPU1_PE4_TX_DN<9> @S9S_MB_2U_LIB.S9S_MB_2U(SCH_1):P5E_CPU1_PE4_TX_DN(9)   I159 @S9S_MB_2U_LIB.S9S_MB_2U(SCH_1):PAGE168

C691 Q_CAP_DIFFBUS_C0201-DIFF BUS_0A
     1 P5E_CPU1_PE4_TX_C_DP<9> @S9S_MB_2U_LIB.S9S_MB_2U(SCH_1):P5E_CPU1_PE4_TX_C_DP(9)   I160 @S9S_MB_2U_LIB.S9S_MB_2U(SCH_1):PAGE168
     2 P5E_CPU1_PE4_TX_DP<9> @S9S_MB_2U_LIB.S9S_MB_2U(SCH_1):P5E_CPU1_PE4_TX_DP(9)   I160 @S9S_MB_2U_LIB.S9S_MB_2U(SCH_1):PAGE168

C692 Q_CAP_DIFFBUS_C0201-DIFF BUS_0A
     1 P5E_CPU1_PE4_TX_C_DN<8> @S9S_MB_2U_LIB.S9S_MB_2U(SCH_1):P5E_CPU1_PE4_TX_C_DN(8)   I158 @S9S_MB_2U_LIB.S9S_MB_2U(SCH_1):PAGE168
     2 P5E_CPU1_PE4_TX_DN<8> @S9S_MB_2U_LIB.S9S_MB_2U(SCH_1):P5E_CPU1_PE4_TX_DN(8)   I158 @S9S_MB_2U_LIB.S9S_MB_2U(SCH_1):PAGE168

C693 Q_CAP_DIFFBUS_C0201-DIFF BUS_0A
     1 P5E_CPU1_PE4_TX_C_DP<8> @S9S_MB_2U_LIB.S9S_MB_2U(SCH_1):P5E_CPU1_PE4_TX_C_DP(8)   I157 @S9S_MB_2U_LIB.S9S_MB_2U(SCH_1):PAGE168
     2 P5E_CPU1_PE4_TX_DP<8> @S9S_MB_2U_LIB.S9S_MB_2U(SCH_1):P5E_CPU1_PE4_TX_DP(8)   I157 @S9S_MB_2U_LIB.S9S_MB_2U(SCH_1):PAGE168

C694 Q_CAP_DIFFBUS_C0201-DIFF BUS_0A
     1 P5E_CPU1_PE4_TX_C_DN<7> @S9S_MB_2U_LIB.S9S_MB_2U(SCH_1):P5E_CPU1_PE4_TX_C_DN(7)   I140 @S9S_MB_2U_LIB.S9S_MB_2U(SCH_1):PAGE168
     2 P5E_CPU1_PE4_TX_DN<7> @S9S_MB_2U_LIB.S9S_MB_2U(SCH_1):P5E_CPU1_PE4_TX_DN(7)   I140 @S9S_MB_2U_LIB.S9S_MB_2U(SCH_1):PAGE168

C695 Q_CAP_DIFFBUS_C0201-DIFF BUS_0A
     1 P5E_CPU1_PE4_TX_C_DP<7> @S9S_MB_2U_LIB.S9S_MB_2U(SCH_1):P5E_CPU1_PE4_TX_C_DP(7)   I139 @S9S_MB_2U_LIB.S9S_MB_2U(SCH_1):PAGE168
     2 P5E_CPU1_PE4_TX_DP<7> @S9S_MB_2U_LIB.S9S_MB_2U(SCH_1):P5E_CPU1_PE4_TX_DP(7)   I139 @S9S_MB_2U_LIB.S9S_MB_2U(SCH_1):PAGE168

C696 Q_CAP_DIFFBUS_C0201-DIFF BUS_0A
     1 P5E_CPU1_PE4_TX_C_DN<6> @S9S_MB_2U_LIB.S9S_MB_2U(SCH_1):P5E_CPU1_PE4_TX_C_DN(6)   I137 @S9S_MB_2U_LIB.S9S_MB_2U(SCH_1):PAGE168
     2 P5E_CPU1_PE4_TX_DN<6> @S9S_MB_2U_LIB.S9S_MB_2U(SCH_1):P5E_CPU1_PE4_TX_DN(6)   I137 @S9S_MB_2U_LIB.S9S_MB_2U(SCH_1):PAGE168

C697 Q_CAP_DIFFBUS_C0201-DIFF BUS_0A
     1 P5E_CPU1_PE4_TX_C_DP<6> @S9S_MB_2U_LIB.S9S_MB_2U(SCH_1):P5E_CPU1_PE4_TX_C_DP(6)   I138 @S9S_MB_2U_LIB.S9S_MB_2U(SCH_1):PAGE168
     2 P5E_CPU1_PE4_TX_DP<6> @S9S_MB_2U_LIB.S9S_MB_2U(SCH_1):P5E_CPU1_PE4_TX_DP(6)   I138 @S9S_MB_2U_LIB.S9S_MB_2U(SCH_1):PAGE168

C698 Q_CAP_DIFFBUS_C0201-DIFF BUS_0A
     1 P5E_CPU1_PE4_TX_C_DN<5> @S9S_MB_2U_LIB.S9S_MB_2U(SCH_1):P5E_CPU1_PE4_TX_C_DN(5)   I135 @S9S_MB_2U_LIB.S9S_MB_2U(SCH_1):PAGE168
     2 P5E_CPU1_PE4_TX_DN<5> @S9S_MB_2U_LIB.S9S_MB_2U(SCH_1):P5E_CPU1_PE4_TX_DN(5)   I135 @S9S_MB_2U_LIB.S9S_MB_2U(SCH_1):PAGE168

C699 Q_CAP_DIFFBUS_C0201-DIFF BUS_0A
     1 P5E_CPU1_PE4_TX_C_DP<5> @S9S_MB_2U_LIB.S9S_MB_2U(SCH_1):P5E_CPU1_PE4_TX_C_DP(5)   I136 @S9S_MB_2U_LIB.S9S_MB_2U(SCH_1):PAGE168
     2 P5E_CPU1_PE4_TX_DP<5> @S9S_MB_2U_LIB.S9S_MB_2U(SCH_1):P5E_CPU1_PE4_TX_DP(5)   I136 @S9S_MB_2U_LIB.S9S_MB_2U(SCH_1):PAGE168

C700 Q_CAP_DIFFBUS_C0201-DIFF BUS_0A
     1 P5E_CPU1_PE4_TX_C_DN<4> @S9S_MB_2U_LIB.S9S_MB_2U(SCH_1):P5E_CPU1_PE4_TX_C_DN(4)   I134 @S9S_MB_2U_LIB.S9S_MB_2U(SCH_1):PAGE168
     2 P5E_CPU1_PE4_TX_DN<4> @S9S_MB_2U_LIB.S9S_MB_2U(SCH_1):P5E_CPU1_PE4_TX_DN(4)   I134 @S9S_MB_2U_LIB.S9S_MB_2U(SCH_1):PAGE168

C701 Q_CAP_DIFFBUS_C0201-DIFF BUS_0A
     1 P5E_CPU1_PE4_TX_C_DP<4> @S9S_MB_2U_LIB.S9S_MB_2U(SCH_1):P5E_CPU1_PE4_TX_C_DP(4)   I131 @S9S_MB_2U_LIB.S9S_MB_2U(SCH_1):PAGE168
     2 P5E_CPU1_PE4_TX_DP<4> @S9S_MB_2U_LIB.S9S_MB_2U(SCH_1):P5E_CPU1_PE4_TX_DP(4)   I131 @S9S_MB_2U_LIB.S9S_MB_2U(SCH_1):PAGE168

C702 Q_CAP_DIFFBUS_C0201-DIFF BUS_0A
     1 P5E_CPU1_PE4_TX_C_DN<3> @S9S_MB_2U_LIB.S9S_MB_2U(SCH_1):P5E_CPU1_PE4_TX_C_DN(3)   I132 @S9S_MB_2U_LIB.S9S_MB_2U(SCH_1):PAGE168
     2 P5E_CPU1_PE4_TX_DN<3> @S9S_MB_2U_LIB.S9S_MB_2U(SCH_1):P5E_CPU1_PE4_TX_DN(3)   I132 @S9S_MB_2U_LIB.S9S_MB_2U(SCH_1):PAGE168

C703 Q_CAP_DIFFBUS_C0201-DIFF BUS_0A
     1 P5E_CPU1_PE4_TX_C_DP<3> @S9S_MB_2U_LIB.S9S_MB_2U(SCH_1):P5E_CPU1_PE4_TX_C_DP(3)   I133 @S9S_MB_2U_LIB.S9S_MB_2U(SCH_1):PAGE168
     2 P5E_CPU1_PE4_TX_DP<3> @S9S_MB_2U_LIB.S9S_MB_2U(SCH_1):P5E_CPU1_PE4_TX_DP(3)   I133 @S9S_MB_2U_LIB.S9S_MB_2U(SCH_1):PAGE168

C704 Q_CAP_DIFFBUS_C0201-DIFF BUS_0A
     1 P5E_CPU1_PE4_TX_C_DN<2> @S9S_MB_2U_LIB.S9S_MB_2U(SCH_1):P5E_CPU1_PE4_TX_C_DN(2)   I129 @S9S_MB_2U_LIB.S9S_MB_2U(SCH_1):PAGE168
     2 P5E_CPU1_PE4_TX_DN<2> @S9S_MB_2U_LIB.S9S_MB_2U(SCH_1):P5E_CPU1_PE4_TX_DN(2)   I129 @S9S_MB_2U_LIB.S9S_MB_2U(SCH_1):PAGE168

C705 Q_CAP_DIFFBUS_C0201-DIFF BUS_0A
     1 P5E_CPU1_PE4_TX_C_DP<2> @S9S_MB_2U_LIB.S9S_MB_2U(SCH_1):P5E_CPU1_PE4_TX_C_DP(2)   I130 @S9S_MB_2U_LIB.S9S_MB_2U(SCH_1):PAGE168
     2 P5E_CPU1_PE4_TX_DP<2> @S9S_MB_2U_LIB.S9S_MB_2U(SCH_1):P5E_CPU1_PE4_TX_DP(2)   I130 @S9S_MB_2U_LIB.S9S_MB_2U(SCH_1):PAGE168

C706 Q_CAP_DIFFBUS_C0201-DIFF BUS_0A
     1 P5E_CPU1_PE4_TX_C_DN<1> @S9S_MB_2U_LIB.S9S_MB_2U(SCH_1):P5E_CPU1_PE4_TX_C_DN(1)   I127 @S9S_MB_2U_LIB.S9S_MB_2U(SCH_1):PAGE168
     2 P5E_CPU1_PE4_TX_DN<1> @S9S_MB_2U_LIB.S9S_MB_2U(SCH_1):P5E_CPU1_PE4_TX_DN(1)   I127 @S9S_MB_2U_LIB.S9S_MB_2U(SCH_1):PAGE168

C707 Q_CAP_DIFFBUS_C0201-DIFF BUS_0A
     1 P5E_CPU1_PE4_TX_C_DP<1> @S9S_MB_2U_LIB.S9S_MB_2U(SCH_1):P5E_CPU1_PE4_TX_C_DP(1)   I128 @S9S_MB_2U_LIB.S9S_MB_2U(SCH_1):PAGE168
     2 P5E_CPU1_PE4_TX_DP<1> @S9S_MB_2U_LIB.S9S_MB_2U(SCH_1):P5E_CPU1_PE4_TX_DP(1)   I128 @S9S_MB_2U_LIB.S9S_MB_2U(SCH_1):PAGE168

C708 Q_CAP_DIFFBUS_C0201-DIFF BUS_0A
     1 P5E_CPU1_PE4_TX_C_DN<0> @S9S_MB_2U_LIB.S9S_MB_2U(SCH_1):P5E_CPU1_PE4_TX_C_DN(0)   I125 @S9S_MB_2U_LIB.S9S_MB_2U(SCH_1):PAGE168
     2 P5E_CPU1_PE4_TX_DN<0> @S9S_MB_2U_LIB.S9S_MB_2U(SCH_1):P5E_CPU1_PE4_TX_DN(0)   I125 @S9S_MB_2U_LIB.S9S_MB_2U(SCH_1):PAGE168

C709 Q_CAP_DIFFBUS_C0201-DIFF BUS_0A
     1 P5E_CPU1_PE4_TX_C_DP<0> @S9S_MB_2U_LIB.S9S_MB_2U(SCH_1):P5E_CPU1_PE4_TX_C_DP(0)   I126 @S9S_MB_2U_LIB.S9S_MB_2U(SCH_1):PAGE168
     2 P5E_CPU1_PE4_TX_DP<0> @S9S_MB_2U_LIB.S9S_MB_2U(SCH_1):P5E_CPU1_PE4_TX_DP(0)   I126 @S9S_MB_2U_LIB.S9S_MB_2U(SCH_1):PAGE168

C710 Q_CAP_DIFFBUS_C0201-DIFF BUS_0A
     1 P5E_CPU1_PE0_TX_C_DN<15> @S9S_MB_2U_LIB.S9S_MB_2U(SCH_1):P5E_CPU1_PE0_TX_C_DN(15)   I299 @S9S_MB_2U_LIB.S9S_MB_2U(SCH_1):PAGE167
     2 P5E_CPU1_PE0_TX_DN<15> @S9S_MB_2U_LIB.S9S_MB_2U(SCH_1):P5E_CPU1_PE0_TX_DN(15)   I299 @S9S_MB_2U_LIB.S9S_MB_2U(SCH_1):PAGE167

C711 Q_CAP_DIFFBUS_C0201-DIFF BUS_0A
     1 P5E_CPU1_PE0_TX_C_DP<15> @S9S_MB_2U_LIB.S9S_MB_2U(SCH_1):P5E_CPU1_PE0_TX_C_DP(15)   I298 @S9S_MB_2U_LIB.S9S_MB_2U(SCH_1):PAGE167
     2 P5E_CPU1_PE0_TX_DP<15> @S9S_MB_2U_LIB.S9S_MB_2U(SCH_1):P5E_CPU1_PE0_TX_DP(15)   I298 @S9S_MB_2U_LIB.S9S_MB_2U(SCH_1):PAGE167

C712 Q_CAP_DIFFBUS_C0201-DIFF BUS_0A
     1 P5E_CPU1_PE0_TX_C_DN<14> @S9S_MB_2U_LIB.S9S_MB_2U(SCH_1):P5E_CPU1_PE0_TX_C_DN(14)   I296 @S9S_MB_2U_LIB.S9S_MB_2U(SCH_1):PAGE167
     2 P5E_CPU1_PE0_TX_DN<14> @S9S_MB_2U_LIB.S9S_MB_2U(SCH_1):P5E_CPU1_PE0_TX_DN(14)   I296 @S9S_MB_2U_LIB.S9S_MB_2U(SCH_1):PAGE167

C713 Q_CAP_DIFFBUS_C0201-DIFF BUS_0A
     1 P5E_CPU1_PE0_TX_C_DP<14> @S9S_MB_2U_LIB.S9S_MB_2U(SCH_1):P5E_CPU1_PE0_TX_C_DP(14)   I297 @S9S_MB_2U_LIB.S9S_MB_2U(SCH_1):PAGE167
     2 P5E_CPU1_PE0_TX_DP<14> @S9S_MB_2U_LIB.S9S_MB_2U(SCH_1):P5E_CPU1_PE0_TX_DP(14)   I297 @S9S_MB_2U_LIB.S9S_MB_2U(SCH_1):PAGE167

C714 Q_CAP_DIFFBUS_C0201-DIFF BUS_0A
     1 P5E_CPU1_PE0_TX_C_DN<13> @S9S_MB_2U_LIB.S9S_MB_2U(SCH_1):P5E_CPU1_PE0_TX_C_DN(13)   I295 @S9S_MB_2U_LIB.S9S_MB_2U(SCH_1):PAGE167
     2 P5E_CPU1_PE0_TX_DN<13> @S9S_MB_2U_LIB.S9S_MB_2U(SCH_1):P5E_CPU1_PE0_TX_DN(13)   I295 @S9S_MB_2U_LIB.S9S_MB_2U(SCH_1):PAGE167

C715 Q_CAP_DIFFBUS_C0201-DIFF BUS_0A
     1 P5E_CPU1_PE0_TX_C_DP<13> @S9S_MB_2U_LIB.S9S_MB_2U(SCH_1):P5E_CPU1_PE0_TX_C_DP(13)   I294 @S9S_MB_2U_LIB.S9S_MB_2U(SCH_1):PAGE167
     2 P5E_CPU1_PE0_TX_DP<13> @S9S_MB_2U_LIB.S9S_MB_2U(SCH_1):P5E_CPU1_PE0_TX_DP(13)   I294 @S9S_MB_2U_LIB.S9S_MB_2U(SCH_1):PAGE167

C716 Q_CAP_DIFFBUS_C0201-DIFF BUS_0A
     1 P5E_CPU1_PE0_TX_C_DN<12> @S9S_MB_2U_LIB.S9S_MB_2U(SCH_1):P5E_CPU1_PE0_TX_C_DN(12)   I283 @S9S_MB_2U_LIB.S9S_MB_2U(SCH_1):PAGE167
     2 P5E_CPU1_PE0_TX_DN<12> @S9S_MB_2U_LIB.S9S_MB_2U(SCH_1):P5E_CPU1_PE0_TX_DN(12)   I283 @S9S_MB_2U_LIB.S9S_MB_2U(SCH_1):PAGE167

C717 Q_CAP_DIFFBUS_C0201-DIFF BUS_0A
     1 P5E_CPU1_PE0_TX_C_DP<12> @S9S_MB_2U_LIB.S9S_MB_2U(SCH_1):P5E_CPU1_PE0_TX_C_DP(12)   I282 @S9S_MB_2U_LIB.S9S_MB_2U(SCH_1):PAGE167
     2 P5E_CPU1_PE0_TX_DP<12> @S9S_MB_2U_LIB.S9S_MB_2U(SCH_1):P5E_CPU1_PE0_TX_DP(12)   I282 @S9S_MB_2U_LIB.S9S_MB_2U(SCH_1):PAGE167

C718 Q_CAP_DIFFBUS_C0201-DIFF BUS_0A
     1 P5E_CPU1_PE0_TX_C_DN<11> @S9S_MB_2U_LIB.S9S_MB_2U(SCH_1):P5E_CPU1_PE0_TX_C_DN(11)   I281 @S9S_MB_2U_LIB.S9S_MB_2U(SCH_1):PAGE167
     2 P5E_CPU1_PE0_TX_DN<11> @S9S_MB_2U_LIB.S9S_MB_2U(SCH_1):P5E_CPU1_PE0_TX_DN(11)   I281 @S9S_MB_2U_LIB.S9S_MB_2U(SCH_1):PAGE167

C719 Q_CAP_DIFFBUS_C0201-DIFF BUS_0A
     1 P5E_CPU1_PE0_TX_C_DP<11> @S9S_MB_2U_LIB.S9S_MB_2U(SCH_1):P5E_CPU1_PE0_TX_C_DP(11)   I280 @S9S_MB_2U_LIB.S9S_MB_2U(SCH_1):PAGE167
     2 P5E_CPU1_PE0_TX_DP<11> @S9S_MB_2U_LIB.S9S_MB_2U(SCH_1):P5E_CPU1_PE0_TX_DP(11)   I280 @S9S_MB_2U_LIB.S9S_MB_2U(SCH_1):PAGE167

C720 Q_CAP_DIFFBUS_C0201-DIFF BUS_0A
     1 P5E_CPU1_PE0_TX_C_DN<10> @S9S_MB_2U_LIB.S9S_MB_2U(SCH_1):P5E_CPU1_PE0_TX_C_DN(10)   I279 @S9S_MB_2U_LIB.S9S_MB_2U(SCH_1):PAGE167
     2 P5E_CPU1_PE0_TX_DN<10> @S9S_MB_2U_LIB.S9S_MB_2U(SCH_1):P5E_CPU1_PE0_TX_DN(10)   I279 @S9S_MB_2U_LIB.S9S_MB_2U(SCH_1):PAGE167

C721 Q_CAP_DIFFBUS_C0201-DIFF BUS_0A
     1 P5E_CPU1_PE0_TX_C_DP<10> @S9S_MB_2U_LIB.S9S_MB_2U(SCH_1):P5E_CPU1_PE0_TX_C_DP(10)   I278 @S9S_MB_2U_LIB.S9S_MB_2U(SCH_1):PAGE167
     2 P5E_CPU1_PE0_TX_DP<10> @S9S_MB_2U_LIB.S9S_MB_2U(SCH_1):P5E_CPU1_PE0_TX_DP(10)   I278 @S9S_MB_2U_LIB.S9S_MB_2U(SCH_1):PAGE167

C722 Q_CAP_DIFFBUS_C0201-DIFF BUS_0A
     1 P5E_CPU1_PE0_TX_C_DN<9> @S9S_MB_2U_LIB.S9S_MB_2U(SCH_1):P5E_CPU1_PE0_TX_C_DN(9)   I276 @S9S_MB_2U_LIB.S9S_MB_2U(SCH_1):PAGE167
     2 P5E_CPU1_PE0_TX_DN<9> @S9S_MB_2U_LIB.S9S_MB_2U(SCH_1):P5E_CPU1_PE0_TX_DN(9)   I276 @S9S_MB_2U_LIB.S9S_MB_2U(SCH_1):PAGE167

C723 Q_CAP_DIFFBUS_C0201-DIFF BUS_0A
     1 P5E_CPU1_PE0_TX_C_DP<9> @S9S_MB_2U_LIB.S9S_MB_2U(SCH_1):P5E_CPU1_PE0_TX_C_DP(9)   I277 @S9S_MB_2U_LIB.S9S_MB_2U(SCH_1):PAGE167
     2 P5E_CPU1_PE0_TX_DP<9> @S9S_MB_2U_LIB.S9S_MB_2U(SCH_1):P5E_CPU1_PE0_TX_DP(9)   I277 @S9S_MB_2U_LIB.S9S_MB_2U(SCH_1):PAGE167

C724 Q_CAP_DIFFBUS_C0201-DIFF BUS_0A
     1 P5E_CPU1_PE0_TX_C_DN<8> @S9S_MB_2U_LIB.S9S_MB_2U(SCH_1):P5E_CPU1_PE0_TX_C_DN(8)   I275 @S9S_MB_2U_LIB.S9S_MB_2U(SCH_1):PAGE167
     2 P5E_CPU1_PE0_TX_DN<8> @S9S_MB_2U_LIB.S9S_MB_2U(SCH_1):P5E_CPU1_PE0_TX_DN(8)   I275 @S9S_MB_2U_LIB.S9S_MB_2U(SCH_1):PAGE167

C725 Q_CAP_DIFFBUS_C0201-DIFF BUS_0A
     1 P5E_CPU1_PE0_TX_C_DP<8> @S9S_MB_2U_LIB.S9S_MB_2U(SCH_1):P5E_CPU1_PE0_TX_C_DP(8)   I274 @S9S_MB_2U_LIB.S9S_MB_2U(SCH_1):PAGE167
     2 P5E_CPU1_PE0_TX_DP<8> @S9S_MB_2U_LIB.S9S_MB_2U(SCH_1):P5E_CPU1_PE0_TX_DP(8)   I274 @S9S_MB_2U_LIB.S9S_MB_2U(SCH_1):PAGE167

C726 Q_CAP_DIFFBUS_C0201-DIFF BUS_0A
     1 P5E_CPU1_PE0_TX_C_DN<7> @S9S_MB_2U_LIB.S9S_MB_2U(SCH_1):P5E_CPU1_PE0_TX_C_DN(7)   I312 @S9S_MB_2U_LIB.S9S_MB_2U(SCH_1):PAGE167
     2 P5E_CPU1_PE0_TX_DN<7> @S9S_MB_2U_LIB.S9S_MB_2U(SCH_1):P5E_CPU1_PE0_TX_DN(7)   I312 @S9S_MB_2U_LIB.S9S_MB_2U(SCH_1):PAGE167

C727 Q_CAP_DIFFBUS_C0201-DIFF BUS_0A
     1 P5E_CPU1_PE0_TX_C_DP<7> @S9S_MB_2U_LIB.S9S_MB_2U(SCH_1):P5E_CPU1_PE0_TX_C_DP(7)   I251 @S9S_MB_2U_LIB.S9S_MB_2U(SCH_1):PAGE167
     2 P5E_CPU1_PE0_TX_DP<7> @S9S_MB_2U_LIB.S9S_MB_2U(SCH_1):P5E_CPU1_PE0_TX_DP(7)   I251 @S9S_MB_2U_LIB.S9S_MB_2U(SCH_1):PAGE167

C728 Q_CAP_DIFFBUS_C0201-DIFF BUS_0A
     1 P5E_CPU1_PE0_TX_C_DN<6> @S9S_MB_2U_LIB.S9S_MB_2U(SCH_1):P5E_CPU1_PE0_TX_C_DN(6)   I250 @S9S_MB_2U_LIB.S9S_MB_2U(SCH_1):PAGE167
     2 P5E_CPU1_PE0_TX_DN<6> @S9S_MB_2U_LIB.S9S_MB_2U(SCH_1):P5E_CPU1_PE0_TX_DN(6)   I250 @S9S_MB_2U_LIB.S9S_MB_2U(SCH_1):PAGE167

C729 Q_CAP_DIFFBUS_C0201-DIFF BUS_0A
     1 P5E_CPU1_PE0_TX_C_DP<6> @S9S_MB_2U_LIB.S9S_MB_2U(SCH_1):P5E_CPU1_PE0_TX_C_DP(6)   I249 @S9S_MB_2U_LIB.S9S_MB_2U(SCH_1):PAGE167
     2 P5E_CPU1_PE0_TX_DP<6> @S9S_MB_2U_LIB.S9S_MB_2U(SCH_1):P5E_CPU1_PE0_TX_DP(6)   I249 @S9S_MB_2U_LIB.S9S_MB_2U(SCH_1):PAGE167

C730 Q_CAP_DIFFBUS_C0201-DIFF BUS_0A
     1 P5E_CPU1_PE0_TX_C_DN<5> @S9S_MB_2U_LIB.S9S_MB_2U(SCH_1):P5E_CPU1_PE0_TX_C_DN(5)   I248 @S9S_MB_2U_LIB.S9S_MB_2U(SCH_1):PAGE167
     2 P5E_CPU1_PE0_TX_DN<5> @S9S_MB_2U_LIB.S9S_MB_2U(SCH_1):P5E_CPU1_PE0_TX_DN(5)   I248 @S9S_MB_2U_LIB.S9S_MB_2U(SCH_1):PAGE167

C731 Q_CAP_DIFFBUS_C0201-DIFF BUS_0A
     1 P5E_CPU1_PE0_TX_C_DP<5> @S9S_MB_2U_LIB.S9S_MB_2U(SCH_1):P5E_CPU1_PE0_TX_C_DP(5)   I247 @S9S_MB_2U_LIB.S9S_MB_2U(SCH_1):PAGE167
     2 P5E_CPU1_PE0_TX_DP<5> @S9S_MB_2U_LIB.S9S_MB_2U(SCH_1):P5E_CPU1_PE0_TX_DP(5)   I247 @S9S_MB_2U_LIB.S9S_MB_2U(SCH_1):PAGE167

C732 Q_CAP_DIFFBUS_C0201-DIFF BUS_0A
     1 P5E_CPU1_PE0_TX_C_DN<4> @S9S_MB_2U_LIB.S9S_MB_2U(SCH_1):P5E_CPU1_PE0_TX_C_DN(4)   I246 @S9S_MB_2U_LIB.S9S_MB_2U(SCH_1):PAGE167
     2 P5E_CPU1_PE0_TX_DN<4> @S9S_MB_2U_LIB.S9S_MB_2U(SCH_1):P5E_CPU1_PE0_TX_DN(4)   I246 @S9S_MB_2U_LIB.S9S_MB_2U(SCH_1):PAGE167

C733 Q_CAP_DIFFBUS_C0201-DIFF BUS_0A
     1 P5E_CPU1_PE0_TX_C_DP<4> @S9S_MB_2U_LIB.S9S_MB_2U(SCH_1):P5E_CPU1_PE0_TX_C_DP(4)   I237 @S9S_MB_2U_LIB.S9S_MB_2U(SCH_1):PAGE167
     2 P5E_CPU1_PE0_TX_DP<4> @S9S_MB_2U_LIB.S9S_MB_2U(SCH_1):P5E_CPU1_PE0_TX_DP(4)   I237 @S9S_MB_2U_LIB.S9S_MB_2U(SCH_1):PAGE167

C734 Q_CAP_DIFFBUS_C0201-DIFF BUS_0A
     1 P5E_CPU1_PE0_TX_C_DN<3> @S9S_MB_2U_LIB.S9S_MB_2U(SCH_1):P5E_CPU1_PE0_TX_C_DN(3)   I235 @S9S_MB_2U_LIB.S9S_MB_2U(SCH_1):PAGE167
     2 P5E_CPU1_PE0_TX_DN<3> @S9S_MB_2U_LIB.S9S_MB_2U(SCH_1):P5E_CPU1_PE0_TX_DN(3)   I235 @S9S_MB_2U_LIB.S9S_MB_2U(SCH_1):PAGE167

C735 Q_CAP_DIFFBUS_C0201-DIFF BUS_0A
     1 P5E_CPU1_PE0_TX_C_DP<3> @S9S_MB_2U_LIB.S9S_MB_2U(SCH_1):P5E_CPU1_PE0_TX_C_DP(3)   I236 @S9S_MB_2U_LIB.S9S_MB_2U(SCH_1):PAGE167
     2 P5E_CPU1_PE0_TX_DP<3> @S9S_MB_2U_LIB.S9S_MB_2U(SCH_1):P5E_CPU1_PE0_TX_DP(3)   I236 @S9S_MB_2U_LIB.S9S_MB_2U(SCH_1):PAGE167

C736 Q_CAP_DIFFBUS_C0201-DIFF BUS_0A
     1 P5E_CPU1_PE0_TX_C_DN<2> @S9S_MB_2U_LIB.S9S_MB_2U(SCH_1):P5E_CPU1_PE0_TX_C_DN(2)   I234 @S9S_MB_2U_LIB.S9S_MB_2U(SCH_1):PAGE167
     2 P5E_CPU1_PE0_TX_DN<2> @S9S_MB_2U_LIB.S9S_MB_2U(SCH_1):P5E_CPU1_PE0_TX_DN(2)   I234 @S9S_MB_2U_LIB.S9S_MB_2U(SCH_1):PAGE167

C737 Q_CAP_DIFFBUS_C0201-DIFF BUS_0A
     1 P5E_CPU1_PE0_TX_C_DP<2> @S9S_MB_2U_LIB.S9S_MB_2U(SCH_1):P5E_CPU1_PE0_TX_C_DP(2)   I233 @S9S_MB_2U_LIB.S9S_MB_2U(SCH_1):PAGE167
     2 P5E_CPU1_PE0_TX_DP<2> @S9S_MB_2U_LIB.S9S_MB_2U(SCH_1):P5E_CPU1_PE0_TX_DP(2)   I233 @S9S_MB_2U_LIB.S9S_MB_2U(SCH_1):PAGE167

C738 Q_CAP_DIFFBUS_C0201-DIFF BUS_0A
     1 P5E_CPU1_PE0_TX_C_DN<1> @S9S_MB_2U_LIB.S9S_MB_2U(SCH_1):P5E_CPU1_PE0_TX_C_DN(1)   I232 @S9S_MB_2U_LIB.S9S_MB_2U(SCH_1):PAGE167
     2 P5E_CPU1_PE0_TX_DN<1> @S9S_MB_2U_LIB.S9S_MB_2U(SCH_1):P5E_CPU1_PE0_TX_DN(1)   I232 @S9S_MB_2U_LIB.S9S_MB_2U(SCH_1):PAGE167

C739 Q_CAP_DIFFBUS_C0201-DIFF BUS_0A
     1 P5E_CPU1_PE0_TX_C_DP<1> @S9S_MB_2U_LIB.S9S_MB_2U(SCH_1):P5E_CPU1_PE0_TX_C_DP(1)   I231 @S9S_MB_2U_LIB.S9S_MB_2U(SCH_1):PAGE167
     2 P5E_CPU1_PE0_TX_DP<1> @S9S_MB_2U_LIB.S9S_MB_2U(SCH_1):P5E_CPU1_PE0_TX_DP(1)   I231 @S9S_MB_2U_LIB.S9S_MB_2U(SCH_1):PAGE167

C740 Q_CAP_DIFFBUS_C0201-DIFF BUS_0A
     1 P5E_CPU1_PE0_TX_C_DN<0> @S9S_MB_2U_LIB.S9S_MB_2U(SCH_1):P5E_CPU1_PE0_TX_C_DN(0)   I229 @S9S_MB_2U_LIB.S9S_MB_2U(SCH_1):PAGE167
     2 P5E_CPU1_PE0_TX_DN<0> @S9S_MB_2U_LIB.S9S_MB_2U(SCH_1):P5E_CPU1_PE0_TX_DN(0)   I229 @S9S_MB_2U_LIB.S9S_MB_2U(SCH_1):PAGE167

C741 Q_CAP_DIFFBUS_C0201-DIFF BUS_0A
     1 P5E_CPU1_PE0_TX_C_DP<0> @S9S_MB_2U_LIB.S9S_MB_2U(SCH_1):P5E_CPU1_PE0_TX_C_DP(0)   I230 @S9S_MB_2U_LIB.S9S_MB_2U(SCH_1):PAGE167
     2 P5E_CPU1_PE0_TX_DP<0> @S9S_MB_2U_LIB.S9S_MB_2U(SCH_1):P5E_CPU1_PE0_TX_DP(0)   I230 @S9S_MB_2U_LIB.S9S_MB_2U(SCH_1):PAGE167

C742 Q_CAP_DIFFBUS_C0201-DIFF BUS_0A
     1 P5E_CPU1_PE2_TX_C_DN<15> @S9S_MB_2U_LIB.S9S_MB_2U(SCH_1):P5E_CPU1_PE2_TX_C_DN(15)   I172 @S9S_MB_2U_LIB.S9S_MB_2U(SCH_1):PAGE167
     2 P5E_CPU1_PE2_TX_DN<15> @S9S_MB_2U_LIB.S9S_MB_2U(SCH_1):P5E_CPU1_PE2_TX_DN(15)   I172 @S9S_MB_2U_LIB.S9S_MB_2U(SCH_1):PAGE167

C743 Q_CAP_DIFFBUS_C0201-DIFF BUS_0A
     1 P5E_CPU1_PE2_TX_C_DP<15> @S9S_MB_2U_LIB.S9S_MB_2U(SCH_1):P5E_CPU1_PE2_TX_C_DP(15)   I171 @S9S_MB_2U_LIB.S9S_MB_2U(SCH_1):PAGE167
     2 P5E_CPU1_PE2_TX_DP<15> @S9S_MB_2U_LIB.S9S_MB_2U(SCH_1):P5E_CPU1_PE2_TX_DP(15)   I171 @S9S_MB_2U_LIB.S9S_MB_2U(SCH_1):PAGE167

C744 Q_CAP_DIFFBUS_C0201-DIFF BUS_0A
     1 P5E_CPU1_PE2_TX_C_DN<14> @S9S_MB_2U_LIB.S9S_MB_2U(SCH_1):P5E_CPU1_PE2_TX_C_DN(14)   I170 @S9S_MB_2U_LIB.S9S_MB_2U(SCH_1):PAGE167
     2 P5E_CPU1_PE2_TX_DN<14> @S9S_MB_2U_LIB.S9S_MB_2U(SCH_1):P5E_CPU1_PE2_TX_DN(14)   I170 @S9S_MB_2U_LIB.S9S_MB_2U(SCH_1):PAGE167

C745 Q_CAP_DIFFBUS_C0201-DIFF BUS_0A
     1 P5E_CPU1_PE2_TX_C_DP<14> @S9S_MB_2U_LIB.S9S_MB_2U(SCH_1):P5E_CPU1_PE2_TX_C_DP(14)   I169 @S9S_MB_2U_LIB.S9S_MB_2U(SCH_1):PAGE167
     2 P5E_CPU1_PE2_TX_DP<14> @S9S_MB_2U_LIB.S9S_MB_2U(SCH_1):P5E_CPU1_PE2_TX_DP(14)   I169 @S9S_MB_2U_LIB.S9S_MB_2U(SCH_1):PAGE167

C746 Q_CAP_DIFFBUS_C0201-DIFF BUS_0A
     1 P5E_CPU1_PE2_TX_C_DN<13> @S9S_MB_2U_LIB.S9S_MB_2U(SCH_1):P5E_CPU1_PE2_TX_C_DN(13)   I168 @S9S_MB_2U_LIB.S9S_MB_2U(SCH_1):PAGE167
     2 P5E_CPU1_PE2_TX_DN<13> @S9S_MB_2U_LIB.S9S_MB_2U(SCH_1):P5E_CPU1_PE2_TX_DN(13)   I168 @S9S_MB_2U_LIB.S9S_MB_2U(SCH_1):PAGE167

C747 Q_CAP_DIFFBUS_C0201-DIFF BUS_0A
     1 P5E_CPU1_PE2_TX_C_DP<13> @S9S_MB_2U_LIB.S9S_MB_2U(SCH_1):P5E_CPU1_PE2_TX_C_DP(13)   I167 @S9S_MB_2U_LIB.S9S_MB_2U(SCH_1):PAGE167
     2 P5E_CPU1_PE2_TX_DP<13> @S9S_MB_2U_LIB.S9S_MB_2U(SCH_1):P5E_CPU1_PE2_TX_DP(13)   I167 @S9S_MB_2U_LIB.S9S_MB_2U(SCH_1):PAGE167

C748 Q_CAP_DIFFBUS_C0201-DIFF BUS_0A
     1 P5E_CPU1_PE2_TX_C_DN<12> @S9S_MB_2U_LIB.S9S_MB_2U(SCH_1):P5E_CPU1_PE2_TX_C_DN(12)   I163 @S9S_MB_2U_LIB.S9S_MB_2U(SCH_1):PAGE167
     2 P5E_CPU1_PE2_TX_DN<12> @S9S_MB_2U_LIB.S9S_MB_2U(SCH_1):P5E_CPU1_PE2_TX_DN(12)   I163 @S9S_MB_2U_LIB.S9S_MB_2U(SCH_1):PAGE167

C749 Q_CAP_DIFFBUS_C0201-DIFF BUS_0A
     1 P5E_CPU1_PE2_TX_C_DP<12> @S9S_MB_2U_LIB.S9S_MB_2U(SCH_1):P5E_CPU1_PE2_TX_C_DP(12)   I162 @S9S_MB_2U_LIB.S9S_MB_2U(SCH_1):PAGE167
     2 P5E_CPU1_PE2_TX_DP<12> @S9S_MB_2U_LIB.S9S_MB_2U(SCH_1):P5E_CPU1_PE2_TX_DP(12)   I162 @S9S_MB_2U_LIB.S9S_MB_2U(SCH_1):PAGE167

C750 Q_CAP_DIFFBUS_C0201-DIFF BUS_0A
     1 P5E_CPU1_PE2_TX_C_DN<11> @S9S_MB_2U_LIB.S9S_MB_2U(SCH_1):P5E_CPU1_PE2_TX_C_DN(11)   I160 @S9S_MB_2U_LIB.S9S_MB_2U(SCH_1):PAGE167
     2 P5E_CPU1_PE2_TX_DN<11> @S9S_MB_2U_LIB.S9S_MB_2U(SCH_1):P5E_CPU1_PE2_TX_DN(11)   I160 @S9S_MB_2U_LIB.S9S_MB_2U(SCH_1):PAGE167

C751 Q_CAP_DIFFBUS_C0201-DIFF BUS_0A
     1 P5E_CPU1_PE2_TX_C_DP<11> @S9S_MB_2U_LIB.S9S_MB_2U(SCH_1):P5E_CPU1_PE2_TX_C_DP(11)   I161 @S9S_MB_2U_LIB.S9S_MB_2U(SCH_1):PAGE167
     2 P5E_CPU1_PE2_TX_DP<11> @S9S_MB_2U_LIB.S9S_MB_2U(SCH_1):P5E_CPU1_PE2_TX_DP(11)   I161 @S9S_MB_2U_LIB.S9S_MB_2U(SCH_1):PAGE167

C752 Q_CAP_DIFFBUS_C0201-DIFF BUS_0A
     1 P5E_CPU1_PE2_TX_C_DN<10> @S9S_MB_2U_LIB.S9S_MB_2U(SCH_1):P5E_CPU1_PE2_TX_C_DN(10)   I159 @S9S_MB_2U_LIB.S9S_MB_2U(SCH_1):PAGE167
     2 P5E_CPU1_PE2_TX_DN<10> @S9S_MB_2U_LIB.S9S_MB_2U(SCH_1):P5E_CPU1_PE2_TX_DN(10)   I159 @S9S_MB_2U_LIB.S9S_MB_2U(SCH_1):PAGE167

C753 Q_CAP_DIFFBUS_C0201-DIFF BUS_0A
     1 P5E_CPU1_PE2_TX_C_DP<10> @S9S_MB_2U_LIB.S9S_MB_2U(SCH_1):P5E_CPU1_PE2_TX_C_DP(10)   I158 @S9S_MB_2U_LIB.S9S_MB_2U(SCH_1):PAGE167
     2 P5E_CPU1_PE2_TX_DP<10> @S9S_MB_2U_LIB.S9S_MB_2U(SCH_1):P5E_CPU1_PE2_TX_DP(10)   I158 @S9S_MB_2U_LIB.S9S_MB_2U(SCH_1):PAGE167

C754 Q_CAP_DIFFBUS_C0201-DIFF BUS_0A
     1 P5E_CPU1_PE2_TX_C_DN<9> @S9S_MB_2U_LIB.S9S_MB_2U(SCH_1):P5E_CPU1_PE2_TX_C_DN(9)   I157 @S9S_MB_2U_LIB.S9S_MB_2U(SCH_1):PAGE167
     2 P5E_CPU1_PE2_TX_DN<9> @S9S_MB_2U_LIB.S9S_MB_2U(SCH_1):P5E_CPU1_PE2_TX_DN(9)   I157 @S9S_MB_2U_LIB.S9S_MB_2U(SCH_1):PAGE167

C755 Q_CAP_DIFFBUS_C0201-DIFF BUS_0A
     1 P5E_CPU1_PE2_TX_C_DP<9> @S9S_MB_2U_LIB.S9S_MB_2U(SCH_1):P5E_CPU1_PE2_TX_C_DP(9)   I156 @S9S_MB_2U_LIB.S9S_MB_2U(SCH_1):PAGE167
     2 P5E_CPU1_PE2_TX_DP<9> @S9S_MB_2U_LIB.S9S_MB_2U(SCH_1):P5E_CPU1_PE2_TX_DP(9)   I156 @S9S_MB_2U_LIB.S9S_MB_2U(SCH_1):PAGE167

C756 Q_CAP_DIFFBUS_C0201-DIFF BUS_0A
     1 P5E_CPU1_PE2_TX_C_DN<8> @S9S_MB_2U_LIB.S9S_MB_2U(SCH_1):P5E_CPU1_PE2_TX_C_DN(8)   I154 @S9S_MB_2U_LIB.S9S_MB_2U(SCH_1):PAGE167
     2 P5E_CPU1_PE2_TX_DN<8> @S9S_MB_2U_LIB.S9S_MB_2U(SCH_1):P5E_CPU1_PE2_TX_DN(8)   I154 @S9S_MB_2U_LIB.S9S_MB_2U(SCH_1):PAGE167

C757 Q_CAP_DIFFBUS_C0201-DIFF BUS_0A
     1 P5E_CPU1_PE2_TX_C_DP<8> @S9S_MB_2U_LIB.S9S_MB_2U(SCH_1):P5E_CPU1_PE2_TX_C_DP(8)   I155 @S9S_MB_2U_LIB.S9S_MB_2U(SCH_1):PAGE167
     2 P5E_CPU1_PE2_TX_DP<8> @S9S_MB_2U_LIB.S9S_MB_2U(SCH_1):P5E_CPU1_PE2_TX_DP(8)   I155 @S9S_MB_2U_LIB.S9S_MB_2U(SCH_1):PAGE167

C758 Q_CAP_DIFFBUS_C0201-DIFF BUS_0A
     1 P5E_CPU1_PE2_TX_C_DN<7> @S9S_MB_2U_LIB.S9S_MB_2U(SCH_1):P5E_CPU1_PE2_TX_C_DN(7)   I140 @S9S_MB_2U_LIB.S9S_MB_2U(SCH_1):PAGE167
     2 P5E_CPU1_PE2_TX_DN<7> @S9S_MB_2U_LIB.S9S_MB_2U(SCH_1):P5E_CPU1_PE2_TX_DN(7)   I140 @S9S_MB_2U_LIB.S9S_MB_2U(SCH_1):PAGE167

C759 Q_CAP_DIFFBUS_C0201-DIFF BUS_0A
     1 P5E_CPU1_PE2_TX_C_DP<7> @S9S_MB_2U_LIB.S9S_MB_2U(SCH_1):P5E_CPU1_PE2_TX_C_DP(7)   I139 @S9S_MB_2U_LIB.S9S_MB_2U(SCH_1):PAGE167
     2 P5E_CPU1_PE2_TX_DP<7> @S9S_MB_2U_LIB.S9S_MB_2U(SCH_1):P5E_CPU1_PE2_TX_DP(7)   I139 @S9S_MB_2U_LIB.S9S_MB_2U(SCH_1):PAGE167

C760 Q_CAP_DIFFBUS_C0201-DIFF BUS_0A
     1 P5E_CPU1_PE2_TX_C_DN<6> @S9S_MB_2U_LIB.S9S_MB_2U(SCH_1):P5E_CPU1_PE2_TX_C_DN(6)   I138 @S9S_MB_2U_LIB.S9S_MB_2U(SCH_1):PAGE167
     2 P5E_CPU1_PE2_TX_DN<6> @S9S_MB_2U_LIB.S9S_MB_2U(SCH_1):P5E_CPU1_PE2_TX_DN(6)   I138 @S9S_MB_2U_LIB.S9S_MB_2U(SCH_1):PAGE167

C761 Q_CAP_DIFFBUS_C0201-DIFF BUS_0A
     1 P5E_CPU1_PE2_TX_C_DP<6> @S9S_MB_2U_LIB.S9S_MB_2U(SCH_1):P5E_CPU1_PE2_TX_C_DP(6)   I137 @S9S_MB_2U_LIB.S9S_MB_2U(SCH_1):PAGE167
     2 P5E_CPU1_PE2_TX_DP<6> @S9S_MB_2U_LIB.S9S_MB_2U(SCH_1):P5E_CPU1_PE2_TX_DP(6)   I137 @S9S_MB_2U_LIB.S9S_MB_2U(SCH_1):PAGE167

C762 Q_CAP_DIFFBUS_C0201-DIFF BUS_0A
     1 P5E_CPU1_PE2_TX_C_DN<5> @S9S_MB_2U_LIB.S9S_MB_2U(SCH_1):P5E_CPU1_PE2_TX_C_DN(5)   I136 @S9S_MB_2U_LIB.S9S_MB_2U(SCH_1):PAGE167
     2 P5E_CPU1_PE2_TX_DN<5> @S9S_MB_2U_LIB.S9S_MB_2U(SCH_1):P5E_CPU1_PE2_TX_DN(5)   I136 @S9S_MB_2U_LIB.S9S_MB_2U(SCH_1):PAGE167

C763 Q_CAP_DIFFBUS_C0201-DIFF BUS_0A
     1 P5E_CPU1_PE2_TX_C_DP<5> @S9S_MB_2U_LIB.S9S_MB_2U(SCH_1):P5E_CPU1_PE2_TX_C_DP(5)   I135 @S9S_MB_2U_LIB.S9S_MB_2U(SCH_1):PAGE167
     2 P5E_CPU1_PE2_TX_DP<5> @S9S_MB_2U_LIB.S9S_MB_2U(SCH_1):P5E_CPU1_PE2_TX_DP(5)   I135 @S9S_MB_2U_LIB.S9S_MB_2U(SCH_1):PAGE167

C764 Q_CAP_DIFFBUS_C0201-DIFF BUS_0A
     1 P5E_CPU1_PE2_TX_C_DN<4> @S9S_MB_2U_LIB.S9S_MB_2U(SCH_1):P5E_CPU1_PE2_TX_C_DN(4)   I130 @S9S_MB_2U_LIB.S9S_MB_2U(SCH_1):PAGE167
     2 P5E_CPU1_PE2_TX_DN<4> @S9S_MB_2U_LIB.S9S_MB_2U(SCH_1):P5E_CPU1_PE2_TX_DN(4)   I130 @S9S_MB_2U_LIB.S9S_MB_2U(SCH_1):PAGE167

C765 Q_CAP_DIFFBUS_C0201-DIFF BUS_0A
     1 P5E_CPU1_PE2_TX_C_DP<4> @S9S_MB_2U_LIB.S9S_MB_2U(SCH_1):P5E_CPU1_PE2_TX_C_DP(4)   I131 @S9S_MB_2U_LIB.S9S_MB_2U(SCH_1):PAGE167
     2 P5E_CPU1_PE2_TX_DP<4> @S9S_MB_2U_LIB.S9S_MB_2U(SCH_1):P5E_CPU1_PE2_TX_DP(4)   I131 @S9S_MB_2U_LIB.S9S_MB_2U(SCH_1):PAGE167

C766 Q_CAP_DIFFBUS_C0201-DIFF BUS_0A
     1 P5E_CPU1_PE2_TX_C_DN<3> @S9S_MB_2U_LIB.S9S_MB_2U(SCH_1):P5E_CPU1_PE2_TX_C_DN(3)   I129 @S9S_MB_2U_LIB.S9S_MB_2U(SCH_1):PAGE167
     2 P5E_CPU1_PE2_TX_DN<3> @S9S_MB_2U_LIB.S9S_MB_2U(SCH_1):P5E_CPU1_PE2_TX_DN(3)   I129 @S9S_MB_2U_LIB.S9S_MB_2U(SCH_1):PAGE167

C767 Q_CAP_DIFFBUS_C0201-DIFF BUS_0A
     1 P5E_CPU1_PE2_TX_C_DP<3> @S9S_MB_2U_LIB.S9S_MB_2U(SCH_1):P5E_CPU1_PE2_TX_C_DP(3)   I128 @S9S_MB_2U_LIB.S9S_MB_2U(SCH_1):PAGE167
     2 P5E_CPU1_PE2_TX_DP<3> @S9S_MB_2U_LIB.S9S_MB_2U(SCH_1):P5E_CPU1_PE2_TX_DP(3)   I128 @S9S_MB_2U_LIB.S9S_MB_2U(SCH_1):PAGE167

C768 Q_CAP_DIFFBUS_C0201-DIFF BUS_0A
     1 P5E_CPU1_PE2_TX_C_DN<2> @S9S_MB_2U_LIB.S9S_MB_2U(SCH_1):P5E_CPU1_PE2_TX_C_DN(2)   I127 @S9S_MB_2U_LIB.S9S_MB_2U(SCH_1):PAGE167
     2 P5E_CPU1_PE2_TX_DN<2> @S9S_MB_2U_LIB.S9S_MB_2U(SCH_1):P5E_CPU1_PE2_TX_DN(2)   I127 @S9S_MB_2U_LIB.S9S_MB_2U(SCH_1):PAGE167

C769 Q_CAP_DIFFBUS_C0201-DIFF BUS_0A
     1 P5E_CPU1_PE2_TX_C_DP<2> @S9S_MB_2U_LIB.S9S_MB_2U(SCH_1):P5E_CPU1_PE2_TX_C_DP(2)   I126 @S9S_MB_2U_LIB.S9S_MB_2U(SCH_1):PAGE167
     2 P5E_CPU1_PE2_TX_DP<2> @S9S_MB_2U_LIB.S9S_MB_2U(SCH_1):P5E_CPU1_PE2_TX_DP(2)   I126 @S9S_MB_2U_LIB.S9S_MB_2U(SCH_1):PAGE167

C770 Q_CAP_DIFFBUS_C0201-DIFF BUS_0A
     1 P5E_CPU1_PE2_TX_C_DN<1> @S9S_MB_2U_LIB.S9S_MB_2U(SCH_1):P5E_CPU1_PE2_TX_C_DN(1)   I125 @S9S_MB_2U_LIB.S9S_MB_2U(SCH_1):PAGE167
     2 P5E_CPU1_PE2_TX_DN<1> @S9S_MB_2U_LIB.S9S_MB_2U(SCH_1):P5E_CPU1_PE2_TX_DN(1)   I125 @S9S_MB_2U_LIB.S9S_MB_2U(SCH_1):PAGE167

C771 Q_CAP_DIFFBUS_C0201-DIFF BUS_0A
     1 P5E_CPU1_PE2_TX_C_DP<1> @S9S_MB_2U_LIB.S9S_MB_2U(SCH_1):P5E_CPU1_PE2_TX_C_DP(1)   I124 @S9S_MB_2U_LIB.S9S_MB_2U(SCH_1):PAGE167
     2 P5E_CPU1_PE2_TX_DP<1> @S9S_MB_2U_LIB.S9S_MB_2U(SCH_1):P5E_CPU1_PE2_TX_DP(1)   I124 @S9S_MB_2U_LIB.S9S_MB_2U(SCH_1):PAGE167

C772 Q_CAP_DIFFBUS_C0201-DIFF BUS_0A
     1 P5E_CPU1_PE2_TX_C_DN<0> @S9S_MB_2U_LIB.S9S_MB_2U(SCH_1):P5E_CPU1_PE2_TX_C_DN(0)   I123 @S9S_MB_2U_LIB.S9S_MB_2U(SCH_1):PAGE167
     2 P5E_CPU1_PE2_TX_DN<0> @S9S_MB_2U_LIB.S9S_MB_2U(SCH_1):P5E_CPU1_PE2_TX_DN(0)   I123 @S9S_MB_2U_LIB.S9S_MB_2U(SCH_1):PAGE167

C773 Q_CAP_DIFFBUS_C0201-DIFF BUS_0A
     1 P5E_CPU1_PE2_TX_C_DP<0> @S9S_MB_2U_LIB.S9S_MB_2U(SCH_1):P5E_CPU1_PE2_TX_C_DP(0)   I122 @S9S_MB_2U_LIB.S9S_MB_2U(SCH_1):PAGE167
     2 P5E_CPU1_PE2_TX_DP<0> @S9S_MB_2U_LIB.S9S_MB_2U(SCH_1):P5E_CPU1_PE2_TX_DP(0)   I122 @S9S_MB_2U_LIB.S9S_MB_2U(SCH_1):PAGE167

C806 Q_CAP_DIFFBUS_C0201-DIFF BUS_0A
     1 P5E_CPU1_PE1_TX_C_DN<15> @S9S_MB_2U_LIB.S9S_MB_2U(SCH_1):P5E_CPU1_PE1_TX_C_DN(15)   I377 @S9S_MB_2U_LIB.S9S_MB_2U(SCH_1):PAGE166
     2 P5E_CPU1_PE1_TX_DN<15> @S9S_MB_2U_LIB.S9S_MB_2U(SCH_1):P5E_CPU1_PE1_TX_DN(15)   I377 @S9S_MB_2U_LIB.S9S_MB_2U(SCH_1):PAGE166

C807 Q_CAP_DIFFBUS_C0201-DIFF BUS_0A
     1 P5E_CPU1_PE1_TX_C_DP<15> @S9S_MB_2U_LIB.S9S_MB_2U(SCH_1):P5E_CPU1_PE1_TX_C_DP(15)   I378 @S9S_MB_2U_LIB.S9S_MB_2U(SCH_1):PAGE166
     2 P5E_CPU1_PE1_TX_DP<15> @S9S_MB_2U_LIB.S9S_MB_2U(SCH_1):P5E_CPU1_PE1_TX_DP(15)   I378 @S9S_MB_2U_LIB.S9S_MB_2U(SCH_1):PAGE166

C808 Q_CAP_DIFFBUS_C0201-DIFF BUS_0A
     1 P5E_CPU1_PE1_TX_C_DN<14> @S9S_MB_2U_LIB.S9S_MB_2U(SCH_1):P5E_CPU1_PE1_TX_C_DN(14)   I376 @S9S_MB_2U_LIB.S9S_MB_2U(SCH_1):PAGE166
     2 P5E_CPU1_PE1_TX_DN<14> @S9S_MB_2U_LIB.S9S_MB_2U(SCH_1):P5E_CPU1_PE1_TX_DN(14)   I376 @S9S_MB_2U_LIB.S9S_MB_2U(SCH_1):PAGE166

C809 Q_CAP_DIFFBUS_C0201-DIFF BUS_0A
     1 P5E_CPU1_PE1_TX_C_DP<14> @S9S_MB_2U_LIB.S9S_MB_2U(SCH_1):P5E_CPU1_PE1_TX_C_DP(14)   I375 @S9S_MB_2U_LIB.S9S_MB_2U(SCH_1):PAGE166
     2 P5E_CPU1_PE1_TX_DP<14> @S9S_MB_2U_LIB.S9S_MB_2U(SCH_1):P5E_CPU1_PE1_TX_DP(14)   I375 @S9S_MB_2U_LIB.S9S_MB_2U(SCH_1):PAGE166

C810 Q_CAP_DIFFBUS_C0201-DIFF BUS_0A
     1 P5E_CPU1_PE1_TX_C_DN<13> @S9S_MB_2U_LIB.S9S_MB_2U(SCH_1):P5E_CPU1_PE1_TX_C_DN(13)   I374 @S9S_MB_2U_LIB.S9S_MB_2U(SCH_1):PAGE166
     2 P5E_CPU1_PE1_TX_DN<13> @S9S_MB_2U_LIB.S9S_MB_2U(SCH_1):P5E_CPU1_PE1_TX_DN(13)   I374 @S9S_MB_2U_LIB.S9S_MB_2U(SCH_1):PAGE166

C811 Q_CAP_DIFFBUS_C0201-DIFF BUS_0A
     1 P5E_CPU1_PE1_TX_C_DP<13> @S9S_MB_2U_LIB.S9S_MB_2U(SCH_1):P5E_CPU1_PE1_TX_C_DP(13)   I373 @S9S_MB_2U_LIB.S9S_MB_2U(SCH_1):PAGE166
     2 P5E_CPU1_PE1_TX_DP<13> @S9S_MB_2U_LIB.S9S_MB_2U(SCH_1):P5E_CPU1_PE1_TX_DP(13)   I373 @S9S_MB_2U_LIB.S9S_MB_2U(SCH_1):PAGE166

C812 Q_CAP_DIFFBUS_C0201-DIFF BUS_0A
     1 P5E_CPU1_PE1_TX_C_DN<12> @S9S_MB_2U_LIB.S9S_MB_2U(SCH_1):P5E_CPU1_PE1_TX_C_DN(12)   I371 @S9S_MB_2U_LIB.S9S_MB_2U(SCH_1):PAGE166
     2 P5E_CPU1_PE1_TX_DN<12> @S9S_MB_2U_LIB.S9S_MB_2U(SCH_1):P5E_CPU1_PE1_TX_DN(12)   I371 @S9S_MB_2U_LIB.S9S_MB_2U(SCH_1):PAGE166

C813 Q_CAP_DIFFBUS_C0201-DIFF BUS_0A
     1 P5E_CPU1_PE1_TX_C_DP<12> @S9S_MB_2U_LIB.S9S_MB_2U(SCH_1):P5E_CPU1_PE1_TX_C_DP(12)   I372 @S9S_MB_2U_LIB.S9S_MB_2U(SCH_1):PAGE166
     2 P5E_CPU1_PE1_TX_DP<12> @S9S_MB_2U_LIB.S9S_MB_2U(SCH_1):P5E_CPU1_PE1_TX_DP(12)   I372 @S9S_MB_2U_LIB.S9S_MB_2U(SCH_1):PAGE166

C814 Q_CAP_DIFFBUS_C0201-DIFF BUS_0A
     1 P5E_CPU1_PE1_TX_C_DN<11> @S9S_MB_2U_LIB.S9S_MB_2U(SCH_1):P5E_CPU1_PE1_TX_C_DN(11)   I370 @S9S_MB_2U_LIB.S9S_MB_2U(SCH_1):PAGE166
     2 P5E_CPU1_PE1_TX_DN<11> @S9S_MB_2U_LIB.S9S_MB_2U(SCH_1):P5E_CPU1_PE1_TX_DN(11)   I370 @S9S_MB_2U_LIB.S9S_MB_2U(SCH_1):PAGE166

C815 Q_CAP_DIFFBUS_C0201-DIFF BUS_0A
     1 P5E_CPU1_PE1_TX_C_DP<11> @S9S_MB_2U_LIB.S9S_MB_2U(SCH_1):P5E_CPU1_PE1_TX_C_DP(11)   I369 @S9S_MB_2U_LIB.S9S_MB_2U(SCH_1):PAGE166
     2 P5E_CPU1_PE1_TX_DP<11> @S9S_MB_2U_LIB.S9S_MB_2U(SCH_1):P5E_CPU1_PE1_TX_DP(11)   I369 @S9S_MB_2U_LIB.S9S_MB_2U(SCH_1):PAGE166

C816 Q_CAP_DIFFBUS_C0201-DIFF BUS_0A
     1 P5E_CPU1_PE1_TX_C_DN<10> @S9S_MB_2U_LIB.S9S_MB_2U(SCH_1):P5E_CPU1_PE1_TX_C_DN(10)   I368 @S9S_MB_2U_LIB.S9S_MB_2U(SCH_1):PAGE166
     2 P5E_CPU1_PE1_TX_DN<10> @S9S_MB_2U_LIB.S9S_MB_2U(SCH_1):P5E_CPU1_PE1_TX_DN(10)   I368 @S9S_MB_2U_LIB.S9S_MB_2U(SCH_1):PAGE166

C817 Q_CAP_DIFFBUS_C0201-DIFF BUS_0A
     1 P5E_CPU1_PE1_TX_C_DP<10> @S9S_MB_2U_LIB.S9S_MB_2U(SCH_1):P5E_CPU1_PE1_TX_C_DP(10)   I367 @S9S_MB_2U_LIB.S9S_MB_2U(SCH_1):PAGE166
     2 P5E_CPU1_PE1_TX_DP<10> @S9S_MB_2U_LIB.S9S_MB_2U(SCH_1):P5E_CPU1_PE1_TX_DP(10)   I367 @S9S_MB_2U_LIB.S9S_MB_2U(SCH_1):PAGE166

C818 Q_CAP_DIFFBUS_C0201-DIFF BUS_0A
     1 P5E_CPU1_PE1_TX_C_DN<9> @S9S_MB_2U_LIB.S9S_MB_2U(SCH_1):P5E_CPU1_PE1_TX_C_DN(9)   I365 @S9S_MB_2U_LIB.S9S_MB_2U(SCH_1):PAGE166
     2 P5E_CPU1_PE1_TX_DN<9> @S9S_MB_2U_LIB.S9S_MB_2U(SCH_1):P5E_CPU1_PE1_TX_DN(9)   I365 @S9S_MB_2U_LIB.S9S_MB_2U(SCH_1):PAGE166

C819 Q_CAP_DIFFBUS_C0201-DIFF BUS_0A
     1 P5E_CPU1_PE1_TX_C_DP<9> @S9S_MB_2U_LIB.S9S_MB_2U(SCH_1):P5E_CPU1_PE1_TX_C_DP(9)   I366 @S9S_MB_2U_LIB.S9S_MB_2U(SCH_1):PAGE166
     2 P5E_CPU1_PE1_TX_DP<9> @S9S_MB_2U_LIB.S9S_MB_2U(SCH_1):P5E_CPU1_PE1_TX_DP(9)   I366 @S9S_MB_2U_LIB.S9S_MB_2U(SCH_1):PAGE166

C820 Q_CAP_DIFFBUS_C0201-DIFF BUS_0A
     1 P5E_CPU1_PE1_TX_C_DN<8> @S9S_MB_2U_LIB.S9S_MB_2U(SCH_1):P5E_CPU1_PE1_TX_C_DN(8)   I363 @S9S_MB_2U_LIB.S9S_MB_2U(SCH_1):PAGE166
     2 P5E_CPU1_PE1_TX_DN<8> @S9S_MB_2U_LIB.S9S_MB_2U(SCH_1):P5E_CPU1_PE1_TX_DN(8)   I363 @S9S_MB_2U_LIB.S9S_MB_2U(SCH_1):PAGE166

C821 Q_CAP_DIFFBUS_C0201-DIFF BUS_0A
     1 P5E_CPU1_PE1_TX_C_DP<8> @S9S_MB_2U_LIB.S9S_MB_2U(SCH_1):P5E_CPU1_PE1_TX_C_DP(8)   I364 @S9S_MB_2U_LIB.S9S_MB_2U(SCH_1):PAGE166
     2 P5E_CPU1_PE1_TX_DP<8> @S9S_MB_2U_LIB.S9S_MB_2U(SCH_1):P5E_CPU1_PE1_TX_DP(8)   I364 @S9S_MB_2U_LIB.S9S_MB_2U(SCH_1):PAGE166

C822 Q_CAP_DIFFBUS_C0201-DIFF BUS_0A
     1 P5E_CPU1_PE1_TX_C_DN<7> @S9S_MB_2U_LIB.S9S_MB_2U(SCH_1):P5E_CPU1_PE1_TX_C_DN(7)   I345 @S9S_MB_2U_LIB.S9S_MB_2U(SCH_1):PAGE166
     2 P5E_CPU1_PE1_TX_DN<7> @S9S_MB_2U_LIB.S9S_MB_2U(SCH_1):P5E_CPU1_PE1_TX_DN(7)   I345 @S9S_MB_2U_LIB.S9S_MB_2U(SCH_1):PAGE166

C823 Q_CAP_DIFFBUS_C0201-DIFF BUS_0A
     1 P5E_CPU1_PE1_TX_C_DP<7> @S9S_MB_2U_LIB.S9S_MB_2U(SCH_1):P5E_CPU1_PE1_TX_C_DP(7)   I346 @S9S_MB_2U_LIB.S9S_MB_2U(SCH_1):PAGE166
     2 P5E_CPU1_PE1_TX_DP<7> @S9S_MB_2U_LIB.S9S_MB_2U(SCH_1):P5E_CPU1_PE1_TX_DP(7)   I346 @S9S_MB_2U_LIB.S9S_MB_2U(SCH_1):PAGE166

C824 Q_CAP_DIFFBUS_C0201-DIFF BUS_0A
     1 P5E_CPU1_PE1_TX_C_DN<6> @S9S_MB_2U_LIB.S9S_MB_2U(SCH_1):P5E_CPU1_PE1_TX_C_DN(6)   I416 @S9S_MB_2U_LIB.S9S_MB_2U(SCH_1):PAGE166
     2 P5E_CPU1_PE1_TX_DN<6> @S9S_MB_2U_LIB.S9S_MB_2U(SCH_1):P5E_CPU1_PE1_TX_DN(6)   I416 @S9S_MB_2U_LIB.S9S_MB_2U(SCH_1):PAGE166

C825 Q_CAP_DIFFBUS_C0201-DIFF BUS_0A
     1 P5E_CPU1_PE1_TX_C_DP<6> @S9S_MB_2U_LIB.S9S_MB_2U(SCH_1):P5E_CPU1_PE1_TX_C_DP(6)   I415 @S9S_MB_2U_LIB.S9S_MB_2U(SCH_1):PAGE166
     2 P5E_CPU1_PE1_TX_DP<6> @S9S_MB_2U_LIB.S9S_MB_2U(SCH_1):P5E_CPU1_PE1_TX_DP(6)   I415 @S9S_MB_2U_LIB.S9S_MB_2U(SCH_1):PAGE166

C826 Q_CAP_DIFFBUS_C0201-DIFF BUS_0A
     1 P5E_CPU1_PE1_TX_C_DN<5> @S9S_MB_2U_LIB.S9S_MB_2U(SCH_1):P5E_CPU1_PE1_TX_C_DN(5)   I344 @S9S_MB_2U_LIB.S9S_MB_2U(SCH_1):PAGE166
     2 P5E_CPU1_PE1_TX_DN<5> @S9S_MB_2U_LIB.S9S_MB_2U(SCH_1):P5E_CPU1_PE1_TX_DN(5)   I344 @S9S_MB_2U_LIB.S9S_MB_2U(SCH_1):PAGE166

C827 Q_CAP_DIFFBUS_C0201-DIFF BUS_0A
     1 P5E_CPU1_PE1_TX_C_DP<5> @S9S_MB_2U_LIB.S9S_MB_2U(SCH_1):P5E_CPU1_PE1_TX_C_DP(5)   I343 @S9S_MB_2U_LIB.S9S_MB_2U(SCH_1):PAGE166
     2 P5E_CPU1_PE1_TX_DP<5> @S9S_MB_2U_LIB.S9S_MB_2U(SCH_1):P5E_CPU1_PE1_TX_DP(5)   I343 @S9S_MB_2U_LIB.S9S_MB_2U(SCH_1):PAGE166

C828 Q_CAP_DIFFBUS_C0201-DIFF BUS_0A
     1 P5E_CPU1_PE1_TX_C_DN<4> @S9S_MB_2U_LIB.S9S_MB_2U(SCH_1):P5E_CPU1_PE1_TX_C_DN(4)   I340 @S9S_MB_2U_LIB.S9S_MB_2U(SCH_1):PAGE166
     2 P5E_CPU1_PE1_TX_DN<4> @S9S_MB_2U_LIB.S9S_MB_2U(SCH_1):P5E_CPU1_PE1_TX_DN(4)   I340 @S9S_MB_2U_LIB.S9S_MB_2U(SCH_1):PAGE166

C829 Q_CAP_DIFFBUS_C0201-DIFF BUS_0A
     1 P5E_CPU1_PE1_TX_C_DP<4> @S9S_MB_2U_LIB.S9S_MB_2U(SCH_1):P5E_CPU1_PE1_TX_C_DP(4)   I342 @S9S_MB_2U_LIB.S9S_MB_2U(SCH_1):PAGE166
     2 P5E_CPU1_PE1_TX_DP<4> @S9S_MB_2U_LIB.S9S_MB_2U(SCH_1):P5E_CPU1_PE1_TX_DP(4)   I342 @S9S_MB_2U_LIB.S9S_MB_2U(SCH_1):PAGE166

C830 Q_CAP_DIFFBUS_C0201-DIFF BUS_0A
     1 P5E_CPU1_PE1_TX_C_DN<3> @S9S_MB_2U_LIB.S9S_MB_2U(SCH_1):P5E_CPU1_PE1_TX_C_DN(3)   I341 @S9S_MB_2U_LIB.S9S_MB_2U(SCH_1):PAGE166
     2 P5E_CPU1_PE1_TX_DN<3> @S9S_MB_2U_LIB.S9S_MB_2U(SCH_1):P5E_CPU1_PE1_TX_DN(3)   I341 @S9S_MB_2U_LIB.S9S_MB_2U(SCH_1):PAGE166

C831 Q_CAP_DIFFBUS_C0201-DIFF BUS_0A
     1 P5E_CPU1_PE1_TX_C_DP<3> @S9S_MB_2U_LIB.S9S_MB_2U(SCH_1):P5E_CPU1_PE1_TX_C_DP(3)   I337 @S9S_MB_2U_LIB.S9S_MB_2U(SCH_1):PAGE166
     2 P5E_CPU1_PE1_TX_DP<3> @S9S_MB_2U_LIB.S9S_MB_2U(SCH_1):P5E_CPU1_PE1_TX_DP(3)   I337 @S9S_MB_2U_LIB.S9S_MB_2U(SCH_1):PAGE166

C832 Q_CAP_DIFFBUS_C0201-DIFF BUS_0A
     1 P5E_CPU1_PE1_TX_C_DN<2> @S9S_MB_2U_LIB.S9S_MB_2U(SCH_1):P5E_CPU1_PE1_TX_C_DN(2)   I338 @S9S_MB_2U_LIB.S9S_MB_2U(SCH_1):PAGE166
     2 P5E_CPU1_PE1_TX_DN<2> @S9S_MB_2U_LIB.S9S_MB_2U(SCH_1):P5E_CPU1_PE1_TX_DN(2)   I338 @S9S_MB_2U_LIB.S9S_MB_2U(SCH_1):PAGE166

C833 Q_CAP_DIFFBUS_C0201-DIFF BUS_0A
     1 P5E_CPU1_PE1_TX_C_DP<2> @S9S_MB_2U_LIB.S9S_MB_2U(SCH_1):P5E_CPU1_PE1_TX_C_DP(2)   I339 @S9S_MB_2U_LIB.S9S_MB_2U(SCH_1):PAGE166
     2 P5E_CPU1_PE1_TX_DP<2> @S9S_MB_2U_LIB.S9S_MB_2U(SCH_1):P5E_CPU1_PE1_TX_DP(2)   I339 @S9S_MB_2U_LIB.S9S_MB_2U(SCH_1):PAGE166

C834 Q_CAP_DIFFBUS_C0201-DIFF BUS_0A
     1 P5E_CPU1_PE1_TX_C_DN<1> @S9S_MB_2U_LIB.S9S_MB_2U(SCH_1):P5E_CPU1_PE1_TX_C_DN(1)   I335 @S9S_MB_2U_LIB.S9S_MB_2U(SCH_1):PAGE166
     2 P5E_CPU1_PE1_TX_DN<1> @S9S_MB_2U_LIB.S9S_MB_2U(SCH_1):P5E_CPU1_PE1_TX_DN(1)   I335 @S9S_MB_2U_LIB.S9S_MB_2U(SCH_1):PAGE166

C835 Q_CAP_DIFFBUS_C0201-DIFF BUS_0A
     1 P5E_CPU1_PE1_TX_C_DP<1> @S9S_MB_2U_LIB.S9S_MB_2U(SCH_1):P5E_CPU1_PE1_TX_C_DP(1)   I336 @S9S_MB_2U_LIB.S9S_MB_2U(SCH_1):PAGE166
     2 P5E_CPU1_PE1_TX_DP<1> @S9S_MB_2U_LIB.S9S_MB_2U(SCH_1):P5E_CPU1_PE1_TX_DP(1)   I336 @S9S_MB_2U_LIB.S9S_MB_2U(SCH_1):PAGE166

C836 Q_CAP_DIFFBUS_C0201-DIFF BUS_0A
     1 P5E_CPU1_PE1_TX_C_DN<0> @S9S_MB_2U_LIB.S9S_MB_2U(SCH_1):P5E_CPU1_PE1_TX_C_DN(0)   I333 @S9S_MB_2U_LIB.S9S_MB_2U(SCH_1):PAGE166
     2 P5E_CPU1_PE1_TX_DN<0> @S9S_MB_2U_LIB.S9S_MB_2U(SCH_1):P5E_CPU1_PE1_TX_DN(0)   I333 @S9S_MB_2U_LIB.S9S_MB_2U(SCH_1):PAGE166

C837 Q_CAP_DIFFBUS_C0201-DIFF BUS_0A
     1 P5E_CPU1_PE1_TX_C_DP<0> @S9S_MB_2U_LIB.S9S_MB_2U(SCH_1):P5E_CPU1_PE1_TX_C_DP(0)   I334 @S9S_MB_2U_LIB.S9S_MB_2U(SCH_1):PAGE166
     2 P5E_CPU1_PE1_TX_DP<0> @S9S_MB_2U_LIB.S9S_MB_2U(SCH_1):P5E_CPU1_PE1_TX_DP(0)   I334 @S9S_MB_2U_LIB.S9S_MB_2U(SCH_1):PAGE166

C838 Q_CAP_DIFFBUS_C0201-DIFF BUS_0A
     1 P5E_CPU0_PE1_TX_C_DN<15> @S9S_MB_2U_LIB.S9S_MB_2U(SCH_1):P5E_CPU0_PE1_TX_C_DN(15)    I80 @S9S_MB_2U_LIB.S9S_MB_2U(SCH_1):PAGE165
     2 P5E_CPU0_PE1_TX_DN<15> @S9S_MB_2U_LIB.S9S_MB_2U(SCH_1):P5E_CPU0_PE1_TX_DN(15)    I80 @S9S_MB_2U_LIB.S9S_MB_2U(SCH_1):PAGE165

C839 Q_CAP_DIFFBUS_C0201-DIFF BUS_0A
     1 P5E_CPU0_PE1_TX_C_DP<15> @S9S_MB_2U_LIB.S9S_MB_2U(SCH_1):P5E_CPU0_PE1_TX_C_DP(15)    I81 @S9S_MB_2U_LIB.S9S_MB_2U(SCH_1):PAGE165
     2 P5E_CPU0_PE1_TX_DP<15> @S9S_MB_2U_LIB.S9S_MB_2U(SCH_1):P5E_CPU0_PE1_TX_DP(15)    I81 @S9S_MB_2U_LIB.S9S_MB_2U(SCH_1):PAGE165

C840 Q_CAP_DIFFBUS_C0201-DIFF BUS_0A
     1 P5E_CPU0_PE1_TX_C_DN<14> @S9S_MB_2U_LIB.S9S_MB_2U(SCH_1):P5E_CPU0_PE1_TX_C_DN(14)    I79 @S9S_MB_2U_LIB.S9S_MB_2U(SCH_1):PAGE165
     2 P5E_CPU0_PE1_TX_DN<14> @S9S_MB_2U_LIB.S9S_MB_2U(SCH_1):P5E_CPU0_PE1_TX_DN(14)    I79 @S9S_MB_2U_LIB.S9S_MB_2U(SCH_1):PAGE165

C841 Q_CAP_DIFFBUS_C0201-DIFF BUS_0A
     1 P5E_CPU0_PE1_TX_C_DP<14> @S9S_MB_2U_LIB.S9S_MB_2U(SCH_1):P5E_CPU0_PE1_TX_C_DP(14)    I78 @S9S_MB_2U_LIB.S9S_MB_2U(SCH_1):PAGE165
     2 P5E_CPU0_PE1_TX_DP<14> @S9S_MB_2U_LIB.S9S_MB_2U(SCH_1):P5E_CPU0_PE1_TX_DP(14)    I78 @S9S_MB_2U_LIB.S9S_MB_2U(SCH_1):PAGE165

C842 Q_CAP_DIFFBUS_C0201-DIFF BUS_0A
     1 P5E_CPU0_PE1_TX_C_DN<13> @S9S_MB_2U_LIB.S9S_MB_2U(SCH_1):P5E_CPU0_PE1_TX_C_DN(13)    I76 @S9S_MB_2U_LIB.S9S_MB_2U(SCH_1):PAGE165
     2 P5E_CPU0_PE1_TX_DN<13> @S9S_MB_2U_LIB.S9S_MB_2U(SCH_1):P5E_CPU0_PE1_TX_DN(13)    I76 @S9S_MB_2U_LIB.S9S_MB_2U(SCH_1):PAGE165

C843 Q_CAP_DIFFBUS_C0201-DIFF BUS_0A
     1 P5E_CPU0_PE1_TX_C_DP<13> @S9S_MB_2U_LIB.S9S_MB_2U(SCH_1):P5E_CPU0_PE1_TX_C_DP(13)    I77 @S9S_MB_2U_LIB.S9S_MB_2U(SCH_1):PAGE165
     2 P5E_CPU0_PE1_TX_DP<13> @S9S_MB_2U_LIB.S9S_MB_2U(SCH_1):P5E_CPU0_PE1_TX_DP(13)    I77 @S9S_MB_2U_LIB.S9S_MB_2U(SCH_1):PAGE165

C844 Q_CAP_DIFFBUS_C0201-DIFF BUS_0A
     1 P5E_CPU0_PE1_TX_C_DN<12> @S9S_MB_2U_LIB.S9S_MB_2U(SCH_1):P5E_CPU0_PE1_TX_C_DN(12)    I70 @S9S_MB_2U_LIB.S9S_MB_2U(SCH_1):PAGE165
     2 P5E_CPU0_PE1_TX_DN<12> @S9S_MB_2U_LIB.S9S_MB_2U(SCH_1):P5E_CPU0_PE1_TX_DN(12)    I70 @S9S_MB_2U_LIB.S9S_MB_2U(SCH_1):PAGE165

C845 Q_CAP_DIFFBUS_C0201-DIFF BUS_0A
     1 P5E_CPU0_PE1_TX_C_DP<12> @S9S_MB_2U_LIB.S9S_MB_2U(SCH_1):P5E_CPU0_PE1_TX_C_DP(12)    I69 @S9S_MB_2U_LIB.S9S_MB_2U(SCH_1):PAGE165
     2 P5E_CPU0_PE1_TX_DP<12> @S9S_MB_2U_LIB.S9S_MB_2U(SCH_1):P5E_CPU0_PE1_TX_DP(12)    I69 @S9S_MB_2U_LIB.S9S_MB_2U(SCH_1):PAGE165

C846 Q_CAP_DIFFBUS_C0201-DIFF BUS_0A
     1 P5E_CPU0_PE1_TX_C_DN<11> @S9S_MB_2U_LIB.S9S_MB_2U(SCH_1):P5E_CPU0_PE1_TX_C_DN(11)    I68 @S9S_MB_2U_LIB.S9S_MB_2U(SCH_1):PAGE165
     2 P5E_CPU0_PE1_TX_DN<11> @S9S_MB_2U_LIB.S9S_MB_2U(SCH_1):P5E_CPU0_PE1_TX_DN(11)    I68 @S9S_MB_2U_LIB.S9S_MB_2U(SCH_1):PAGE165

C847 Q_CAP_DIFFBUS_C0201-DIFF BUS_0A
     1 P5E_CPU0_PE1_TX_C_DP<11> @S9S_MB_2U_LIB.S9S_MB_2U(SCH_1):P5E_CPU0_PE1_TX_C_DP(11)    I67 @S9S_MB_2U_LIB.S9S_MB_2U(SCH_1):PAGE165
     2 P5E_CPU0_PE1_TX_DP<11> @S9S_MB_2U_LIB.S9S_MB_2U(SCH_1):P5E_CPU0_PE1_TX_DP(11)    I67 @S9S_MB_2U_LIB.S9S_MB_2U(SCH_1):PAGE165

C848 Q_CAP_DIFFBUS_C0201-DIFF BUS_0A
     1 P5E_CPU0_PE1_TX_C_DN<10> @S9S_MB_2U_LIB.S9S_MB_2U(SCH_1):P5E_CPU0_PE1_TX_C_DN(10)    I66 @S9S_MB_2U_LIB.S9S_MB_2U(SCH_1):PAGE165
     2 P5E_CPU0_PE1_TX_DN<10> @S9S_MB_2U_LIB.S9S_MB_2U(SCH_1):P5E_CPU0_PE1_TX_DN(10)    I66 @S9S_MB_2U_LIB.S9S_MB_2U(SCH_1):PAGE165

C849 Q_CAP_DIFFBUS_C0201-DIFF BUS_0A
     1 P5E_CPU0_PE1_TX_C_DP<10> @S9S_MB_2U_LIB.S9S_MB_2U(SCH_1):P5E_CPU0_PE1_TX_C_DP(10)    I65 @S9S_MB_2U_LIB.S9S_MB_2U(SCH_1):PAGE165
     2 P5E_CPU0_PE1_TX_DP<10> @S9S_MB_2U_LIB.S9S_MB_2U(SCH_1):P5E_CPU0_PE1_TX_DP(10)    I65 @S9S_MB_2U_LIB.S9S_MB_2U(SCH_1):PAGE165

C850 Q_CAP_DIFFBUS_C0201-DIFF BUS_0A
     1 P5E_CPU0_PE1_TX_C_DN<9> @S9S_MB_2U_LIB.S9S_MB_2U(SCH_1):P5E_CPU0_PE1_TX_C_DN(9)    I64 @S9S_MB_2U_LIB.S9S_MB_2U(SCH_1):PAGE165
     2 P5E_CPU0_PE1_TX_DN<9> @S9S_MB_2U_LIB.S9S_MB_2U(SCH_1):P5E_CPU0_PE1_TX_DN(9)    I64 @S9S_MB_2U_LIB.S9S_MB_2U(SCH_1):PAGE165

C851 Q_CAP_DIFFBUS_C0201-DIFF BUS_0A
     1 P5E_CPU0_PE1_TX_C_DP<9> @S9S_MB_2U_LIB.S9S_MB_2U(SCH_1):P5E_CPU0_PE1_TX_C_DP(9)    I63 @S9S_MB_2U_LIB.S9S_MB_2U(SCH_1):PAGE165
     2 P5E_CPU0_PE1_TX_DP<9> @S9S_MB_2U_LIB.S9S_MB_2U(SCH_1):P5E_CPU0_PE1_TX_DP(9)    I63 @S9S_MB_2U_LIB.S9S_MB_2U(SCH_1):PAGE165

C852 Q_CAP_DIFFBUS_C0201-DIFF BUS_0A
     1 P5E_CPU0_PE1_TX_C_DN<8> @S9S_MB_2U_LIB.S9S_MB_2U(SCH_1):P5E_CPU0_PE1_TX_C_DN(8)    I61 @S9S_MB_2U_LIB.S9S_MB_2U(SCH_1):PAGE165
     2 P5E_CPU0_PE1_TX_DN<8> @S9S_MB_2U_LIB.S9S_MB_2U(SCH_1):P5E_CPU0_PE1_TX_DN(8)    I61 @S9S_MB_2U_LIB.S9S_MB_2U(SCH_1):PAGE165

C853 Q_CAP_DIFFBUS_C0201-DIFF BUS_0A
     1 P5E_CPU0_PE1_TX_C_DP<8> @S9S_MB_2U_LIB.S9S_MB_2U(SCH_1):P5E_CPU0_PE1_TX_C_DP(8)    I62 @S9S_MB_2U_LIB.S9S_MB_2U(SCH_1):PAGE165
     2 P5E_CPU0_PE1_TX_DP<8> @S9S_MB_2U_LIB.S9S_MB_2U(SCH_1):P5E_CPU0_PE1_TX_DP(8)    I62 @S9S_MB_2U_LIB.S9S_MB_2U(SCH_1):PAGE165

C854 Q_CAP_DIFFBUS_C0201-DIFF BUS_0A
     1 P5E_CPU0_PE1_TX_C_DN<7> @S9S_MB_2U_LIB.S9S_MB_2U(SCH_1):P5E_CPU0_PE1_TX_C_DN(7)    I41 @S9S_MB_2U_LIB.S9S_MB_2U(SCH_1):PAGE165
     2 P5E_CPU0_PE1_TX_DN<7> @S9S_MB_2U_LIB.S9S_MB_2U(SCH_1):P5E_CPU0_PE1_TX_DN(7)    I41 @S9S_MB_2U_LIB.S9S_MB_2U(SCH_1):PAGE165

C855 Q_CAP_DIFFBUS_C0201-DIFF BUS_0A
     1 P5E_CPU0_PE1_TX_C_DP<7> @S9S_MB_2U_LIB.S9S_MB_2U(SCH_1):P5E_CPU0_PE1_TX_C_DP(7)    I40 @S9S_MB_2U_LIB.S9S_MB_2U(SCH_1):PAGE165
     2 P5E_CPU0_PE1_TX_DP<7> @S9S_MB_2U_LIB.S9S_MB_2U(SCH_1):P5E_CPU0_PE1_TX_DP(7)    I40 @S9S_MB_2U_LIB.S9S_MB_2U(SCH_1):PAGE165

C856 Q_CAP_DIFFBUS_C0201-DIFF BUS_0A
     1 P5E_CPU0_PE1_TX_C_DN<6> @S9S_MB_2U_LIB.S9S_MB_2U(SCH_1):P5E_CPU0_PE1_TX_C_DN(6)    I39 @S9S_MB_2U_LIB.S9S_MB_2U(SCH_1):PAGE165
     2 P5E_CPU0_PE1_TX_DN<6> @S9S_MB_2U_LIB.S9S_MB_2U(SCH_1):P5E_CPU0_PE1_TX_DN(6)    I39 @S9S_MB_2U_LIB.S9S_MB_2U(SCH_1):PAGE165

C857 Q_CAP_DIFFBUS_C0201-DIFF BUS_0A
     1 P5E_CPU0_PE1_TX_C_DP<6> @S9S_MB_2U_LIB.S9S_MB_2U(SCH_1):P5E_CPU0_PE1_TX_C_DP(6)    I38 @S9S_MB_2U_LIB.S9S_MB_2U(SCH_1):PAGE165
     2 P5E_CPU0_PE1_TX_DP<6> @S9S_MB_2U_LIB.S9S_MB_2U(SCH_1):P5E_CPU0_PE1_TX_DP(6)    I38 @S9S_MB_2U_LIB.S9S_MB_2U(SCH_1):PAGE165

C858 Q_CAP_DIFFBUS_C0201-DIFF BUS_0A
     1 P5E_CPU0_PE1_TX_C_DN<5> @S9S_MB_2U_LIB.S9S_MB_2U(SCH_1):P5E_CPU0_PE1_TX_C_DN(5)    I37 @S9S_MB_2U_LIB.S9S_MB_2U(SCH_1):PAGE165
     2 P5E_CPU0_PE1_TX_DN<5> @S9S_MB_2U_LIB.S9S_MB_2U(SCH_1):P5E_CPU0_PE1_TX_DN(5)    I37 @S9S_MB_2U_LIB.S9S_MB_2U(SCH_1):PAGE165

C859 Q_CAP_DIFFBUS_C0201-DIFF BUS_0A
     1 P5E_CPU0_PE1_TX_C_DP<5> @S9S_MB_2U_LIB.S9S_MB_2U(SCH_1):P5E_CPU0_PE1_TX_C_DP(5)    I36 @S9S_MB_2U_LIB.S9S_MB_2U(SCH_1):PAGE165
     2 P5E_CPU0_PE1_TX_DP<5> @S9S_MB_2U_LIB.S9S_MB_2U(SCH_1):P5E_CPU0_PE1_TX_DP(5)    I36 @S9S_MB_2U_LIB.S9S_MB_2U(SCH_1):PAGE165

C860 Q_CAP_DIFFBUS_C0201-DIFF BUS_0A
     1 P5E_CPU0_PE1_TX_C_DN<4> @S9S_MB_2U_LIB.S9S_MB_2U(SCH_1):P5E_CPU0_PE1_TX_C_DN(4)    I30 @S9S_MB_2U_LIB.S9S_MB_2U(SCH_1):PAGE165
     2 P5E_CPU0_PE1_TX_DN<4> @S9S_MB_2U_LIB.S9S_MB_2U(SCH_1):P5E_CPU0_PE1_TX_DN(4)    I30 @S9S_MB_2U_LIB.S9S_MB_2U(SCH_1):PAGE165

C861 Q_CAP_DIFFBUS_C0201-DIFF BUS_0A
     1 P5E_CPU0_PE1_TX_C_DP<4> @S9S_MB_2U_LIB.S9S_MB_2U(SCH_1):P5E_CPU0_PE1_TX_C_DP(4)    I29 @S9S_MB_2U_LIB.S9S_MB_2U(SCH_1):PAGE165
     2 P5E_CPU0_PE1_TX_DP<4> @S9S_MB_2U_LIB.S9S_MB_2U(SCH_1):P5E_CPU0_PE1_TX_DP(4)    I29 @S9S_MB_2U_LIB.S9S_MB_2U(SCH_1):PAGE165

C862 Q_CAP_DIFFBUS_C0201-DIFF BUS_0A
     1 P5E_CPU0_PE1_TX_C_DN<3> @S9S_MB_2U_LIB.S9S_MB_2U(SCH_1):P5E_CPU0_PE1_TX_C_DN(3)    I28 @S9S_MB_2U_LIB.S9S_MB_2U(SCH_1):PAGE165
     2 P5E_CPU0_PE1_TX_DN<3> @S9S_MB_2U_LIB.S9S_MB_2U(SCH_1):P5E_CPU0_PE1_TX_DN(3)    I28 @S9S_MB_2U_LIB.S9S_MB_2U(SCH_1):PAGE165

C863 Q_CAP_DIFFBUS_C0201-DIFF BUS_0A
     1 P5E_CPU0_PE1_TX_C_DP<3> @S9S_MB_2U_LIB.S9S_MB_2U(SCH_1):P5E_CPU0_PE1_TX_C_DP(3)    I27 @S9S_MB_2U_LIB.S9S_MB_2U(SCH_1):PAGE165
     2 P5E_CPU0_PE1_TX_DP<3> @S9S_MB_2U_LIB.S9S_MB_2U(SCH_1):P5E_CPU0_PE1_TX_DP(3)    I27 @S9S_MB_2U_LIB.S9S_MB_2U(SCH_1):PAGE165

C864 Q_CAP_DIFFBUS_C0201-DIFF BUS_0A
     1 P5E_CPU0_PE1_TX_C_DN<2> @S9S_MB_2U_LIB.S9S_MB_2U(SCH_1):P5E_CPU0_PE1_TX_C_DN(2)    I25 @S9S_MB_2U_LIB.S9S_MB_2U(SCH_1):PAGE165
     2 P5E_CPU0_PE1_TX_DN<2> @S9S_MB_2U_LIB.S9S_MB_2U(SCH_1):P5E_CPU0_PE1_TX_DN(2)    I25 @S9S_MB_2U_LIB.S9S_MB_2U(SCH_1):PAGE165

C865 Q_CAP_DIFFBUS_C0201-DIFF BUS_0A
     1 P5E_CPU0_PE1_TX_C_DP<2> @S9S_MB_2U_LIB.S9S_MB_2U(SCH_1):P5E_CPU0_PE1_TX_C_DP(2)    I26 @S9S_MB_2U_LIB.S9S_MB_2U(SCH_1):PAGE165
     2 P5E_CPU0_PE1_TX_DP<2> @S9S_MB_2U_LIB.S9S_MB_2U(SCH_1):P5E_CPU0_PE1_TX_DP(2)    I26 @S9S_MB_2U_LIB.S9S_MB_2U(SCH_1):PAGE165

C866 Q_CAP_DIFFBUS_C0201-DIFF BUS_0A
     1 P5E_CPU0_PE1_TX_C_DN<1> @S9S_MB_2U_LIB.S9S_MB_2U(SCH_1):P5E_CPU0_PE1_TX_C_DN(1)    I24 @S9S_MB_2U_LIB.S9S_MB_2U(SCH_1):PAGE165
     2 P5E_CPU0_PE1_TX_DN<1> @S9S_MB_2U_LIB.S9S_MB_2U(SCH_1):P5E_CPU0_PE1_TX_DN(1)    I24 @S9S_MB_2U_LIB.S9S_MB_2U(SCH_1):PAGE165

C867 Q_CAP_DIFFBUS_C0201-DIFF BUS_0A
     1 P5E_CPU0_PE1_TX_C_DP<1> @S9S_MB_2U_LIB.S9S_MB_2U(SCH_1):P5E_CPU0_PE1_TX_C_DP(1)    I23 @S9S_MB_2U_LIB.S9S_MB_2U(SCH_1):PAGE165
     2 P5E_CPU0_PE1_TX_DP<1> @S9S_MB_2U_LIB.S9S_MB_2U(SCH_1):P5E_CPU0_PE1_TX_DP(1)    I23 @S9S_MB_2U_LIB.S9S_MB_2U(SCH_1):PAGE165

C868 Q_CAP_DIFFBUS_C0201-DIFF BUS_0A
     1 P5E_CPU0_PE1_TX_C_DN<0> @S9S_MB_2U_LIB.S9S_MB_2U(SCH_1):P5E_CPU0_PE1_TX_C_DN(0)    I22 @S9S_MB_2U_LIB.S9S_MB_2U(SCH_1):PAGE165
     2 P5E_CPU0_PE1_TX_DN<0> @S9S_MB_2U_LIB.S9S_MB_2U(SCH_1):P5E_CPU0_PE1_TX_DN(0)    I22 @S9S_MB_2U_LIB.S9S_MB_2U(SCH_1):PAGE165

C869 Q_CAP_DIFFBUS_C0201-DIFF BUS_0A
     1 P5E_CPU0_PE1_TX_C_DP<0> @S9S_MB_2U_LIB.S9S_MB_2U(SCH_1):P5E_CPU0_PE1_TX_C_DP(0)    I21 @S9S_MB_2U_LIB.S9S_MB_2U(SCH_1):PAGE165
     2 P5E_CPU0_PE1_TX_DP<0> @S9S_MB_2U_LIB.S9S_MB_2U(SCH_1):P5E_CPU0_PE1_TX_DP(0)    I21 @S9S_MB_2U_LIB.S9S_MB_2U(SCH_1):PAGE165

C870 Q_CAP_DIFFBUS_C0201-DIFF BUS_0A
     1 P5E_CPU0_PE3_TX_C_DN<15> @S9S_MB_2U_LIB.S9S_MB_2U(SCH_1):P5E_CPU0_PE3_TX_C_DN(15)   I169 @S9S_MB_2U_LIB.S9S_MB_2U(SCH_1):PAGE165
     2 P5E_CPU0_PE3_TX_DN<15> @S9S_MB_2U_LIB.S9S_MB_2U(SCH_1):P5E_CPU0_PE3_TX_DN(15)   I169 @S9S_MB_2U_LIB.S9S_MB_2U(SCH_1):PAGE165

C871 Q_CAP_DIFFBUS_C0201-DIFF BUS_0A
     1 P5E_CPU0_PE3_TX_C_DP<15> @S9S_MB_2U_LIB.S9S_MB_2U(SCH_1):P5E_CPU0_PE3_TX_C_DP(15)   I168 @S9S_MB_2U_LIB.S9S_MB_2U(SCH_1):PAGE165
     2 P5E_CPU0_PE3_TX_DP<15> @S9S_MB_2U_LIB.S9S_MB_2U(SCH_1):P5E_CPU0_PE3_TX_DP(15)   I168 @S9S_MB_2U_LIB.S9S_MB_2U(SCH_1):PAGE165

C872 Q_CAP_DIFFBUS_C0201-DIFF BUS_0A
     1 P5E_CPU0_PE3_TX_C_DN<14> @S9S_MB_2U_LIB.S9S_MB_2U(SCH_1):P5E_CPU0_PE3_TX_C_DN(14)   I167 @S9S_MB_2U_LIB.S9S_MB_2U(SCH_1):PAGE165
     2 P5E_CPU0_PE3_TX_DN<14> @S9S_MB_2U_LIB.S9S_MB_2U(SCH_1):P5E_CPU0_PE3_TX_DN(14)   I167 @S9S_MB_2U_LIB.S9S_MB_2U(SCH_1):PAGE165

C873 Q_CAP_DIFFBUS_C0201-DIFF BUS_0A
     1 P5E_CPU0_PE3_TX_C_DP<14> @S9S_MB_2U_LIB.S9S_MB_2U(SCH_1):P5E_CPU0_PE3_TX_C_DP(14)   I166 @S9S_MB_2U_LIB.S9S_MB_2U(SCH_1):PAGE165
     2 P5E_CPU0_PE3_TX_DP<14> @S9S_MB_2U_LIB.S9S_MB_2U(SCH_1):P5E_CPU0_PE3_TX_DP(14)   I166 @S9S_MB_2U_LIB.S9S_MB_2U(SCH_1):PAGE165

C874 Q_CAP_DIFFBUS_C0201-DIFF BUS_0A
     1 P5E_CPU0_PE3_TX_C_DN<13> @S9S_MB_2U_LIB.S9S_MB_2U(SCH_1):P5E_CPU0_PE3_TX_C_DN(13)   I165 @S9S_MB_2U_LIB.S9S_MB_2U(SCH_1):PAGE165
     2 P5E_CPU0_PE3_TX_DN<13> @S9S_MB_2U_LIB.S9S_MB_2U(SCH_1):P5E_CPU0_PE3_TX_DN(13)   I165 @S9S_MB_2U_LIB.S9S_MB_2U(SCH_1):PAGE165

C875 Q_CAP_DIFFBUS_C0201-DIFF BUS_0A
     1 P5E_CPU0_PE3_TX_C_DP<13> @S9S_MB_2U_LIB.S9S_MB_2U(SCH_1):P5E_CPU0_PE3_TX_C_DP(13)   I164 @S9S_MB_2U_LIB.S9S_MB_2U(SCH_1):PAGE165
     2 P5E_CPU0_PE3_TX_DP<13> @S9S_MB_2U_LIB.S9S_MB_2U(SCH_1):P5E_CPU0_PE3_TX_DP(13)   I164 @S9S_MB_2U_LIB.S9S_MB_2U(SCH_1):PAGE165

C876 Q_CAP_DIFFBUS_C0201-DIFF BUS_0A
     1 P5E_CPU0_PE3_TX_C_DN<12> @S9S_MB_2U_LIB.S9S_MB_2U(SCH_1):P5E_CPU0_PE3_TX_C_DN(12)   I160 @S9S_MB_2U_LIB.S9S_MB_2U(SCH_1):PAGE165
     2 P5E_CPU0_PE3_TX_DN<12> @S9S_MB_2U_LIB.S9S_MB_2U(SCH_1):P5E_CPU0_PE3_TX_DN(12)   I160 @S9S_MB_2U_LIB.S9S_MB_2U(SCH_1):PAGE165

C877 Q_CAP_DIFFBUS_C0201-DIFF BUS_0A
     1 P5E_CPU0_PE3_TX_C_DP<12> @S9S_MB_2U_LIB.S9S_MB_2U(SCH_1):P5E_CPU0_PE3_TX_C_DP(12)   I159 @S9S_MB_2U_LIB.S9S_MB_2U(SCH_1):PAGE165
     2 P5E_CPU0_PE3_TX_DP<12> @S9S_MB_2U_LIB.S9S_MB_2U(SCH_1):P5E_CPU0_PE3_TX_DP(12)   I159 @S9S_MB_2U_LIB.S9S_MB_2U(SCH_1):PAGE165

C878 Q_CAP_DIFFBUS_C0201-DIFF BUS_0A
     1 P5E_CPU0_PE3_TX_C_DN<11> @S9S_MB_2U_LIB.S9S_MB_2U(SCH_1):P5E_CPU0_PE3_TX_C_DN(11)   I157 @S9S_MB_2U_LIB.S9S_MB_2U(SCH_1):PAGE165
     2 P5E_CPU0_PE3_TX_DN<11> @S9S_MB_2U_LIB.S9S_MB_2U(SCH_1):P5E_CPU0_PE3_TX_DN(11)   I157 @S9S_MB_2U_LIB.S9S_MB_2U(SCH_1):PAGE165

C879 Q_CAP_DIFFBUS_C0201-DIFF BUS_0A
     1 P5E_CPU0_PE3_TX_C_DP<11> @S9S_MB_2U_LIB.S9S_MB_2U(SCH_1):P5E_CPU0_PE3_TX_C_DP(11)   I158 @S9S_MB_2U_LIB.S9S_MB_2U(SCH_1):PAGE165
     2 P5E_CPU0_PE3_TX_DP<11> @S9S_MB_2U_LIB.S9S_MB_2U(SCH_1):P5E_CPU0_PE3_TX_DP(11)   I158 @S9S_MB_2U_LIB.S9S_MB_2U(SCH_1):PAGE165

C880 Q_CAP_DIFFBUS_C0201-DIFF BUS_0A
     1 P5E_CPU0_PE3_TX_C_DN<10> @S9S_MB_2U_LIB.S9S_MB_2U(SCH_1):P5E_CPU0_PE3_TX_C_DN(10)   I156 @S9S_MB_2U_LIB.S9S_MB_2U(SCH_1):PAGE165
     2 P5E_CPU0_PE3_TX_DN<10> @S9S_MB_2U_LIB.S9S_MB_2U(SCH_1):P5E_CPU0_PE3_TX_DN(10)   I156 @S9S_MB_2U_LIB.S9S_MB_2U(SCH_1):PAGE165

C881 Q_CAP_DIFFBUS_C0201-DIFF BUS_0A
     1 P5E_CPU0_PE3_TX_C_DP<10> @S9S_MB_2U_LIB.S9S_MB_2U(SCH_1):P5E_CPU0_PE3_TX_C_DP(10)   I155 @S9S_MB_2U_LIB.S9S_MB_2U(SCH_1):PAGE165
     2 P5E_CPU0_PE3_TX_DP<10> @S9S_MB_2U_LIB.S9S_MB_2U(SCH_1):P5E_CPU0_PE3_TX_DP(10)   I155 @S9S_MB_2U_LIB.S9S_MB_2U(SCH_1):PAGE165

C882 Q_CAP_DIFFBUS_C0201-DIFF BUS_0A
     1 P5E_CPU0_PE3_TX_C_DN<9> @S9S_MB_2U_LIB.S9S_MB_2U(SCH_1):P5E_CPU0_PE3_TX_C_DN(9)   I154 @S9S_MB_2U_LIB.S9S_MB_2U(SCH_1):PAGE165
     2 P5E_CPU0_PE3_TX_DN<9> @S9S_MB_2U_LIB.S9S_MB_2U(SCH_1):P5E_CPU0_PE3_TX_DN(9)   I154 @S9S_MB_2U_LIB.S9S_MB_2U(SCH_1):PAGE165

C883 Q_CAP_DIFFBUS_C0201-DIFF BUS_0A
     1 P5E_CPU0_PE3_TX_C_DP<9> @S9S_MB_2U_LIB.S9S_MB_2U(SCH_1):P5E_CPU0_PE3_TX_C_DP(9)   I153 @S9S_MB_2U_LIB.S9S_MB_2U(SCH_1):PAGE165
     2 P5E_CPU0_PE3_TX_DP<9> @S9S_MB_2U_LIB.S9S_MB_2U(SCH_1):P5E_CPU0_PE3_TX_DP(9)   I153 @S9S_MB_2U_LIB.S9S_MB_2U(SCH_1):PAGE165

C884 Q_CAP_DIFFBUS_C0201-DIFF BUS_0A
     1 P5E_CPU0_PE3_TX_C_DN<8> @S9S_MB_2U_LIB.S9S_MB_2U(SCH_1):P5E_CPU0_PE3_TX_C_DN(8)   I151 @S9S_MB_2U_LIB.S9S_MB_2U(SCH_1):PAGE165
     2 P5E_CPU0_PE3_TX_DN<8> @S9S_MB_2U_LIB.S9S_MB_2U(SCH_1):P5E_CPU0_PE3_TX_DN(8)   I151 @S9S_MB_2U_LIB.S9S_MB_2U(SCH_1):PAGE165

C885 Q_CAP_DIFFBUS_C0201-DIFF BUS_0A
     1 P5E_CPU0_PE3_TX_C_DP<8> @S9S_MB_2U_LIB.S9S_MB_2U(SCH_1):P5E_CPU0_PE3_TX_C_DP(8)   I152 @S9S_MB_2U_LIB.S9S_MB_2U(SCH_1):PAGE165
     2 P5E_CPU0_PE3_TX_DP<8> @S9S_MB_2U_LIB.S9S_MB_2U(SCH_1):P5E_CPU0_PE3_TX_DP(8)   I152 @S9S_MB_2U_LIB.S9S_MB_2U(SCH_1):PAGE165

C886 Q_CAP_DIFFBUS_C0201-DIFF BUS_0A
     1 P5E_CPU0_PE3_TX_C_DN<7> @S9S_MB_2U_LIB.S9S_MB_2U(SCH_1):P5E_CPU0_PE3_TX_C_DN(7)   I137 @S9S_MB_2U_LIB.S9S_MB_2U(SCH_1):PAGE165
     2 P5E_CPU0_PE3_TX_DN<7> @S9S_MB_2U_LIB.S9S_MB_2U(SCH_1):P5E_CPU0_PE3_TX_DN(7)   I137 @S9S_MB_2U_LIB.S9S_MB_2U(SCH_1):PAGE165

C887 Q_CAP_DIFFBUS_C0201-DIFF BUS_0A
     1 P5E_CPU0_PE3_TX_C_DP<7> @S9S_MB_2U_LIB.S9S_MB_2U(SCH_1):P5E_CPU0_PE3_TX_C_DP(7)   I136 @S9S_MB_2U_LIB.S9S_MB_2U(SCH_1):PAGE165
     2 P5E_CPU0_PE3_TX_DP<7> @S9S_MB_2U_LIB.S9S_MB_2U(SCH_1):P5E_CPU0_PE3_TX_DP(7)   I136 @S9S_MB_2U_LIB.S9S_MB_2U(SCH_1):PAGE165

C888 Q_CAP_DIFFBUS_C0201-DIFF BUS_0A
     1 P5E_CPU0_PE3_TX_C_DN<6> @S9S_MB_2U_LIB.S9S_MB_2U(SCH_1):P5E_CPU0_PE3_TX_C_DN(6)   I135 @S9S_MB_2U_LIB.S9S_MB_2U(SCH_1):PAGE165
     2 P5E_CPU0_PE3_TX_DN<6> @S9S_MB_2U_LIB.S9S_MB_2U(SCH_1):P5E_CPU0_PE3_TX_DN(6)   I135 @S9S_MB_2U_LIB.S9S_MB_2U(SCH_1):PAGE165

C889 Q_CAP_DIFFBUS_C0201-DIFF BUS_0A
     1 P5E_CPU0_PE3_TX_C_DP<6> @S9S_MB_2U_LIB.S9S_MB_2U(SCH_1):P5E_CPU0_PE3_TX_C_DP(6)   I134 @S9S_MB_2U_LIB.S9S_MB_2U(SCH_1):PAGE165
     2 P5E_CPU0_PE3_TX_DP<6> @S9S_MB_2U_LIB.S9S_MB_2U(SCH_1):P5E_CPU0_PE3_TX_DP(6)   I134 @S9S_MB_2U_LIB.S9S_MB_2U(SCH_1):PAGE165

C890 Q_CAP_DIFFBUS_C0201-DIFF BUS_0A
     1 P5E_CPU0_PE3_TX_C_DN<5> @S9S_MB_2U_LIB.S9S_MB_2U(SCH_1):P5E_CPU0_PE3_TX_C_DN(5)   I133 @S9S_MB_2U_LIB.S9S_MB_2U(SCH_1):PAGE165
     2 P5E_CPU0_PE3_TX_DN<5> @S9S_MB_2U_LIB.S9S_MB_2U(SCH_1):P5E_CPU0_PE3_TX_DN(5)   I133 @S9S_MB_2U_LIB.S9S_MB_2U(SCH_1):PAGE165

C891 Q_CAP_DIFFBUS_C0201-DIFF BUS_0A
     1 P5E_CPU0_PE3_TX_C_DP<5> @S9S_MB_2U_LIB.S9S_MB_2U(SCH_1):P5E_CPU0_PE3_TX_C_DP(5)   I132 @S9S_MB_2U_LIB.S9S_MB_2U(SCH_1):PAGE165
     2 P5E_CPU0_PE3_TX_DP<5> @S9S_MB_2U_LIB.S9S_MB_2U(SCH_1):P5E_CPU0_PE3_TX_DP(5)   I132 @S9S_MB_2U_LIB.S9S_MB_2U(SCH_1):PAGE165

C892 Q_CAP_DIFFBUS_C0201-DIFF BUS_0A
     1 P5E_CPU0_PE3_TX_C_DN<4> @S9S_MB_2U_LIB.S9S_MB_2U(SCH_1):P5E_CPU0_PE3_TX_C_DN(4)   I127 @S9S_MB_2U_LIB.S9S_MB_2U(SCH_1):PAGE165
     2 P5E_CPU0_PE3_TX_DN<4> @S9S_MB_2U_LIB.S9S_MB_2U(SCH_1):P5E_CPU0_PE3_TX_DN(4)   I127 @S9S_MB_2U_LIB.S9S_MB_2U(SCH_1):PAGE165

C893 Q_CAP_DIFFBUS_C0201-DIFF BUS_0A
     1 P5E_CPU0_PE3_TX_C_DP<4> @S9S_MB_2U_LIB.S9S_MB_2U(SCH_1):P5E_CPU0_PE3_TX_C_DP(4)   I128 @S9S_MB_2U_LIB.S9S_MB_2U(SCH_1):PAGE165
     2 P5E_CPU0_PE3_TX_DP<4> @S9S_MB_2U_LIB.S9S_MB_2U(SCH_1):P5E_CPU0_PE3_TX_DP(4)   I128 @S9S_MB_2U_LIB.S9S_MB_2U(SCH_1):PAGE165

C894 Q_CAP_DIFFBUS_C0201-DIFF BUS_0A
     1 P5E_CPU0_PE3_TX_C_DN<3> @S9S_MB_2U_LIB.S9S_MB_2U(SCH_1):P5E_CPU0_PE3_TX_C_DN(3)   I126 @S9S_MB_2U_LIB.S9S_MB_2U(SCH_1):PAGE165
     2 P5E_CPU0_PE3_TX_DN<3> @S9S_MB_2U_LIB.S9S_MB_2U(SCH_1):P5E_CPU0_PE3_TX_DN(3)   I126 @S9S_MB_2U_LIB.S9S_MB_2U(SCH_1):PAGE165

C895 Q_CAP_DIFFBUS_C0201-DIFF BUS_0A
     1 P5E_CPU0_PE3_TX_C_DP<3> @S9S_MB_2U_LIB.S9S_MB_2U(SCH_1):P5E_CPU0_PE3_TX_C_DP(3)   I125 @S9S_MB_2U_LIB.S9S_MB_2U(SCH_1):PAGE165
     2 P5E_CPU0_PE3_TX_DP<3> @S9S_MB_2U_LIB.S9S_MB_2U(SCH_1):P5E_CPU0_PE3_TX_DP(3)   I125 @S9S_MB_2U_LIB.S9S_MB_2U(SCH_1):PAGE165

C896 Q_CAP_DIFFBUS_C0201-DIFF BUS_0A
     1 P5E_CPU0_PE3_TX_C_DN<2> @S9S_MB_2U_LIB.S9S_MB_2U(SCH_1):P5E_CPU0_PE3_TX_C_DN(2)   I124 @S9S_MB_2U_LIB.S9S_MB_2U(SCH_1):PAGE165
     2 P5E_CPU0_PE3_TX_DN<2> @S9S_MB_2U_LIB.S9S_MB_2U(SCH_1):P5E_CPU0_PE3_TX_DN(2)   I124 @S9S_MB_2U_LIB.S9S_MB_2U(SCH_1):PAGE165

C897 Q_CAP_DIFFBUS_C0201-DIFF BUS_0A
     1 P5E_CPU0_PE3_TX_C_DP<2> @S9S_MB_2U_LIB.S9S_MB_2U(SCH_1):P5E_CPU0_PE3_TX_C_DP(2)   I123 @S9S_MB_2U_LIB.S9S_MB_2U(SCH_1):PAGE165
     2 P5E_CPU0_PE3_TX_DP<2> @S9S_MB_2U_LIB.S9S_MB_2U(SCH_1):P5E_CPU0_PE3_TX_DP(2)   I123 @S9S_MB_2U_LIB.S9S_MB_2U(SCH_1):PAGE165

C898 Q_CAP_DIFFBUS_C0201-DIFF BUS_0A
     1 P5E_CPU0_PE3_TX_C_DN<1> @S9S_MB_2U_LIB.S9S_MB_2U(SCH_1):P5E_CPU0_PE3_TX_C_DN(1)   I206 @S9S_MB_2U_LIB.S9S_MB_2U(SCH_1):PAGE165
     2 P5E_CPU0_PE3_TX_DN<1> @S9S_MB_2U_LIB.S9S_MB_2U(SCH_1):P5E_CPU0_PE3_TX_DN(1)   I206 @S9S_MB_2U_LIB.S9S_MB_2U(SCH_1):PAGE165

C899 Q_CAP_DIFFBUS_C0201-DIFF BUS_0A
     1 P5E_CPU0_PE3_TX_C_DP<1> @S9S_MB_2U_LIB.S9S_MB_2U(SCH_1):P5E_CPU0_PE3_TX_C_DP(1)   I122 @S9S_MB_2U_LIB.S9S_MB_2U(SCH_1):PAGE165
     2 P5E_CPU0_PE3_TX_DP<1> @S9S_MB_2U_LIB.S9S_MB_2U(SCH_1):P5E_CPU0_PE3_TX_DP(1)   I122 @S9S_MB_2U_LIB.S9S_MB_2U(SCH_1):PAGE165

C900 Q_CAP_DIFFBUS_C0201-DIFF BUS_0A
     1 P5E_CPU0_PE3_TX_C_DN<0> @S9S_MB_2U_LIB.S9S_MB_2U(SCH_1):P5E_CPU0_PE3_TX_C_DN(0)   I121 @S9S_MB_2U_LIB.S9S_MB_2U(SCH_1):PAGE165
     2 P5E_CPU0_PE3_TX_DN<0> @S9S_MB_2U_LIB.S9S_MB_2U(SCH_1):P5E_CPU0_PE3_TX_DN(0)   I121 @S9S_MB_2U_LIB.S9S_MB_2U(SCH_1):PAGE165

C901 Q_CAP_DIFFBUS_C0201-DIFF BUS_0A
     1 P5E_CPU0_PE3_TX_C_DP<0> @S9S_MB_2U_LIB.S9S_MB_2U(SCH_1):P5E_CPU0_PE3_TX_C_DP(0)   I120 @S9S_MB_2U_LIB.S9S_MB_2U(SCH_1):PAGE165
     2 P5E_CPU0_PE3_TX_DP<0> @S9S_MB_2U_LIB.S9S_MB_2U(SCH_1):P5E_CPU0_PE3_TX_DP(0)   I120 @S9S_MB_2U_LIB.S9S_MB_2U(SCH_1):PAGE165

C902 Q_CAP_DIFFBUS_C0201-DIFF BUS_0A
     1 P5E_CPU0_PE0_TX_C_DN<15> @S9S_MB_2U_LIB.S9S_MB_2U(SCH_1):P5E_CPU0_PE0_TX_C_DN(15)    I68 @S9S_MB_2U_LIB.S9S_MB_2U(SCH_1):PAGE164
     2 P5E_CPU0_PE0_TX_DN<15> @S9S_MB_2U_LIB.S9S_MB_2U(SCH_1):P5E_CPU0_PE0_TX_DN(15)    I68 @S9S_MB_2U_LIB.S9S_MB_2U(SCH_1):PAGE164

C903 Q_CAP_DIFFBUS_C0201-DIFF BUS_0A
     1 P5E_CPU0_PE0_TX_C_DP<15> @S9S_MB_2U_LIB.S9S_MB_2U(SCH_1):P5E_CPU0_PE0_TX_C_DP(15)    I67 @S9S_MB_2U_LIB.S9S_MB_2U(SCH_1):PAGE164
     2 P5E_CPU0_PE0_TX_DP<15> @S9S_MB_2U_LIB.S9S_MB_2U(SCH_1):P5E_CPU0_PE0_TX_DP(15)    I67 @S9S_MB_2U_LIB.S9S_MB_2U(SCH_1):PAGE164

C904 Q_CAP_DIFFBUS_C0201-DIFF BUS_0A
     1 P5E_CPU0_PE0_TX_C_DN<14> @S9S_MB_2U_LIB.S9S_MB_2U(SCH_1):P5E_CPU0_PE0_TX_C_DN(14)    I66 @S9S_MB_2U_LIB.S9S_MB_2U(SCH_1):PAGE164
     2 P5E_CPU0_PE0_TX_DN<14> @S9S_MB_2U_LIB.S9S_MB_2U(SCH_1):P5E_CPU0_PE0_TX_DN(14)    I66 @S9S_MB_2U_LIB.S9S_MB_2U(SCH_1):PAGE164

C905 Q_CAP_DIFFBUS_C0201-DIFF BUS_0A
     1 P5E_CPU0_PE0_TX_C_DP<14> @S9S_MB_2U_LIB.S9S_MB_2U(SCH_1):P5E_CPU0_PE0_TX_C_DP(14)    I65 @S9S_MB_2U_LIB.S9S_MB_2U(SCH_1):PAGE164
     2 P5E_CPU0_PE0_TX_DP<14> @S9S_MB_2U_LIB.S9S_MB_2U(SCH_1):P5E_CPU0_PE0_TX_DP(14)    I65 @S9S_MB_2U_LIB.S9S_MB_2U(SCH_1):PAGE164

C906 Q_CAP_DIFFBUS_C0201-DIFF BUS_0A
     1 P5E_CPU0_PE0_TX_C_DN<13> @S9S_MB_2U_LIB.S9S_MB_2U(SCH_1):P5E_CPU0_PE0_TX_C_DN(13)    I63 @S9S_MB_2U_LIB.S9S_MB_2U(SCH_1):PAGE164
     2 P5E_CPU0_PE0_TX_DN<13> @S9S_MB_2U_LIB.S9S_MB_2U(SCH_1):P5E_CPU0_PE0_TX_DN(13)    I63 @S9S_MB_2U_LIB.S9S_MB_2U(SCH_1):PAGE164

C907 Q_CAP_DIFFBUS_C0201-DIFF BUS_0A
     1 P5E_CPU0_PE0_TX_C_DP<13> @S9S_MB_2U_LIB.S9S_MB_2U(SCH_1):P5E_CPU0_PE0_TX_C_DP(13)    I64 @S9S_MB_2U_LIB.S9S_MB_2U(SCH_1):PAGE164
     2 P5E_CPU0_PE0_TX_DP<13> @S9S_MB_2U_LIB.S9S_MB_2U(SCH_1):P5E_CPU0_PE0_TX_DP(13)    I64 @S9S_MB_2U_LIB.S9S_MB_2U(SCH_1):PAGE164

C908 Q_CAP_DIFFBUS_C0201-DIFF BUS_0A
     1 P5E_CPU0_PE0_TX_C_DN<12> @S9S_MB_2U_LIB.S9S_MB_2U(SCH_1):P5E_CPU0_PE0_TX_C_DN(12)    I62 @S9S_MB_2U_LIB.S9S_MB_2U(SCH_1):PAGE164
     2 P5E_CPU0_PE0_TX_DN<12> @S9S_MB_2U_LIB.S9S_MB_2U(SCH_1):P5E_CPU0_PE0_TX_DN(12)    I62 @S9S_MB_2U_LIB.S9S_MB_2U(SCH_1):PAGE164

C909 Q_CAP_DIFFBUS_C0201-DIFF BUS_0A
     1 P5E_CPU0_PE0_TX_C_DP<12> @S9S_MB_2U_LIB.S9S_MB_2U(SCH_1):P5E_CPU0_PE0_TX_C_DP(12)    I61 @S9S_MB_2U_LIB.S9S_MB_2U(SCH_1):PAGE164
     2 P5E_CPU0_PE0_TX_DP<12> @S9S_MB_2U_LIB.S9S_MB_2U(SCH_1):P5E_CPU0_PE0_TX_DP(12)    I61 @S9S_MB_2U_LIB.S9S_MB_2U(SCH_1):PAGE164

C910 Q_CAP_DIFFBUS_C0201-DIFF BUS_0A
     1 P5E_CPU0_PE0_TX_C_DN<11> @S9S_MB_2U_LIB.S9S_MB_2U(SCH_1):P5E_CPU0_PE0_TX_C_DN(11)    I60 @S9S_MB_2U_LIB.S9S_MB_2U(SCH_1):PAGE164
     2 P5E_CPU0_PE0_TX_DN<11> @S9S_MB_2U_LIB.S9S_MB_2U(SCH_1):P5E_CPU0_PE0_TX_DN(11)    I60 @S9S_MB_2U_LIB.S9S_MB_2U(SCH_1):PAGE164

C911 Q_CAP_DIFFBUS_C0201-DIFF BUS_0A
     1 P5E_CPU0_PE0_TX_C_DP<11> @S9S_MB_2U_LIB.S9S_MB_2U(SCH_1):P5E_CPU0_PE0_TX_C_DP(11)    I59 @S9S_MB_2U_LIB.S9S_MB_2U(SCH_1):PAGE164
     2 P5E_CPU0_PE0_TX_DP<11> @S9S_MB_2U_LIB.S9S_MB_2U(SCH_1):P5E_CPU0_PE0_TX_DP(11)    I59 @S9S_MB_2U_LIB.S9S_MB_2U(SCH_1):PAGE164

C912 Q_CAP_DIFFBUS_C0201-DIFF BUS_0A
     1 P5E_CPU0_PE0_TX_C_DN<10> @S9S_MB_2U_LIB.S9S_MB_2U(SCH_1):P5E_CPU0_PE0_TX_C_DN(10)    I58 @S9S_MB_2U_LIB.S9S_MB_2U(SCH_1):PAGE164
     2 P5E_CPU0_PE0_TX_DN<10> @S9S_MB_2U_LIB.S9S_MB_2U(SCH_1):P5E_CPU0_PE0_TX_DN(10)    I58 @S9S_MB_2U_LIB.S9S_MB_2U(SCH_1):PAGE164

C913 Q_CAP_DIFFBUS_C0201-DIFF BUS_0A
     1 P5E_CPU0_PE0_TX_C_DP<10> @S9S_MB_2U_LIB.S9S_MB_2U(SCH_1):P5E_CPU0_PE0_TX_C_DP(10)    I57 @S9S_MB_2U_LIB.S9S_MB_2U(SCH_1):PAGE164
     2 P5E_CPU0_PE0_TX_DP<10> @S9S_MB_2U_LIB.S9S_MB_2U(SCH_1):P5E_CPU0_PE0_TX_DP(10)    I57 @S9S_MB_2U_LIB.S9S_MB_2U(SCH_1):PAGE164

C914 Q_CAP_DIFFBUS_C0201-DIFF BUS_0A
     1 P5E_CPU0_PE0_TX_C_DN<9> @S9S_MB_2U_LIB.S9S_MB_2U(SCH_1):P5E_CPU0_PE0_TX_C_DN(9)    I56 @S9S_MB_2U_LIB.S9S_MB_2U(SCH_1):PAGE164
     2 P5E_CPU0_PE0_TX_DN<9> @S9S_MB_2U_LIB.S9S_MB_2U(SCH_1):P5E_CPU0_PE0_TX_DN(9)    I56 @S9S_MB_2U_LIB.S9S_MB_2U(SCH_1):PAGE164

C915 Q_CAP_DIFFBUS_C0201-DIFF BUS_0A
     1 P5E_CPU0_PE0_TX_C_DP<9> @S9S_MB_2U_LIB.S9S_MB_2U(SCH_1):P5E_CPU0_PE0_TX_C_DP(9)    I55 @S9S_MB_2U_LIB.S9S_MB_2U(SCH_1):PAGE164
     2 P5E_CPU0_PE0_TX_DP<9> @S9S_MB_2U_LIB.S9S_MB_2U(SCH_1):P5E_CPU0_PE0_TX_DP(9)    I55 @S9S_MB_2U_LIB.S9S_MB_2U(SCH_1):PAGE164

C916 Q_CAP_DIFFBUS_C0201-DIFF BUS_0A
     1 P5E_CPU0_PE0_TX_C_DN<8> @S9S_MB_2U_LIB.S9S_MB_2U(SCH_1):P5E_CPU0_PE0_TX_C_DN(8)    I53 @S9S_MB_2U_LIB.S9S_MB_2U(SCH_1):PAGE164
     2 P5E_CPU0_PE0_TX_DN<8> @S9S_MB_2U_LIB.S9S_MB_2U(SCH_1):P5E_CPU0_PE0_TX_DN(8)    I53 @S9S_MB_2U_LIB.S9S_MB_2U(SCH_1):PAGE164

C917 Q_CAP_DIFFBUS_C0201-DIFF BUS_0A
     1 P5E_CPU0_PE0_TX_C_DP<8> @S9S_MB_2U_LIB.S9S_MB_2U(SCH_1):P5E_CPU0_PE0_TX_C_DP(8)    I54 @S9S_MB_2U_LIB.S9S_MB_2U(SCH_1):PAGE164
     2 P5E_CPU0_PE0_TX_DP<8> @S9S_MB_2U_LIB.S9S_MB_2U(SCH_1):P5E_CPU0_PE0_TX_DP(8)    I54 @S9S_MB_2U_LIB.S9S_MB_2U(SCH_1):PAGE164

C918 Q_CAP_DIFFBUS_C0201-DIFF BUS_0A
     1 P5E_CPU0_PE0_TX_C_DN<7> @S9S_MB_2U_LIB.S9S_MB_2U(SCH_1):P5E_CPU0_PE0_TX_C_DN(7)    I35 @S9S_MB_2U_LIB.S9S_MB_2U(SCH_1):PAGE164
     2 P5E_CPU0_PE0_TX_DN<7> @S9S_MB_2U_LIB.S9S_MB_2U(SCH_1):P5E_CPU0_PE0_TX_DN(7)    I35 @S9S_MB_2U_LIB.S9S_MB_2U(SCH_1):PAGE164

C919 Q_CAP_DIFFBUS_C0201-DIFF BUS_0A
     1 P5E_CPU0_PE0_TX_C_DP<7> @S9S_MB_2U_LIB.S9S_MB_2U(SCH_1):P5E_CPU0_PE0_TX_C_DP(7)    I36 @S9S_MB_2U_LIB.S9S_MB_2U(SCH_1):PAGE164
     2 P5E_CPU0_PE0_TX_DP<7> @S9S_MB_2U_LIB.S9S_MB_2U(SCH_1):P5E_CPU0_PE0_TX_DP(7)    I36 @S9S_MB_2U_LIB.S9S_MB_2U(SCH_1):PAGE164

C920 Q_CAP_DIFFBUS_C0201-DIFF BUS_0A
     1 P5E_CPU0_PE0_TX_C_DN<6> @S9S_MB_2U_LIB.S9S_MB_2U(SCH_1):P5E_CPU0_PE0_TX_C_DN(6)    I34 @S9S_MB_2U_LIB.S9S_MB_2U(SCH_1):PAGE164
     2 P5E_CPU0_PE0_TX_DN<6> @S9S_MB_2U_LIB.S9S_MB_2U(SCH_1):P5E_CPU0_PE0_TX_DN(6)    I34 @S9S_MB_2U_LIB.S9S_MB_2U(SCH_1):PAGE164

C921 Q_CAP_DIFFBUS_C0201-DIFF BUS_0A
     1 P5E_CPU0_PE0_TX_C_DP<6> @S9S_MB_2U_LIB.S9S_MB_2U(SCH_1):P5E_CPU0_PE0_TX_C_DP(6)    I33 @S9S_MB_2U_LIB.S9S_MB_2U(SCH_1):PAGE164
     2 P5E_CPU0_PE0_TX_DP<6> @S9S_MB_2U_LIB.S9S_MB_2U(SCH_1):P5E_CPU0_PE0_TX_DP(6)    I33 @S9S_MB_2U_LIB.S9S_MB_2U(SCH_1):PAGE164

C922 Q_CAP_DIFFBUS_C0201-DIFF BUS_0A
     1 P5E_CPU0_PE0_TX_C_DN<5> @S9S_MB_2U_LIB.S9S_MB_2U(SCH_1):P5E_CPU0_PE0_TX_C_DN(5)    I32 @S9S_MB_2U_LIB.S9S_MB_2U(SCH_1):PAGE164
     2 P5E_CPU0_PE0_TX_DN<5> @S9S_MB_2U_LIB.S9S_MB_2U(SCH_1):P5E_CPU0_PE0_TX_DN(5)    I32 @S9S_MB_2U_LIB.S9S_MB_2U(SCH_1):PAGE164

C923 Q_CAP_DIFFBUS_C0201-DIFF BUS_0A
     1 P5E_CPU0_PE0_TX_C_DP<5> @S9S_MB_2U_LIB.S9S_MB_2U(SCH_1):P5E_CPU0_PE0_TX_C_DP(5)    I31 @S9S_MB_2U_LIB.S9S_MB_2U(SCH_1):PAGE164
     2 P5E_CPU0_PE0_TX_DP<5> @S9S_MB_2U_LIB.S9S_MB_2U(SCH_1):P5E_CPU0_PE0_TX_DP(5)    I31 @S9S_MB_2U_LIB.S9S_MB_2U(SCH_1):PAGE164

C924 Q_CAP_DIFFBUS_C0201-DIFF BUS_0A
     1 P5E_CPU0_PE0_TX_C_DN<4> @S9S_MB_2U_LIB.S9S_MB_2U(SCH_1):P5E_CPU0_PE0_TX_C_DN(4)    I30 @S9S_MB_2U_LIB.S9S_MB_2U(SCH_1):PAGE164
     2 P5E_CPU0_PE0_TX_DN<4> @S9S_MB_2U_LIB.S9S_MB_2U(SCH_1):P5E_CPU0_PE0_TX_DN(4)    I30 @S9S_MB_2U_LIB.S9S_MB_2U(SCH_1):PAGE164

C925 Q_CAP_DIFFBUS_C0201-DIFF BUS_0A
     1 P5E_CPU0_PE0_TX_C_DP<4> @S9S_MB_2U_LIB.S9S_MB_2U(SCH_1):P5E_CPU0_PE0_TX_C_DP(4)    I29 @S9S_MB_2U_LIB.S9S_MB_2U(SCH_1):PAGE164
     2 P5E_CPU0_PE0_TX_DP<4> @S9S_MB_2U_LIB.S9S_MB_2U(SCH_1):P5E_CPU0_PE0_TX_DP(4)    I29 @S9S_MB_2U_LIB.S9S_MB_2U(SCH_1):PAGE164

C926 Q_CAP_DIFFBUS_C0201-DIFF BUS_0A
     1 P5E_CPU0_PE0_TX_C_DN<3> @S9S_MB_2U_LIB.S9S_MB_2U(SCH_1):P5E_CPU0_PE0_TX_C_DN(3)    I28 @S9S_MB_2U_LIB.S9S_MB_2U(SCH_1):PAGE164
     2 P5E_CPU0_PE0_TX_DN<3> @S9S_MB_2U_LIB.S9S_MB_2U(SCH_1):P5E_CPU0_PE0_TX_DN(3)    I28 @S9S_MB_2U_LIB.S9S_MB_2U(SCH_1):PAGE164

C927 Q_CAP_DIFFBUS_C0201-DIFF BUS_0A
     1 P5E_CPU0_PE0_TX_C_DP<3> @S9S_MB_2U_LIB.S9S_MB_2U(SCH_1):P5E_CPU0_PE0_TX_C_DP(3)    I27 @S9S_MB_2U_LIB.S9S_MB_2U(SCH_1):PAGE164
     2 P5E_CPU0_PE0_TX_DP<3> @S9S_MB_2U_LIB.S9S_MB_2U(SCH_1):P5E_CPU0_PE0_TX_DP(3)    I27 @S9S_MB_2U_LIB.S9S_MB_2U(SCH_1):PAGE164

C928 Q_CAP_DIFFBUS_C0201-DIFF BUS_0A
     1 P5E_CPU0_PE0_TX_C_DN<2> @S9S_MB_2U_LIB.S9S_MB_2U(SCH_1):P5E_CPU0_PE0_TX_C_DN(2)    I25 @S9S_MB_2U_LIB.S9S_MB_2U(SCH_1):PAGE164
     2 P5E_CPU0_PE0_TX_DN<2> @S9S_MB_2U_LIB.S9S_MB_2U(SCH_1):P5E_CPU0_PE0_TX_DN(2)    I25 @S9S_MB_2U_LIB.S9S_MB_2U(SCH_1):PAGE164

C929 Q_CAP_DIFFBUS_C0201-DIFF BUS_0A
     1 P5E_CPU0_PE0_TX_C_DP<2> @S9S_MB_2U_LIB.S9S_MB_2U(SCH_1):P5E_CPU0_PE0_TX_C_DP(2)    I26 @S9S_MB_2U_LIB.S9S_MB_2U(SCH_1):PAGE164
     2 P5E_CPU0_PE0_TX_DP<2> @S9S_MB_2U_LIB.S9S_MB_2U(SCH_1):P5E_CPU0_PE0_TX_DP(2)    I26 @S9S_MB_2U_LIB.S9S_MB_2U(SCH_1):PAGE164

C930 Q_CAP_DIFFBUS_C0201-DIFF BUS_0A
     1 P5E_CPU0_PE0_TX_C_DN<1> @S9S_MB_2U_LIB.S9S_MB_2U(SCH_1):P5E_CPU0_PE0_TX_C_DN(1)    I24 @S9S_MB_2U_LIB.S9S_MB_2U(SCH_1):PAGE164
     2 P5E_CPU0_PE0_TX_DN<1> @S9S_MB_2U_LIB.S9S_MB_2U(SCH_1):P5E_CPU0_PE0_TX_DN(1)    I24 @S9S_MB_2U_LIB.S9S_MB_2U(SCH_1):PAGE164

C931 Q_CAP_DIFFBUS_C0201-DIFF BUS_0A
     1 P5E_CPU0_PE0_TX_C_DP<1> @S9S_MB_2U_LIB.S9S_MB_2U(SCH_1):P5E_CPU0_PE0_TX_C_DP(1)    I23 @S9S_MB_2U_LIB.S9S_MB_2U(SCH_1):PAGE164
     2 P5E_CPU0_PE0_TX_DP<1> @S9S_MB_2U_LIB.S9S_MB_2U(SCH_1):P5E_CPU0_PE0_TX_DP(1)    I23 @S9S_MB_2U_LIB.S9S_MB_2U(SCH_1):PAGE164

C932 Q_CAP_DIFFBUS_C0201-DIFF BUS_0A
     1 P5E_CPU0_PE0_TX_C_DN<0> @S9S_MB_2U_LIB.S9S_MB_2U(SCH_1):P5E_CPU0_PE0_TX_C_DN(0)    I21 @S9S_MB_2U_LIB.S9S_MB_2U(SCH_1):PAGE164
     2 P5E_CPU0_PE0_TX_DN<0> @S9S_MB_2U_LIB.S9S_MB_2U(SCH_1):P5E_CPU0_PE0_TX_DN(0)    I21 @S9S_MB_2U_LIB.S9S_MB_2U(SCH_1):PAGE164

C933 Q_CAP_DIFFBUS_C0201-DIFF BUS_0A
     1 P5E_CPU0_PE0_TX_C_DP<0> @S9S_MB_2U_LIB.S9S_MB_2U(SCH_1):P5E_CPU0_PE0_TX_C_DP(0)    I22 @S9S_MB_2U_LIB.S9S_MB_2U(SCH_1):PAGE164
     2 P5E_CPU0_PE0_TX_DP<0> @S9S_MB_2U_LIB.S9S_MB_2U(SCH_1):P5E_CPU0_PE0_TX_DP(0)    I22 @S9S_MB_2U_LIB.S9S_MB_2U(SCH_1):PAGE164

C934 Q_CAP_DIFFBUS_C0201-DIFF BUS_0A
     1 P5E_CPU0_PE2_TX_C_DN<15> @S9S_MB_2U_LIB.S9S_MB_2U(SCH_1):P5E_CPU0_PE2_TX_C_DN(15)   I169 @S9S_MB_2U_LIB.S9S_MB_2U(SCH_1):PAGE164
     2 P5E_CPU0_PE2_TX_DN<15> @S9S_MB_2U_LIB.S9S_MB_2U(SCH_1):P5E_CPU0_PE2_TX_DN(15)   I169 @S9S_MB_2U_LIB.S9S_MB_2U(SCH_1):PAGE164

C935 Q_CAP_DIFFBUS_C0201-DIFF BUS_0A
     1 P5E_CPU0_PE2_TX_C_DP<15> @S9S_MB_2U_LIB.S9S_MB_2U(SCH_1):P5E_CPU0_PE2_TX_C_DP(15)   I168 @S9S_MB_2U_LIB.S9S_MB_2U(SCH_1):PAGE164
     2 P5E_CPU0_PE2_TX_DP<15> @S9S_MB_2U_LIB.S9S_MB_2U(SCH_1):P5E_CPU0_PE2_TX_DP(15)   I168 @S9S_MB_2U_LIB.S9S_MB_2U(SCH_1):PAGE164

C936 Q_CAP_DIFFBUS_C0201-DIFF BUS_0A
     1 P5E_CPU0_PE2_TX_C_DN<14> @S9S_MB_2U_LIB.S9S_MB_2U(SCH_1):P5E_CPU0_PE2_TX_C_DN(14)   I167 @S9S_MB_2U_LIB.S9S_MB_2U(SCH_1):PAGE164
     2 P5E_CPU0_PE2_TX_DN<14> @S9S_MB_2U_LIB.S9S_MB_2U(SCH_1):P5E_CPU0_PE2_TX_DN(14)   I167 @S9S_MB_2U_LIB.S9S_MB_2U(SCH_1):PAGE164

C937 Q_CAP_DIFFBUS_C0201-DIFF BUS_0A
     1 P5E_CPU0_PE2_TX_C_DP<14> @S9S_MB_2U_LIB.S9S_MB_2U(SCH_1):P5E_CPU0_PE2_TX_C_DP(14)   I166 @S9S_MB_2U_LIB.S9S_MB_2U(SCH_1):PAGE164
     2 P5E_CPU0_PE2_TX_DP<14> @S9S_MB_2U_LIB.S9S_MB_2U(SCH_1):P5E_CPU0_PE2_TX_DP(14)   I166 @S9S_MB_2U_LIB.S9S_MB_2U(SCH_1):PAGE164

C938 Q_CAP_DIFFBUS_C0201-DIFF BUS_0A
     1 P5E_CPU0_PE2_TX_C_DN<13> @S9S_MB_2U_LIB.S9S_MB_2U(SCH_1):P5E_CPU0_PE2_TX_C_DN(13)   I165 @S9S_MB_2U_LIB.S9S_MB_2U(SCH_1):PAGE164
     2 P5E_CPU0_PE2_TX_DN<13> @S9S_MB_2U_LIB.S9S_MB_2U(SCH_1):P5E_CPU0_PE2_TX_DN(13)   I165 @S9S_MB_2U_LIB.S9S_MB_2U(SCH_1):PAGE164

C939 Q_CAP_DIFFBUS_C0201-DIFF BUS_0A
     1 P5E_CPU0_PE2_TX_C_DP<13> @S9S_MB_2U_LIB.S9S_MB_2U(SCH_1):P5E_CPU0_PE2_TX_C_DP(13)   I164 @S9S_MB_2U_LIB.S9S_MB_2U(SCH_1):PAGE164
     2 P5E_CPU0_PE2_TX_DP<13> @S9S_MB_2U_LIB.S9S_MB_2U(SCH_1):P5E_CPU0_PE2_TX_DP(13)   I164 @S9S_MB_2U_LIB.S9S_MB_2U(SCH_1):PAGE164

C940 Q_CAP_DIFFBUS_C0201-DIFF BUS_0A
     1 P5E_CPU0_PE2_TX_C_DN<12> @S9S_MB_2U_LIB.S9S_MB_2U(SCH_1):P5E_CPU0_PE2_TX_C_DN(12)   I160 @S9S_MB_2U_LIB.S9S_MB_2U(SCH_1):PAGE164
     2 P5E_CPU0_PE2_TX_DN<12> @S9S_MB_2U_LIB.S9S_MB_2U(SCH_1):P5E_CPU0_PE2_TX_DN(12)   I160 @S9S_MB_2U_LIB.S9S_MB_2U(SCH_1):PAGE164

C941 Q_CAP_DIFFBUS_C0201-DIFF BUS_0A
     1 P5E_CPU0_PE2_TX_C_DP<12> @S9S_MB_2U_LIB.S9S_MB_2U(SCH_1):P5E_CPU0_PE2_TX_C_DP(12)   I159 @S9S_MB_2U_LIB.S9S_MB_2U(SCH_1):PAGE164
     2 P5E_CPU0_PE2_TX_DP<12> @S9S_MB_2U_LIB.S9S_MB_2U(SCH_1):P5E_CPU0_PE2_TX_DP(12)   I159 @S9S_MB_2U_LIB.S9S_MB_2U(SCH_1):PAGE164

C942 Q_CAP_DIFFBUS_C0201-DIFF BUS_0A
     1 P5E_CPU0_PE2_TX_C_DN<11> @S9S_MB_2U_LIB.S9S_MB_2U(SCH_1):P5E_CPU0_PE2_TX_C_DN(11)   I158 @S9S_MB_2U_LIB.S9S_MB_2U(SCH_1):PAGE164
     2 P5E_CPU0_PE2_TX_DN<11> @S9S_MB_2U_LIB.S9S_MB_2U(SCH_1):P5E_CPU0_PE2_TX_DN(11)   I158 @S9S_MB_2U_LIB.S9S_MB_2U(SCH_1):PAGE164

C943 Q_CAP_DIFFBUS_C0201-DIFF BUS_0A
     1 P5E_CPU0_PE2_TX_C_DP<11> @S9S_MB_2U_LIB.S9S_MB_2U(SCH_1):P5E_CPU0_PE2_TX_C_DP(11)   I157 @S9S_MB_2U_LIB.S9S_MB_2U(SCH_1):PAGE164
     2 P5E_CPU0_PE2_TX_DP<11> @S9S_MB_2U_LIB.S9S_MB_2U(SCH_1):P5E_CPU0_PE2_TX_DP(11)   I157 @S9S_MB_2U_LIB.S9S_MB_2U(SCH_1):PAGE164

C944 Q_CAP_DIFFBUS_C0201-DIFF BUS_0A
     1 P5E_CPU0_PE2_TX_C_DN<10> @S9S_MB_2U_LIB.S9S_MB_2U(SCH_1):P5E_CPU0_PE2_TX_C_DN(10)   I156 @S9S_MB_2U_LIB.S9S_MB_2U(SCH_1):PAGE164
     2 P5E_CPU0_PE2_TX_DN<10> @S9S_MB_2U_LIB.S9S_MB_2U(SCH_1):P5E_CPU0_PE2_TX_DN(10)   I156 @S9S_MB_2U_LIB.S9S_MB_2U(SCH_1):PAGE164

C945 Q_CAP_DIFFBUS_C0201-DIFF BUS_0A
     1 P5E_CPU0_PE2_TX_C_DP<10> @S9S_MB_2U_LIB.S9S_MB_2U(SCH_1):P5E_CPU0_PE2_TX_C_DP(10)   I155 @S9S_MB_2U_LIB.S9S_MB_2U(SCH_1):PAGE164
     2 P5E_CPU0_PE2_TX_DP<10> @S9S_MB_2U_LIB.S9S_MB_2U(SCH_1):P5E_CPU0_PE2_TX_DP(10)   I155 @S9S_MB_2U_LIB.S9S_MB_2U(SCH_1):PAGE164

C946 Q_CAP_DIFFBUS_C0201-DIFF BUS_0A
     1 P5E_CPU0_PE2_TX_C_DN<9> @S9S_MB_2U_LIB.S9S_MB_2U(SCH_1):P5E_CPU0_PE2_TX_C_DN(9)   I154 @S9S_MB_2U_LIB.S9S_MB_2U(SCH_1):PAGE164
     2 P5E_CPU0_PE2_TX_DN<9> @S9S_MB_2U_LIB.S9S_MB_2U(SCH_1):P5E_CPU0_PE2_TX_DN(9)   I154 @S9S_MB_2U_LIB.S9S_MB_2U(SCH_1):PAGE164

C947 Q_CAP_DIFFBUS_C0201-DIFF BUS_0A
     1 P5E_CPU0_PE2_TX_C_DP<9> @S9S_MB_2U_LIB.S9S_MB_2U(SCH_1):P5E_CPU0_PE2_TX_C_DP(9)   I153 @S9S_MB_2U_LIB.S9S_MB_2U(SCH_1):PAGE164
     2 P5E_CPU0_PE2_TX_DP<9> @S9S_MB_2U_LIB.S9S_MB_2U(SCH_1):P5E_CPU0_PE2_TX_DP(9)   I153 @S9S_MB_2U_LIB.S9S_MB_2U(SCH_1):PAGE164

C948 Q_CAP_DIFFBUS_C0201-DIFF BUS_0A
     1 P5E_CPU0_PE2_TX_C_DN<8> @S9S_MB_2U_LIB.S9S_MB_2U(SCH_1):P5E_CPU0_PE2_TX_C_DN(8)   I152 @S9S_MB_2U_LIB.S9S_MB_2U(SCH_1):PAGE164
     2 P5E_CPU0_PE2_TX_DN<8> @S9S_MB_2U_LIB.S9S_MB_2U(SCH_1):P5E_CPU0_PE2_TX_DN(8)   I152 @S9S_MB_2U_LIB.S9S_MB_2U(SCH_1):PAGE164

C949 Q_CAP_DIFFBUS_C0201-DIFF BUS_0A
     1 P5E_CPU0_PE2_TX_C_DP<8> @S9S_MB_2U_LIB.S9S_MB_2U(SCH_1):P5E_CPU0_PE2_TX_C_DP(8)   I151 @S9S_MB_2U_LIB.S9S_MB_2U(SCH_1):PAGE164
     2 P5E_CPU0_PE2_TX_DP<8> @S9S_MB_2U_LIB.S9S_MB_2U(SCH_1):P5E_CPU0_PE2_TX_DP(8)   I151 @S9S_MB_2U_LIB.S9S_MB_2U(SCH_1):PAGE164

C950 Q_CAP_DIFFBUS_C0201-DIFF BUS_0A
     1 P5E_CPU0_PE2_TX_C_DN<7> @S9S_MB_2U_LIB.S9S_MB_2U(SCH_1):P5E_CPU0_PE2_TX_C_DN(7)   I137 @S9S_MB_2U_LIB.S9S_MB_2U(SCH_1):PAGE164
     2 P5E_CPU0_PE2_TX_DN<7> @S9S_MB_2U_LIB.S9S_MB_2U(SCH_1):P5E_CPU0_PE2_TX_DN(7)   I137 @S9S_MB_2U_LIB.S9S_MB_2U(SCH_1):PAGE164

C951 Q_CAP_DIFFBUS_C0201-DIFF BUS_0A
     1 P5E_CPU0_PE2_TX_C_DP<7> @S9S_MB_2U_LIB.S9S_MB_2U(SCH_1):P5E_CPU0_PE2_TX_C_DP(7)   I136 @S9S_MB_2U_LIB.S9S_MB_2U(SCH_1):PAGE164
     2 P5E_CPU0_PE2_TX_DP<7> @S9S_MB_2U_LIB.S9S_MB_2U(SCH_1):P5E_CPU0_PE2_TX_DP(7)   I136 @S9S_MB_2U_LIB.S9S_MB_2U(SCH_1):PAGE164

C952 Q_CAP_DIFFBUS_C0201-DIFF BUS_0A
     1 P5E_CPU0_PE2_TX_C_DN<6> @S9S_MB_2U_LIB.S9S_MB_2U(SCH_1):P5E_CPU0_PE2_TX_C_DN(6)   I135 @S9S_MB_2U_LIB.S9S_MB_2U(SCH_1):PAGE164
     2 P5E_CPU0_PE2_TX_DN<6> @S9S_MB_2U_LIB.S9S_MB_2U(SCH_1):P5E_CPU0_PE2_TX_DN(6)   I135 @S9S_MB_2U_LIB.S9S_MB_2U(SCH_1):PAGE164

C953 Q_CAP_DIFFBUS_C0201-DIFF BUS_0A
     1 P5E_CPU0_PE2_TX_C_DP<6> @S9S_MB_2U_LIB.S9S_MB_2U(SCH_1):P5E_CPU0_PE2_TX_C_DP(6)   I134 @S9S_MB_2U_LIB.S9S_MB_2U(SCH_1):PAGE164
     2 P5E_CPU0_PE2_TX_DP<6> @S9S_MB_2U_LIB.S9S_MB_2U(SCH_1):P5E_CPU0_PE2_TX_DP(6)   I134 @S9S_MB_2U_LIB.S9S_MB_2U(SCH_1):PAGE164

C954 Q_CAP_DIFFBUS_C0201-DIFF BUS_0A
     1 P5E_CPU0_PE2_TX_C_DN<5> @S9S_MB_2U_LIB.S9S_MB_2U(SCH_1):P5E_CPU0_PE2_TX_C_DN(5)   I133 @S9S_MB_2U_LIB.S9S_MB_2U(SCH_1):PAGE164
     2 P5E_CPU0_PE2_TX_DN<5> @S9S_MB_2U_LIB.S9S_MB_2U(SCH_1):P5E_CPU0_PE2_TX_DN(5)   I133 @S9S_MB_2U_LIB.S9S_MB_2U(SCH_1):PAGE164

C955 Q_CAP_DIFFBUS_C0201-DIFF BUS_0A
     1 P5E_CPU0_PE2_TX_C_DP<5> @S9S_MB_2U_LIB.S9S_MB_2U(SCH_1):P5E_CPU0_PE2_TX_C_DP(5)   I208 @S9S_MB_2U_LIB.S9S_MB_2U(SCH_1):PAGE164
     2 P5E_CPU0_PE2_TX_DP<5> @S9S_MB_2U_LIB.S9S_MB_2U(SCH_1):P5E_CPU0_PE2_TX_DP(5)   I208 @S9S_MB_2U_LIB.S9S_MB_2U(SCH_1):PAGE164

C956 Q_CAP_DIFFBUS_C0201-DIFF BUS_0A
     1 P5E_CPU0_PE2_TX_C_DN<4> @S9S_MB_2U_LIB.S9S_MB_2U(SCH_1):P5E_CPU0_PE2_TX_C_DN(4)   I207 @S9S_MB_2U_LIB.S9S_MB_2U(SCH_1):PAGE164
     2 P5E_CPU0_PE2_TX_DN<4> @S9S_MB_2U_LIB.S9S_MB_2U(SCH_1):P5E_CPU0_PE2_TX_DN(4)   I207 @S9S_MB_2U_LIB.S9S_MB_2U(SCH_1):PAGE164

C957 Q_CAP_DIFFBUS_C0201-DIFF BUS_0A
     1 P5E_CPU0_PE2_TX_C_DP<4> @S9S_MB_2U_LIB.S9S_MB_2U(SCH_1):P5E_CPU0_PE2_TX_C_DP(4)   I206 @S9S_MB_2U_LIB.S9S_MB_2U(SCH_1):PAGE164
     2 P5E_CPU0_PE2_TX_DP<4> @S9S_MB_2U_LIB.S9S_MB_2U(SCH_1):P5E_CPU0_PE2_TX_DP(4)   I206 @S9S_MB_2U_LIB.S9S_MB_2U(SCH_1):PAGE164

C958 Q_CAP_DIFFBUS_C0201-DIFF BUS_0A
     1 P5E_CPU0_PE2_TX_C_DN<3> @S9S_MB_2U_LIB.S9S_MB_2U(SCH_1):P5E_CPU0_PE2_TX_C_DN(3)   I128 @S9S_MB_2U_LIB.S9S_MB_2U(SCH_1):PAGE164
     2 P5E_CPU0_PE2_TX_DN<3> @S9S_MB_2U_LIB.S9S_MB_2U(SCH_1):P5E_CPU0_PE2_TX_DN(3)   I128 @S9S_MB_2U_LIB.S9S_MB_2U(SCH_1):PAGE164

C959 Q_CAP_DIFFBUS_C0201-DIFF BUS_0A
     1 P5E_CPU0_PE2_TX_C_DP<3> @S9S_MB_2U_LIB.S9S_MB_2U(SCH_1):P5E_CPU0_PE2_TX_C_DP(3)   I127 @S9S_MB_2U_LIB.S9S_MB_2U(SCH_1):PAGE164
     2 P5E_CPU0_PE2_TX_DP<3> @S9S_MB_2U_LIB.S9S_MB_2U(SCH_1):P5E_CPU0_PE2_TX_DP(3)   I127 @S9S_MB_2U_LIB.S9S_MB_2U(SCH_1):PAGE164

C960 Q_CAP_DIFFBUS_C0201-DIFF BUS_0A
     1 P5E_CPU0_PE2_TX_C_DN<2> @S9S_MB_2U_LIB.S9S_MB_2U(SCH_1):P5E_CPU0_PE2_TX_C_DN(2)   I126 @S9S_MB_2U_LIB.S9S_MB_2U(SCH_1):PAGE164
     2 P5E_CPU0_PE2_TX_DN<2> @S9S_MB_2U_LIB.S9S_MB_2U(SCH_1):P5E_CPU0_PE2_TX_DN(2)   I126 @S9S_MB_2U_LIB.S9S_MB_2U(SCH_1):PAGE164

C961 Q_CAP_DIFFBUS_C0201-DIFF BUS_0A
     1 P5E_CPU0_PE2_TX_C_DP<2> @S9S_MB_2U_LIB.S9S_MB_2U(SCH_1):P5E_CPU0_PE2_TX_C_DP(2)   I125 @S9S_MB_2U_LIB.S9S_MB_2U(SCH_1):PAGE164
     2 P5E_CPU0_PE2_TX_DP<2> @S9S_MB_2U_LIB.S9S_MB_2U(SCH_1):P5E_CPU0_PE2_TX_DP(2)   I125 @S9S_MB_2U_LIB.S9S_MB_2U(SCH_1):PAGE164

C962 Q_CAP_DIFFBUS_C0201-DIFF BUS_0A
     1 P5E_CPU0_PE2_TX_C_DN<1> @S9S_MB_2U_LIB.S9S_MB_2U(SCH_1):P5E_CPU0_PE2_TX_C_DN(1)   I124 @S9S_MB_2U_LIB.S9S_MB_2U(SCH_1):PAGE164
     2 P5E_CPU0_PE2_TX_DN<1> @S9S_MB_2U_LIB.S9S_MB_2U(SCH_1):P5E_CPU0_PE2_TX_DN(1)   I124 @S9S_MB_2U_LIB.S9S_MB_2U(SCH_1):PAGE164

C963 Q_CAP_DIFFBUS_C0201-DIFF BUS_0A
     1 P5E_CPU0_PE2_TX_C_DP<1> @S9S_MB_2U_LIB.S9S_MB_2U(SCH_1):P5E_CPU0_PE2_TX_C_DP(1)   I123 @S9S_MB_2U_LIB.S9S_MB_2U(SCH_1):PAGE164
     2 P5E_CPU0_PE2_TX_DP<1> @S9S_MB_2U_LIB.S9S_MB_2U(SCH_1):P5E_CPU0_PE2_TX_DP(1)   I123 @S9S_MB_2U_LIB.S9S_MB_2U(SCH_1):PAGE164

C964 Q_CAP_DIFFBUS_C0201-DIFF BUS_0A
     1 P5E_CPU0_PE2_TX_C_DN<0> @S9S_MB_2U_LIB.S9S_MB_2U(SCH_1):P5E_CPU0_PE2_TX_C_DN(0)   I122 @S9S_MB_2U_LIB.S9S_MB_2U(SCH_1):PAGE164
     2 P5E_CPU0_PE2_TX_DN<0> @S9S_MB_2U_LIB.S9S_MB_2U(SCH_1):P5E_CPU0_PE2_TX_DN(0)   I122 @S9S_MB_2U_LIB.S9S_MB_2U(SCH_1):PAGE164

C965 Q_CAP_DIFFBUS_C0201-DIFF BUS_0A
     1 P5E_CPU0_PE2_TX_C_DP<0> @S9S_MB_2U_LIB.S9S_MB_2U(SCH_1):P5E_CPU0_PE2_TX_C_DP(0)   I121 @S9S_MB_2U_LIB.S9S_MB_2U(SCH_1):PAGE164
     2 P5E_CPU0_PE2_TX_DP<0> @S9S_MB_2U_LIB.S9S_MB_2U(SCH_1):P5E_CPU0_PE2_TX_DP(0)   I121 @S9S_MB_2U_LIB.S9S_MB_2U(SCH_1):PAGE164

C966 Q_CAP_C0402-10UF,6.3V,20%,X6S,B
     1 PVCCIN_CPU0 @S9S_MB_2U_LIB.S9S_MB_2U(SCH_1):PVCCIN_CPU0    I27 @S9S_MB_2U_LIB.S9S_MB_2U(SCH_1):PAGE74
     2    GND @S9S_MB_2U_LIB.S9S_MB_2U(SCH_1):GND    I27 @S9S_MB_2U_LIB.S9S_MB_2U(SCH_1):PAGE74

C967 Q_CAP_C0402-10UF,6.3V,20%,X6S,B
     1 PVCCIN_CPU0 @S9S_MB_2U_LIB.S9S_MB_2U(SCH_1):PVCCIN_CPU0    I25 @S9S_MB_2U_LIB.S9S_MB_2U(SCH_1):PAGE74
     2    GND @S9S_MB_2U_LIB.S9S_MB_2U(SCH_1):GND    I25 @S9S_MB_2U_LIB.S9S_MB_2U(SCH_1):PAGE74

C968 Q_CAP_C0402-10UF,6.3V,20%,X6S,B
     1 PVCCIN_CPU0 @S9S_MB_2U_LIB.S9S_MB_2U(SCH_1):PVCCIN_CPU0    I23 @S9S_MB_2U_LIB.S9S_MB_2U(SCH_1):PAGE74
     2    GND @S9S_MB_2U_LIB.S9S_MB_2U(SCH_1):GND    I23 @S9S_MB_2U_LIB.S9S_MB_2U(SCH_1):PAGE74

C969 Q_CAP_C0402-10UF,6.3V,20%,X6S,B
     1 PVCCIN_CPU0 @S9S_MB_2U_LIB.S9S_MB_2U(SCH_1):PVCCIN_CPU0    I15 @S9S_MB_2U_LIB.S9S_MB_2U(SCH_1):PAGE74
     2    GND @S9S_MB_2U_LIB.S9S_MB_2U(SCH_1):GND    I15 @S9S_MB_2U_LIB.S9S_MB_2U(SCH_1):PAGE74

C970 Q_CAP_C0402-10UF,6.3V,20%,X6S,B
     1 PVCCIN_CPU0 @S9S_MB_2U_LIB.S9S_MB_2U(SCH_1):PVCCIN_CPU0    I31 @S9S_MB_2U_LIB.S9S_MB_2U(SCH_1):PAGE74
     2    GND @S9S_MB_2U_LIB.S9S_MB_2U(SCH_1):GND    I31 @S9S_MB_2U_LIB.S9S_MB_2U(SCH_1):PAGE74

C971 Q_CAP_C0402-10UF,6.3V,20%,X6S,B
     1 PVCCIN_CPU0 @S9S_MB_2U_LIB.S9S_MB_2U(SCH_1):PVCCIN_CPU0    I30 @S9S_MB_2U_LIB.S9S_MB_2U(SCH_1):PAGE74
     2    GND @S9S_MB_2U_LIB.S9S_MB_2U(SCH_1):GND    I30 @S9S_MB_2U_LIB.S9S_MB_2U(SCH_1):PAGE74

C972 Q_CAP_C0402-10UF,6.3V,20%,X6S,B
     1 PVCCIN_CPU0 @S9S_MB_2U_LIB.S9S_MB_2U(SCH_1):PVCCIN_CPU0    I28 @S9S_MB_2U_LIB.S9S_MB_2U(SCH_1):PAGE74
     2    GND @S9S_MB_2U_LIB.S9S_MB_2U(SCH_1):GND    I28 @S9S_MB_2U_LIB.S9S_MB_2U(SCH_1):PAGE74

C973 Q_CAP_C0402-10UF,6.3V,20%,X6S,B
     1 PVCCIN_CPU0 @S9S_MB_2U_LIB.S9S_MB_2U(SCH_1):PVCCIN_CPU0    I21 @S9S_MB_2U_LIB.S9S_MB_2U(SCH_1):PAGE74
     2    GND @S9S_MB_2U_LIB.S9S_MB_2U(SCH_1):GND    I21 @S9S_MB_2U_LIB.S9S_MB_2U(SCH_1):PAGE74

C974 Q_CAP_C0402-10UF,6.3V,20%,X6S,B
     1 PVCCIN_CPU0 @S9S_MB_2U_LIB.S9S_MB_2U(SCH_1):PVCCIN_CPU0    I33 @S9S_MB_2U_LIB.S9S_MB_2U(SCH_1):PAGE74
     2    GND @S9S_MB_2U_LIB.S9S_MB_2U(SCH_1):GND    I33 @S9S_MB_2U_LIB.S9S_MB_2U(SCH_1):PAGE74

C975 Q_CAP_C0402-10UF,6.3V,20%,X6S,B
     1 PVCCIN_CPU0 @S9S_MB_2U_LIB.S9S_MB_2U(SCH_1):PVCCIN_CPU0    I32 @S9S_MB_2U_LIB.S9S_MB_2U(SCH_1):PAGE74
     2    GND @S9S_MB_2U_LIB.S9S_MB_2U(SCH_1):GND    I32 @S9S_MB_2U_LIB.S9S_MB_2U(SCH_1):PAGE74

C976 Q_CAP_C0402-10UF,6.3V,20%,X6S,B
     1 PVCCIN_CPU0 @S9S_MB_2U_LIB.S9S_MB_2U(SCH_1):PVCCIN_CPU0    I29 @S9S_MB_2U_LIB.S9S_MB_2U(SCH_1):PAGE74
     2    GND @S9S_MB_2U_LIB.S9S_MB_2U(SCH_1):GND    I29 @S9S_MB_2U_LIB.S9S_MB_2U(SCH_1):PAGE74

C977 Q_CAP_C0402-10UF,6.3V,20%,X6S,B
     1 PVCCIN_CPU0 @S9S_MB_2U_LIB.S9S_MB_2U(SCH_1):PVCCIN_CPU0    I22 @S9S_MB_2U_LIB.S9S_MB_2U(SCH_1):PAGE74
     2    GND @S9S_MB_2U_LIB.S9S_MB_2U(SCH_1):GND    I22 @S9S_MB_2U_LIB.S9S_MB_2U(SCH_1):PAGE74

C978 Q_CAP_C0402-10UF,6.3V,20%,X6S,B
     1 PVCCIN_CPU0 @S9S_MB_2U_LIB.S9S_MB_2U(SCH_1):PVCCIN_CPU0    I51 @S9S_MB_2U_LIB.S9S_MB_2U(SCH_1):PAGE74
     2    GND @S9S_MB_2U_LIB.S9S_MB_2U(SCH_1):GND    I51 @S9S_MB_2U_LIB.S9S_MB_2U(SCH_1):PAGE74

C979 Q_CAP_C0402-10UF,6.3V,20%,X6S,B
     1 PVCCIN_CPU0 @S9S_MB_2U_LIB.S9S_MB_2U(SCH_1):PVCCIN_CPU0    I50 @S9S_MB_2U_LIB.S9S_MB_2U(SCH_1):PAGE74
     2    GND @S9S_MB_2U_LIB.S9S_MB_2U(SCH_1):GND    I50 @S9S_MB_2U_LIB.S9S_MB_2U(SCH_1):PAGE74

C980 Q_CAP_C0402-10UF,6.3V,20%,X6S,B
     1 PVCCIN_CPU0 @S9S_MB_2U_LIB.S9S_MB_2U(SCH_1):PVCCIN_CPU0    I48 @S9S_MB_2U_LIB.S9S_MB_2U(SCH_1):PAGE74
     2    GND @S9S_MB_2U_LIB.S9S_MB_2U(SCH_1):GND    I48 @S9S_MB_2U_LIB.S9S_MB_2U(SCH_1):PAGE74

C981 Q_CAP_C0402-10UF,6.3V,20%,X6S,B
     1 PVCCIN_CPU0 @S9S_MB_2U_LIB.S9S_MB_2U(SCH_1):PVCCIN_CPU0    I37 @S9S_MB_2U_LIB.S9S_MB_2U(SCH_1):PAGE74
     2    GND @S9S_MB_2U_LIB.S9S_MB_2U(SCH_1):GND    I37 @S9S_MB_2U_LIB.S9S_MB_2U(SCH_1):PAGE74

C982 Q_CAP_C0402-10UF,6.3V,20%,X6S,B
     1 PVCCIN_CPU0 @S9S_MB_2U_LIB.S9S_MB_2U(SCH_1):PVCCIN_CPU0    I53 @S9S_MB_2U_LIB.S9S_MB_2U(SCH_1):PAGE74
     2    GND @S9S_MB_2U_LIB.S9S_MB_2U(SCH_1):GND    I53 @S9S_MB_2U_LIB.S9S_MB_2U(SCH_1):PAGE74

C983 Q_CAP_C0402-10UF,6.3V,20%,X6S,B
     1 PVCCIN_CPU0 @S9S_MB_2U_LIB.S9S_MB_2U(SCH_1):PVCCIN_CPU0    I52 @S9S_MB_2U_LIB.S9S_MB_2U(SCH_1):PAGE74
     2    GND @S9S_MB_2U_LIB.S9S_MB_2U(SCH_1):GND    I52 @S9S_MB_2U_LIB.S9S_MB_2U(SCH_1):PAGE74

C984 Q_CAP_C0402-10UF,6.3V,20%,X6S,B
     1 PVCCIN_CPU0 @S9S_MB_2U_LIB.S9S_MB_2U(SCH_1):PVCCIN_CPU0    I49 @S9S_MB_2U_LIB.S9S_MB_2U(SCH_1):PAGE74
     2    GND @S9S_MB_2U_LIB.S9S_MB_2U(SCH_1):GND    I49 @S9S_MB_2U_LIB.S9S_MB_2U(SCH_1):PAGE74

C985 Q_CAP_C0402-10UF,6.3V,20%,X6S,B
     1 PVCCIN_CPU0 @S9S_MB_2U_LIB.S9S_MB_2U(SCH_1):PVCCIN_CPU0    I38 @S9S_MB_2U_LIB.S9S_MB_2U(SCH_1):PAGE74
     2    GND @S9S_MB_2U_LIB.S9S_MB_2U(SCH_1):GND    I38 @S9S_MB_2U_LIB.S9S_MB_2U(SCH_1):PAGE74

C986 Q_CAP_C0402-10UF,6.3V,20%,X6S,B
     1 PVCCIN_CPU0 @S9S_MB_2U_LIB.S9S_MB_2U(SCH_1):PVCCIN_CPU0    I58 @S9S_MB_2U_LIB.S9S_MB_2U(SCH_1):PAGE74
     2    GND @S9S_MB_2U_LIB.S9S_MB_2U(SCH_1):GND    I58 @S9S_MB_2U_LIB.S9S_MB_2U(SCH_1):PAGE74

C987 Q_CAP_C0402-10UF,6.3V,20%,X6S,B
     1 PVCCIN_CPU0 @S9S_MB_2U_LIB.S9S_MB_2U(SCH_1):PVCCIN_CPU0    I57 @S9S_MB_2U_LIB.S9S_MB_2U(SCH_1):PAGE74
     2    GND @S9S_MB_2U_LIB.S9S_MB_2U(SCH_1):GND    I57 @S9S_MB_2U_LIB.S9S_MB_2U(SCH_1):PAGE74

C988 Q_CAP_C0402-10UF,6.3V,20%,X6S,B
     1 PVCCIN_CPU0 @S9S_MB_2U_LIB.S9S_MB_2U(SCH_1):PVCCIN_CPU0    I54 @S9S_MB_2U_LIB.S9S_MB_2U(SCH_1):PAGE74
     2    GND @S9S_MB_2U_LIB.S9S_MB_2U(SCH_1):GND    I54 @S9S_MB_2U_LIB.S9S_MB_2U(SCH_1):PAGE74

C989 Q_CAP_C0402-10UF,6.3V,20%,X6S,B
     1 PVCCIN_CPU0 @S9S_MB_2U_LIB.S9S_MB_2U(SCH_1):PVCCIN_CPU0    I45 @S9S_MB_2U_LIB.S9S_MB_2U(SCH_1):PAGE74
     2    GND @S9S_MB_2U_LIB.S9S_MB_2U(SCH_1):GND    I45 @S9S_MB_2U_LIB.S9S_MB_2U(SCH_1):PAGE74

C990 Q_CAP_C0402-10UF,6.3V,20%,X6S,B
     1 PVCCIN_CPU0 @S9S_MB_2U_LIB.S9S_MB_2U(SCH_1):PVCCIN_CPU0    I60 @S9S_MB_2U_LIB.S9S_MB_2U(SCH_1):PAGE74
     2    GND @S9S_MB_2U_LIB.S9S_MB_2U(SCH_1):GND    I60 @S9S_MB_2U_LIB.S9S_MB_2U(SCH_1):PAGE74

C991 Q_CAP_C0402-10UF,6.3V,20%,X6S,B
     1 PVCCIN_CPU0 @S9S_MB_2U_LIB.S9S_MB_2U(SCH_1):PVCCIN_CPU0    I59 @S9S_MB_2U_LIB.S9S_MB_2U(SCH_1):PAGE74
     2    GND @S9S_MB_2U_LIB.S9S_MB_2U(SCH_1):GND    I59 @S9S_MB_2U_LIB.S9S_MB_2U(SCH_1):PAGE74

C992 Q_CAP_C0402-10UF,6.3V,20%,X6S,B
     1 PVCCIN_CPU0 @S9S_MB_2U_LIB.S9S_MB_2U(SCH_1):PVCCIN_CPU0    I55 @S9S_MB_2U_LIB.S9S_MB_2U(SCH_1):PAGE74
     2    GND @S9S_MB_2U_LIB.S9S_MB_2U(SCH_1):GND    I55 @S9S_MB_2U_LIB.S9S_MB_2U(SCH_1):PAGE74

C993 Q_CAP_C0402-10UF,6.3V,20%,X6S,B
     1 PVCCIN_CPU0 @S9S_MB_2U_LIB.S9S_MB_2U(SCH_1):PVCCIN_CPU0    I46 @S9S_MB_2U_LIB.S9S_MB_2U(SCH_1):PAGE74
     2    GND @S9S_MB_2U_LIB.S9S_MB_2U(SCH_1):GND    I46 @S9S_MB_2U_LIB.S9S_MB_2U(SCH_1):PAGE74

C994 Q_CAP_C0402-10UF,6.3V,20%,X6S,B
     1 PVCCIN_CPU0 @S9S_MB_2U_LIB.S9S_MB_2U(SCH_1):PVCCIN_CPU0    I62 @S9S_MB_2U_LIB.S9S_MB_2U(SCH_1):PAGE74
     2    GND @S9S_MB_2U_LIB.S9S_MB_2U(SCH_1):GND    I62 @S9S_MB_2U_LIB.S9S_MB_2U(SCH_1):PAGE74

C995 Q_CAP_C0402-10UF,6.3V,20%,X6S,B
     1 PVCCIN_CPU0 @S9S_MB_2U_LIB.S9S_MB_2U(SCH_1):PVCCIN_CPU0    I61 @S9S_MB_2U_LIB.S9S_MB_2U(SCH_1):PAGE74
     2    GND @S9S_MB_2U_LIB.S9S_MB_2U(SCH_1):GND    I61 @S9S_MB_2U_LIB.S9S_MB_2U(SCH_1):PAGE74

C996 Q_CAP_C0402-10UF,6.3V,20%,X6S,B
     1 PVCCIN_CPU0 @S9S_MB_2U_LIB.S9S_MB_2U(SCH_1):PVCCIN_CPU0    I56 @S9S_MB_2U_LIB.S9S_MB_2U(SCH_1):PAGE74
     2    GND @S9S_MB_2U_LIB.S9S_MB_2U(SCH_1):GND    I56 @S9S_MB_2U_LIB.S9S_MB_2U(SCH_1):PAGE74

C997 Q_CAP_C0402-10UF,6.3V,20%,X6S,B
     1 PVCCIN_CPU0 @S9S_MB_2U_LIB.S9S_MB_2U(SCH_1):PVCCIN_CPU0    I47 @S9S_MB_2U_LIB.S9S_MB_2U(SCH_1):PAGE74
     2    GND @S9S_MB_2U_LIB.S9S_MB_2U(SCH_1):GND    I47 @S9S_MB_2U_LIB.S9S_MB_2U(SCH_1):PAGE74

C998 Q_CAP_C0402-10UF,6.3V,20%,X6S,B
     1 PVCCIN_CPU0 @S9S_MB_2U_LIB.S9S_MB_2U(SCH_1):PVCCIN_CPU0    I86 @S9S_MB_2U_LIB.S9S_MB_2U(SCH_1):PAGE74
     2    GND @S9S_MB_2U_LIB.S9S_MB_2U(SCH_1):GND    I86 @S9S_MB_2U_LIB.S9S_MB_2U(SCH_1):PAGE74

C999 Q_CAP_C0402-10UF,6.3V,20%,X6S,B
     1 PVCCIN_CPU0 @S9S_MB_2U_LIB.S9S_MB_2U(SCH_1):PVCCIN_CPU0    I85 @S9S_MB_2U_LIB.S9S_MB_2U(SCH_1):PAGE74
     2    GND @S9S_MB_2U_LIB.S9S_MB_2U(SCH_1):GND    I85 @S9S_MB_2U_LIB.S9S_MB_2U(SCH_1):PAGE74

C1000 Q_CAP_C0402-10UF,6.3V,20%,X6S,B
     1 PVCCIN_CPU0 @S9S_MB_2U_LIB.S9S_MB_2U(SCH_1):PVCCIN_CPU0    I81 @S9S_MB_2U_LIB.S9S_MB_2U(SCH_1):PAGE74
     2    GND @S9S_MB_2U_LIB.S9S_MB_2U(SCH_1):GND    I81 @S9S_MB_2U_LIB.S9S_MB_2U(SCH_1):PAGE74

C1001 Q_CAP_C0402-10UF,6.3V,20%,X6S,B
     1 PVCCIN_CPU0 @S9S_MB_2U_LIB.S9S_MB_2U(SCH_1):PVCCIN_CPU0    I75 @S9S_MB_2U_LIB.S9S_MB_2U(SCH_1):PAGE74
     2    GND @S9S_MB_2U_LIB.S9S_MB_2U(SCH_1):GND    I75 @S9S_MB_2U_LIB.S9S_MB_2U(SCH_1):PAGE74

C1002 Q_CAP_C0402-10UF,6.3V,20%,X6S,B
     1 PVCCIN_CPU0 @S9S_MB_2U_LIB.S9S_MB_2U(SCH_1):PVCCIN_CPU0    I89 @S9S_MB_2U_LIB.S9S_MB_2U(SCH_1):PAGE74
     2    GND @S9S_MB_2U_LIB.S9S_MB_2U(SCH_1):GND    I89 @S9S_MB_2U_LIB.S9S_MB_2U(SCH_1):PAGE74

C1003 Q_CAP_C0402-10UF,6.3V,20%,X6S,B
     1 PVCCIN_CPU0 @S9S_MB_2U_LIB.S9S_MB_2U(SCH_1):PVCCIN_CPU0    I87 @S9S_MB_2U_LIB.S9S_MB_2U(SCH_1):PAGE74
     2    GND @S9S_MB_2U_LIB.S9S_MB_2U(SCH_1):GND    I87 @S9S_MB_2U_LIB.S9S_MB_2U(SCH_1):PAGE74

C1004 Q_CAP_C0402-10UF,6.3V,20%,X6S,B
     1 PVCCIN_CPU0 @S9S_MB_2U_LIB.S9S_MB_2U(SCH_1):PVCCIN_CPU0    I83 @S9S_MB_2U_LIB.S9S_MB_2U(SCH_1):PAGE74
     2    GND @S9S_MB_2U_LIB.S9S_MB_2U(SCH_1):GND    I83 @S9S_MB_2U_LIB.S9S_MB_2U(SCH_1):PAGE74

C1005 Q_CAP_C0402-10UF,6.3V,20%,X6S,B
     1 PVCCIN_CPU0 @S9S_MB_2U_LIB.S9S_MB_2U(SCH_1):PVCCIN_CPU0    I77 @S9S_MB_2U_LIB.S9S_MB_2U(SCH_1):PAGE74
     2    GND @S9S_MB_2U_LIB.S9S_MB_2U(SCH_1):GND    I77 @S9S_MB_2U_LIB.S9S_MB_2U(SCH_1):PAGE74

C1006 Q_CAP_C0402-22UF,4V,20%,X6S,CHA
     1 PVCCIN_CPU0 @S9S_MB_2U_LIB.S9S_MB_2U(SCH_1):PVCCIN_CPU0    I95 @S9S_MB_2U_LIB.S9S_MB_2U(SCH_1):PAGE74
     2    GND @S9S_MB_2U_LIB.S9S_MB_2U(SCH_1):GND    I95 @S9S_MB_2U_LIB.S9S_MB_2U(SCH_1):PAGE74

C1007 Q_CAP_C0402-22UF,4V,20%,X6S,CHA
     1 PVCCIN_CPU0 @S9S_MB_2U_LIB.S9S_MB_2U(SCH_1):PVCCIN_CPU0    I93 @S9S_MB_2U_LIB.S9S_MB_2U(SCH_1):PAGE74
     2    GND @S9S_MB_2U_LIB.S9S_MB_2U(SCH_1):GND    I93 @S9S_MB_2U_LIB.S9S_MB_2U(SCH_1):PAGE74

C1008 Q_CAP_C0402-22UF,4V,20%,X6S,CHA
     1 PVCCIN_CPU0 @S9S_MB_2U_LIB.S9S_MB_2U(SCH_1):PVCCIN_CPU0    I90 @S9S_MB_2U_LIB.S9S_MB_2U(SCH_1):PAGE74
     2    GND @S9S_MB_2U_LIB.S9S_MB_2U(SCH_1):GND    I90 @S9S_MB_2U_LIB.S9S_MB_2U(SCH_1):PAGE74

C1009 Q_CAP_C0402-22UF,4V,20%,X6S,CHA
     1 PVCCIN_CPU0 @S9S_MB_2U_LIB.S9S_MB_2U(SCH_1):PVCCIN_CPU0    I78 @S9S_MB_2U_LIB.S9S_MB_2U(SCH_1):PAGE74
     2    GND @S9S_MB_2U_LIB.S9S_MB_2U(SCH_1):GND    I78 @S9S_MB_2U_LIB.S9S_MB_2U(SCH_1):PAGE74

C1010 Q_CAP_C0402-22UF,4V,20%,X6S,CHA
     1 PVCCIN_CPU0 @S9S_MB_2U_LIB.S9S_MB_2U(SCH_1):PVCCIN_CPU0    I97 @S9S_MB_2U_LIB.S9S_MB_2U(SCH_1):PAGE74
     2    GND @S9S_MB_2U_LIB.S9S_MB_2U(SCH_1):GND    I97 @S9S_MB_2U_LIB.S9S_MB_2U(SCH_1):PAGE74

C1011 Q_CAP_C0402-22UF,4V,20%,X6S,CHA
     1 PVCCIN_CPU0 @S9S_MB_2U_LIB.S9S_MB_2U(SCH_1):PVCCIN_CPU0    I96 @S9S_MB_2U_LIB.S9S_MB_2U(SCH_1):PAGE74
     2    GND @S9S_MB_2U_LIB.S9S_MB_2U(SCH_1):GND    I96 @S9S_MB_2U_LIB.S9S_MB_2U(SCH_1):PAGE74

C1012 Q_CAP_C0402-22UF,4V,20%,X6S,CHA
     1 PVCCIN_CPU0 @S9S_MB_2U_LIB.S9S_MB_2U(SCH_1):PVCCIN_CPU0    I92 @S9S_MB_2U_LIB.S9S_MB_2U(SCH_1):PAGE74
     2    GND @S9S_MB_2U_LIB.S9S_MB_2U(SCH_1):GND    I92 @S9S_MB_2U_LIB.S9S_MB_2U(SCH_1):PAGE74

C1013 Q_CAP_C0402-22UF,4V,20%,X6S,CHA
     1 PVCCIN_CPU0 @S9S_MB_2U_LIB.S9S_MB_2U(SCH_1):PVCCIN_CPU0    I80 @S9S_MB_2U_LIB.S9S_MB_2U(SCH_1):PAGE74
     2    GND @S9S_MB_2U_LIB.S9S_MB_2U(SCH_1):GND    I80 @S9S_MB_2U_LIB.S9S_MB_2U(SCH_1):PAGE74

C1014 Q_CAP_C0402-22UF,4V,20%,X6S,CHA
     1 PVCCIN_CPU0 @S9S_MB_2U_LIB.S9S_MB_2U(SCH_1):PVCCIN_CPU0   I114 @S9S_MB_2U_LIB.S9S_MB_2U(SCH_1):PAGE74
     2    GND @S9S_MB_2U_LIB.S9S_MB_2U(SCH_1):GND   I114 @S9S_MB_2U_LIB.S9S_MB_2U(SCH_1):PAGE74

C1015 Q_CAP_C0402-22UF,4V,20%,X6S,CHA
     1 PVCCIN_CPU0 @S9S_MB_2U_LIB.S9S_MB_2U(SCH_1):PVCCIN_CPU0   I113 @S9S_MB_2U_LIB.S9S_MB_2U(SCH_1):PAGE74
     2    GND @S9S_MB_2U_LIB.S9S_MB_2U(SCH_1):GND   I113 @S9S_MB_2U_LIB.S9S_MB_2U(SCH_1):PAGE74

C1016 Q_CAP_C0402-22UF,4V,20%,X6S,CHA
     1 PVCCIN_CPU0 @S9S_MB_2U_LIB.S9S_MB_2U(SCH_1):PVCCIN_CPU0   I111 @S9S_MB_2U_LIB.S9S_MB_2U(SCH_1):PAGE74
     2    GND @S9S_MB_2U_LIB.S9S_MB_2U(SCH_1):GND   I111 @S9S_MB_2U_LIB.S9S_MB_2U(SCH_1):PAGE74

C1017 Q_CAP_C0402-22UF,4V,20%,X6S,CHA
     1 PVCCIN_CPU0 @S9S_MB_2U_LIB.S9S_MB_2U(SCH_1):PVCCIN_CPU0   I105 @S9S_MB_2U_LIB.S9S_MB_2U(SCH_1):PAGE74
     2    GND @S9S_MB_2U_LIB.S9S_MB_2U(SCH_1):GND   I105 @S9S_MB_2U_LIB.S9S_MB_2U(SCH_1):PAGE74

C1018 Q_CAP_C0402-22UF,4V,20%,X6S,CHA
     1 PVCCIN_CPU0 @S9S_MB_2U_LIB.S9S_MB_2U(SCH_1):PVCCIN_CPU0   I116 @S9S_MB_2U_LIB.S9S_MB_2U(SCH_1):PAGE74
     2    GND @S9S_MB_2U_LIB.S9S_MB_2U(SCH_1):GND   I116 @S9S_MB_2U_LIB.S9S_MB_2U(SCH_1):PAGE74

C1019 Q_CAP_C0402-22UF,4V,20%,X6S,CHA
     1 PVCCIN_CPU0 @S9S_MB_2U_LIB.S9S_MB_2U(SCH_1):PVCCIN_CPU0   I115 @S9S_MB_2U_LIB.S9S_MB_2U(SCH_1):PAGE74
     2    GND @S9S_MB_2U_LIB.S9S_MB_2U(SCH_1):GND   I115 @S9S_MB_2U_LIB.S9S_MB_2U(SCH_1):PAGE74

C1020 Q_CAP_C0402-22UF,4V,20%,X6S,CHA
     1 PVCCIN_CPU0 @S9S_MB_2U_LIB.S9S_MB_2U(SCH_1):PVCCIN_CPU0   I112 @S9S_MB_2U_LIB.S9S_MB_2U(SCH_1):PAGE74
     2    GND @S9S_MB_2U_LIB.S9S_MB_2U(SCH_1):GND   I112 @S9S_MB_2U_LIB.S9S_MB_2U(SCH_1):PAGE74

C1021 Q_CAP_C0402-22UF,4V,20%,X6S,CHA
     1 PVCCIN_CPU0 @S9S_MB_2U_LIB.S9S_MB_2U(SCH_1):PVCCIN_CPU0   I106 @S9S_MB_2U_LIB.S9S_MB_2U(SCH_1):PAGE74
     2    GND @S9S_MB_2U_LIB.S9S_MB_2U(SCH_1):GND   I106 @S9S_MB_2U_LIB.S9S_MB_2U(SCH_1):PAGE74

C1022 Q_CAP_C0402-22UF,4V,20%,X6S,CHA
     1 PVCCIN_CPU0 @S9S_MB_2U_LIB.S9S_MB_2U(SCH_1):PVCCIN_CPU0   I122 @S9S_MB_2U_LIB.S9S_MB_2U(SCH_1):PAGE74
     2    GND @S9S_MB_2U_LIB.S9S_MB_2U(SCH_1):GND   I122 @S9S_MB_2U_LIB.S9S_MB_2U(SCH_1):PAGE74

C1023 Q_CAP_C0402-22UF,4V,20%,X6S,CHA
     1 PVCCIN_CPU0 @S9S_MB_2U_LIB.S9S_MB_2U(SCH_1):PVCCIN_CPU0   I120 @S9S_MB_2U_LIB.S9S_MB_2U(SCH_1):PAGE74
     2    GND @S9S_MB_2U_LIB.S9S_MB_2U(SCH_1):GND   I120 @S9S_MB_2U_LIB.S9S_MB_2U(SCH_1):PAGE74

C1024 Q_CAP_C0402-22UF,4V,20%,X6S,CHA
     1 PVCCIN_CPU0 @S9S_MB_2U_LIB.S9S_MB_2U(SCH_1):PVCCIN_CPU0   I117 @S9S_MB_2U_LIB.S9S_MB_2U(SCH_1):PAGE74
     2    GND @S9S_MB_2U_LIB.S9S_MB_2U(SCH_1):GND   I117 @S9S_MB_2U_LIB.S9S_MB_2U(SCH_1):PAGE74

C1025 Q_CAP_C0402-22UF,4V,20%,X6S,CHA
     1 PVCCIN_CPU0 @S9S_MB_2U_LIB.S9S_MB_2U(SCH_1):PVCCIN_CPU0   I108 @S9S_MB_2U_LIB.S9S_MB_2U(SCH_1):PAGE74
     2    GND @S9S_MB_2U_LIB.S9S_MB_2U(SCH_1):GND   I108 @S9S_MB_2U_LIB.S9S_MB_2U(SCH_1):PAGE74

C1026 Q_CAP_C0402-22UF,4V,20%,X6S,CHA
     1 PVCCIN_CPU0 @S9S_MB_2U_LIB.S9S_MB_2U(SCH_1):PVCCIN_CPU0   I123 @S9S_MB_2U_LIB.S9S_MB_2U(SCH_1):PAGE74
     2    GND @S9S_MB_2U_LIB.S9S_MB_2U(SCH_1):GND   I123 @S9S_MB_2U_LIB.S9S_MB_2U(SCH_1):PAGE74

C1027 Q_CAP_C0402-22UF,4V,20%,X6S,CHA
     1 PVCCIN_CPU0 @S9S_MB_2U_LIB.S9S_MB_2U(SCH_1):PVCCIN_CPU0   I121 @S9S_MB_2U_LIB.S9S_MB_2U(SCH_1):PAGE74
     2    GND @S9S_MB_2U_LIB.S9S_MB_2U(SCH_1):GND   I121 @S9S_MB_2U_LIB.S9S_MB_2U(SCH_1):PAGE74

C1028 Q_CAP_C0402-22UF,4V,20%,X6S,CHA
     1 PVCCIN_CPU0 @S9S_MB_2U_LIB.S9S_MB_2U(SCH_1):PVCCIN_CPU0   I118 @S9S_MB_2U_LIB.S9S_MB_2U(SCH_1):PAGE74
     2    GND @S9S_MB_2U_LIB.S9S_MB_2U(SCH_1):GND   I118 @S9S_MB_2U_LIB.S9S_MB_2U(SCH_1):PAGE74

C1029 Q_CAP_C0402-22UF,4V,20%,X6S,CHA
     1 PVCCIN_CPU0 @S9S_MB_2U_LIB.S9S_MB_2U(SCH_1):PVCCIN_CPU0   I109 @S9S_MB_2U_LIB.S9S_MB_2U(SCH_1):PAGE74
     2    GND @S9S_MB_2U_LIB.S9S_MB_2U(SCH_1):GND   I109 @S9S_MB_2U_LIB.S9S_MB_2U(SCH_1):PAGE74

C1030 Q_CAP_C0402-22UF,4V,20%,X6S,CHA
     1 PVCCIN_CPU0 @S9S_MB_2U_LIB.S9S_MB_2U(SCH_1):PVCCIN_CPU0   I125 @S9S_MB_2U_LIB.S9S_MB_2U(SCH_1):PAGE74
     2    GND @S9S_MB_2U_LIB.S9S_MB_2U(SCH_1):GND   I125 @S9S_MB_2U_LIB.S9S_MB_2U(SCH_1):PAGE74

C1031 Q_CAP_C0402-22UF,4V,20%,X6S,CHA
     1 PVCCIN_CPU0 @S9S_MB_2U_LIB.S9S_MB_2U(SCH_1):PVCCIN_CPU0   I124 @S9S_MB_2U_LIB.S9S_MB_2U(SCH_1):PAGE74
     2    GND @S9S_MB_2U_LIB.S9S_MB_2U(SCH_1):GND   I124 @S9S_MB_2U_LIB.S9S_MB_2U(SCH_1):PAGE74

C1032 Q_CAP_C0402-22UF,4V,20%,X6S,CHA
     1 PVCCIN_CPU0 @S9S_MB_2U_LIB.S9S_MB_2U(SCH_1):PVCCIN_CPU0   I119 @S9S_MB_2U_LIB.S9S_MB_2U(SCH_1):PAGE74
     2    GND @S9S_MB_2U_LIB.S9S_MB_2U(SCH_1):GND   I119 @S9S_MB_2U_LIB.S9S_MB_2U(SCH_1):PAGE74

C1033 Q_CAP_C0402-22UF,4V,20%,X6S,CHA
     1 PVCCIN_CPU0 @S9S_MB_2U_LIB.S9S_MB_2U(SCH_1):PVCCIN_CPU0   I110 @S9S_MB_2U_LIB.S9S_MB_2U(SCH_1):PAGE74
     2    GND @S9S_MB_2U_LIB.S9S_MB_2U(SCH_1):GND   I110 @S9S_MB_2U_LIB.S9S_MB_2U(SCH_1):PAGE74

C1034 Q_CAP_C0402-22UF,4V,20%,X6S,CHA
     1 PVCCIN_CPU0 @S9S_MB_2U_LIB.S9S_MB_2U(SCH_1):PVCCIN_CPU0   I134 @S9S_MB_2U_LIB.S9S_MB_2U(SCH_1):PAGE74
     2    GND @S9S_MB_2U_LIB.S9S_MB_2U(SCH_1):GND   I134 @S9S_MB_2U_LIB.S9S_MB_2U(SCH_1):PAGE74

C1035 Q_CAP_C0402-22UF,4V,20%,X6S,CHA
     1 PVCCIN_CPU0 @S9S_MB_2U_LIB.S9S_MB_2U(SCH_1):PVCCIN_CPU0   I133 @S9S_MB_2U_LIB.S9S_MB_2U(SCH_1):PAGE74
     2    GND @S9S_MB_2U_LIB.S9S_MB_2U(SCH_1):GND   I133 @S9S_MB_2U_LIB.S9S_MB_2U(SCH_1):PAGE74

C1036 Q_CAP_C0402-22UF,4V,20%,X6S,CHA
     1 PVCCIN_CPU0 @S9S_MB_2U_LIB.S9S_MB_2U(SCH_1):PVCCIN_CPU0   I131 @S9S_MB_2U_LIB.S9S_MB_2U(SCH_1):PAGE74
     2    GND @S9S_MB_2U_LIB.S9S_MB_2U(SCH_1):GND   I131 @S9S_MB_2U_LIB.S9S_MB_2U(SCH_1):PAGE74

C1037 Q_CAP_C0402-22UF,4V,20%,X6S,CHA
     1 PVCCIN_CPU0 @S9S_MB_2U_LIB.S9S_MB_2U(SCH_1):PVCCIN_CPU0   I127 @S9S_MB_2U_LIB.S9S_MB_2U(SCH_1):PAGE74
     2    GND @S9S_MB_2U_LIB.S9S_MB_2U(SCH_1):GND   I127 @S9S_MB_2U_LIB.S9S_MB_2U(SCH_1):PAGE74

C1038 Q_CAP_C0402-22UF,4V,20%,X6S,CHA
     1 PVCCIN_CPU0 @S9S_MB_2U_LIB.S9S_MB_2U(SCH_1):PVCCIN_CPU0   I137 @S9S_MB_2U_LIB.S9S_MB_2U(SCH_1):PAGE74
     2    GND @S9S_MB_2U_LIB.S9S_MB_2U(SCH_1):GND   I137 @S9S_MB_2U_LIB.S9S_MB_2U(SCH_1):PAGE74

C1039 Q_CAP_C0402-22UF,4V,20%,X6S,CHA
     1 PVCCIN_CPU0 @S9S_MB_2U_LIB.S9S_MB_2U(SCH_1):PVCCIN_CPU0   I135 @S9S_MB_2U_LIB.S9S_MB_2U(SCH_1):PAGE74
     2    GND @S9S_MB_2U_LIB.S9S_MB_2U(SCH_1):GND   I135 @S9S_MB_2U_LIB.S9S_MB_2U(SCH_1):PAGE74

C1040 Q_CAP_C0402-22UF,4V,20%,X6S,CHA
     1 PVCCIN_CPU0 @S9S_MB_2U_LIB.S9S_MB_2U(SCH_1):PVCCIN_CPU0   I132 @S9S_MB_2U_LIB.S9S_MB_2U(SCH_1):PAGE74
     2    GND @S9S_MB_2U_LIB.S9S_MB_2U(SCH_1):GND   I132 @S9S_MB_2U_LIB.S9S_MB_2U(SCH_1):PAGE74

C1041 Q_CAP_C0402-22UF,4V,20%,X6S,CHA
     1 PVCCIN_CPU0 @S9S_MB_2U_LIB.S9S_MB_2U(SCH_1):PVCCIN_CPU0   I128 @S9S_MB_2U_LIB.S9S_MB_2U(SCH_1):PAGE74
     2    GND @S9S_MB_2U_LIB.S9S_MB_2U(SCH_1):GND   I128 @S9S_MB_2U_LIB.S9S_MB_2U(SCH_1):PAGE74

C1042 Q_CAP_C0402-100NF,50V,10%,X7R,A
     1 P5V_AUX @S9S_MB_2U_LIB.S9S_MB_2U(SCH_1):P5V_AUX    I11 @S9S_MB_2U_LIB.S9S_MB_2U(SCH_1):PAGE246
     2    GND @S9S_MB_2U_LIB.S9S_MB_2U(SCH_1):GND    I11 @S9S_MB_2U_LIB.S9S_MB_2U(SCH_1):PAGE246

C1043 Q_CAP_C0402-22UF,4V,20%,X6S,CHA
     1 PVCCIN_CPU0 @S9S_MB_2U_LIB.S9S_MB_2U(SCH_1):PVCCIN_CPU0   I141 @S9S_MB_2U_LIB.S9S_MB_2U(SCH_1):PAGE74
     2    GND @S9S_MB_2U_LIB.S9S_MB_2U(SCH_1):GND   I141 @S9S_MB_2U_LIB.S9S_MB_2U(SCH_1):PAGE74

C1044 Q_CAP_C0402-22UF,4V,20%,X6S,CHA
     1 PVCCIN_CPU0 @S9S_MB_2U_LIB.S9S_MB_2U(SCH_1):PVCCIN_CPU0   I139 @S9S_MB_2U_LIB.S9S_MB_2U(SCH_1):PAGE74
     2    GND @S9S_MB_2U_LIB.S9S_MB_2U(SCH_1):GND   I139 @S9S_MB_2U_LIB.S9S_MB_2U(SCH_1):PAGE74

C1045 Q_CAP_C0402-22UF,4V,20%,X6S,CHA
     1 PVCCIN_CPU0 @S9S_MB_2U_LIB.S9S_MB_2U(SCH_1):PVCCIN_CPU0   I130 @S9S_MB_2U_LIB.S9S_MB_2U(SCH_1):PAGE74
     2    GND @S9S_MB_2U_LIB.S9S_MB_2U(SCH_1):GND   I130 @S9S_MB_2U_LIB.S9S_MB_2U(SCH_1):PAGE74

C1096 Q_CAP_C0201-0.1UF,6.3V,10%,X6SA
     1 USB3_PCH_TX_DP<4> @S9S_MB_2U_LIB.S9S_MB_2U(SCH_1):USB3_PCH_TX_DP(4)    I80 @S9S_MB_2U_LIB.S9S_MB_2U(SCH_1):PAGE173
     2 USB3_PCH_TX_C_DP<4> @S9S_MB_2U_LIB.S9S_MB_2U(SCH_1):USB3_PCH_TX_C_DP(4)    I80 @S9S_MB_2U_LIB.S9S_MB_2U(SCH_1):PAGE173

C1097 Q_CAP_C0201-0.1UF,6.3V,10%,X6SA
     1 USB3_PCH_TX_DN<4> @S9S_MB_2U_LIB.S9S_MB_2U(SCH_1):USB3_PCH_TX_DN(4)    I78 @S9S_MB_2U_LIB.S9S_MB_2U(SCH_1):PAGE173
     2 USB3_PCH_TX_C_DN<4> @S9S_MB_2U_LIB.S9S_MB_2U(SCH_1):USB3_PCH_TX_C_DN(4)    I78 @S9S_MB_2U_LIB.S9S_MB_2U(SCH_1):PAGE173

C1098 Q_CAP_DIFFBUS_C0201-DIFF BUS_0A
     1 P3E_PCH_M2_TX_DP<3> @S9S_MB_2U_LIB.S9S_MB_2U(SCH_1):P3E_PCH_M2_TX_DP(3)    I67 @S9S_MB_2U_LIB.S9S_MB_2U(SCH_1):PAGE173
     2 P3E_PCH_M2_TX_C_DP<3> @S9S_MB_2U_LIB.S9S_MB_2U(SCH_1):P3E_PCH_M2_TX_C_DP(3)    I67 @S9S_MB_2U_LIB.S9S_MB_2U(SCH_1):PAGE173

C1099 Q_CAP_DIFFBUS_C0201-DIFF BUS_0A
     1 P3E_PCH_M2_TX_DN<3> @S9S_MB_2U_LIB.S9S_MB_2U(SCH_1):P3E_PCH_M2_TX_DN(3)    I66 @S9S_MB_2U_LIB.S9S_MB_2U(SCH_1):PAGE173
     2 P3E_PCH_M2_TX_C_DN<3> @S9S_MB_2U_LIB.S9S_MB_2U(SCH_1):P3E_PCH_M2_TX_C_DN(3)    I66 @S9S_MB_2U_LIB.S9S_MB_2U(SCH_1):PAGE173

C1100 Q_CAP_DIFFBUS_C0201-DIFF BUS_0A
     1 P3E_PCH_M2_TX_DP<2> @S9S_MB_2U_LIB.S9S_MB_2U(SCH_1):P3E_PCH_M2_TX_DP(2)    I64 @S9S_MB_2U_LIB.S9S_MB_2U(SCH_1):PAGE173
     2 P3E_PCH_M2_TX_C_DP<2> @S9S_MB_2U_LIB.S9S_MB_2U(SCH_1):P3E_PCH_M2_TX_C_DP(2)    I64 @S9S_MB_2U_LIB.S9S_MB_2U(SCH_1):PAGE173

C1101 Q_CAP_DIFFBUS_C0201-DIFF BUS_0A
     1 P3E_PCH_M2_TX_DN<2> @S9S_MB_2U_LIB.S9S_MB_2U(SCH_1):P3E_PCH_M2_TX_DN(2)    I65 @S9S_MB_2U_LIB.S9S_MB_2U(SCH_1):PAGE173
     2 P3E_PCH_M2_TX_C_DN<2> @S9S_MB_2U_LIB.S9S_MB_2U(SCH_1):P3E_PCH_M2_TX_C_DN(2)    I65 @S9S_MB_2U_LIB.S9S_MB_2U(SCH_1):PAGE173

C1102 Q_CAP_DIFFBUS_C0201-DIFF BUS_0A
     1 P3E_PCH_M2_TX_DP<1> @S9S_MB_2U_LIB.S9S_MB_2U(SCH_1):P3E_PCH_M2_TX_DP(1)    I63 @S9S_MB_2U_LIB.S9S_MB_2U(SCH_1):PAGE173
     2 P3E_PCH_M2_TX_C_DP<1> @S9S_MB_2U_LIB.S9S_MB_2U(SCH_1):P3E_PCH_M2_TX_C_DP(1)    I63 @S9S_MB_2U_LIB.S9S_MB_2U(SCH_1):PAGE173

C1103 Q_CAP_DIFFBUS_C0201-DIFF BUS_0A
     1 P3E_PCH_M2_TX_DN<1> @S9S_MB_2U_LIB.S9S_MB_2U(SCH_1):P3E_PCH_M2_TX_DN(1)    I62 @S9S_MB_2U_LIB.S9S_MB_2U(SCH_1):PAGE173
     2 P3E_PCH_M2_TX_C_DN<1> @S9S_MB_2U_LIB.S9S_MB_2U(SCH_1):P3E_PCH_M2_TX_C_DN(1)    I62 @S9S_MB_2U_LIB.S9S_MB_2U(SCH_1):PAGE173

C1104 Q_CAP_DIFFBUS_C0201-DIFF BUS_0A
     1 P3E_PCH_M2_TX_DP<0> @S9S_MB_2U_LIB.S9S_MB_2U(SCH_1):P3E_PCH_M2_TX_DP(0)    I61 @S9S_MB_2U_LIB.S9S_MB_2U(SCH_1):PAGE173
     2 P3E_PCH_M2_TX_C_DP<0> @S9S_MB_2U_LIB.S9S_MB_2U(SCH_1):P3E_PCH_M2_TX_C_DP(0)    I61 @S9S_MB_2U_LIB.S9S_MB_2U(SCH_1):PAGE173

C1105 Q_CAP_DIFFBUS_C0201-DIFF BUS_0A
     1 P3E_PCH_M2_TX_DN<0> @S9S_MB_2U_LIB.S9S_MB_2U(SCH_1):P3E_PCH_M2_TX_DN(0)    I60 @S9S_MB_2U_LIB.S9S_MB_2U(SCH_1):PAGE173
     2 P3E_PCH_M2_TX_C_DN<0> @S9S_MB_2U_LIB.S9S_MB_2U(SCH_1):P3E_PCH_M2_TX_C_DN(0)    I60 @S9S_MB_2U_LIB.S9S_MB_2U(SCH_1):PAGE173

C1113 Q_CAP_C0402-0.01UF,50V,10%,X7RA
     1 P3V3_AUX_FPGA_VCCIO3 @S9S_MB_2U_LIB.S9S_MB_2U(SCH_1):P3V3_AUX_FPGA_VCCIO3    I99 @S9S_MB_2U_LIB.S9S_MB_2U(SCH_1):PAGE202
     2    GND @S9S_MB_2U_LIB.S9S_MB_2U(SCH_1):GND    I99 @S9S_MB_2U_LIB.S9S_MB_2U(SCH_1):PAGE202

C1118 Q_CAP_C0402-0.01UF,50V,10%,X7RA
     1 P3V3_AUX_FPGA_VCCIO3 @S9S_MB_2U_LIB.S9S_MB_2U(SCH_1):P3V3_AUX_FPGA_VCCIO3    I97 @S9S_MB_2U_LIB.S9S_MB_2U(SCH_1):PAGE202
     2    GND @S9S_MB_2U_LIB.S9S_MB_2U(SCH_1):GND    I97 @S9S_MB_2U_LIB.S9S_MB_2U(SCH_1):PAGE202

C1122 Q_CAP_0402-0.1UF,25V,10%,X7R,CA
     1 P3V3_AUX_FPGA_VCCIO2 @S9S_MB_2U_LIB.S9S_MB_2U(SCH_1):P3V3_AUX_FPGA_VCCIO2    I56 @S9S_MB_2U_LIB.S9S_MB_2U(SCH_1):PAGE202
     2    GND @S9S_MB_2U_LIB.S9S_MB_2U(SCH_1):GND    I56 @S9S_MB_2U_LIB.S9S_MB_2U(SCH_1):PAGE202

C1124 Q_CAP_C0402-0.01UF,50V,10%,X7RA
     1 P3V3_AUX_FPGA_VCCIO3 @S9S_MB_2U_LIB.S9S_MB_2U(SCH_1):P3V3_AUX_FPGA_VCCIO3   I100 @S9S_MB_2U_LIB.S9S_MB_2U(SCH_1):PAGE202
     2    GND @S9S_MB_2U_LIB.S9S_MB_2U(SCH_1):GND   I100 @S9S_MB_2U_LIB.S9S_MB_2U(SCH_1):PAGE202

C1127 Q_CAP_C0402-0.01UF,50V,10%,X7RA
     1 P3V3_AUX_FPGA_VCCIO2 @S9S_MB_2U_LIB.S9S_MB_2U(SCH_1):P3V3_AUX_FPGA_VCCIO2    I52 @S9S_MB_2U_LIB.S9S_MB_2U(SCH_1):PAGE202
     2    GND @S9S_MB_2U_LIB.S9S_MB_2U(SCH_1):GND    I52 @S9S_MB_2U_LIB.S9S_MB_2U(SCH_1):PAGE202

C1133 Q_CAP_C0402-0.01UF,50V,10%,X7RA
     1 P3V3_AUX_FPGA_VCCIO2 @S9S_MB_2U_LIB.S9S_MB_2U(SCH_1):P3V3_AUX_FPGA_VCCIO2    I51 @S9S_MB_2U_LIB.S9S_MB_2U(SCH_1):PAGE202
     2    GND @S9S_MB_2U_LIB.S9S_MB_2U(SCH_1):GND    I51 @S9S_MB_2U_LIB.S9S_MB_2U(SCH_1):PAGE202

C1138 Q_CAP_C0402-0.01UF,50V,10%,X7RA
     1 P3V3_AUX_FPGA_VCCIO2 @S9S_MB_2U_LIB.S9S_MB_2U(SCH_1):P3V3_AUX_FPGA_VCCIO2    I50 @S9S_MB_2U_LIB.S9S_MB_2U(SCH_1):PAGE202
     2    GND @S9S_MB_2U_LIB.S9S_MB_2U(SCH_1):GND    I50 @S9S_MB_2U_LIB.S9S_MB_2U(SCH_1):PAGE202

C1142 Q_CAP_C0402-0.01UF,50V,10%,X7RA
     1 P3V3_AUX_FPGA_VCCIO2 @S9S_MB_2U_LIB.S9S_MB_2U(SCH_1):P3V3_AUX_FPGA_VCCIO2    I49 @S9S_MB_2U_LIB.S9S_MB_2U(SCH_1):PAGE202
     2    GND @S9S_MB_2U_LIB.S9S_MB_2U(SCH_1):GND    I49 @S9S_MB_2U_LIB.S9S_MB_2U(SCH_1):PAGE202

C1146 Q_CAP_C0402-0.01UF,50V,10%,X7RA
     1 P3V3_AUX_FPGA_VCCIO2 @S9S_MB_2U_LIB.S9S_MB_2U(SCH_1):P3V3_AUX_FPGA_VCCIO2    I15 @S9S_MB_2U_LIB.S9S_MB_2U(SCH_1):PAGE202
     2    GND @S9S_MB_2U_LIB.S9S_MB_2U(SCH_1):GND    I15 @S9S_MB_2U_LIB.S9S_MB_2U(SCH_1):PAGE202

C1150 Q_CAP_0402-0.1UF,25V,10%,X7R,CA
     1 VCC_PLD_CORE @S9S_MB_2U_LIB.S9S_MB_2U(SCH_1):VCC_PLD_CORE   I121 @S9S_MB_2U_LIB.S9S_MB_2U(SCH_1):PAGE202
     2    GND @S9S_MB_2U_LIB.S9S_MB_2U(SCH_1):GND   I121 @S9S_MB_2U_LIB.S9S_MB_2U(SCH_1):PAGE202

C1152 Q_CAP_C0402-0.01UF,50V,10%,X7RA
     1 VCC_PLD_CORE @S9S_MB_2U_LIB.S9S_MB_2U(SCH_1):VCC_PLD_CORE     I5 @S9S_MB_2U_LIB.S9S_MB_2U(SCH_1):PAGE202
     2    GND @S9S_MB_2U_LIB.S9S_MB_2U(SCH_1):GND     I5 @S9S_MB_2U_LIB.S9S_MB_2U(SCH_1):PAGE202

C1154 Q_CAP_C0402-0.01UF,50V,10%,X7RA
     1 VCC_PLD_CORE @S9S_MB_2U_LIB.S9S_MB_2U(SCH_1):VCC_PLD_CORE     I3 @S9S_MB_2U_LIB.S9S_MB_2U(SCH_1):PAGE202
     2    GND @S9S_MB_2U_LIB.S9S_MB_2U(SCH_1):GND     I3 @S9S_MB_2U_LIB.S9S_MB_2U(SCH_1):PAGE202

C1170 Q_CAP_C0805-10UF,16V,10%,X6S,CA
     1 P5V_AUX @S9S_MB_2U_LIB.S9S_MB_2U(SCH_1):P5V_AUX    I24 @S9S_MB_2U_LIB.S9S_MB_2U(SCH_1):PAGE246
     2    GND @S9S_MB_2U_LIB.S9S_MB_2U(SCH_1):GND    I24 @S9S_MB_2U_LIB.S9S_MB_2U(SCH_1):PAGE246

C1171 Q_CAP_C0805-10UF,16V,10%,EMPTYA
     1 P5V_AUX @S9S_MB_2U_LIB.S9S_MB_2U(SCH_1):P5V_AUX    I25 @S9S_MB_2U_LIB.S9S_MB_2U(SCH_1):PAGE246
     2    GND @S9S_MB_2U_LIB.S9S_MB_2U(SCH_1):GND    I25 @S9S_MB_2U_LIB.S9S_MB_2U(SCH_1):PAGE246

C1172 Q_CAP_C0402-100NF,50V,10%,X7R,A
     1    P5V @S9S_MB_2U_LIB.S9S_MB_2U(SCH_1):P5V     I2 @S9S_MB_2U_LIB.S9S_MB_2U(SCH_1):PAGE246
     2    GND @S9S_MB_2U_LIB.S9S_MB_2U(SCH_1):GND     I2 @S9S_MB_2U_LIB.S9S_MB_2U(SCH_1):PAGE246

C1173 Q_CAP_0402-0.1UF,25V,10%,X7R,CA
     1 P3V3_AUX @S9S_MB_2U_LIB.S9S_MB_2U(SCH_1):P3V3_AUX     I4 @S9S_MB_2U_LIB.S9S_MB_2U(SCH_1):PAGE152
     2    GND @S9S_MB_2U_LIB.S9S_MB_2U(SCH_1):GND     I4 @S9S_MB_2U_LIB.S9S_MB_2U(SCH_1):PAGE152

C1175 Q_CAP_0402-0.1UF,25V,10%,X7R,CA
     1 P3V3_AUX @S9S_MB_2U_LIB.S9S_MB_2U(SCH_1):P3V3_AUX    I24 @S9S_MB_2U_LIB.S9S_MB_2U(SCH_1):PAGE152
     2    GND @S9S_MB_2U_LIB.S9S_MB_2U(SCH_1):GND    I24 @S9S_MB_2U_LIB.S9S_MB_2U(SCH_1):PAGE152

C1177 Q_CAP_C0402-1UF,25V,10%,X6S,CHA
     1 RST_RTCRST_N @S9S_MB_2U_LIB.S9S_MB_2U(SCH_1):RST_RTCRST_N   I128 @S9S_MB_2U_LIB.S9S_MB_2U(SCH_1):PAGE189
     2    GND @S9S_MB_2U_LIB.S9S_MB_2U(SCH_1):GND   I128 @S9S_MB_2U_LIB.S9S_MB_2U(SCH_1):PAGE189

C1178 Q_CAP_C0603-22UF,4V,20%,X6S,CHA
     1 P1V05_PCH_AUX @S9S_MB_2U_LIB.S9S_MB_2U(SCH_1):P1V05_PCH_AUX     I6 @S9S_MB_2U_LIB.S9S_MB_2U(SCH_1):PAGE181
     2    GND @S9S_MB_2U_LIB.S9S_MB_2U(SCH_1):GND     I6 @S9S_MB_2U_LIB.S9S_MB_2U(SCH_1):PAGE181

C1181 Q_CAP_C0603-22UF,4V,20%,X6S,CHA
     1 P1V8_PCH_AUX @S9S_MB_2U_LIB.S9S_MB_2U(SCH_1):P1V8_PCH_AUX    I27 @S9S_MB_2U_LIB.S9S_MB_2U(SCH_1):PAGE181
     2    GND @S9S_MB_2U_LIB.S9S_MB_2U(SCH_1):GND    I27 @S9S_MB_2U_LIB.S9S_MB_2U(SCH_1):PAGE181

C1182 Q_CAP_C0603-22UF,4V,20%,X6S,CHA
     1 P1V05_PCH_AUX @S9S_MB_2U_LIB.S9S_MB_2U(SCH_1):P1V05_PCH_AUX    I42 @S9S_MB_2U_LIB.S9S_MB_2U(SCH_1):PAGE181
     2    GND @S9S_MB_2U_LIB.S9S_MB_2U(SCH_1):GND    I42 @S9S_MB_2U_LIB.S9S_MB_2U(SCH_1):PAGE181

C1183 Q_CAP_C0402-2.2UF,10V,10%,X6S,A
     1 P1V05_PCH_AUX @S9S_MB_2U_LIB.S9S_MB_2U(SCH_1):P1V05_PCH_AUX    I51 @S9S_MB_2U_LIB.S9S_MB_2U(SCH_1):PAGE181
     2    GND @S9S_MB_2U_LIB.S9S_MB_2U(SCH_1):GND    I51 @S9S_MB_2U_LIB.S9S_MB_2U(SCH_1):PAGE181

C1184 Q_CAP_C0603-22UF,6.3V,20%,X6S,A
     1 P3V3_AUX @S9S_MB_2U_LIB.S9S_MB_2U(SCH_1):P3V3_AUX    I91 @S9S_MB_2U_LIB.S9S_MB_2U(SCH_1):PAGE181
     2    GND @S9S_MB_2U_LIB.S9S_MB_2U(SCH_1):GND    I91 @S9S_MB_2U_LIB.S9S_MB_2U(SCH_1):PAGE181

C1185 Q_CAP_C0603-22UF,4V,20%,X6S,CHA
     1 P1V05_PCH_AUX @S9S_MB_2U_LIB.S9S_MB_2U(SCH_1):P1V05_PCH_AUX     I7 @S9S_MB_2U_LIB.S9S_MB_2U(SCH_1):PAGE181
     2    GND @S9S_MB_2U_LIB.S9S_MB_2U(SCH_1):GND     I7 @S9S_MB_2U_LIB.S9S_MB_2U(SCH_1):PAGE181

C1186 Q_CAP_C0603-22UF,4V,20%,X6S,CHA
     1 P1V8_PCH_AUX @S9S_MB_2U_LIB.S9S_MB_2U(SCH_1):P1V8_PCH_AUX    I25 @S9S_MB_2U_LIB.S9S_MB_2U(SCH_1):PAGE181
     2    GND @S9S_MB_2U_LIB.S9S_MB_2U(SCH_1):GND    I25 @S9S_MB_2U_LIB.S9S_MB_2U(SCH_1):PAGE181

C1187 Q_CAP_C0603-22UF,4V,20%,X6S,CHA
     1 P1V05_PCH_AUX @S9S_MB_2U_LIB.S9S_MB_2U(SCH_1):P1V05_PCH_AUX    I40 @S9S_MB_2U_LIB.S9S_MB_2U(SCH_1):PAGE181
     2    GND @S9S_MB_2U_LIB.S9S_MB_2U(SCH_1):GND    I40 @S9S_MB_2U_LIB.S9S_MB_2U(SCH_1):PAGE181

C1189 Q_CAP_C0402-2.2UF,10V,10%,X6S,A
     1 P1V05_PCH_AUX @S9S_MB_2U_LIB.S9S_MB_2U(SCH_1):P1V05_PCH_AUX    I58 @S9S_MB_2U_LIB.S9S_MB_2U(SCH_1):PAGE181
     2    GND @S9S_MB_2U_LIB.S9S_MB_2U(SCH_1):GND    I58 @S9S_MB_2U_LIB.S9S_MB_2U(SCH_1):PAGE181

C1191 Q_CAP_C0603-22UF,6.3V,20%,X6S,A
     1 P3V3_AUX @S9S_MB_2U_LIB.S9S_MB_2U(SCH_1):P3V3_AUX    I89 @S9S_MB_2U_LIB.S9S_MB_2U(SCH_1):PAGE181
     2    GND @S9S_MB_2U_LIB.S9S_MB_2U(SCH_1):GND    I89 @S9S_MB_2U_LIB.S9S_MB_2U(SCH_1):PAGE181

C1192 Q_CAP_C0603-22UF,4V,20%,X6S,CHA
     1 P1V05_PCH_AUX @S9S_MB_2U_LIB.S9S_MB_2U(SCH_1):P1V05_PCH_AUX     I8 @S9S_MB_2U_LIB.S9S_MB_2U(SCH_1):PAGE181
     2    GND @S9S_MB_2U_LIB.S9S_MB_2U(SCH_1):GND     I8 @S9S_MB_2U_LIB.S9S_MB_2U(SCH_1):PAGE181

C1197 Q_CAP_C0603-22UF,4V,20%,X6S,CHA
     1 P1V8_PCH_AUX @S9S_MB_2U_LIB.S9S_MB_2U(SCH_1):P1V8_PCH_AUX    I30 @S9S_MB_2U_LIB.S9S_MB_2U(SCH_1):PAGE181
     2    GND @S9S_MB_2U_LIB.S9S_MB_2U(SCH_1):GND    I30 @S9S_MB_2U_LIB.S9S_MB_2U(SCH_1):PAGE181

C1198 Q_CAP_C0603-22UF,4V,20%,X6S,CHA
     1 P1V05_PCH_AUX @S9S_MB_2U_LIB.S9S_MB_2U(SCH_1):P1V05_PCH_AUX    I43 @S9S_MB_2U_LIB.S9S_MB_2U(SCH_1):PAGE181
     2    GND @S9S_MB_2U_LIB.S9S_MB_2U(SCH_1):GND    I43 @S9S_MB_2U_LIB.S9S_MB_2U(SCH_1):PAGE181

C1200 Q_CAP_C0402-2.2UF,10V,10%,X6S,A
     1 P1V05_PCH_AUX @S9S_MB_2U_LIB.S9S_MB_2U(SCH_1):P1V05_PCH_AUX    I59 @S9S_MB_2U_LIB.S9S_MB_2U(SCH_1):PAGE181
     2    GND @S9S_MB_2U_LIB.S9S_MB_2U(SCH_1):GND    I59 @S9S_MB_2U_LIB.S9S_MB_2U(SCH_1):PAGE181

C1201 Q_CAP_C0603-22UF,6.3V,20%,X6S,A
     1 P3V3_AUX @S9S_MB_2U_LIB.S9S_MB_2U(SCH_1):P3V3_AUX    I87 @S9S_MB_2U_LIB.S9S_MB_2U(SCH_1):PAGE181
     2    GND @S9S_MB_2U_LIB.S9S_MB_2U(SCH_1):GND    I87 @S9S_MB_2U_LIB.S9S_MB_2U(SCH_1):PAGE181

C1202 Q_CAP_C0603-22UF,4V,20%,X6S,CHA
     1 P1V8_PCH_AUX @S9S_MB_2U_LIB.S9S_MB_2U(SCH_1):P1V8_PCH_AUX    I29 @S9S_MB_2U_LIB.S9S_MB_2U(SCH_1):PAGE181
     2    GND @S9S_MB_2U_LIB.S9S_MB_2U(SCH_1):GND    I29 @S9S_MB_2U_LIB.S9S_MB_2U(SCH_1):PAGE181

C1203 Q_CAP_C0402-10UF,6.3V,20%,X6S,A
     1 P1V05_PCH_AUX @S9S_MB_2U_LIB.S9S_MB_2U(SCH_1):P1V05_PCH_AUX    I48 @S9S_MB_2U_LIB.S9S_MB_2U(SCH_1):PAGE181
     2    GND @S9S_MB_2U_LIB.S9S_MB_2U(SCH_1):GND    I48 @S9S_MB_2U_LIB.S9S_MB_2U(SCH_1):PAGE181

C1204 Q_CAP_C0402-2.2UF,10V,10%,X6S,A
     1 P1V05_PCH_AUX @S9S_MB_2U_LIB.S9S_MB_2U(SCH_1):P1V05_PCH_AUX    I60 @S9S_MB_2U_LIB.S9S_MB_2U(SCH_1):PAGE181
     2    GND @S9S_MB_2U_LIB.S9S_MB_2U(SCH_1):GND    I60 @S9S_MB_2U_LIB.S9S_MB_2U(SCH_1):PAGE181

C1205 Q_CAP_C0402-10UF,6.3V,20%,X6S,A
     1 P1V05_PCH_AUX @S9S_MB_2U_LIB.S9S_MB_2U(SCH_1):P1V05_PCH_AUX    I12 @S9S_MB_2U_LIB.S9S_MB_2U(SCH_1):PAGE181
     2    GND @S9S_MB_2U_LIB.S9S_MB_2U(SCH_1):GND    I12 @S9S_MB_2U_LIB.S9S_MB_2U(SCH_1):PAGE181

C1206 Q_CAP_C0402-10UF,6.3V,20%,X6S,A
     1 P3V3_AUX @S9S_MB_2U_LIB.S9S_MB_2U(SCH_1):P3V3_AUX    I78 @S9S_MB_2U_LIB.S9S_MB_2U(SCH_1):PAGE181
     2    GND @S9S_MB_2U_LIB.S9S_MB_2U(SCH_1):GND    I78 @S9S_MB_2U_LIB.S9S_MB_2U(SCH_1):PAGE181

C1207 Q_CAP_C0402-10UF,6.3V,20%,X6S,A
     1 P1V8_PCH_AUX @S9S_MB_2U_LIB.S9S_MB_2U(SCH_1):P1V8_PCH_AUX    I32 @S9S_MB_2U_LIB.S9S_MB_2U(SCH_1):PAGE181
     2    GND @S9S_MB_2U_LIB.S9S_MB_2U(SCH_1):GND    I32 @S9S_MB_2U_LIB.S9S_MB_2U(SCH_1):PAGE181

C1209 Q_CAP_0402-100PF,50V,5%,NPO,CHA
     1 PWRGD_SYS_PWROK_R @S9S_MB_2U_LIB.S9S_MB_2U(SCH_1):PWRGD_SYS_PWROK_R     I3 @S9S_MB_2U_LIB.S9S_MB_2U(SCH_1):PAGE209
     2    GND @S9S_MB_2U_LIB.S9S_MB_2U(SCH_1):GND     I3 @S9S_MB_2U_LIB.S9S_MB_2U(SCH_1):PAGE209

C1210 Q_CAP_C0402-10UF,6.3V,20%,X6S,A
     1 P1V05_PCH_AUX @S9S_MB_2U_LIB.S9S_MB_2U(SCH_1):P1V05_PCH_AUX    I45 @S9S_MB_2U_LIB.S9S_MB_2U(SCH_1):PAGE181
     2    GND @S9S_MB_2U_LIB.S9S_MB_2U(SCH_1):GND    I45 @S9S_MB_2U_LIB.S9S_MB_2U(SCH_1):PAGE181

C1211 Q_CAP_0402-100PF,50V,5%,NPO,CHA
     1 PWRGD_PCH_PWROK_R @S9S_MB_2U_LIB.S9S_MB_2U(SCH_1):PWRGD_PCH_PWROK_R     I4 @S9S_MB_2U_LIB.S9S_MB_2U(SCH_1):PAGE209
     2    GND @S9S_MB_2U_LIB.S9S_MB_2U(SCH_1):GND     I4 @S9S_MB_2U_LIB.S9S_MB_2U(SCH_1):PAGE209

C1213 Q_CAP_C0805-22UF,16V,20%,X6S,CB
     1 P12V_OCP_SFF @S9S_MB_2U_LIB.S9S_MB_2U(SCH_1):P12V_OCP_SFF    I89 @S9S_MB_2U_LIB.S9S_MB_2U(SCH_1):PAGE150
     2    GND @S9S_MB_2U_LIB.S9S_MB_2U(SCH_1):GND    I89 @S9S_MB_2U_LIB.S9S_MB_2U(SCH_1):PAGE150

C1214 Q_CAP_C0402-2.2UF,10V,10%,X6S,A
     1 P1V05_PCH_AUX @S9S_MB_2U_LIB.S9S_MB_2U(SCH_1):P1V05_PCH_AUX    I61 @S9S_MB_2U_LIB.S9S_MB_2U(SCH_1):PAGE181
     2    GND @S9S_MB_2U_LIB.S9S_MB_2U(SCH_1):GND    I61 @S9S_MB_2U_LIB.S9S_MB_2U(SCH_1):PAGE181

C1226 Q_CAP_C0402-0.22UF,25V,10%,X7RA
     1 VR_P5V_EN_D_R @S9S_MB_2U_LIB.S9S_MB_2U(SCH_1):VR_P5V_EN_D_R    I68 @S9S_MB_2U_LIB.S9S_MB_2U(SCH_1):PAGE246
     2    GND @S9S_MB_2U_LIB.S9S_MB_2U(SCH_1):GND    I68 @S9S_MB_2U_LIB.S9S_MB_2U(SCH_1):PAGE246

C1227 Q_CAP_C0402-100NF,50V,10%,X7R,A
     1    P5V @S9S_MB_2U_LIB.S9S_MB_2U(SCH_1):P5V    I44 @S9S_MB_2U_LIB.S9S_MB_2U(SCH_1):PAGE246
     2    GND @S9S_MB_2U_LIB.S9S_MB_2U(SCH_1):GND    I44 @S9S_MB_2U_LIB.S9S_MB_2U(SCH_1):PAGE246

C1228 Q_CAP_C0402-10UF,6.3V,20%,X6S,A
     1 P1V05_PCH_AUX @S9S_MB_2U_LIB.S9S_MB_2U(SCH_1):P1V05_PCH_AUX    I13 @S9S_MB_2U_LIB.S9S_MB_2U(SCH_1):PAGE181
     2    GND @S9S_MB_2U_LIB.S9S_MB_2U(SCH_1):GND    I13 @S9S_MB_2U_LIB.S9S_MB_2U(SCH_1):PAGE181

C1231 Q_CAP_C0402-10UF,6.3V,20%,X6S,A
     1 P1V05_PCH_AUX @S9S_MB_2U_LIB.S9S_MB_2U(SCH_1):P1V05_PCH_AUX    I49 @S9S_MB_2U_LIB.S9S_MB_2U(SCH_1):PAGE181
     2    GND @S9S_MB_2U_LIB.S9S_MB_2U(SCH_1):GND    I49 @S9S_MB_2U_LIB.S9S_MB_2U(SCH_1):PAGE181

C1232 Q_CAP_C0805-22UF,16V,20%,X6S,CB
     1 P12V_OCP_SFF @S9S_MB_2U_LIB.S9S_MB_2U(SCH_1):P12V_OCP_SFF    I90 @S9S_MB_2U_LIB.S9S_MB_2U(SCH_1):PAGE150
     2    GND @S9S_MB_2U_LIB.S9S_MB_2U(SCH_1):GND    I90 @S9S_MB_2U_LIB.S9S_MB_2U(SCH_1):PAGE150

C1233 Q_CAP_0402-0.1UF,25V,10%,X7R,CA
     1 P12V_OCP_SFF @S9S_MB_2U_LIB.S9S_MB_2U(SCH_1):P12V_OCP_SFF    I91 @S9S_MB_2U_LIB.S9S_MB_2U(SCH_1):PAGE150
     2    GND @S9S_MB_2U_LIB.S9S_MB_2U(SCH_1):GND    I91 @S9S_MB_2U_LIB.S9S_MB_2U(SCH_1):PAGE150

C1234 Q_CAP_0402-0.1UF,25V,10%,X7R,CA
     1 P12V_OCP_SFF @S9S_MB_2U_LIB.S9S_MB_2U(SCH_1):P12V_OCP_SFF   I110 @S9S_MB_2U_LIB.S9S_MB_2U(SCH_1):PAGE150
     2    GND @S9S_MB_2U_LIB.S9S_MB_2U(SCH_1):GND   I110 @S9S_MB_2U_LIB.S9S_MB_2U(SCH_1):PAGE150

C1235 Q_CAP_0402-0.1UF,25V,10%,X7R,CA
     1 P12V_OCP_SFF @S9S_MB_2U_LIB.S9S_MB_2U(SCH_1):P12V_OCP_SFF   I111 @S9S_MB_2U_LIB.S9S_MB_2U(SCH_1):PAGE150
     2    GND @S9S_MB_2U_LIB.S9S_MB_2U(SCH_1):GND   I111 @S9S_MB_2U_LIB.S9S_MB_2U(SCH_1):PAGE150

C1236 Q_CAP_0402-0.1UF,25V,10%,X7R,CA
     1 P12V_OCP_SFF @S9S_MB_2U_LIB.S9S_MB_2U(SCH_1):P12V_OCP_SFF   I113 @S9S_MB_2U_LIB.S9S_MB_2U(SCH_1):PAGE150
     2    GND @S9S_MB_2U_LIB.S9S_MB_2U(SCH_1):GND   I113 @S9S_MB_2U_LIB.S9S_MB_2U(SCH_1):PAGE150

C1237 Q_CAP_0402-0.1UF,25V,10%,X7R,CA
     1 P3V3_OCP_SFF @S9S_MB_2U_LIB.S9S_MB_2U(SCH_1):P3V3_OCP_SFF   I114 @S9S_MB_2U_LIB.S9S_MB_2U(SCH_1):PAGE150
     2    GND @S9S_MB_2U_LIB.S9S_MB_2U(SCH_1):GND   I114 @S9S_MB_2U_LIB.S9S_MB_2U(SCH_1):PAGE150

C1238 Q_CAP_0402-0.1UF,25V,10%,X7R,CA
     1 P3V3_OCP_SFF @S9S_MB_2U_LIB.S9S_MB_2U(SCH_1):P3V3_OCP_SFF   I115 @S9S_MB_2U_LIB.S9S_MB_2U(SCH_1):PAGE150
     2    GND @S9S_MB_2U_LIB.S9S_MB_2U(SCH_1):GND   I115 @S9S_MB_2U_LIB.S9S_MB_2U(SCH_1):PAGE150

C1239 Q_CAP_0402-0.1UF,25V,10%,X7R,CA
     1 P3V3_OCP_SFF @S9S_MB_2U_LIB.S9S_MB_2U(SCH_1):P3V3_OCP_SFF   I116 @S9S_MB_2U_LIB.S9S_MB_2U(SCH_1):PAGE150
     2    GND @S9S_MB_2U_LIB.S9S_MB_2U(SCH_1):GND   I116 @S9S_MB_2U_LIB.S9S_MB_2U(SCH_1):PAGE150

C1240 Q_CAP_0402-0.1UF,25V,10%,X7R,CA
     1 P3V3_OCP_SFF @S9S_MB_2U_LIB.S9S_MB_2U(SCH_1):P3V3_OCP_SFF   I168 @S9S_MB_2U_LIB.S9S_MB_2U(SCH_1):PAGE150
     2    GND @S9S_MB_2U_LIB.S9S_MB_2U(SCH_1):GND   I168 @S9S_MB_2U_LIB.S9S_MB_2U(SCH_1):PAGE150

C1242 Q_CAP_C0402-2.2UF,10V,10%,X6S,A
     1 P1V05_PCH_AUX @S9S_MB_2U_LIB.S9S_MB_2U(SCH_1):P1V05_PCH_AUX    I63 @S9S_MB_2U_LIB.S9S_MB_2U(SCH_1):PAGE181
     2    GND @S9S_MB_2U_LIB.S9S_MB_2U(SCH_1):GND    I63 @S9S_MB_2U_LIB.S9S_MB_2U(SCH_1):PAGE181

C1243 Q_CAP_C0805-47UF,6.3V,20%,X6S,A
     1 P3V3_AUX @S9S_MB_2U_LIB.S9S_MB_2U(SCH_1):P3V3_AUX   I162 @S9S_MB_2U_LIB.S9S_MB_2U(SCH_1):PAGE181
     2    GND @S9S_MB_2U_LIB.S9S_MB_2U(SCH_1):GND   I162 @S9S_MB_2U_LIB.S9S_MB_2U(SCH_1):PAGE181

C1244 Q_CAP_C0805-47UF,4V,20%,X6S,CHA
     1 P1V05_PCH_AUX @S9S_MB_2U_LIB.S9S_MB_2U(SCH_1):P1V05_PCH_AUX   I152 @S9S_MB_2U_LIB.S9S_MB_2U(SCH_1):PAGE181
     2    GND @S9S_MB_2U_LIB.S9S_MB_2U(SCH_1):GND   I152 @S9S_MB_2U_LIB.S9S_MB_2U(SCH_1):PAGE181

C1245 Q_CAP_C0805-47UF,6.3V,20%,X6S,A
     1 P3V3_AUX @S9S_MB_2U_LIB.S9S_MB_2U(SCH_1):P3V3_AUX   I163 @S9S_MB_2U_LIB.S9S_MB_2U(SCH_1):PAGE181
     2    GND @S9S_MB_2U_LIB.S9S_MB_2U(SCH_1):GND   I163 @S9S_MB_2U_LIB.S9S_MB_2U(SCH_1):PAGE181

C1246 Q_CAP_C0805-47UF,4V,20%,X6S,CHA
     1 P1V05_PCH_AUX @S9S_MB_2U_LIB.S9S_MB_2U(SCH_1):P1V05_PCH_AUX   I153 @S9S_MB_2U_LIB.S9S_MB_2U(SCH_1):PAGE181
     2    GND @S9S_MB_2U_LIB.S9S_MB_2U(SCH_1):GND   I153 @S9S_MB_2U_LIB.S9S_MB_2U(SCH_1):PAGE181

C1247 Q_CAP_C0805-47UF,4V,20%,X6S,CHA
     1 P1V05_PCH_AUX @S9S_MB_2U_LIB.S9S_MB_2U(SCH_1):P1V05_PCH_AUX   I154 @S9S_MB_2U_LIB.S9S_MB_2U(SCH_1):PAGE181
     2    GND @S9S_MB_2U_LIB.S9S_MB_2U(SCH_1):GND   I154 @S9S_MB_2U_LIB.S9S_MB_2U(SCH_1):PAGE181

C1248 Q_CAP_C0805-47UF,4V,20%,X6S,CHA
     1 P1V05_PCH_AUX @S9S_MB_2U_LIB.S9S_MB_2U(SCH_1):P1V05_PCH_AUX   I155 @S9S_MB_2U_LIB.S9S_MB_2U(SCH_1):PAGE181
     2    GND @S9S_MB_2U_LIB.S9S_MB_2U(SCH_1):GND   I155 @S9S_MB_2U_LIB.S9S_MB_2U(SCH_1):PAGE181

C1249 Q_CAP_C0805-47UF,4V,20%,X6S,CHA
     1 P1V05_PCH_AUX @S9S_MB_2U_LIB.S9S_MB_2U(SCH_1):P1V05_PCH_AUX   I156 @S9S_MB_2U_LIB.S9S_MB_2U(SCH_1):PAGE181
     2    GND @S9S_MB_2U_LIB.S9S_MB_2U(SCH_1):GND   I156 @S9S_MB_2U_LIB.S9S_MB_2U(SCH_1):PAGE181

C1250 Q_CAP_0402-1UF,6.3V,10%,EMPTY,A
     1 P1V05_PCH_AUX @S9S_MB_2U_LIB.S9S_MB_2U(SCH_1):P1V05_PCH_AUX   I137 @S9S_MB_2U_LIB.S9S_MB_2U(SCH_1):PAGE181
     2    GND @S9S_MB_2U_LIB.S9S_MB_2U(SCH_1):GND   I137 @S9S_MB_2U_LIB.S9S_MB_2U(SCH_1):PAGE181

C1251 Q_CAP_C0603-10UF,6.3V,20%,X6S,A
     1 P1V05_PCH_PLL_AUX @S9S_MB_2U_LIB.S9S_MB_2U(SCH_1):P1V05_PCH_PLL_AUX   I110 @S9S_MB_2U_LIB.S9S_MB_2U(SCH_1):PAGE181
     2    GND @S9S_MB_2U_LIB.S9S_MB_2U(SCH_1):GND   I110 @S9S_MB_2U_LIB.S9S_MB_2U(SCH_1):PAGE181

C1252 Q_CAP_C0603-10UF,6.3V,20%,X6S,A
     1 P1V8_PCH_PLL_AUX @S9S_MB_2U_LIB.S9S_MB_2U(SCH_1):P1V8_PCH_PLL_AUX   I125 @S9S_MB_2U_LIB.S9S_MB_2U(SCH_1):PAGE181
     2    GND @S9S_MB_2U_LIB.S9S_MB_2U(SCH_1):GND   I125 @S9S_MB_2U_LIB.S9S_MB_2U(SCH_1):PAGE181

C1253 Q_CAP_0402-1UF,6.3V,10%,EMPTY,A
     1 P1V8_PCH_AUX @S9S_MB_2U_LIB.S9S_MB_2U(SCH_1):P1V8_PCH_AUX   I147 @S9S_MB_2U_LIB.S9S_MB_2U(SCH_1):PAGE181
     2    GND @S9S_MB_2U_LIB.S9S_MB_2U(SCH_1):GND   I147 @S9S_MB_2U_LIB.S9S_MB_2U(SCH_1):PAGE181

C1254 Q_CAP_C0603-10UF,6.3V,20%,X6S,A
     1 P1V05_PCH_PLL_AUX @S9S_MB_2U_LIB.S9S_MB_2U(SCH_1):P1V05_PCH_PLL_AUX   I111 @S9S_MB_2U_LIB.S9S_MB_2U(SCH_1):PAGE181
     2    GND @S9S_MB_2U_LIB.S9S_MB_2U(SCH_1):GND   I111 @S9S_MB_2U_LIB.S9S_MB_2U(SCH_1):PAGE181

C1255 Q_CAP_C0603-10UF,6.3V,20%,X6S,A
     1 P1V8_PCH_PLL_AUX @S9S_MB_2U_LIB.S9S_MB_2U(SCH_1):P1V8_PCH_PLL_AUX   I123 @S9S_MB_2U_LIB.S9S_MB_2U(SCH_1):PAGE181
     2    GND @S9S_MB_2U_LIB.S9S_MB_2U(SCH_1):GND   I123 @S9S_MB_2U_LIB.S9S_MB_2U(SCH_1):PAGE181

C1256 Q_CAP_0402-1UF,6.3V,10%,EMPTY,A
     1 P1V05_PCH_PLL_AUX @S9S_MB_2U_LIB.S9S_MB_2U(SCH_1):P1V05_PCH_PLL_AUX   I136 @S9S_MB_2U_LIB.S9S_MB_2U(SCH_1):PAGE181
     2    GND @S9S_MB_2U_LIB.S9S_MB_2U(SCH_1):GND   I136 @S9S_MB_2U_LIB.S9S_MB_2U(SCH_1):PAGE181

C1257 Q_CAP_0402-1UF,6.3V,10%,EMPTY,A
     1 P1V8_PCH_PLL_AUX @S9S_MB_2U_LIB.S9S_MB_2U(SCH_1):P1V8_PCH_PLL_AUX   I146 @S9S_MB_2U_LIB.S9S_MB_2U(SCH_1):PAGE181
     2    GND @S9S_MB_2U_LIB.S9S_MB_2U(SCH_1):GND   I146 @S9S_MB_2U_LIB.S9S_MB_2U(SCH_1):PAGE181

C1258 Q_CAP_C0805-47UF,4V,20%,X6S,CHA
     1 P1V05_PCH_PLL_AUX @S9S_MB_2U_LIB.S9S_MB_2U(SCH_1):P1V05_PCH_PLL_AUX   I157 @S9S_MB_2U_LIB.S9S_MB_2U(SCH_1):PAGE181
     2    GND @S9S_MB_2U_LIB.S9S_MB_2U(SCH_1):GND   I157 @S9S_MB_2U_LIB.S9S_MB_2U(SCH_1):PAGE181

C1259 Q_CAP_C0805-47UF,4V,20%,X6S,CHA
     1 P1V8_PCH_PLL_AUX @S9S_MB_2U_LIB.S9S_MB_2U(SCH_1):P1V8_PCH_PLL_AUX   I158 @S9S_MB_2U_LIB.S9S_MB_2U(SCH_1):PAGE181
     2    GND @S9S_MB_2U_LIB.S9S_MB_2U(SCH_1):GND   I158 @S9S_MB_2U_LIB.S9S_MB_2U(SCH_1):PAGE181

C1260 Q_CAP_C0603-10UF,6.3V,20%,X6S,A
     1 P1V05_PCH_PLL_AUX @S9S_MB_2U_LIB.S9S_MB_2U(SCH_1):P1V05_PCH_PLL_AUX   I131 @S9S_MB_2U_LIB.S9S_MB_2U(SCH_1):PAGE181
     2    GND @S9S_MB_2U_LIB.S9S_MB_2U(SCH_1):GND   I131 @S9S_MB_2U_LIB.S9S_MB_2U(SCH_1):PAGE181

C1261 Q_CAP_C0603-10UF,6.3V,20%,X6S,A
     1 P1V8_PCH_PLL_AUX @S9S_MB_2U_LIB.S9S_MB_2U(SCH_1):P1V8_PCH_PLL_AUX   I142 @S9S_MB_2U_LIB.S9S_MB_2U(SCH_1):PAGE181
     2    GND @S9S_MB_2U_LIB.S9S_MB_2U(SCH_1):GND   I142 @S9S_MB_2U_LIB.S9S_MB_2U(SCH_1):PAGE181

C1262 Q_CAP_C0402-10UF,6.3V,20%,X6S,A
     1 P1V05_PCH_PLL_AUX @S9S_MB_2U_LIB.S9S_MB_2U(SCH_1):P1V05_PCH_PLL_AUX   I104 @S9S_MB_2U_LIB.S9S_MB_2U(SCH_1):PAGE181
     2    GND @S9S_MB_2U_LIB.S9S_MB_2U(SCH_1):GND   I104 @S9S_MB_2U_LIB.S9S_MB_2U(SCH_1):PAGE181

C1263 Q_CAP_C0402-10UF,6.3V,20%,X6S,A
     1 P1V8_PCH_PLL_AUX @S9S_MB_2U_LIB.S9S_MB_2U(SCH_1):P1V8_PCH_PLL_AUX   I119 @S9S_MB_2U_LIB.S9S_MB_2U(SCH_1):PAGE181
     2    GND @S9S_MB_2U_LIB.S9S_MB_2U(SCH_1):GND   I119 @S9S_MB_2U_LIB.S9S_MB_2U(SCH_1):PAGE181

C1264 Q_CAP_0402-1UF,6.3V,10%,EMPTY,A
     1 P1V05_PCH_PLL_AUX @S9S_MB_2U_LIB.S9S_MB_2U(SCH_1):P1V05_PCH_PLL_AUX   I133 @S9S_MB_2U_LIB.S9S_MB_2U(SCH_1):PAGE181
     2    GND @S9S_MB_2U_LIB.S9S_MB_2U(SCH_1):GND   I133 @S9S_MB_2U_LIB.S9S_MB_2U(SCH_1):PAGE181

C1265 Q_CAP_0402-1UF,6.3V,10%,EMPTY,A
     1 P1V8_PCH_PLL_AUX @S9S_MB_2U_LIB.S9S_MB_2U(SCH_1):P1V8_PCH_PLL_AUX   I140 @S9S_MB_2U_LIB.S9S_MB_2U(SCH_1):PAGE181
     2    GND @S9S_MB_2U_LIB.S9S_MB_2U(SCH_1):GND   I140 @S9S_MB_2U_LIB.S9S_MB_2U(SCH_1):PAGE181

C1266 Q_CAP_C0402-10UF,6.3V,20%,X6S,A
     1 P1V8_PCH_PLL_AUX @S9S_MB_2U_LIB.S9S_MB_2U(SCH_1):P1V8_PCH_PLL_AUX   I127 @S9S_MB_2U_LIB.S9S_MB_2U(SCH_1):PAGE181
     2    GND @S9S_MB_2U_LIB.S9S_MB_2U(SCH_1):GND   I127 @S9S_MB_2U_LIB.S9S_MB_2U(SCH_1):PAGE181

C1272 Q_CAP_C0805-47UF,4V,20%,X6S,CHA
     1 P1V05_PCH_PLL_AUX @S9S_MB_2U_LIB.S9S_MB_2U(SCH_1):P1V05_PCH_PLL_AUX   I159 @S9S_MB_2U_LIB.S9S_MB_2U(SCH_1):PAGE181
     2    GND @S9S_MB_2U_LIB.S9S_MB_2U(SCH_1):GND   I159 @S9S_MB_2U_LIB.S9S_MB_2U(SCH_1):PAGE181

C1273 Q_CAP_C0805-47UF,4V,20%,X6S,CHA
     1 P1V8_PCH_PLL_AUX @S9S_MB_2U_LIB.S9S_MB_2U(SCH_1):P1V8_PCH_PLL_AUX   I151 @S9S_MB_2U_LIB.S9S_MB_2U(SCH_1):PAGE181
     2    GND @S9S_MB_2U_LIB.S9S_MB_2U(SCH_1):GND   I151 @S9S_MB_2U_LIB.S9S_MB_2U(SCH_1):PAGE181

C1274 Q_CAP_0402-0.1UF,25V,10%,X7R,CA
     1 P3V3_AUX @S9S_MB_2U_LIB.S9S_MB_2U(SCH_1):P3V3_AUX    I59 @S9S_MB_2U_LIB.S9S_MB_2U(SCH_1):PAGE152
     2    GND @S9S_MB_2U_LIB.S9S_MB_2U(SCH_1):GND    I59 @S9S_MB_2U_LIB.S9S_MB_2U(SCH_1):PAGE152

C1275 Q_CAP_0402-0.1UF,25V,10%,X7R,CA
     1 P3V3_AUX @S9S_MB_2U_LIB.S9S_MB_2U(SCH_1):P3V3_AUX    I49 @S9S_MB_2U_LIB.S9S_MB_2U(SCH_1):PAGE152
     2    GND @S9S_MB_2U_LIB.S9S_MB_2U(SCH_1):GND    I49 @S9S_MB_2U_LIB.S9S_MB_2U(SCH_1):PAGE152

C1276 Q_CAP_C0805-22UF,16V,20%,X6S,CA
     1 P12V_E1S_0 @S9S_MB_2U_LIB.S9S_MB_2U(SCH_1):P12V_E1S_0   I260 @S9S_MB_2U_LIB.S9S_MB_2U(SCH_1):PAGE297
     2    GND @S9S_MB_2U_LIB.S9S_MB_2U(SCH_1):GND   I260 @S9S_MB_2U_LIB.S9S_MB_2U(SCH_1):PAGE297

C1277 Q_CAP_C0805-22UF,16V,20%,X6S,CA
     1 P12V_E1S_0 @S9S_MB_2U_LIB.S9S_MB_2U(SCH_1):P12V_E1S_0   I237 @S9S_MB_2U_LIB.S9S_MB_2U(SCH_1):PAGE297
     2    GND @S9S_MB_2U_LIB.S9S_MB_2U(SCH_1):GND   I237 @S9S_MB_2U_LIB.S9S_MB_2U(SCH_1):PAGE297

C1278 Q_CAP_0402-0.1UF,25V,10%,X7R,CA
     1 P12V_E1S_0 @S9S_MB_2U_LIB.S9S_MB_2U(SCH_1):P12V_E1S_0   I258 @S9S_MB_2U_LIB.S9S_MB_2U(SCH_1):PAGE297
     2    GND @S9S_MB_2U_LIB.S9S_MB_2U(SCH_1):GND   I258 @S9S_MB_2U_LIB.S9S_MB_2U(SCH_1):PAGE297

C1279 Q_CAP_0402-0.1UF,25V,10%,X7R,CA
     1 P12V_E1S_0 @S9S_MB_2U_LIB.S9S_MB_2U(SCH_1):P12V_E1S_0   I252 @S9S_MB_2U_LIB.S9S_MB_2U(SCH_1):PAGE297
     2    GND @S9S_MB_2U_LIB.S9S_MB_2U(SCH_1):GND   I252 @S9S_MB_2U_LIB.S9S_MB_2U(SCH_1):PAGE297

C1282 Q_CAP_0402-0.1UF,25V,10%,X7R,CA
     1 P3V3_E1S_0 @S9S_MB_2U_LIB.S9S_MB_2U(SCH_1):P3V3_E1S_0   I247 @S9S_MB_2U_LIB.S9S_MB_2U(SCH_1):PAGE297
     2    GND @S9S_MB_2U_LIB.S9S_MB_2U(SCH_1):GND   I247 @S9S_MB_2U_LIB.S9S_MB_2U(SCH_1):PAGE297

C1283 Q_CAP_0402-0.1UF,25V,10%,X7R,CA
     1 P3V3_E1S_0 @S9S_MB_2U_LIB.S9S_MB_2U(SCH_1):P3V3_E1S_0   I245 @S9S_MB_2U_LIB.S9S_MB_2U(SCH_1):PAGE297
     2    GND @S9S_MB_2U_LIB.S9S_MB_2U(SCH_1):GND   I245 @S9S_MB_2U_LIB.S9S_MB_2U(SCH_1):PAGE297

C1288 Q_CAP_0402-0.1UF,25V,10%,X7R,CA
     1 P3V3_AUX @S9S_MB_2U_LIB.S9S_MB_2U(SCH_1):P3V3_AUX   I112 @S9S_MB_2U_LIB.S9S_MB_2U(SCH_1):PAGE137
     2    GND @S9S_MB_2U_LIB.S9S_MB_2U(SCH_1):GND   I112 @S9S_MB_2U_LIB.S9S_MB_2U(SCH_1):PAGE137

C1289 Q_CAP_C0402-1UF,25V,10%,X6S,CHA
     1 P3V3_AUX @S9S_MB_2U_LIB.S9S_MB_2U(SCH_1):P3V3_AUX   I110 @S9S_MB_2U_LIB.S9S_MB_2U(SCH_1):PAGE137
     2    GND @S9S_MB_2U_LIB.S9S_MB_2U(SCH_1):GND   I110 @S9S_MB_2U_LIB.S9S_MB_2U(SCH_1):PAGE137

C1290 Q_CAP_C0402-1UF,25V,10%,X6S,CHA
     1 P3V3_AUX @S9S_MB_2U_LIB.S9S_MB_2U(SCH_1):P3V3_AUX    I43 @S9S_MB_2U_LIB.S9S_MB_2U(SCH_1):PAGE226
     2    GND @S9S_MB_2U_LIB.S9S_MB_2U(SCH_1):GND    I43 @S9S_MB_2U_LIB.S9S_MB_2U(SCH_1):PAGE226

C1291 Q_CAP_C0402-1UF,25V,10%,X6S,CHA
     1 P3V3_AUX @S9S_MB_2U_LIB.S9S_MB_2U(SCH_1):P3V3_AUX    I16 @S9S_MB_2U_LIB.S9S_MB_2U(SCH_1):PAGE226
     2    GND @S9S_MB_2U_LIB.S9S_MB_2U(SCH_1):GND    I16 @S9S_MB_2U_LIB.S9S_MB_2U(SCH_1):PAGE226

C1292 Q_CAP_0402-0.1UF,25V,10%,X7R,CA
     1 P3V3_AUX @S9S_MB_2U_LIB.S9S_MB_2U(SCH_1):P3V3_AUX    I90 @S9S_MB_2U_LIB.S9S_MB_2U(SCH_1):PAGE137
     2    GND @S9S_MB_2U_LIB.S9S_MB_2U(SCH_1):GND    I90 @S9S_MB_2U_LIB.S9S_MB_2U(SCH_1):PAGE137

C1293 Q_CAP_C0402-1UF,25V,10%,X6S,CHA
     1 FM_BMC_EN_DET @S9S_MB_2U_LIB.S9S_MB_2U(SCH_1):FM_BMC_EN_DET    I95 @S9S_MB_2U_LIB.S9S_MB_2U(SCH_1):PAGE137
     2    GND @S9S_MB_2U_LIB.S9S_MB_2U(SCH_1):GND    I95 @S9S_MB_2U_LIB.S9S_MB_2U(SCH_1):PAGE137

C1296 Q_CAP_0402-1000PF,50V,5%,X7R,TA
     1 PWRGD_PVNN_MAIN_CPU0 @S9S_MB_2U_LIB.S9S_MB_2U(SCH_1):PWRGD_PVNN_MAIN_CPU0    I31 @S9S_MB_2U_LIB.S9S_MB_2U(SCH_1):PAGE268
     2    GND @S9S_MB_2U_LIB.S9S_MB_2U(SCH_1):GND    I31 @S9S_MB_2U_LIB.S9S_MB_2U(SCH_1):PAGE268

C1297 Q_CAP_0402-1000PF,50V,5%,X7R,TA
     1 PWRGD_PVNN_MAIN_CPU1 @S9S_MB_2U_LIB.S9S_MB_2U(SCH_1):PWRGD_PVNN_MAIN_CPU1    I37 @S9S_MB_2U_LIB.S9S_MB_2U(SCH_1):PAGE286
     2    GND @S9S_MB_2U_LIB.S9S_MB_2U(SCH_1):GND    I37 @S9S_MB_2U_LIB.S9S_MB_2U(SCH_1):PAGE286

C1300 Q_CAP_0402-1000PF,50V,5%,EMPTYA
     1 FM_PVPP_HBM_CPU0_EN @S9S_MB_2U_LIB.S9S_MB_2U(SCH_1):FM_PVPP_HBM_CPU0_EN    I12 @S9S_MB_2U_LIB.S9S_MB_2U(SCH_1):PAGE267
     2    GND @S9S_MB_2U_LIB.S9S_MB_2U(SCH_1):GND    I12 @S9S_MB_2U_LIB.S9S_MB_2U(SCH_1):PAGE267

C1301 Q_CAP_0402-1000PF,50V,5%,X7R,TA
     1 PWRGD_PVPP_HBM_CPU0_R @S9S_MB_2U_LIB.S9S_MB_2U(SCH_1):PWRGD_PVPP_HBM_CPU0_R    I30 @S9S_MB_2U_LIB.S9S_MB_2U(SCH_1):PAGE267
     2    GND @S9S_MB_2U_LIB.S9S_MB_2U(SCH_1):GND    I30 @S9S_MB_2U_LIB.S9S_MB_2U(SCH_1):PAGE267

C1302 Q_CAP_C0402-22UF,4V,20%,X6S,CHA
     1 PVNN_TERM_CPU0 @S9S_MB_2U_LIB.S9S_MB_2U(SCH_1):PVNN_TERM_CPU0    I82 @S9S_MB_2U_LIB.S9S_MB_2U(SCH_1):PAGE227
     2    GND @S9S_MB_2U_LIB.S9S_MB_2U(SCH_1):GND    I82 @S9S_MB_2U_LIB.S9S_MB_2U(SCH_1):PAGE227

C1305 Q_CAP_0402-0.1UF,25V,10%,X7R,CA
     1 P3V3_AUX @S9S_MB_2U_LIB.S9S_MB_2U(SCH_1):P3V3_AUX    I52 @S9S_MB_2U_LIB.S9S_MB_2U(SCH_1):PAGE183
     2    GND @S9S_MB_2U_LIB.S9S_MB_2U(SCH_1):GND    I52 @S9S_MB_2U_LIB.S9S_MB_2U(SCH_1):PAGE183

C1307 Q_CAP_0402-1000PF,50V,5%,EMPTYA
     1 FM_PVNN_MAIN_CPU0_EN @S9S_MB_2U_LIB.S9S_MB_2U(SCH_1):FM_PVNN_MAIN_CPU0_EN     I4 @S9S_MB_2U_LIB.S9S_MB_2U(SCH_1):PAGE268
     2    GND @S9S_MB_2U_LIB.S9S_MB_2U(SCH_1):GND     I4 @S9S_MB_2U_LIB.S9S_MB_2U(SCH_1):PAGE268

C1308 Q_CAP_0402-1000PF,50V,5%,EMPTYA
     1 FM_PVNN_MAIN_CPU1_EN @S9S_MB_2U_LIB.S9S_MB_2U(SCH_1):FM_PVNN_MAIN_CPU1_EN     I6 @S9S_MB_2U_LIB.S9S_MB_2U(SCH_1):PAGE286
     2    GND @S9S_MB_2U_LIB.S9S_MB_2U(SCH_1):GND     I6 @S9S_MB_2U_LIB.S9S_MB_2U(SCH_1):PAGE286

C1309 Q_CAP_C0603-10UF,6.3V,20%,X6S,A
     1 P3V3_AUX_CLK_GEN_VDDXTAL_CK440 @S9S_MB_2U_LIB.S9S_MB_2U(SCH_1):P3V3_AUX_CLK_GEN_VDDXTAL_CK440    I44 @S9S_MB_2U_LIB.S9S_MB_2U(SCH_1):PAGE199
     2    GND @S9S_MB_2U_LIB.S9S_MB_2U(SCH_1):GND    I44 @S9S_MB_2U_LIB.S9S_MB_2U(SCH_1):PAGE199

C1310 Q_CAP_C0603-10UF,6.3V,20%,X6S,A
     1 P3V3_AUX_CLK_GEN_VDDMXCK_CK440 @S9S_MB_2U_LIB.S9S_MB_2U(SCH_1):P3V3_AUX_CLK_GEN_VDDMXCK_CK440    I59 @S9S_MB_2U_LIB.S9S_MB_2U(SCH_1):PAGE199
     2    GND @S9S_MB_2U_LIB.S9S_MB_2U(SCH_1):GND    I59 @S9S_MB_2U_LIB.S9S_MB_2U(SCH_1):PAGE199

C1311 Q_CAP_C0402-1UF,25V,10%,X6S,CHA
     1 P3V3_AUX_CLK_GEN_VDDXTAL_CK440 @S9S_MB_2U_LIB.S9S_MB_2U(SCH_1):P3V3_AUX_CLK_GEN_VDDXTAL_CK440    I43 @S9S_MB_2U_LIB.S9S_MB_2U(SCH_1):PAGE199
     2    GND @S9S_MB_2U_LIB.S9S_MB_2U(SCH_1):GND    I43 @S9S_MB_2U_LIB.S9S_MB_2U(SCH_1):PAGE199

C1312 Q_CAP_C0402-1UF,25V,10%,X6S,CHA
     1 P3V3_AUX_CLK_GEN_VDDMXCK_CK440 @S9S_MB_2U_LIB.S9S_MB_2U(SCH_1):P3V3_AUX_CLK_GEN_VDDMXCK_CK440    I58 @S9S_MB_2U_LIB.S9S_MB_2U(SCH_1):PAGE199
     2    GND @S9S_MB_2U_LIB.S9S_MB_2U(SCH_1):GND    I58 @S9S_MB_2U_LIB.S9S_MB_2U(SCH_1):PAGE199

C1313 Q_CAP_C0603-10UF,6.3V,20%,X6S,A
     1 P3V3_AUX_CLK_GEN_VDDA25M_CK440 @S9S_MB_2U_LIB.S9S_MB_2U(SCH_1):P3V3_AUX_CLK_GEN_VDDA25M_CK440    I48 @S9S_MB_2U_LIB.S9S_MB_2U(SCH_1):PAGE199
     2    GND @S9S_MB_2U_LIB.S9S_MB_2U(SCH_1):GND    I48 @S9S_MB_2U_LIB.S9S_MB_2U(SCH_1):PAGE199

C1314 Q_CAP_C0603-10UF,6.3V,20%,X6S,A
     1 P3V3_AUX_CLK_GEN_VDDPT_CK440 @S9S_MB_2U_LIB.S9S_MB_2U(SCH_1):P3V3_AUX_CLK_GEN_VDDPT_CK440    I53 @S9S_MB_2U_LIB.S9S_MB_2U(SCH_1):PAGE199
     2    GND @S9S_MB_2U_LIB.S9S_MB_2U(SCH_1):GND    I53 @S9S_MB_2U_LIB.S9S_MB_2U(SCH_1):PAGE199

C1315 Q_CAP_C0402-1UF,25V,10%,X6S,CHA
     1 P3V3_AUX @S9S_MB_2U_LIB.S9S_MB_2U(SCH_1):P3V3_AUX    I24 @S9S_MB_2U_LIB.S9S_MB_2U(SCH_1):PAGE232
     2    GND @S9S_MB_2U_LIB.S9S_MB_2U(SCH_1):GND    I24 @S9S_MB_2U_LIB.S9S_MB_2U(SCH_1):PAGE232

C1316 Q_CAP_C0402-0.047UF,25V,10%,X7A
     1 FM_COMP_P3V3_STBY_CEXT @S9S_MB_2U_LIB.S9S_MB_2U(SCH_1):FM_COMP_P3V3_STBY_CEXT    I47 @S9S_MB_2U_LIB.S9S_MB_2U(SCH_1):PAGE232
     2    GND @S9S_MB_2U_LIB.S9S_MB_2U(SCH_1):GND    I47 @S9S_MB_2U_LIB.S9S_MB_2U(SCH_1):PAGE232

C1317 Q_CAP_0402-0.1UF,25V,10%,X7R,CA
     1 P3V3_AUX @S9S_MB_2U_LIB.S9S_MB_2U(SCH_1):P3V3_AUX     I9 @S9S_MB_2U_LIB.S9S_MB_2U(SCH_1):PAGE232
     2    GND @S9S_MB_2U_LIB.S9S_MB_2U(SCH_1):GND     I9 @S9S_MB_2U_LIB.S9S_MB_2U(SCH_1):PAGE232

C1318 Q_CAP_C0402-1UF,25V,10%,EMPTY,A
     1 PWRGD_DSW_PWROK_R1 @S9S_MB_2U_LIB.S9S_MB_2U(SCH_1):PWRGD_DSW_PWROK_R1     I7 @S9S_MB_2U_LIB.S9S_MB_2U(SCH_1):PAGE232
     2    GND @S9S_MB_2U_LIB.S9S_MB_2U(SCH_1):GND     I7 @S9S_MB_2U_LIB.S9S_MB_2U(SCH_1):PAGE232

C1319 Q_CAP_C0402-1UF,25V,10%,X6S,CHA
     1 PWRGD_DSW_PWROK @S9S_MB_2U_LIB.S9S_MB_2U(SCH_1):PWRGD_DSW_PWROK    I35 @S9S_MB_2U_LIB.S9S_MB_2U(SCH_1):PAGE232
     2    GND @S9S_MB_2U_LIB.S9S_MB_2U(SCH_1):GND    I35 @S9S_MB_2U_LIB.S9S_MB_2U(SCH_1):PAGE232

C1320 Q_CAP_0402-0.1UF,25V,10%,X7R,CA
     1 P3V3_AUX @S9S_MB_2U_LIB.S9S_MB_2U(SCH_1):P3V3_AUX   I126 @S9S_MB_2U_LIB.S9S_MB_2U(SCH_1):PAGE313
     2    GND @S9S_MB_2U_LIB.S9S_MB_2U(SCH_1):GND   I126 @S9S_MB_2U_LIB.S9S_MB_2U(SCH_1):PAGE313

C1321 Q_CAP_0402-0.1UF,25V,10%,X7R,CA
     1 P3V3_AUX @S9S_MB_2U_LIB.S9S_MB_2U(SCH_1):P3V3_AUX    I55 @S9S_MB_2U_LIB.S9S_MB_2U(SCH_1):PAGE226
     2    GND @S9S_MB_2U_LIB.S9S_MB_2U(SCH_1):GND    I55 @S9S_MB_2U_LIB.S9S_MB_2U(SCH_1):PAGE226

C1322 Q_CAP_0402-0.1UF,25V,10%,X7R,CA
     1 P3V3_AUX @S9S_MB_2U_LIB.S9S_MB_2U(SCH_1):P3V3_AUX    I27 @S9S_MB_2U_LIB.S9S_MB_2U(SCH_1):PAGE226
     2    GND @S9S_MB_2U_LIB.S9S_MB_2U(SCH_1):GND    I27 @S9S_MB_2U_LIB.S9S_MB_2U(SCH_1):PAGE226

C1323 Q_CAP_0402-0.1UF,25V,10%,X7R,CA
     1 P1V8_PCH_AUX @S9S_MB_2U_LIB.S9S_MB_2U(SCH_1):P1V8_PCH_AUX    I28 @S9S_MB_2U_LIB.S9S_MB_2U(SCH_1):PAGE183
     2    GND @S9S_MB_2U_LIB.S9S_MB_2U(SCH_1):GND    I28 @S9S_MB_2U_LIB.S9S_MB_2U(SCH_1):PAGE183

C1324 Q_CAP_0402-0.1UF,25V,10%,EMPTYA
     1 FM_CK440Q_DEV_25M_EN @S9S_MB_2U_LIB.S9S_MB_2U(SCH_1):FM_CK440Q_DEV_25M_EN   I286 @S9S_MB_2U_LIB.S9S_MB_2U(SCH_1):PAGE197
     2    GND @S9S_MB_2U_LIB.S9S_MB_2U(SCH_1):GND   I286 @S9S_MB_2U_LIB.S9S_MB_2U(SCH_1):PAGE197

C1325 Q_CAP_0402-0.1UF,25V,10%,X7R,CA
     1 FM_PLD_REV_N @S9S_MB_2U_LIB.S9S_MB_2U(SCH_1):FM_PLD_REV_N    I39 @S9S_MB_2U_LIB.S9S_MB_2U(SCH_1):PAGE312
     2    GND @S9S_MB_2U_LIB.S9S_MB_2U(SCH_1):GND    I39 @S9S_MB_2U_LIB.S9S_MB_2U(SCH_1):PAGE312

C1331 Q_CAP_C0805-10UF,16V,10%,X6S,CA
     1    P5V @S9S_MB_2U_LIB.S9S_MB_2U(SCH_1):P5V    I45 @S9S_MB_2U_LIB.S9S_MB_2U(SCH_1):PAGE246
     2    GND @S9S_MB_2U_LIB.S9S_MB_2U(SCH_1):GND    I45 @S9S_MB_2U_LIB.S9S_MB_2U(SCH_1):PAGE246

C1332 Q_CAP_C0402-100NF,50V,10%,X7R,A
     1 P3V3_AUX @S9S_MB_2U_LIB.S9S_MB_2U(SCH_1):P3V3_AUX    I48 @S9S_MB_2U_LIB.S9S_MB_2U(SCH_1):PAGE246
     2    GND @S9S_MB_2U_LIB.S9S_MB_2U(SCH_1):GND    I48 @S9S_MB_2U_LIB.S9S_MB_2U(SCH_1):PAGE246

C1333 Q_CAP_C0805-10UF,16V,10%,X6S,CA
     1 P3V3_AUX @S9S_MB_2U_LIB.S9S_MB_2U(SCH_1):P3V3_AUX    I49 @S9S_MB_2U_LIB.S9S_MB_2U(SCH_1):PAGE246
     2    GND @S9S_MB_2U_LIB.S9S_MB_2U(SCH_1):GND    I49 @S9S_MB_2U_LIB.S9S_MB_2U(SCH_1):PAGE246

C1336 Q_CAP_C0402-10UF,6.3V,20%,X6S,B
     1 PVNN_TERM_CPU1 @S9S_MB_2U_LIB.S9S_MB_2U(SCH_1):PVNN_TERM_CPU1    I24 @S9S_MB_2U_LIB.S9S_MB_2U(SCH_1):PAGE282
     2    GND @S9S_MB_2U_LIB.S9S_MB_2U(SCH_1):GND    I24 @S9S_MB_2U_LIB.S9S_MB_2U(SCH_1):PAGE282

C1337 Q_CAP_0402-0.1UF,25V,10%,X7R,CA
     1 PVNN_TERM_CPU1 @S9S_MB_2U_LIB.S9S_MB_2U(SCH_1):PVNN_TERM_CPU1    I28 @S9S_MB_2U_LIB.S9S_MB_2U(SCH_1):PAGE282
     2    GND @S9S_MB_2U_LIB.S9S_MB_2U(SCH_1):GND    I28 @S9S_MB_2U_LIB.S9S_MB_2U(SCH_1):PAGE282

C1338 Q_CAP_C0805-10UF,16V,10%,EMPTYA
     1 P3V3_AUX @S9S_MB_2U_LIB.S9S_MB_2U(SCH_1):P3V3_AUX    I50 @S9S_MB_2U_LIB.S9S_MB_2U(SCH_1):PAGE246
     2    GND @S9S_MB_2U_LIB.S9S_MB_2U(SCH_1):GND    I50 @S9S_MB_2U_LIB.S9S_MB_2U(SCH_1):PAGE246

C1339 Q_CAP_C0402-100NF,50V,10%,X7R,A
     1   P3V3 @S9S_MB_2U_LIB.S9S_MB_2U(SCH_1):P3V3    I58 @S9S_MB_2U_LIB.S9S_MB_2U(SCH_1):PAGE246
     2    GND @S9S_MB_2U_LIB.S9S_MB_2U(SCH_1):GND    I58 @S9S_MB_2U_LIB.S9S_MB_2U(SCH_1):PAGE246

C1340 Q_CAP_C0805-10UF,16V,10%,X6S,CA
     1   P3V3 @S9S_MB_2U_LIB.S9S_MB_2U(SCH_1):P3V3    I61 @S9S_MB_2U_LIB.S9S_MB_2U(SCH_1):PAGE246
     2    GND @S9S_MB_2U_LIB.S9S_MB_2U(SCH_1):GND    I61 @S9S_MB_2U_LIB.S9S_MB_2U(SCH_1):PAGE246

C1344 Q_CAP_0402-100PF,50V,5%,EMPTY,A
     1 P12V_AUX_ADC_MAM @S9S_MB_2U_LIB.S9S_MB_2U(SCH_1):P12V_AUX_ADC_MAM   I205 @S9S_MB_2U_LIB.S9S_MB_2U(SCH_1):PAGE239
     2    GND @S9S_MB_2U_LIB.S9S_MB_2U(SCH_1):GND   I205 @S9S_MB_2U_LIB.S9S_MB_2U(SCH_1):PAGE239

C1347 Q_CAP_0402-0.1UF,25V,10%,EMPTYA
     1 MAX11617_VREF @S9S_MB_2U_LIB.S9S_MB_2U(SCH_1):MAX11617_VREF    I70 @S9S_MB_2U_LIB.S9S_MB_2U(SCH_1):PAGE239
     2    GND @S9S_MB_2U_LIB.S9S_MB_2U(SCH_1):GND    I70 @S9S_MB_2U_LIB.S9S_MB_2U(SCH_1):PAGE239

C1353 Q_CAP_C0402-22UF,4V,20%,X6S,CHA
     1 PVNN_MAIN_CPU1 @S9S_MB_2U_LIB.S9S_MB_2U(SCH_1):PVNN_MAIN_CPU1    I49 @S9S_MB_2U_LIB.S9S_MB_2U(SCH_1):PAGE79
     2    GND @S9S_MB_2U_LIB.S9S_MB_2U(SCH_1):GND    I49 @S9S_MB_2U_LIB.S9S_MB_2U(SCH_1):PAGE79

C1362 Q_CAP_C0402-22UF,4V,20%,X6S,CHA
     1 PVNN_MAIN_CPU0 @S9S_MB_2U_LIB.S9S_MB_2U(SCH_1):PVNN_MAIN_CPU0    I16 @S9S_MB_2U_LIB.S9S_MB_2U(SCH_1):PAGE76
     2    GND @S9S_MB_2U_LIB.S9S_MB_2U(SCH_1):GND    I16 @S9S_MB_2U_LIB.S9S_MB_2U(SCH_1):PAGE76

C1363 Q_CAP_C0402-22UF,4V,20%,X6S,CHA
     1 PVNN_MAIN_CPU0 @S9S_MB_2U_LIB.S9S_MB_2U(SCH_1):PVNN_MAIN_CPU0     I5 @S9S_MB_2U_LIB.S9S_MB_2U(SCH_1):PAGE80
     2    GND @S9S_MB_2U_LIB.S9S_MB_2U(SCH_1):GND     I5 @S9S_MB_2U_LIB.S9S_MB_2U(SCH_1):PAGE80

C1364 Q_CAP_C0402-22UF,4V,20%,X6S,CHA
     1 PVNN_MAIN_CPU0 @S9S_MB_2U_LIB.S9S_MB_2U(SCH_1):PVNN_MAIN_CPU0     I9 @S9S_MB_2U_LIB.S9S_MB_2U(SCH_1):PAGE80
     2    GND @S9S_MB_2U_LIB.S9S_MB_2U(SCH_1):GND     I9 @S9S_MB_2U_LIB.S9S_MB_2U(SCH_1):PAGE80

C1365 Q_CAP_C0402-22UF,4V,20%,X6S,CHA
     1 PVNN_MAIN_CPU1 @S9S_MB_2U_LIB.S9S_MB_2U(SCH_1):PVNN_MAIN_CPU1    I20 @S9S_MB_2U_LIB.S9S_MB_2U(SCH_1):PAGE80
     2    GND @S9S_MB_2U_LIB.S9S_MB_2U(SCH_1):GND    I20 @S9S_MB_2U_LIB.S9S_MB_2U(SCH_1):PAGE80

C1366 Q_CAP_C0402-22UF,4V,20%,X6S,CHA
     1 PVNN_MAIN_CPU1 @S9S_MB_2U_LIB.S9S_MB_2U(SCH_1):PVNN_MAIN_CPU1    I28 @S9S_MB_2U_LIB.S9S_MB_2U(SCH_1):PAGE80
     2    GND @S9S_MB_2U_LIB.S9S_MB_2U(SCH_1):GND    I28 @S9S_MB_2U_LIB.S9S_MB_2U(SCH_1):PAGE80

C1387 Q_CAP_C0805-47UF,4V,20%,X6S,CHA
     1 PVNN_MAIN_CPU1 @S9S_MB_2U_LIB.S9S_MB_2U(SCH_1):PVNN_MAIN_CPU1    I49 @S9S_MB_2U_LIB.S9S_MB_2U(SCH_1):PAGE78
     2    GND @S9S_MB_2U_LIB.S9S_MB_2U(SCH_1):GND    I49 @S9S_MB_2U_LIB.S9S_MB_2U(SCH_1):PAGE78

C1388 Q_CAP_C0805-47UF,4V,20%,X6S,CHA
     1 PVPP_HBM_CPU1 @S9S_MB_2U_LIB.S9S_MB_2U(SCH_1):PVPP_HBM_CPU1    I46 @S9S_MB_2U_LIB.S9S_MB_2U(SCH_1):PAGE78
     2    GND @S9S_MB_2U_LIB.S9S_MB_2U(SCH_1):GND    I46 @S9S_MB_2U_LIB.S9S_MB_2U(SCH_1):PAGE78

C1389 Q_CAP_C0603-47UF,2.5V,20%,X6S,A
     1 PVNN_MAIN_CPU1 @S9S_MB_2U_LIB.S9S_MB_2U(SCH_1):PVNN_MAIN_CPU1    I51 @S9S_MB_2U_LIB.S9S_MB_2U(SCH_1):PAGE78
     2    GND @S9S_MB_2U_LIB.S9S_MB_2U(SCH_1):GND    I51 @S9S_MB_2U_LIB.S9S_MB_2U(SCH_1):PAGE78

C1390 Q_CAP_C0805-47UF,4V,20%,X6S,CHA
     1 PVPP_HBM_CPU1 @S9S_MB_2U_LIB.S9S_MB_2U(SCH_1):PVPP_HBM_CPU1    I48 @S9S_MB_2U_LIB.S9S_MB_2U(SCH_1):PAGE78
     2    GND @S9S_MB_2U_LIB.S9S_MB_2U(SCH_1):GND    I48 @S9S_MB_2U_LIB.S9S_MB_2U(SCH_1):PAGE78

C1391 Q_CAP_C0603-47UF,2.5V,20%,X6S,A
     1 PVNN_MAIN_CPU1 @S9S_MB_2U_LIB.S9S_MB_2U(SCH_1):PVNN_MAIN_CPU1    I52 @S9S_MB_2U_LIB.S9S_MB_2U(SCH_1):PAGE78
     2    GND @S9S_MB_2U_LIB.S9S_MB_2U(SCH_1):GND    I52 @S9S_MB_2U_LIB.S9S_MB_2U(SCH_1):PAGE78

C1392 Q_CAP_C0805-47UF,4V,20%,X6S,CHA
     1 PVPP_HBM_CPU1 @S9S_MB_2U_LIB.S9S_MB_2U(SCH_1):PVPP_HBM_CPU1    I53 @S9S_MB_2U_LIB.S9S_MB_2U(SCH_1):PAGE78
     2    GND @S9S_MB_2U_LIB.S9S_MB_2U(SCH_1):GND    I53 @S9S_MB_2U_LIB.S9S_MB_2U(SCH_1):PAGE78

C1393 Q_CAP_C0603-47UF,2.5V,20%,X6S,A
     1 PVNN_MAIN_CPU1 @S9S_MB_2U_LIB.S9S_MB_2U(SCH_1):PVNN_MAIN_CPU1    I57 @S9S_MB_2U_LIB.S9S_MB_2U(SCH_1):PAGE78
     2    GND @S9S_MB_2U_LIB.S9S_MB_2U(SCH_1):GND    I57 @S9S_MB_2U_LIB.S9S_MB_2U(SCH_1):PAGE78

C1396 Q_CAP_C0805-47UF,4V,20%,X6S,CHA
     1 PVPP_HBM_CPU0 @S9S_MB_2U_LIB.S9S_MB_2U(SCH_1):PVPP_HBM_CPU0    I43 @S9S_MB_2U_LIB.S9S_MB_2U(SCH_1):PAGE75
     2    GND @S9S_MB_2U_LIB.S9S_MB_2U(SCH_1):GND    I43 @S9S_MB_2U_LIB.S9S_MB_2U(SCH_1):PAGE75

C1397 Q_CAP_C0805-47UF,4V,20%,X6S,CHA
     1 PVPP_HBM_CPU0 @S9S_MB_2U_LIB.S9S_MB_2U(SCH_1):PVPP_HBM_CPU0    I44 @S9S_MB_2U_LIB.S9S_MB_2U(SCH_1):PAGE75
     2    GND @S9S_MB_2U_LIB.S9S_MB_2U(SCH_1):GND    I44 @S9S_MB_2U_LIB.S9S_MB_2U(SCH_1):PAGE75

C1398 Q_CAP_C0805-47UF,4V,20%,X6S,CHA
     1 PVPP_HBM_CPU0 @S9S_MB_2U_LIB.S9S_MB_2U(SCH_1):PVPP_HBM_CPU0    I58 @S9S_MB_2U_LIB.S9S_MB_2U(SCH_1):PAGE75
     2    GND @S9S_MB_2U_LIB.S9S_MB_2U(SCH_1):GND    I58 @S9S_MB_2U_LIB.S9S_MB_2U(SCH_1):PAGE75

C1399 Q_CAP_C0805-47UF,4V,20%,X6S,CHA
     1 PVNN_MAIN_CPU0 @S9S_MB_2U_LIB.S9S_MB_2U(SCH_1):PVNN_MAIN_CPU0    I13 @S9S_MB_2U_LIB.S9S_MB_2U(SCH_1):PAGE76
     2    GND @S9S_MB_2U_LIB.S9S_MB_2U(SCH_1):GND    I13 @S9S_MB_2U_LIB.S9S_MB_2U(SCH_1):PAGE76

C1400 Q_CAP_C0805-47UF,4V,20%,X6S,CHA
     1 PVNN_MAIN_CPU0 @S9S_MB_2U_LIB.S9S_MB_2U(SCH_1):PVNN_MAIN_CPU0    I14 @S9S_MB_2U_LIB.S9S_MB_2U(SCH_1):PAGE76
     2    GND @S9S_MB_2U_LIB.S9S_MB_2U(SCH_1):GND    I14 @S9S_MB_2U_LIB.S9S_MB_2U(SCH_1):PAGE76

C1403 Q_CAP_C0805-47UF,4V,20%,X6S,CHA
     1 PVNN_MAIN_CPU1 @S9S_MB_2U_LIB.S9S_MB_2U(SCH_1):PVNN_MAIN_CPU1    I43 @S9S_MB_2U_LIB.S9S_MB_2U(SCH_1):PAGE79
     2    GND @S9S_MB_2U_LIB.S9S_MB_2U(SCH_1):GND    I43 @S9S_MB_2U_LIB.S9S_MB_2U(SCH_1):PAGE79

C1404 Q_CAP_C0805-47UF,4V,20%,X6S,CHA
     1 PVNN_MAIN_CPU1 @S9S_MB_2U_LIB.S9S_MB_2U(SCH_1):PVNN_MAIN_CPU1    I44 @S9S_MB_2U_LIB.S9S_MB_2U(SCH_1):PAGE79
     2    GND @S9S_MB_2U_LIB.S9S_MB_2U(SCH_1):GND    I44 @S9S_MB_2U_LIB.S9S_MB_2U(SCH_1):PAGE79

C1405 Q_CAP_C0603-47UF,2.5V,20%,X6S,A
     1 PVNN_MAIN_CPU0 @S9S_MB_2U_LIB.S9S_MB_2U(SCH_1):PVNN_MAIN_CPU0    I47 @S9S_MB_2U_LIB.S9S_MB_2U(SCH_1):PAGE75
     2    GND @S9S_MB_2U_LIB.S9S_MB_2U(SCH_1):GND    I47 @S9S_MB_2U_LIB.S9S_MB_2U(SCH_1):PAGE75

C1406 Q_CAP_C0603-47UF,2.5V,20%,X6S,A
     1 PVNN_MAIN_CPU0 @S9S_MB_2U_LIB.S9S_MB_2U(SCH_1):PVNN_MAIN_CPU0    I61 @S9S_MB_2U_LIB.S9S_MB_2U(SCH_1):PAGE75
     2    GND @S9S_MB_2U_LIB.S9S_MB_2U(SCH_1):GND    I61 @S9S_MB_2U_LIB.S9S_MB_2U(SCH_1):PAGE75

C1407 Q_CAP_C0603-47UF,2.5V,20%,X6S,A
     1 PVNN_MAIN_CPU0 @S9S_MB_2U_LIB.S9S_MB_2U(SCH_1):PVNN_MAIN_CPU0    I62 @S9S_MB_2U_LIB.S9S_MB_2U(SCH_1):PAGE75
     2    GND @S9S_MB_2U_LIB.S9S_MB_2U(SCH_1):GND    I62 @S9S_MB_2U_LIB.S9S_MB_2U(SCH_1):PAGE75

C1409 Q_CAP_C0603-10UF,6.3V,20%,X6S,A
     1 P3V3_DB2000_VDD @S9S_MB_2U_LIB.S9S_MB_2U(SCH_1):P3V3_DB2000_VDD   I419 @S9S_MB_2U_LIB.S9S_MB_2U(SCH_1):PAGE195
     2    GND @S9S_MB_2U_LIB.S9S_MB_2U(SCH_1):GND   I419 @S9S_MB_2U_LIB.S9S_MB_2U(SCH_1):PAGE195

C1436 Q_CAP_C0201-0.22UF,6.3V,10%,X6A
     1 PVPP_HBM_CPU0 @S9S_MB_2U_LIB.S9S_MB_2U(SCH_1):PVPP_HBM_CPU0    I59 @S9S_MB_2U_LIB.S9S_MB_2U(SCH_1):PAGE75
     2    GND @S9S_MB_2U_LIB.S9S_MB_2U(SCH_1):GND    I59 @S9S_MB_2U_LIB.S9S_MB_2U(SCH_1):PAGE75

C1437 Q_CAP_C0201-0.22UF,6.3V,10%,X6A
     1 PVPP_HBM_CPU1 @S9S_MB_2U_LIB.S9S_MB_2U(SCH_1):PVPP_HBM_CPU1    I55 @S9S_MB_2U_LIB.S9S_MB_2U(SCH_1):PAGE78
     2    GND @S9S_MB_2U_LIB.S9S_MB_2U(SCH_1):GND    I55 @S9S_MB_2U_LIB.S9S_MB_2U(SCH_1):PAGE78

C1507 Q_CAP_0402-18PF,50V,5%,C0G,CH0A
     1 XTAL_PCH_RTC2_R @S9S_MB_2U_LIB.S9S_MB_2U(SCH_1):XTAL_PCH_RTC2_R    I10 @S9S_MB_2U_LIB.S9S_MB_2U(SCH_1):PAGE171
     2    GND @S9S_MB_2U_LIB.S9S_MB_2U(SCH_1):GND    I10 @S9S_MB_2U_LIB.S9S_MB_2U(SCH_1):PAGE171

C1508 Q_CAP_0402-18PF,50V,5%,C0G,CH0A
     1 XTAL_PCH_RTC1 @S9S_MB_2U_LIB.S9S_MB_2U(SCH_1):XTAL_PCH_RTC1    I17 @S9S_MB_2U_LIB.S9S_MB_2U(SCH_1):PAGE171
     2    GND @S9S_MB_2U_LIB.S9S_MB_2U(SCH_1):GND    I17 @S9S_MB_2U_LIB.S9S_MB_2U(SCH_1):PAGE171

C1516 Q_CAP_DIFFBUS_C0201-DIFF BUS_0A
     1 P5E_CPU1_PE3_TX_C_DN<15> @S9S_MB_2U_LIB.S9S_MB_2U(SCH_1):P5E_CPU1_PE3_TX_C_DN(15)   I302 @S9S_MB_2U_LIB.S9S_MB_2U(SCH_1):PAGE168
     2 P5E_CPU1_PE3_TX_DN<15> @S9S_MB_2U_LIB.S9S_MB_2U(SCH_1):P5E_CPU1_PE3_TX_DN(15)   I302 @S9S_MB_2U_LIB.S9S_MB_2U(SCH_1):PAGE168

C1517 Q_CAP_DIFFBUS_C0201-DIFF BUS_0A
     1 P5E_CPU1_PE3_TX_C_DP<15> @S9S_MB_2U_LIB.S9S_MB_2U(SCH_1):P5E_CPU1_PE3_TX_C_DP(15)   I301 @S9S_MB_2U_LIB.S9S_MB_2U(SCH_1):PAGE168
     2 P5E_CPU1_PE3_TX_DP<15> @S9S_MB_2U_LIB.S9S_MB_2U(SCH_1):P5E_CPU1_PE3_TX_DP(15)   I301 @S9S_MB_2U_LIB.S9S_MB_2U(SCH_1):PAGE168

C1518 Q_CAP_DIFFBUS_C0201-DIFF BUS_0A
     1 P5E_CPU1_PE3_TX_C_DN<14> @S9S_MB_2U_LIB.S9S_MB_2U(SCH_1):P5E_CPU1_PE3_TX_C_DN(14)   I300 @S9S_MB_2U_LIB.S9S_MB_2U(SCH_1):PAGE168
     2 P5E_CPU1_PE3_TX_DN<14> @S9S_MB_2U_LIB.S9S_MB_2U(SCH_1):P5E_CPU1_PE3_TX_DN(14)   I300 @S9S_MB_2U_LIB.S9S_MB_2U(SCH_1):PAGE168

C1519 Q_CAP_DIFFBUS_C0201-DIFF BUS_0A
     1 P5E_CPU1_PE3_TX_C_DP<14> @S9S_MB_2U_LIB.S9S_MB_2U(SCH_1):P5E_CPU1_PE3_TX_C_DP(14)   I299 @S9S_MB_2U_LIB.S9S_MB_2U(SCH_1):PAGE168
     2 P5E_CPU1_PE3_TX_DP<14> @S9S_MB_2U_LIB.S9S_MB_2U(SCH_1):P5E_CPU1_PE3_TX_DP(14)   I299 @S9S_MB_2U_LIB.S9S_MB_2U(SCH_1):PAGE168

C1520 Q_CAP_DIFFBUS_C0201-DIFF BUS_0A
     1 P5E_CPU1_PE3_TX_C_DN<13> @S9S_MB_2U_LIB.S9S_MB_2U(SCH_1):P5E_CPU1_PE3_TX_C_DN(13)   I297 @S9S_MB_2U_LIB.S9S_MB_2U(SCH_1):PAGE168
     2 P5E_CPU1_PE3_TX_DN<13> @S9S_MB_2U_LIB.S9S_MB_2U(SCH_1):P5E_CPU1_PE3_TX_DN(13)   I297 @S9S_MB_2U_LIB.S9S_MB_2U(SCH_1):PAGE168

C1521 Q_CAP_DIFFBUS_C0201-DIFF BUS_0A
     1 P5E_CPU1_PE3_TX_C_DP<13> @S9S_MB_2U_LIB.S9S_MB_2U(SCH_1):P5E_CPU1_PE3_TX_C_DP(13)   I298 @S9S_MB_2U_LIB.S9S_MB_2U(SCH_1):PAGE168
     2 P5E_CPU1_PE3_TX_DP<13> @S9S_MB_2U_LIB.S9S_MB_2U(SCH_1):P5E_CPU1_PE3_TX_DP(13)   I298 @S9S_MB_2U_LIB.S9S_MB_2U(SCH_1):PAGE168

C1522 Q_CAP_DIFFBUS_C0201-DIFF BUS_0A
     1 P5E_CPU1_PE3_TX_C_DN<12> @S9S_MB_2U_LIB.S9S_MB_2U(SCH_1):P5E_CPU1_PE3_TX_C_DN(12)   I286 @S9S_MB_2U_LIB.S9S_MB_2U(SCH_1):PAGE168
     2 P5E_CPU1_PE3_TX_DN<12> @S9S_MB_2U_LIB.S9S_MB_2U(SCH_1):P5E_CPU1_PE3_TX_DN(12)   I286 @S9S_MB_2U_LIB.S9S_MB_2U(SCH_1):PAGE168

C1523 Q_CAP_DIFFBUS_C0201-DIFF BUS_0A
     1 P5E_CPU1_PE3_TX_C_DP<12> @S9S_MB_2U_LIB.S9S_MB_2U(SCH_1):P5E_CPU1_PE3_TX_C_DP(12)   I285 @S9S_MB_2U_LIB.S9S_MB_2U(SCH_1):PAGE168
     2 P5E_CPU1_PE3_TX_DP<12> @S9S_MB_2U_LIB.S9S_MB_2U(SCH_1):P5E_CPU1_PE3_TX_DP(12)   I285 @S9S_MB_2U_LIB.S9S_MB_2U(SCH_1):PAGE168

C1524 Q_CAP_DIFFBUS_C0201-DIFF BUS_0A
     1 P5E_CPU1_PE3_TX_C_DN<11> @S9S_MB_2U_LIB.S9S_MB_2U(SCH_1):P5E_CPU1_PE3_TX_C_DN(11)   I284 @S9S_MB_2U_LIB.S9S_MB_2U(SCH_1):PAGE168
     2 P5E_CPU1_PE3_TX_DN<11> @S9S_MB_2U_LIB.S9S_MB_2U(SCH_1):P5E_CPU1_PE3_TX_DN(11)   I284 @S9S_MB_2U_LIB.S9S_MB_2U(SCH_1):PAGE168

C1525 Q_CAP_DIFFBUS_C0201-DIFF BUS_0A
     1 P5E_CPU1_PE3_TX_C_DP<11> @S9S_MB_2U_LIB.S9S_MB_2U(SCH_1):P5E_CPU1_PE3_TX_C_DP(11)   I283 @S9S_MB_2U_LIB.S9S_MB_2U(SCH_1):PAGE168
     2 P5E_CPU1_PE3_TX_DP<11> @S9S_MB_2U_LIB.S9S_MB_2U(SCH_1):P5E_CPU1_PE3_TX_DP(11)   I283 @S9S_MB_2U_LIB.S9S_MB_2U(SCH_1):PAGE168

C1526 Q_CAP_DIFFBUS_C0201-DIFF BUS_0A
     1 P5E_CPU1_PE3_TX_C_DN<10> @S9S_MB_2U_LIB.S9S_MB_2U(SCH_1):P5E_CPU1_PE3_TX_C_DN(10)   I282 @S9S_MB_2U_LIB.S9S_MB_2U(SCH_1):PAGE168
     2 P5E_CPU1_PE3_TX_DN<10> @S9S_MB_2U_LIB.S9S_MB_2U(SCH_1):P5E_CPU1_PE3_TX_DN(10)   I282 @S9S_MB_2U_LIB.S9S_MB_2U(SCH_1):PAGE168

C1527 Q_CAP_DIFFBUS_C0201-DIFF BUS_0A
     1 P5E_CPU1_PE3_TX_C_DP<10> @S9S_MB_2U_LIB.S9S_MB_2U(SCH_1):P5E_CPU1_PE3_TX_C_DP(10)   I281 @S9S_MB_2U_LIB.S9S_MB_2U(SCH_1):PAGE168
     2 P5E_CPU1_PE3_TX_DP<10> @S9S_MB_2U_LIB.S9S_MB_2U(SCH_1):P5E_CPU1_PE3_TX_DP(10)   I281 @S9S_MB_2U_LIB.S9S_MB_2U(SCH_1):PAGE168

C1528 Q_CAP_DIFFBUS_C0201-DIFF BUS_0A
     1 P5E_CPU1_PE3_TX_C_DN<9> @S9S_MB_2U_LIB.S9S_MB_2U(SCH_1):P5E_CPU1_PE3_TX_C_DN(9)   I280 @S9S_MB_2U_LIB.S9S_MB_2U(SCH_1):PAGE168
     2 P5E_CPU1_PE3_TX_DN<9> @S9S_MB_2U_LIB.S9S_MB_2U(SCH_1):P5E_CPU1_PE3_TX_DN(9)   I280 @S9S_MB_2U_LIB.S9S_MB_2U(SCH_1):PAGE168

C1529 Q_CAP_DIFFBUS_C0201-DIFF BUS_0A
     1 P5E_CPU1_PE3_TX_C_DP<9> @S9S_MB_2U_LIB.S9S_MB_2U(SCH_1):P5E_CPU1_PE3_TX_C_DP(9)   I279 @S9S_MB_2U_LIB.S9S_MB_2U(SCH_1):PAGE168
     2 P5E_CPU1_PE3_TX_DP<9> @S9S_MB_2U_LIB.S9S_MB_2U(SCH_1):P5E_CPU1_PE3_TX_DP(9)   I279 @S9S_MB_2U_LIB.S9S_MB_2U(SCH_1):PAGE168

C1530 Q_CAP_DIFFBUS_C0201-DIFF BUS_0A
     1 P5E_CPU1_PE3_TX_C_DN<8> @S9S_MB_2U_LIB.S9S_MB_2U(SCH_1):P5E_CPU1_PE3_TX_C_DN(8)   I277 @S9S_MB_2U_LIB.S9S_MB_2U(SCH_1):PAGE168
     2 P5E_CPU1_PE3_TX_DN<8> @S9S_MB_2U_LIB.S9S_MB_2U(SCH_1):P5E_CPU1_PE3_TX_DN(8)   I277 @S9S_MB_2U_LIB.S9S_MB_2U(SCH_1):PAGE168

C1531 Q_CAP_DIFFBUS_C0201-DIFF BUS_0A
     1 P5E_CPU1_PE3_TX_C_DP<8> @S9S_MB_2U_LIB.S9S_MB_2U(SCH_1):P5E_CPU1_PE3_TX_C_DP(8)   I278 @S9S_MB_2U_LIB.S9S_MB_2U(SCH_1):PAGE168
     2 P5E_CPU1_PE3_TX_DP<8> @S9S_MB_2U_LIB.S9S_MB_2U(SCH_1):P5E_CPU1_PE3_TX_DP(8)   I278 @S9S_MB_2U_LIB.S9S_MB_2U(SCH_1):PAGE168

C1532 Q_CAP_DIFFBUS_C0201-DIFF BUS_0A
     1 P5E_CPU1_PE3_TX_C_DN<7> @S9S_MB_2U_LIB.S9S_MB_2U(SCH_1):P5E_CPU1_PE3_TX_C_DN(7)   I254 @S9S_MB_2U_LIB.S9S_MB_2U(SCH_1):PAGE168
     2 P5E_CPU1_PE3_TX_DN<7> @S9S_MB_2U_LIB.S9S_MB_2U(SCH_1):P5E_CPU1_PE3_TX_DN(7)   I254 @S9S_MB_2U_LIB.S9S_MB_2U(SCH_1):PAGE168

C1533 Q_CAP_DIFFBUS_C0201-DIFF BUS_0A
     1 P5E_CPU1_PE3_TX_C_DP<7> @S9S_MB_2U_LIB.S9S_MB_2U(SCH_1):P5E_CPU1_PE3_TX_C_DP(7)   I253 @S9S_MB_2U_LIB.S9S_MB_2U(SCH_1):PAGE168
     2 P5E_CPU1_PE3_TX_DP<7> @S9S_MB_2U_LIB.S9S_MB_2U(SCH_1):P5E_CPU1_PE3_TX_DP(7)   I253 @S9S_MB_2U_LIB.S9S_MB_2U(SCH_1):PAGE168

C1534 Q_CAP_DIFFBUS_C0201-DIFF BUS_0A
     1 P5E_CPU1_PE3_TX_C_DN<6> @S9S_MB_2U_LIB.S9S_MB_2U(SCH_1):P5E_CPU1_PE3_TX_C_DN(6)   I251 @S9S_MB_2U_LIB.S9S_MB_2U(SCH_1):PAGE168
     2 P5E_CPU1_PE3_TX_DN<6> @S9S_MB_2U_LIB.S9S_MB_2U(SCH_1):P5E_CPU1_PE3_TX_DN(6)   I251 @S9S_MB_2U_LIB.S9S_MB_2U(SCH_1):PAGE168

C1535 Q_CAP_DIFFBUS_C0201-DIFF BUS_0A
     1 P5E_CPU1_PE3_TX_C_DP<6> @S9S_MB_2U_LIB.S9S_MB_2U(SCH_1):P5E_CPU1_PE3_TX_C_DP(6)   I252 @S9S_MB_2U_LIB.S9S_MB_2U(SCH_1):PAGE168
     2 P5E_CPU1_PE3_TX_DP<6> @S9S_MB_2U_LIB.S9S_MB_2U(SCH_1):P5E_CPU1_PE3_TX_DP(6)   I252 @S9S_MB_2U_LIB.S9S_MB_2U(SCH_1):PAGE168

C1536 Q_CAP_DIFFBUS_C0201-DIFF BUS_0A
     1 P5E_CPU1_PE3_TX_C_DN<5> @S9S_MB_2U_LIB.S9S_MB_2U(SCH_1):P5E_CPU1_PE3_TX_C_DN(5)   I250 @S9S_MB_2U_LIB.S9S_MB_2U(SCH_1):PAGE168
     2 P5E_CPU1_PE3_TX_DN<5> @S9S_MB_2U_LIB.S9S_MB_2U(SCH_1):P5E_CPU1_PE3_TX_DN(5)   I250 @S9S_MB_2U_LIB.S9S_MB_2U(SCH_1):PAGE168

C1537 Q_CAP_DIFFBUS_C0201-DIFF BUS_0A
     1 P5E_CPU1_PE3_TX_C_DP<5> @S9S_MB_2U_LIB.S9S_MB_2U(SCH_1):P5E_CPU1_PE3_TX_C_DP(5)   I249 @S9S_MB_2U_LIB.S9S_MB_2U(SCH_1):PAGE168
     2 P5E_CPU1_PE3_TX_DP<5> @S9S_MB_2U_LIB.S9S_MB_2U(SCH_1):P5E_CPU1_PE3_TX_DP(5)   I249 @S9S_MB_2U_LIB.S9S_MB_2U(SCH_1):PAGE168

C1538 Q_CAP_DIFFBUS_C0201-DIFF BUS_0A
     1 P5E_CPU1_PE3_TX_C_DN<4> @S9S_MB_2U_LIB.S9S_MB_2U(SCH_1):P5E_CPU1_PE3_TX_C_DN(4)   I238 @S9S_MB_2U_LIB.S9S_MB_2U(SCH_1):PAGE168
     2 P5E_CPU1_PE3_TX_DN<4> @S9S_MB_2U_LIB.S9S_MB_2U(SCH_1):P5E_CPU1_PE3_TX_DN(4)   I238 @S9S_MB_2U_LIB.S9S_MB_2U(SCH_1):PAGE168

C1539 Q_CAP_DIFFBUS_C0201-DIFF BUS_0A
     1 P5E_CPU1_PE3_TX_C_DP<4> @S9S_MB_2U_LIB.S9S_MB_2U(SCH_1):P5E_CPU1_PE3_TX_C_DP(4)   I237 @S9S_MB_2U_LIB.S9S_MB_2U(SCH_1):PAGE168
     2 P5E_CPU1_PE3_TX_DP<4> @S9S_MB_2U_LIB.S9S_MB_2U(SCH_1):P5E_CPU1_PE3_TX_DP(4)   I237 @S9S_MB_2U_LIB.S9S_MB_2U(SCH_1):PAGE168

C1540 Q_CAP_DIFFBUS_C0201-DIFF BUS_0A
     1 P5E_CPU1_PE3_TX_C_DN<3> @S9S_MB_2U_LIB.S9S_MB_2U(SCH_1):P5E_CPU1_PE3_TX_C_DN(3)   I236 @S9S_MB_2U_LIB.S9S_MB_2U(SCH_1):PAGE168
     2 P5E_CPU1_PE3_TX_DN<3> @S9S_MB_2U_LIB.S9S_MB_2U(SCH_1):P5E_CPU1_PE3_TX_DN(3)   I236 @S9S_MB_2U_LIB.S9S_MB_2U(SCH_1):PAGE168

C1541 Q_CAP_DIFFBUS_C0201-DIFF BUS_0A
     1 P5E_CPU1_PE3_TX_C_DP<3> @S9S_MB_2U_LIB.S9S_MB_2U(SCH_1):P5E_CPU1_PE3_TX_C_DP(3)   I235 @S9S_MB_2U_LIB.S9S_MB_2U(SCH_1):PAGE168
     2 P5E_CPU1_PE3_TX_DP<3> @S9S_MB_2U_LIB.S9S_MB_2U(SCH_1):P5E_CPU1_PE3_TX_DP(3)   I235 @S9S_MB_2U_LIB.S9S_MB_2U(SCH_1):PAGE168

C1542 Q_CAP_DIFFBUS_C0201-DIFF BUS_0A
     1 P5E_CPU1_PE3_TX_C_DN<2> @S9S_MB_2U_LIB.S9S_MB_2U(SCH_1):P5E_CPU1_PE3_TX_C_DN(2)   I233 @S9S_MB_2U_LIB.S9S_MB_2U(SCH_1):PAGE168
     2 P5E_CPU1_PE3_TX_DN<2> @S9S_MB_2U_LIB.S9S_MB_2U(SCH_1):P5E_CPU1_PE3_TX_DN(2)   I233 @S9S_MB_2U_LIB.S9S_MB_2U(SCH_1):PAGE168

C1543 Q_CAP_DIFFBUS_C0201-DIFF BUS_0A
     1 P5E_CPU1_PE3_TX_C_DP<2> @S9S_MB_2U_LIB.S9S_MB_2U(SCH_1):P5E_CPU1_PE3_TX_C_DP(2)   I234 @S9S_MB_2U_LIB.S9S_MB_2U(SCH_1):PAGE168
     2 P5E_CPU1_PE3_TX_DP<2> @S9S_MB_2U_LIB.S9S_MB_2U(SCH_1):P5E_CPU1_PE3_TX_DP(2)   I234 @S9S_MB_2U_LIB.S9S_MB_2U(SCH_1):PAGE168

C1544 Q_CAP_DIFFBUS_C0201-DIFF BUS_0A
     1 P5E_CPU1_PE3_TX_C_DN<1> @S9S_MB_2U_LIB.S9S_MB_2U(SCH_1):P5E_CPU1_PE3_TX_C_DN(1)   I232 @S9S_MB_2U_LIB.S9S_MB_2U(SCH_1):PAGE168
     2 P5E_CPU1_PE3_TX_DN<1> @S9S_MB_2U_LIB.S9S_MB_2U(SCH_1):P5E_CPU1_PE3_TX_DN(1)   I232 @S9S_MB_2U_LIB.S9S_MB_2U(SCH_1):PAGE168

C1545 Q_CAP_DIFFBUS_C0201-DIFF BUS_0A
     1 P5E_CPU1_PE3_TX_C_DP<1> @S9S_MB_2U_LIB.S9S_MB_2U(SCH_1):P5E_CPU1_PE3_TX_C_DP(1)   I231 @S9S_MB_2U_LIB.S9S_MB_2U(SCH_1):PAGE168
     2 P5E_CPU1_PE3_TX_DP<1> @S9S_MB_2U_LIB.S9S_MB_2U(SCH_1):P5E_CPU1_PE3_TX_DP(1)   I231 @S9S_MB_2U_LIB.S9S_MB_2U(SCH_1):PAGE168

C1546 Q_CAP_DIFFBUS_C0201-DIFF BUS_0A
     1 P5E_CPU1_PE3_TX_C_DN<0> @S9S_MB_2U_LIB.S9S_MB_2U(SCH_1):P5E_CPU1_PE3_TX_C_DN(0)   I230 @S9S_MB_2U_LIB.S9S_MB_2U(SCH_1):PAGE168
     2 P5E_CPU1_PE3_TX_DN<0> @S9S_MB_2U_LIB.S9S_MB_2U(SCH_1):P5E_CPU1_PE3_TX_DN(0)   I230 @S9S_MB_2U_LIB.S9S_MB_2U(SCH_1):PAGE168

C1547 Q_CAP_DIFFBUS_C0201-DIFF BUS_0A
     1 P5E_CPU1_PE3_TX_C_DP<0> @S9S_MB_2U_LIB.S9S_MB_2U(SCH_1):P5E_CPU1_PE3_TX_C_DP(0)   I229 @S9S_MB_2U_LIB.S9S_MB_2U(SCH_1):PAGE168
     2 P5E_CPU1_PE3_TX_DP<0> @S9S_MB_2U_LIB.S9S_MB_2U(SCH_1):P5E_CPU1_PE3_TX_DP(0)   I229 @S9S_MB_2U_LIB.S9S_MB_2U(SCH_1):PAGE168

C1548 Q_CAP_DIFFBUS_C0201-DIFF BUS_0A
     1 P5E_CPU0_PE4_TX_C_DN<15> @S9S_MB_2U_LIB.S9S_MB_2U(SCH_1):P5E_CPU0_PE4_TX_C_DN(15)   I273 @S9S_MB_2U_LIB.S9S_MB_2U(SCH_1):PAGE166
     2 P5E_CPU0_PE4_TX_DN<15> @S9S_MB_2U_LIB.S9S_MB_2U(SCH_1):P5E_CPU0_PE4_TX_DN(15)   I273 @S9S_MB_2U_LIB.S9S_MB_2U(SCH_1):PAGE166

C1549 Q_CAP_DIFFBUS_C0201-DIFF BUS_0A
     1 P5E_CPU0_PE4_TX_C_DP<15> @S9S_MB_2U_LIB.S9S_MB_2U(SCH_1):P5E_CPU0_PE4_TX_C_DP(15)   I274 @S9S_MB_2U_LIB.S9S_MB_2U(SCH_1):PAGE166
     2 P5E_CPU0_PE4_TX_DP<15> @S9S_MB_2U_LIB.S9S_MB_2U(SCH_1):P5E_CPU0_PE4_TX_DP(15)   I274 @S9S_MB_2U_LIB.S9S_MB_2U(SCH_1):PAGE166

C1550 Q_CAP_DIFFBUS_C0201-DIFF BUS_0A
     1 P5E_CPU0_PE4_TX_C_DN<14> @S9S_MB_2U_LIB.S9S_MB_2U(SCH_1):P5E_CPU0_PE4_TX_C_DN(14)   I272 @S9S_MB_2U_LIB.S9S_MB_2U(SCH_1):PAGE166
     2 P5E_CPU0_PE4_TX_DN<14> @S9S_MB_2U_LIB.S9S_MB_2U(SCH_1):P5E_CPU0_PE4_TX_DN(14)   I272 @S9S_MB_2U_LIB.S9S_MB_2U(SCH_1):PAGE166

C1552 Q_CAP_DIFFBUS_C0201-DIFF BUS_0A
     1 P5E_CPU0_PE4_TX_C_DN<13> @S9S_MB_2U_LIB.S9S_MB_2U(SCH_1):P5E_CPU0_PE4_TX_C_DN(13)   I270 @S9S_MB_2U_LIB.S9S_MB_2U(SCH_1):PAGE166
     2 P5E_CPU0_PE4_TX_DN<13> @S9S_MB_2U_LIB.S9S_MB_2U(SCH_1):P5E_CPU0_PE4_TX_DN(13)   I270 @S9S_MB_2U_LIB.S9S_MB_2U(SCH_1):PAGE166

C1553 Q_CAP_DIFFBUS_C0201-DIFF BUS_0A
     1 P5E_CPU0_PE4_TX_C_DP<13> @S9S_MB_2U_LIB.S9S_MB_2U(SCH_1):P5E_CPU0_PE4_TX_C_DP(13)   I269 @S9S_MB_2U_LIB.S9S_MB_2U(SCH_1):PAGE166
     2 P5E_CPU0_PE4_TX_DP<13> @S9S_MB_2U_LIB.S9S_MB_2U(SCH_1):P5E_CPU0_PE4_TX_DP(13)   I269 @S9S_MB_2U_LIB.S9S_MB_2U(SCH_1):PAGE166

C1554 Q_CAP_DIFFBUS_C0201-DIFF BUS_0A
     1 P5E_CPU0_PE4_TX_C_DN<12> @S9S_MB_2U_LIB.S9S_MB_2U(SCH_1):P5E_CPU0_PE4_TX_C_DN(12)   I268 @S9S_MB_2U_LIB.S9S_MB_2U(SCH_1):PAGE166
     2 P5E_CPU0_PE4_TX_DN<12> @S9S_MB_2U_LIB.S9S_MB_2U(SCH_1):P5E_CPU0_PE4_TX_DN(12)   I268 @S9S_MB_2U_LIB.S9S_MB_2U(SCH_1):PAGE166

C1555 Q_CAP_DIFFBUS_C0201-DIFF BUS_0A
     1 P5E_CPU0_PE4_TX_C_DP<12> @S9S_MB_2U_LIB.S9S_MB_2U(SCH_1):P5E_CPU0_PE4_TX_C_DP(12)   I267 @S9S_MB_2U_LIB.S9S_MB_2U(SCH_1):PAGE166
     2 P5E_CPU0_PE4_TX_DP<12> @S9S_MB_2U_LIB.S9S_MB_2U(SCH_1):P5E_CPU0_PE4_TX_DP(12)   I267 @S9S_MB_2U_LIB.S9S_MB_2U(SCH_1):PAGE166

C1556 Q_CAP_DIFFBUS_C0201-DIFF BUS_0A
     1 P5E_CPU0_PE4_TX_C_DN<11> @S9S_MB_2U_LIB.S9S_MB_2U(SCH_1):P5E_CPU0_PE4_TX_C_DN(11)   I265 @S9S_MB_2U_LIB.S9S_MB_2U(SCH_1):PAGE166
     2 P5E_CPU0_PE4_TX_DN<11> @S9S_MB_2U_LIB.S9S_MB_2U(SCH_1):P5E_CPU0_PE4_TX_DN(11)   I265 @S9S_MB_2U_LIB.S9S_MB_2U(SCH_1):PAGE166

C1557 Q_CAP_DIFFBUS_C0201-DIFF BUS_0A
     1 P5E_CPU0_PE4_TX_C_DP<11> @S9S_MB_2U_LIB.S9S_MB_2U(SCH_1):P5E_CPU0_PE4_TX_C_DP(11)   I266 @S9S_MB_2U_LIB.S9S_MB_2U(SCH_1):PAGE166
     2 P5E_CPU0_PE4_TX_DP<11> @S9S_MB_2U_LIB.S9S_MB_2U(SCH_1):P5E_CPU0_PE4_TX_DP(11)   I266 @S9S_MB_2U_LIB.S9S_MB_2U(SCH_1):PAGE166

C1558 Q_CAP_DIFFBUS_C0201-DIFF BUS_0A
     1 P5E_CPU0_PE4_TX_C_DN<10> @S9S_MB_2U_LIB.S9S_MB_2U(SCH_1):P5E_CPU0_PE4_TX_C_DN(10)   I264 @S9S_MB_2U_LIB.S9S_MB_2U(SCH_1):PAGE166
     2 P5E_CPU0_PE4_TX_DN<10> @S9S_MB_2U_LIB.S9S_MB_2U(SCH_1):P5E_CPU0_PE4_TX_DN(10)   I264 @S9S_MB_2U_LIB.S9S_MB_2U(SCH_1):PAGE166

C1559 Q_CAP_DIFFBUS_C0201-DIFF BUS_0A
     1 P5E_CPU0_PE4_TX_C_DP<10> @S9S_MB_2U_LIB.S9S_MB_2U(SCH_1):P5E_CPU0_PE4_TX_C_DP(10)   I263 @S9S_MB_2U_LIB.S9S_MB_2U(SCH_1):PAGE166
     2 P5E_CPU0_PE4_TX_DP<10> @S9S_MB_2U_LIB.S9S_MB_2U(SCH_1):P5E_CPU0_PE4_TX_DP(10)   I263 @S9S_MB_2U_LIB.S9S_MB_2U(SCH_1):PAGE166

C1560 Q_CAP_DIFFBUS_C0201-DIFF BUS_0A
     1 P5E_CPU0_PE4_TX_C_DN<9> @S9S_MB_2U_LIB.S9S_MB_2U(SCH_1):P5E_CPU0_PE4_TX_C_DN(9)   I262 @S9S_MB_2U_LIB.S9S_MB_2U(SCH_1):PAGE166
     2 P5E_CPU0_PE4_TX_DN<9> @S9S_MB_2U_LIB.S9S_MB_2U(SCH_1):P5E_CPU0_PE4_TX_DN(9)   I262 @S9S_MB_2U_LIB.S9S_MB_2U(SCH_1):PAGE166

C1561 Q_CAP_C0402-1UF,25V,10%,X6S,CHA
     1 U206_VDD @S9S_MB_2U_LIB.S9S_MB_2U(SCH_1):U206_VDD    I90 @S9S_MB_2U_LIB.S9S_MB_2U(SCH_1):PAGE326
     2    GND @S9S_MB_2U_LIB.S9S_MB_2U(SCH_1):GND    I90 @S9S_MB_2U_LIB.S9S_MB_2U(SCH_1):PAGE326

C1562 Q_CAP_C0402-1UF,25V,10%,EMPTY,A
     1 U205_VDD @S9S_MB_2U_LIB.S9S_MB_2U(SCH_1):U205_VDD    I89 @S9S_MB_2U_LIB.S9S_MB_2U(SCH_1):PAGE326
     2    GND @S9S_MB_2U_LIB.S9S_MB_2U(SCH_1):GND    I89 @S9S_MB_2U_LIB.S9S_MB_2U(SCH_1):PAGE326

C1563 Q_CAP_DIFFBUS_C0201-DIFF BUS_0A
     1 P5E_CPU0_PE4_TX_C_DP<8> @S9S_MB_2U_LIB.S9S_MB_2U(SCH_1):P5E_CPU0_PE4_TX_C_DP(8)   I259 @S9S_MB_2U_LIB.S9S_MB_2U(SCH_1):PAGE166
     2 P5E_CPU0_PE4_TX_DP<8> @S9S_MB_2U_LIB.S9S_MB_2U(SCH_1):P5E_CPU0_PE4_TX_DP(8)   I259 @S9S_MB_2U_LIB.S9S_MB_2U(SCH_1):PAGE166

C1564 Q_CAP_DIFFBUS_C0201-DIFF BUS_0A
     1 P5E_CPU0_PE4_TX_C_DN<7> @S9S_MB_2U_LIB.S9S_MB_2U(SCH_1):P5E_CPU0_PE4_TX_C_DN(7)   I242 @S9S_MB_2U_LIB.S9S_MB_2U(SCH_1):PAGE166
     2 P5E_CPU0_PE4_TX_DN<7> @S9S_MB_2U_LIB.S9S_MB_2U(SCH_1):P5E_CPU0_PE4_TX_DN(7)   I242 @S9S_MB_2U_LIB.S9S_MB_2U(SCH_1):PAGE166

C1565 Q_CAP_DIFFBUS_C0201-DIFF BUS_0A
     1 P5E_CPU0_PE4_TX_C_DP<7> @S9S_MB_2U_LIB.S9S_MB_2U(SCH_1):P5E_CPU0_PE4_TX_C_DP(7)   I241 @S9S_MB_2U_LIB.S9S_MB_2U(SCH_1):PAGE166
     2 P5E_CPU0_PE4_TX_DP<7> @S9S_MB_2U_LIB.S9S_MB_2U(SCH_1):P5E_CPU0_PE4_TX_DP(7)   I241 @S9S_MB_2U_LIB.S9S_MB_2U(SCH_1):PAGE166

C1566 Q_CAP_DIFFBUS_C0201-DIFF BUS_0A
     1 P5E_CPU0_PE4_TX_C_DN<6> @S9S_MB_2U_LIB.S9S_MB_2U(SCH_1):P5E_CPU0_PE4_TX_C_DN(6)   I240 @S9S_MB_2U_LIB.S9S_MB_2U(SCH_1):PAGE166
     2 P5E_CPU0_PE4_TX_DN<6> @S9S_MB_2U_LIB.S9S_MB_2U(SCH_1):P5E_CPU0_PE4_TX_DN(6)   I240 @S9S_MB_2U_LIB.S9S_MB_2U(SCH_1):PAGE166

C1567 Q_CAP_DIFFBUS_C0201-DIFF BUS_0A
     1 P5E_CPU0_PE4_TX_C_DP<6> @S9S_MB_2U_LIB.S9S_MB_2U(SCH_1):P5E_CPU0_PE4_TX_C_DP(6)   I239 @S9S_MB_2U_LIB.S9S_MB_2U(SCH_1):PAGE166
     2 P5E_CPU0_PE4_TX_DP<6> @S9S_MB_2U_LIB.S9S_MB_2U(SCH_1):P5E_CPU0_PE4_TX_DP(6)   I239 @S9S_MB_2U_LIB.S9S_MB_2U(SCH_1):PAGE166

C1568 Q_CAP_DIFFBUS_C0201-DIFF BUS_0A
     1 P5E_CPU0_PE4_TX_C_DN<5> @S9S_MB_2U_LIB.S9S_MB_2U(SCH_1):P5E_CPU0_PE4_TX_C_DN(5)   I238 @S9S_MB_2U_LIB.S9S_MB_2U(SCH_1):PAGE166
     2 P5E_CPU0_PE4_TX_DN<5> @S9S_MB_2U_LIB.S9S_MB_2U(SCH_1):P5E_CPU0_PE4_TX_DN(5)   I238 @S9S_MB_2U_LIB.S9S_MB_2U(SCH_1):PAGE166

C1569 Q_CAP_DIFFBUS_C0201-DIFF BUS_0A
     1 P5E_CPU0_PE4_TX_C_DP<5> @S9S_MB_2U_LIB.S9S_MB_2U(SCH_1):P5E_CPU0_PE4_TX_C_DP(5)   I237 @S9S_MB_2U_LIB.S9S_MB_2U(SCH_1):PAGE166
     2 P5E_CPU0_PE4_TX_DP<5> @S9S_MB_2U_LIB.S9S_MB_2U(SCH_1):P5E_CPU0_PE4_TX_DP(5)   I237 @S9S_MB_2U_LIB.S9S_MB_2U(SCH_1):PAGE166

C1570 Q_CAP_DIFFBUS_C0201-DIFF BUS_0A
     1 P5E_CPU0_PE4_TX_C_DN<4> @S9S_MB_2U_LIB.S9S_MB_2U(SCH_1):P5E_CPU0_PE4_TX_C_DN(4)   I235 @S9S_MB_2U_LIB.S9S_MB_2U(SCH_1):PAGE166
     2 P5E_CPU0_PE4_TX_DN<4> @S9S_MB_2U_LIB.S9S_MB_2U(SCH_1):P5E_CPU0_PE4_TX_DN(4)   I235 @S9S_MB_2U_LIB.S9S_MB_2U(SCH_1):PAGE166

C1571 Q_CAP_DIFFBUS_C0201-DIFF BUS_0A
     1 P5E_CPU0_PE4_TX_C_DP<4> @S9S_MB_2U_LIB.S9S_MB_2U(SCH_1):P5E_CPU0_PE4_TX_C_DP(4)   I236 @S9S_MB_2U_LIB.S9S_MB_2U(SCH_1):PAGE166
     2 P5E_CPU0_PE4_TX_DP<4> @S9S_MB_2U_LIB.S9S_MB_2U(SCH_1):P5E_CPU0_PE4_TX_DP(4)   I236 @S9S_MB_2U_LIB.S9S_MB_2U(SCH_1):PAGE166

C1572 Q_CAP_DIFFBUS_C0201-DIFF BUS_0A
     1 P5E_CPU0_PE4_TX_C_DN<3> @S9S_MB_2U_LIB.S9S_MB_2U(SCH_1):P5E_CPU0_PE4_TX_C_DN(3)   I234 @S9S_MB_2U_LIB.S9S_MB_2U(SCH_1):PAGE166
     2 P5E_CPU0_PE4_TX_DN<3> @S9S_MB_2U_LIB.S9S_MB_2U(SCH_1):P5E_CPU0_PE4_TX_DN(3)   I234 @S9S_MB_2U_LIB.S9S_MB_2U(SCH_1):PAGE166

C1573 Q_CAP_DIFFBUS_C0201-DIFF BUS_0A
     1 P5E_CPU0_PE4_TX_C_DP<3> @S9S_MB_2U_LIB.S9S_MB_2U(SCH_1):P5E_CPU0_PE4_TX_C_DP(3)   I233 @S9S_MB_2U_LIB.S9S_MB_2U(SCH_1):PAGE166
     2 P5E_CPU0_PE4_TX_DP<3> @S9S_MB_2U_LIB.S9S_MB_2U(SCH_1):P5E_CPU0_PE4_TX_DP(3)   I233 @S9S_MB_2U_LIB.S9S_MB_2U(SCH_1):PAGE166

C1574 Q_CAP_DIFFBUS_C0201-DIFF BUS_0A
     1 P5E_CPU0_PE4_TX_C_DN<2> @S9S_MB_2U_LIB.S9S_MB_2U(SCH_1):P5E_CPU0_PE4_TX_C_DN(2)   I232 @S9S_MB_2U_LIB.S9S_MB_2U(SCH_1):PAGE166
     2 P5E_CPU0_PE4_TX_DN<2> @S9S_MB_2U_LIB.S9S_MB_2U(SCH_1):P5E_CPU0_PE4_TX_DN(2)   I232 @S9S_MB_2U_LIB.S9S_MB_2U(SCH_1):PAGE166

C1575 Q_CAP_DIFFBUS_C0201-DIFF BUS_0A
     1 P5E_CPU0_PE4_TX_C_DP<2> @S9S_MB_2U_LIB.S9S_MB_2U(SCH_1):P5E_CPU0_PE4_TX_C_DP(2)   I231 @S9S_MB_2U_LIB.S9S_MB_2U(SCH_1):PAGE166
     2 P5E_CPU0_PE4_TX_DP<2> @S9S_MB_2U_LIB.S9S_MB_2U(SCH_1):P5E_CPU0_PE4_TX_DP(2)   I231 @S9S_MB_2U_LIB.S9S_MB_2U(SCH_1):PAGE166

C1576 Q_CAP_DIFFBUS_C0201-DIFF BUS_0A
     1 P5E_CPU0_PE4_TX_C_DN<1> @S9S_MB_2U_LIB.S9S_MB_2U(SCH_1):P5E_CPU0_PE4_TX_C_DN(1)   I312 @S9S_MB_2U_LIB.S9S_MB_2U(SCH_1):PAGE166
     2 P5E_CPU0_PE4_TX_DN<1> @S9S_MB_2U_LIB.S9S_MB_2U(SCH_1):P5E_CPU0_PE4_TX_DN(1)   I312 @S9S_MB_2U_LIB.S9S_MB_2U(SCH_1):PAGE166

C1577 Q_CAP_DIFFBUS_C0201-DIFF BUS_0A
     1 P5E_CPU0_PE4_TX_C_DP<1> @S9S_MB_2U_LIB.S9S_MB_2U(SCH_1):P5E_CPU0_PE4_TX_C_DP(1)   I311 @S9S_MB_2U_LIB.S9S_MB_2U(SCH_1):PAGE166
     2 P5E_CPU0_PE4_TX_DP<1> @S9S_MB_2U_LIB.S9S_MB_2U(SCH_1):P5E_CPU0_PE4_TX_DP(1)   I311 @S9S_MB_2U_LIB.S9S_MB_2U(SCH_1):PAGE166

C1578 Q_CAP_DIFFBUS_C0201-DIFF BUS_0A
     1 P5E_CPU0_PE4_TX_C_DN<0> @S9S_MB_2U_LIB.S9S_MB_2U(SCH_1):P5E_CPU0_PE4_TX_C_DN(0)   I230 @S9S_MB_2U_LIB.S9S_MB_2U(SCH_1):PAGE166
     2 P5E_CPU0_PE4_TX_DN<0> @S9S_MB_2U_LIB.S9S_MB_2U(SCH_1):P5E_CPU0_PE4_TX_DN(0)   I230 @S9S_MB_2U_LIB.S9S_MB_2U(SCH_1):PAGE166

C1579 Q_CAP_DIFFBUS_C0201-DIFF BUS_0A
     1 P5E_CPU0_PE4_TX_C_DP<0> @S9S_MB_2U_LIB.S9S_MB_2U(SCH_1):P5E_CPU0_PE4_TX_C_DP(0)   I229 @S9S_MB_2U_LIB.S9S_MB_2U(SCH_1):PAGE166
     2 P5E_CPU0_PE4_TX_DP<0> @S9S_MB_2U_LIB.S9S_MB_2U(SCH_1):P5E_CPU0_PE4_TX_DP(0)   I229 @S9S_MB_2U_LIB.S9S_MB_2U(SCH_1):PAGE166

C1592 Q_CAP_0402-0.1UF,25V,10%,X7R,CA
     1 P3V3_AUX @S9S_MB_2U_LIB.S9S_MB_2U(SCH_1):P3V3_AUX   I304 @S9S_MB_2U_LIB.S9S_MB_2U(SCH_1):PAGE297
     2    GND @S9S_MB_2U_LIB.S9S_MB_2U(SCH_1):GND   I304 @S9S_MB_2U_LIB.S9S_MB_2U(SCH_1):PAGE297

C1612 Q_CAP_C0402-1UF,25V,10%,X6S,CHA
     1 P3V3_AUX @S9S_MB_2U_LIB.S9S_MB_2U(SCH_1):P3V3_AUX    I36 @S9S_MB_2U_LIB.S9S_MB_2U(SCH_1):PAGE185
     2    GND @S9S_MB_2U_LIB.S9S_MB_2U(SCH_1):GND    I36 @S9S_MB_2U_LIB.S9S_MB_2U(SCH_1):PAGE185

C1613 Q_CAP_0402-0.1UF,25V,10%,X7R,CA
     1 P3V3_AUX @S9S_MB_2U_LIB.S9S_MB_2U(SCH_1):P3V3_AUX    I68 @S9S_MB_2U_LIB.S9S_MB_2U(SCH_1):PAGE224
     2    GND @S9S_MB_2U_LIB.S9S_MB_2U(SCH_1):GND    I68 @S9S_MB_2U_LIB.S9S_MB_2U(SCH_1):PAGE224

C1614 Q_CAP_0402-0.1UF,25V,10%,X7R,CA
     1 P3V3_AUX @S9S_MB_2U_LIB.S9S_MB_2U(SCH_1):P3V3_AUX   I170 @S9S_MB_2U_LIB.S9S_MB_2U(SCH_1):PAGE297
     2    GND @S9S_MB_2U_LIB.S9S_MB_2U(SCH_1):GND   I170 @S9S_MB_2U_LIB.S9S_MB_2U(SCH_1):PAGE297

C1619 Q_CAP_0402-0.1UF,25V,10%,X7R,CA
     1 P3V3_AUX @S9S_MB_2U_LIB.S9S_MB_2U(SCH_1):P3V3_AUX     I5 @S9S_MB_2U_LIB.S9S_MB_2U(SCH_1):PAGE213
     2    GND @S9S_MB_2U_LIB.S9S_MB_2U(SCH_1):GND     I5 @S9S_MB_2U_LIB.S9S_MB_2U(SCH_1):PAGE213

C1647 Q_CAP_0402-0.1UF,25V,10%,X7R,CA
     1 P3V3_AUX @S9S_MB_2U_LIB.S9S_MB_2U(SCH_1):P3V3_AUX    I84 @S9S_MB_2U_LIB.S9S_MB_2U(SCH_1):PAGE190
     2    GND @S9S_MB_2U_LIB.S9S_MB_2U(SCH_1):GND    I84 @S9S_MB_2U_LIB.S9S_MB_2U(SCH_1):PAGE190

C1663 Q_CAP_0402-0.1UF,25V,10%,X7R,CA
     1 P3V3_AUX @S9S_MB_2U_LIB.S9S_MB_2U(SCH_1):P3V3_AUX    I68 @S9S_MB_2U_LIB.S9S_MB_2U(SCH_1):PAGE152
     2    GND @S9S_MB_2U_LIB.S9S_MB_2U(SCH_1):GND    I68 @S9S_MB_2U_LIB.S9S_MB_2U(SCH_1):PAGE152

C1664 Q_CAP_0402-0.1UF,25V,10%,X7R,CA
     1 P0V7_JTAG_VREF_2 @S9S_MB_2U_LIB.S9S_MB_2U(SCH_1):P0V7_JTAG_VREF_2    I93 @S9S_MB_2U_LIB.S9S_MB_2U(SCH_1):PAGE226
     2    GND @S9S_MB_2U_LIB.S9S_MB_2U(SCH_1):GND    I93 @S9S_MB_2U_LIB.S9S_MB_2U(SCH_1):PAGE226

C1707 Q_CAP_0402-0.1UF,25V,10%,X7R,CA
     1 P3V3_AUX @S9S_MB_2U_LIB.S9S_MB_2U(SCH_1):P3V3_AUX    I58 @S9S_MB_2U_LIB.S9S_MB_2U(SCH_1):PAGE222
     2    GND @S9S_MB_2U_LIB.S9S_MB_2U(SCH_1):GND    I58 @S9S_MB_2U_LIB.S9S_MB_2U(SCH_1):PAGE222

C1708 Q_CAP_0402-0.1UF,25V,10%,EMPTYA
     1 P3V3_AUX @S9S_MB_2U_LIB.S9S_MB_2U(SCH_1):P3V3_AUX    I34 @S9S_MB_2U_LIB.S9S_MB_2U(SCH_1):PAGE222
     2    GND @S9S_MB_2U_LIB.S9S_MB_2U(SCH_1):GND    I34 @S9S_MB_2U_LIB.S9S_MB_2U(SCH_1):PAGE222

C1713 Q_CAP_0402-0.1UF,25V,10%,X7R,CA
     1 P3V3_AUX @S9S_MB_2U_LIB.S9S_MB_2U(SCH_1):P3V3_AUX    I87 @S9S_MB_2U_LIB.S9S_MB_2U(SCH_1):PAGE214
     2    GND @S9S_MB_2U_LIB.S9S_MB_2U(SCH_1):GND    I87 @S9S_MB_2U_LIB.S9S_MB_2U(SCH_1):PAGE214

C1751 Q_CAP_0402-0.1UF,25V,10%,X7R,CA
     1 P3V3_AUX @S9S_MB_2U_LIB.S9S_MB_2U(SCH_1):P3V3_AUX    I19 @S9S_MB_2U_LIB.S9S_MB_2U(SCH_1):PAGE233
     2    GND @S9S_MB_2U_LIB.S9S_MB_2U(SCH_1):GND    I19 @S9S_MB_2U_LIB.S9S_MB_2U(SCH_1):PAGE233

C1754 Q_CAP_0402-1000PF,50V,5%,EMPTYA
     1 FM_SWB_BIC_READY_ISO_N @S9S_MB_2U_LIB.S9S_MB_2U(SCH_1):FM_SWB_BIC_READY_ISO_N    I92 @S9S_MB_2U_LIB.S9S_MB_2U(SCH_1):PAGE145
     2    GND @S9S_MB_2U_LIB.S9S_MB_2U(SCH_1):GND    I92 @S9S_MB_2U_LIB.S9S_MB_2U(SCH_1):PAGE145

C1756 Q_CAP_0402-1000PF,50V,5%,EMPTYA
     1 FM_GPU_PWRGD_ISO @S9S_MB_2U_LIB.S9S_MB_2U(SCH_1):FM_GPU_PWRGD_ISO   I105 @S9S_MB_2U_LIB.S9S_MB_2U(SCH_1):PAGE145
     2    GND @S9S_MB_2U_LIB.S9S_MB_2U(SCH_1):GND   I105 @S9S_MB_2U_LIB.S9S_MB_2U(SCH_1):PAGE145

C1757 Q_CAP_0402-0.1UF,25V,10%,EMPTYA
     1 P3V3_MAX11617_VDD @S9S_MB_2U_LIB.S9S_MB_2U(SCH_1):P3V3_MAX11617 _VDD    I58 @S9S_MB_2U_LIB.S9S_MB_2U(SCH_1):PAGE239
     2    GND @S9S_MB_2U_LIB.S9S_MB_2U(SCH_1):GND    I58 @S9S_MB_2U_LIB.S9S_MB_2U(SCH_1):PAGE239

C1766 Q_CAP_0402-0.1UF,25V,10%,X7R,CA
     1 P3V3_AUX @S9S_MB_2U_LIB.S9S_MB_2U(SCH_1):P3V3_AUX    I66 @S9S_MB_2U_LIB.S9S_MB_2U(SCH_1):PAGE222
     2    GND @S9S_MB_2U_LIB.S9S_MB_2U(SCH_1):GND    I66 @S9S_MB_2U_LIB.S9S_MB_2U(SCH_1):PAGE222

C1767 Q_CAP_C0805-10UF,16V,10%,EMPTYA
     1 MAX11617_VREF @S9S_MB_2U_LIB.S9S_MB_2U(SCH_1):MAX11617_VREF    I68 @S9S_MB_2U_LIB.S9S_MB_2U(SCH_1):PAGE239
     2    GND @S9S_MB_2U_LIB.S9S_MB_2U(SCH_1):GND    I68 @S9S_MB_2U_LIB.S9S_MB_2U(SCH_1):PAGE239

C1768 Q_CAP_C0805-10UF,16V,10%,EMPTYA
     1 P3V3_MAX11617_VDD @S9S_MB_2U_LIB.S9S_MB_2U(SCH_1):P3V3_MAX11617 _VDD    I61 @S9S_MB_2U_LIB.S9S_MB_2U(SCH_1):PAGE239
     2    GND @S9S_MB_2U_LIB.S9S_MB_2U(SCH_1):GND    I61 @S9S_MB_2U_LIB.S9S_MB_2U(SCH_1):PAGE239

C1769 Q_CAP_0402-0.1UF,25V,10%,X7R,CA
     1 P3V3_AUX @S9S_MB_2U_LIB.S9S_MB_2U(SCH_1):P3V3_AUX    I89 @S9S_MB_2U_LIB.S9S_MB_2U(SCH_1):PAGE140
     2    GND @S9S_MB_2U_LIB.S9S_MB_2U(SCH_1):GND    I89 @S9S_MB_2U_LIB.S9S_MB_2U(SCH_1):PAGE140

C1770 Q_CAP_0402-0.1UF,25V,10%,X7R,CA
     1 P3V3_AUX @S9S_MB_2U_LIB.S9S_MB_2U(SCH_1):P3V3_AUX   I140 @S9S_MB_2U_LIB.S9S_MB_2U(SCH_1):PAGE140
     2    GND @S9S_MB_2U_LIB.S9S_MB_2U(SCH_1):GND   I140 @S9S_MB_2U_LIB.S9S_MB_2U(SCH_1):PAGE140

C1772 Q_CAP_0402-1000PF,50V,5%,EMPTYA
     1 RST_BMC_FROM_SWB_ISO_N @S9S_MB_2U_LIB.S9S_MB_2U(SCH_1):RST_BMC_FROM_SWB_ISO_N   I116 @S9S_MB_2U_LIB.S9S_MB_2U(SCH_1):PAGE145
     2    GND @S9S_MB_2U_LIB.S9S_MB_2U(SCH_1):GND   I116 @S9S_MB_2U_LIB.S9S_MB_2U(SCH_1):PAGE145

C1773 Q_CAP_0402-1000PF,50V,5%,EMPTYA
     1 BIC_MONITER_ISO @S9S_MB_2U_LIB.S9S_MB_2U(SCH_1):BIC_MONITER_ISO   I114 @S9S_MB_2U_LIB.S9S_MB_2U(SCH_1):PAGE145
     2    GND @S9S_MB_2U_LIB.S9S_MB_2U(SCH_1):GND   I114 @S9S_MB_2U_LIB.S9S_MB_2U(SCH_1):PAGE145

C1774 Q_CAP_0402-1000PF,50V,5%,EMPTYA
     1 FM_SWB_PWRGD_ISO @S9S_MB_2U_LIB.S9S_MB_2U(SCH_1):FM_SWB_PWRGD_ISO   I111 @S9S_MB_2U_LIB.S9S_MB_2U(SCH_1):PAGE145
     2    GND @S9S_MB_2U_LIB.S9S_MB_2U(SCH_1):GND   I111 @S9S_MB_2U_LIB.S9S_MB_2U(SCH_1):PAGE145

C1775 Q_CAP_0402-0.1UF,25V,10%,X7R,CA
     1 P3V3_AUX @S9S_MB_2U_LIB.S9S_MB_2U(SCH_1):P3V3_AUX    I14 @S9S_MB_2U_LIB.S9S_MB_2U(SCH_1):PAGE230
     2    GND @S9S_MB_2U_LIB.S9S_MB_2U(SCH_1):GND    I14 @S9S_MB_2U_LIB.S9S_MB_2U(SCH_1):PAGE230

C1791 Q_CAP_DIFFBUS_C0201-DIFF BUS_0A
     1 DMI_CPU0_PCH_TX_C_DP<7> @S9S_MB_2U_LIB.S9S_MB_2U(SCH_1):DMI_CPU0_PCH_TX_C_DP(7)    I36 @S9S_MB_2U_LIB.S9S_MB_2U(SCH_1):PAGE169
     2 DMI_CPU0_PCH_TX_DP<7> @S9S_MB_2U_LIB.S9S_MB_2U(SCH_1):DMI_CPU0_PCH_TX_DP(7)    I36 @S9S_MB_2U_LIB.S9S_MB_2U(SCH_1):PAGE169

C1792 Q_CAP_DIFFBUS_C0201-DIFF BUS_0A
     1 P5E_CPU0_PE4_TX_C_DP<14> @S9S_MB_2U_LIB.S9S_MB_2U(SCH_1):P5E_CPU0_PE4_TX_C_DP(14)   I271 @S9S_MB_2U_LIB.S9S_MB_2U(SCH_1):PAGE166
     2 P5E_CPU0_PE4_TX_DP<14> @S9S_MB_2U_LIB.S9S_MB_2U(SCH_1):P5E_CPU0_PE4_TX_DP(14)   I271 @S9S_MB_2U_LIB.S9S_MB_2U(SCH_1):PAGE166

C1793 Q_CAP_DIFFBUS_C0201-DIFF BUS_0A
     1 P5E_CPU0_PE4_TX_C_DP<9> @S9S_MB_2U_LIB.S9S_MB_2U(SCH_1):P5E_CPU0_PE4_TX_C_DP(9)   I261 @S9S_MB_2U_LIB.S9S_MB_2U(SCH_1):PAGE166
     2 P5E_CPU0_PE4_TX_DP<9> @S9S_MB_2U_LIB.S9S_MB_2U(SCH_1):P5E_CPU0_PE4_TX_DP(9)   I261 @S9S_MB_2U_LIB.S9S_MB_2U(SCH_1):PAGE166

C1794 Q_CAP_DIFFBUS_C0201-DIFF BUS_0A
     1 P5E_CPU0_PE4_TX_C_DN<8> @S9S_MB_2U_LIB.S9S_MB_2U(SCH_1):P5E_CPU0_PE4_TX_C_DN(8)   I260 @S9S_MB_2U_LIB.S9S_MB_2U(SCH_1):PAGE166
     2 P5E_CPU0_PE4_TX_DN<8> @S9S_MB_2U_LIB.S9S_MB_2U(SCH_1):P5E_CPU0_PE4_TX_DN(8)   I260 @S9S_MB_2U_LIB.S9S_MB_2U(SCH_1):PAGE166

C1796 Q_CAP_0402-0.1UF,25V,10%,X7R,CA
     1 P3V3_AUX @S9S_MB_2U_LIB.S9S_MB_2U(SCH_1):P3V3_AUX    I20 @S9S_MB_2U_LIB.S9S_MB_2U(SCH_1):PAGE222
     2    GND @S9S_MB_2U_LIB.S9S_MB_2U(SCH_1):GND    I20 @S9S_MB_2U_LIB.S9S_MB_2U(SCH_1):PAGE222

C1797 Q_CAP_0402-0.1UF,25V,10%,X7R,CA
     1 PDB_PRSNT_N @S9S_MB_2U_LIB.S9S_MB_2U(SCH_1):PDB_PRSNT_N     I3 @S9S_MB_2U_LIB.S9S_MB_2U(SCH_1):PAGE303
     2    GND @S9S_MB_2U_LIB.S9S_MB_2U(SCH_1):GND     I3 @S9S_MB_2U_LIB.S9S_MB_2U(SCH_1):PAGE303

C1802 Q_CAP_0402-1000PF,50V,5%,EMPTYA
     1 FM_SMB_1_ALERT_GPU_ISO_N @S9S_MB_2U_LIB.S9S_MB_2U(SCH_1):FM_SMB_1_ALERT_GPU_ISO_N   I148 @S9S_MB_2U_LIB.S9S_MB_2U(SCH_1):PAGE145
     2    GND @S9S_MB_2U_LIB.S9S_MB_2U(SCH_1):GND   I148 @S9S_MB_2U_LIB.S9S_MB_2U(SCH_1):PAGE145

C1803 Q_CAP_0402-0.1UF,25V,10%,X7R,CA
     1 P3V3_AUX @S9S_MB_2U_LIB.S9S_MB_2U(SCH_1):P3V3_AUX   I166 @S9S_MB_2U_LIB.S9S_MB_2U(SCH_1):PAGE140
     2    GND @S9S_MB_2U_LIB.S9S_MB_2U(SCH_1):GND   I166 @S9S_MB_2U_LIB.S9S_MB_2U(SCH_1):PAGE140

C1804 Q_CAP_0402-1000PF,50V,5%,EMPTYA
     1 FM_SMB_2_ALERT_GPU_ISO_N @S9S_MB_2U_LIB.S9S_MB_2U(SCH_1):FM_SMB_2_ALERT_GPU_ISO_N   I125 @S9S_MB_2U_LIB.S9S_MB_2U(SCH_1):PAGE145
     2    GND @S9S_MB_2U_LIB.S9S_MB_2U(SCH_1):GND   I125 @S9S_MB_2U_LIB.S9S_MB_2U(SCH_1):PAGE145

C1809 Q_CAP_0402-0.1UF,25V,10%,X7R,CA
     1 P3V3_AUX @S9S_MB_2U_LIB.S9S_MB_2U(SCH_1):P3V3_AUX    I26 @S9S_MB_2U_LIB.S9S_MB_2U(SCH_1):PAGE131
     2    GND @S9S_MB_2U_LIB.S9S_MB_2U(SCH_1):GND    I26 @S9S_MB_2U_LIB.S9S_MB_2U(SCH_1):PAGE131

C1810 Q_CAP_0402-0.1UF,25V,10%,X7R,CA
     1 P3V3_AUX @S9S_MB_2U_LIB.S9S_MB_2U(SCH_1):P3V3_AUX    I21 @S9S_MB_2U_LIB.S9S_MB_2U(SCH_1):PAGE131
     2    GND @S9S_MB_2U_LIB.S9S_MB_2U(SCH_1):GND    I21 @S9S_MB_2U_LIB.S9S_MB_2U(SCH_1):PAGE131

C1817 Q_CAP_0402-0.1UF,25V,10%,X7R,CA
     1 P3V3_AUX @S9S_MB_2U_LIB.S9S_MB_2U(SCH_1):P3V3_AUX    I39 @S9S_MB_2U_LIB.S9S_MB_2U(SCH_1):PAGE132
     2    GND @S9S_MB_2U_LIB.S9S_MB_2U(SCH_1):GND    I39 @S9S_MB_2U_LIB.S9S_MB_2U(SCH_1):PAGE132

C1818 Q_CAP_0402-0.1UF,25V,10%,X7R,CA
     1 P3V3_AUX @S9S_MB_2U_LIB.S9S_MB_2U(SCH_1):P3V3_AUX    I15 @S9S_MB_2U_LIB.S9S_MB_2U(SCH_1):PAGE132
     2    GND @S9S_MB_2U_LIB.S9S_MB_2U(SCH_1):GND    I15 @S9S_MB_2U_LIB.S9S_MB_2U(SCH_1):PAGE132

C1819 Q_CAP_0402-0.1UF,25V,10%,X7R,CA
     1 P3V3_OCP_V3_2 @S9S_MB_2U_LIB.S9S_MB_2U(SCH_1):P3V3_OCP_V3_2    I87 @S9S_MB_2U_LIB.S9S_MB_2U(SCH_1):PAGE132
     2    GND @S9S_MB_2U_LIB.S9S_MB_2U(SCH_1):GND    I87 @S9S_MB_2U_LIB.S9S_MB_2U(SCH_1):PAGE132

C1820 Q_CAP_0402-0.1UF,25V,10%,X7R,CA
     1 P3V3_AUX @S9S_MB_2U_LIB.S9S_MB_2U(SCH_1):P3V3_AUX    I58 @S9S_MB_2U_LIB.S9S_MB_2U(SCH_1):PAGE132
     2    GND @S9S_MB_2U_LIB.S9S_MB_2U(SCH_1):GND    I58 @S9S_MB_2U_LIB.S9S_MB_2U(SCH_1):PAGE132

C1821 Q_CAP_0402-0.1UF,25V,10%,X7R,CA
     1 P3V3_AUX @S9S_MB_2U_LIB.S9S_MB_2U(SCH_1):P3V3_AUX    I12 @S9S_MB_2U_LIB.S9S_MB_2U(SCH_1):PAGE156
     2    GND @S9S_MB_2U_LIB.S9S_MB_2U(SCH_1):GND    I12 @S9S_MB_2U_LIB.S9S_MB_2U(SCH_1):PAGE156

C1822 Q_CAP_0402-0.1UF,25V,10%,X7R,CA
     1 P3V3_AUX @S9S_MB_2U_LIB.S9S_MB_2U(SCH_1):P3V3_AUX    I27 @S9S_MB_2U_LIB.S9S_MB_2U(SCH_1):PAGE156
     2    GND @S9S_MB_2U_LIB.S9S_MB_2U(SCH_1):GND    I27 @S9S_MB_2U_LIB.S9S_MB_2U(SCH_1):PAGE156

C1823 Q_CAP_0402-0.1UF,25V,10%,X7R,CA
     1 P3V3_AUX @S9S_MB_2U_LIB.S9S_MB_2U(SCH_1):P3V3_AUX    I33 @S9S_MB_2U_LIB.S9S_MB_2U(SCH_1):PAGE156
     2    GND @S9S_MB_2U_LIB.S9S_MB_2U(SCH_1):GND    I33 @S9S_MB_2U_LIB.S9S_MB_2U(SCH_1):PAGE156

C1824 Q_CAP_0402-0.1UF,25V,10%,X7R,CA
     1 P3V3_AUX @S9S_MB_2U_LIB.S9S_MB_2U(SCH_1):P3V3_AUX    I47 @S9S_MB_2U_LIB.S9S_MB_2U(SCH_1):PAGE156
     2    GND @S9S_MB_2U_LIB.S9S_MB_2U(SCH_1):GND    I47 @S9S_MB_2U_LIB.S9S_MB_2U(SCH_1):PAGE156

C1825 Q_CAP_0402-0.1UF,25V,10%,X7R,CA
     1 P3V3_AUX @S9S_MB_2U_LIB.S9S_MB_2U(SCH_1):P3V3_AUX    I17 @S9S_MB_2U_LIB.S9S_MB_2U(SCH_1):PAGE307
     2    GND @S9S_MB_2U_LIB.S9S_MB_2U(SCH_1):GND    I17 @S9S_MB_2U_LIB.S9S_MB_2U(SCH_1):PAGE307

C1826 Q_CAP_0402-0.1UF,25V,10%,X7R,CA
     1 P3V3_AUX @S9S_MB_2U_LIB.S9S_MB_2U(SCH_1):P3V3_AUX    I33 @S9S_MB_2U_LIB.S9S_MB_2U(SCH_1):PAGE307
     2    GND @S9S_MB_2U_LIB.S9S_MB_2U(SCH_1):GND    I33 @S9S_MB_2U_LIB.S9S_MB_2U(SCH_1):PAGE307

C1827 Q_CAP_0402-0.1UF,25V,10%,X7R,CA
     1 P3V3_AUX @S9S_MB_2U_LIB.S9S_MB_2U(SCH_1):P3V3_AUX    I77 @S9S_MB_2U_LIB.S9S_MB_2U(SCH_1):PAGE307
     2    GND @S9S_MB_2U_LIB.S9S_MB_2U(SCH_1):GND    I77 @S9S_MB_2U_LIB.S9S_MB_2U(SCH_1):PAGE307

C1829 Q_CAP_C0805-22UF,16V,20%,X6S,CB
     1 P12V_OCP_V3_2 @S9S_MB_2U_LIB.S9S_MB_2U(SCH_1):P12V_OCP_V3_2   I166 @S9S_MB_2U_LIB.S9S_MB_2U(SCH_1):PAGE146
     2    GND @S9S_MB_2U_LIB.S9S_MB_2U(SCH_1):GND   I166 @S9S_MB_2U_LIB.S9S_MB_2U(SCH_1):PAGE146

C1830 Q_CAP_C0805-22UF,16V,20%,X6S,CB
     1 P12V_OCP_V3_2 @S9S_MB_2U_LIB.S9S_MB_2U(SCH_1):P12V_OCP_V3_2   I167 @S9S_MB_2U_LIB.S9S_MB_2U(SCH_1):PAGE146
     2    GND @S9S_MB_2U_LIB.S9S_MB_2U(SCH_1):GND   I167 @S9S_MB_2U_LIB.S9S_MB_2U(SCH_1):PAGE146

C1831 Q_CAP_0402-0.1UF,25V,10%,X7R,CA
     1 P12V_OCP_V3_2 @S9S_MB_2U_LIB.S9S_MB_2U(SCH_1):P12V_OCP_V3_2   I168 @S9S_MB_2U_LIB.S9S_MB_2U(SCH_1):PAGE146
     2    GND @S9S_MB_2U_LIB.S9S_MB_2U(SCH_1):GND   I168 @S9S_MB_2U_LIB.S9S_MB_2U(SCH_1):PAGE146

C1832 Q_CAP_0402-0.1UF,25V,10%,X7R,CA
     1 P12V_OCP_V3_2 @S9S_MB_2U_LIB.S9S_MB_2U(SCH_1):P12V_OCP_V3_2   I179 @S9S_MB_2U_LIB.S9S_MB_2U(SCH_1):PAGE146
     2    GND @S9S_MB_2U_LIB.S9S_MB_2U(SCH_1):GND   I179 @S9S_MB_2U_LIB.S9S_MB_2U(SCH_1):PAGE146

C1833 Q_CAP_0402-0.1UF,25V,10%,X7R,CA
     1 P12V_OCP_V3_2 @S9S_MB_2U_LIB.S9S_MB_2U(SCH_1):P12V_OCP_V3_2   I169 @S9S_MB_2U_LIB.S9S_MB_2U(SCH_1):PAGE146
     2    GND @S9S_MB_2U_LIB.S9S_MB_2U(SCH_1):GND   I169 @S9S_MB_2U_LIB.S9S_MB_2U(SCH_1):PAGE146

C1834 Q_CAP_0402-0.1UF,25V,10%,X7R,CA
     1 P12V_OCP_V3_2 @S9S_MB_2U_LIB.S9S_MB_2U(SCH_1):P12V_OCP_V3_2   I171 @S9S_MB_2U_LIB.S9S_MB_2U(SCH_1):PAGE146
     2    GND @S9S_MB_2U_LIB.S9S_MB_2U(SCH_1):GND   I171 @S9S_MB_2U_LIB.S9S_MB_2U(SCH_1):PAGE146

C1835 Q_CAP_0402-0.1UF,25V,10%,X7R,CA
     1 P3V3_OCP_V3_2 @S9S_MB_2U_LIB.S9S_MB_2U(SCH_1):P3V3_OCP_V3_2   I173 @S9S_MB_2U_LIB.S9S_MB_2U(SCH_1):PAGE146
     2    GND @S9S_MB_2U_LIB.S9S_MB_2U(SCH_1):GND   I173 @S9S_MB_2U_LIB.S9S_MB_2U(SCH_1):PAGE146

C1836 Q_CAP_0402-0.1UF,25V,10%,X7R,CA
     1 P3V3_OCP_V3_2 @S9S_MB_2U_LIB.S9S_MB_2U(SCH_1):P3V3_OCP_V3_2   I174 @S9S_MB_2U_LIB.S9S_MB_2U(SCH_1):PAGE146
     2    GND @S9S_MB_2U_LIB.S9S_MB_2U(SCH_1):GND   I174 @S9S_MB_2U_LIB.S9S_MB_2U(SCH_1):PAGE146

C1837 Q_CAP_0402-0.1UF,25V,10%,X7R,CA
     1 P3V3_OCP_V3_2 @S9S_MB_2U_LIB.S9S_MB_2U(SCH_1):P3V3_OCP_V3_2   I175 @S9S_MB_2U_LIB.S9S_MB_2U(SCH_1):PAGE146
     2    GND @S9S_MB_2U_LIB.S9S_MB_2U(SCH_1):GND   I175 @S9S_MB_2U_LIB.S9S_MB_2U(SCH_1):PAGE146

C1838 Q_CAP_0402-0.1UF,25V,10%,X7R,CA
     1 P3V3_OCP_V3_2 @S9S_MB_2U_LIB.S9S_MB_2U(SCH_1):P3V3_OCP_V3_2   I177 @S9S_MB_2U_LIB.S9S_MB_2U(SCH_1):PAGE146
     2    GND @S9S_MB_2U_LIB.S9S_MB_2U(SCH_1):GND   I177 @S9S_MB_2U_LIB.S9S_MB_2U(SCH_1):PAGE146

C1839 Q_CAP_0402-0.1UF,25V,10%,X7R,CA
     1 P12V_OCP_V3_2 @S9S_MB_2U_LIB.S9S_MB_2U(SCH_1):P12V_OCP_V3_2   I180 @S9S_MB_2U_LIB.S9S_MB_2U(SCH_1):PAGE146
     2    GND @S9S_MB_2U_LIB.S9S_MB_2U(SCH_1):GND   I180 @S9S_MB_2U_LIB.S9S_MB_2U(SCH_1):PAGE146

C1840 Q_CAP_0402-0.1UF,25V,10%,X7R,CA
     1 P3V3_AUX @S9S_MB_2U_LIB.S9S_MB_2U(SCH_1):P3V3_AUX     I8 @S9S_MB_2U_LIB.S9S_MB_2U(SCH_1):PAGE151
     2    GND @S9S_MB_2U_LIB.S9S_MB_2U(SCH_1):GND     I8 @S9S_MB_2U_LIB.S9S_MB_2U(SCH_1):PAGE151

C1841 Q_CAP_0402-0.1UF,25V,10%,X7R,CA
     1 P3V3_AUX @S9S_MB_2U_LIB.S9S_MB_2U(SCH_1):P3V3_AUX    I65 @S9S_MB_2U_LIB.S9S_MB_2U(SCH_1):PAGE156
     2    GND @S9S_MB_2U_LIB.S9S_MB_2U(SCH_1):GND    I65 @S9S_MB_2U_LIB.S9S_MB_2U(SCH_1):PAGE156

C1842 Q_CAP_C0402-10UF,6.3V,20%,X6S,A
     1 P3V3_AUX_FPGA_VCCIO3 @S9S_MB_2U_LIB.S9S_MB_2U(SCH_1):P3V3_AUX_FPGA_VCCIO3   I107 @S9S_MB_2U_LIB.S9S_MB_2U(SCH_1):PAGE202
     2    GND @S9S_MB_2U_LIB.S9S_MB_2U(SCH_1):GND   I107 @S9S_MB_2U_LIB.S9S_MB_2U(SCH_1):PAGE202

C1859 Q_CAP_0402-0.1UF,25V,10%,X7R,CA
     1 P3V3_AUX @S9S_MB_2U_LIB.S9S_MB_2U(SCH_1):P3V3_AUX    I10 @S9S_MB_2U_LIB.S9S_MB_2U(SCH_1):PAGE216
     2    GND @S9S_MB_2U_LIB.S9S_MB_2U(SCH_1):GND    I10 @S9S_MB_2U_LIB.S9S_MB_2U(SCH_1):PAGE216

C1860 Q_CAP_0402-0.1UF,25V,10%,X7R,CA
     1 P3V3_AUX @S9S_MB_2U_LIB.S9S_MB_2U(SCH_1):P3V3_AUX    I17 @S9S_MB_2U_LIB.S9S_MB_2U(SCH_1):PAGE216
     2    GND @S9S_MB_2U_LIB.S9S_MB_2U(SCH_1):GND    I17 @S9S_MB_2U_LIB.S9S_MB_2U(SCH_1):PAGE216

C1861 Q_CAP_0402-0.1UF,25V,10%,X7R,CA
     1 P3V3_OCP_V3_2 @S9S_MB_2U_LIB.S9S_MB_2U(SCH_1):P3V3_OCP_V3_2    I11 @S9S_MB_2U_LIB.S9S_MB_2U(SCH_1):PAGE216
     2    GND @S9S_MB_2U_LIB.S9S_MB_2U(SCH_1):GND    I11 @S9S_MB_2U_LIB.S9S_MB_2U(SCH_1):PAGE216

C1862 Q_CAP_0402-0.1UF,25V,10%,X7R,CA
     1 P3V3_OCP_SFF @S9S_MB_2U_LIB.S9S_MB_2U(SCH_1):P3V3_OCP_SFF    I23 @S9S_MB_2U_LIB.S9S_MB_2U(SCH_1):PAGE216
     2    GND @S9S_MB_2U_LIB.S9S_MB_2U(SCH_1):GND    I23 @S9S_MB_2U_LIB.S9S_MB_2U(SCH_1):PAGE216

C1863 Q_CAP_0402-0.1UF,25V,10%,X7R,CA
     1 P3V3_AUX @S9S_MB_2U_LIB.S9S_MB_2U(SCH_1):P3V3_AUX    I49 @S9S_MB_2U_LIB.S9S_MB_2U(SCH_1):PAGE136
     2    GND @S9S_MB_2U_LIB.S9S_MB_2U(SCH_1):GND    I49 @S9S_MB_2U_LIB.S9S_MB_2U(SCH_1):PAGE136

C1864 Q_CAP_0402-0.1UF,25V,10%,X7R,CA
     1 P3V3_AUX @S9S_MB_2U_LIB.S9S_MB_2U(SCH_1):P3V3_AUX    I51 @S9S_MB_2U_LIB.S9S_MB_2U(SCH_1):PAGE136
     2    GND @S9S_MB_2U_LIB.S9S_MB_2U(SCH_1):GND    I51 @S9S_MB_2U_LIB.S9S_MB_2U(SCH_1):PAGE136

C1865 Q_CAP_0402-0.1UF,25V,10%,X7R,CA
     1 P3V3_AUX @S9S_MB_2U_LIB.S9S_MB_2U(SCH_1):P3V3_AUX    I52 @S9S_MB_2U_LIB.S9S_MB_2U(SCH_1):PAGE136
     2    GND @S9S_MB_2U_LIB.S9S_MB_2U(SCH_1):GND    I52 @S9S_MB_2U_LIB.S9S_MB_2U(SCH_1):PAGE136

C1866 Q_CAP_0402-0.1UF,25V,10%,X7R,CA
     1 P3V3_AUX @S9S_MB_2U_LIB.S9S_MB_2U(SCH_1):P3V3_AUX    I53 @S9S_MB_2U_LIB.S9S_MB_2U(SCH_1):PAGE136
     2    GND @S9S_MB_2U_LIB.S9S_MB_2U(SCH_1):GND    I53 @S9S_MB_2U_LIB.S9S_MB_2U(SCH_1):PAGE136

C1867 Q_CAP_C0805-10UF,25V,10%,X6S,CA
     1 P3V3_AUX @S9S_MB_2U_LIB.S9S_MB_2U(SCH_1):P3V3_AUX    I48 @S9S_MB_2U_LIB.S9S_MB_2U(SCH_1):PAGE136
     2    GND @S9S_MB_2U_LIB.S9S_MB_2U(SCH_1):GND    I48 @S9S_MB_2U_LIB.S9S_MB_2U(SCH_1):PAGE136

C1868 Q_CAP_0402-0.1UF,25V,10%,X7R,CA
     1 P2E_MB_BMC_RX_BUF_C_DP<0> @S9S_MB_2U_LIB.S9S_MB_2U(SCH_1):P2E_MB_BMC_RX_BUF_C_DP(0)    I29 @S9S_MB_2U_LIB.S9S_MB_2U(SCH_1):PAGE159
     2 P2E_MB_BMC_RX_BUF_DP<0> @S9S_MB_2U_LIB.S9S_MB_2U(SCH_1):P2E_MB_BMC_RX_BUF_DP(0)    I29 @S9S_MB_2U_LIB.S9S_MB_2U(SCH_1):PAGE159

C1869 Q_CAP_0402-0.1UF,25V,10%,X7R,CA
     1 P2E_MB_BMC_RX_BUF_C_DN<0> @S9S_MB_2U_LIB.S9S_MB_2U(SCH_1):P2E_MB_BMC_RX_BUF_C_DN(0)    I30 @S9S_MB_2U_LIB.S9S_MB_2U(SCH_1):PAGE159
     2 P2E_MB_BMC_RX_BUF_DN<0> @S9S_MB_2U_LIB.S9S_MB_2U(SCH_1):P2E_MB_BMC_RX_BUF_DN(0)    I30 @S9S_MB_2U_LIB.S9S_MB_2U(SCH_1):PAGE159

C1870 Q_CAP_0402-0.1UF,25V,10%,X7R,CA
     1 P2E_MB_BMC_TX_BUF_DP<0> @S9S_MB_2U_LIB.S9S_MB_2U(SCH_1):P2E_MB_BMC_TX_BUF_DP(0)    I33 @S9S_MB_2U_LIB.S9S_MB_2U(SCH_1):PAGE159
     2 P2E_MB_BMC_TX_BUF_C_DP<0> @S9S_MB_2U_LIB.S9S_MB_2U(SCH_1):P2E_MB_BMC_TX_BUF_C_DP(0)    I33 @S9S_MB_2U_LIB.S9S_MB_2U(SCH_1):PAGE159

C1871 Q_CAP_0402-0.1UF,25V,10%,X7R,CA
     1 P2E_MB_BMC_TX_BUF_DN<0> @S9S_MB_2U_LIB.S9S_MB_2U(SCH_1):P2E_MB_BMC_TX_BUF_DN(0)    I34 @S9S_MB_2U_LIB.S9S_MB_2U(SCH_1):PAGE159
     2 P2E_MB_BMC_TX_BUF_C_DN<0> @S9S_MB_2U_LIB.S9S_MB_2U(SCH_1):P2E_MB_BMC_TX_BUF_C_DN(0)    I34 @S9S_MB_2U_LIB.S9S_MB_2U(SCH_1):PAGE159

C1873 Q_CAP_0402-0.1UF,25V,10%,X7R,CA
     1 P3V3_AUX @S9S_MB_2U_LIB.S9S_MB_2U(SCH_1):P3V3_AUX   I308 @S9S_MB_2U_LIB.S9S_MB_2U(SCH_1):PAGE182
     2    GND @S9S_MB_2U_LIB.S9S_MB_2U(SCH_1):GND   I308 @S9S_MB_2U_LIB.S9S_MB_2U(SCH_1):PAGE182

C1874 Q_CAP_0402-0.1UF,25V,10%,X7R,CA
     1 P3V3_AUX @S9S_MB_2U_LIB.S9S_MB_2U(SCH_1):P3V3_AUX    I22 @S9S_MB_2U_LIB.S9S_MB_2U(SCH_1):PAGE170
     2    GND @S9S_MB_2U_LIB.S9S_MB_2U(SCH_1):GND    I22 @S9S_MB_2U_LIB.S9S_MB_2U(SCH_1):PAGE170

C1875 Q_CAP_0402-0.1UF,25V,10%,X7R,CA
     1 P3V3_AUX @S9S_MB_2U_LIB.S9S_MB_2U(SCH_1):P3V3_AUX    I21 @S9S_MB_2U_LIB.S9S_MB_2U(SCH_1):PAGE170
     2    GND @S9S_MB_2U_LIB.S9S_MB_2U(SCH_1):GND    I21 @S9S_MB_2U_LIB.S9S_MB_2U(SCH_1):PAGE170

C1876 Q_CAP_0402-0.1UF,25V,10%,X7R,CA
     1 P3V3_AUX @S9S_MB_2U_LIB.S9S_MB_2U(SCH_1):P3V3_AUX    I41 @S9S_MB_2U_LIB.S9S_MB_2U(SCH_1):PAGE170
     2    GND @S9S_MB_2U_LIB.S9S_MB_2U(SCH_1):GND    I41 @S9S_MB_2U_LIB.S9S_MB_2U(SCH_1):PAGE170

C1877 Q_CAP_0402-0.1UF,25V,10%,X7R,CA
     1 P3V3_AUX @S9S_MB_2U_LIB.S9S_MB_2U(SCH_1):P3V3_AUX    I34 @S9S_MB_2U_LIB.S9S_MB_2U(SCH_1):PAGE170
     2    GND @S9S_MB_2U_LIB.S9S_MB_2U(SCH_1):GND    I34 @S9S_MB_2U_LIB.S9S_MB_2U(SCH_1):PAGE170

C1878 Q_CAP_0402-0.1UF,25V,10%,X7R,CA
     1 P3V3_AUX @S9S_MB_2U_LIB.S9S_MB_2U(SCH_1):P3V3_AUX    I37 @S9S_MB_2U_LIB.S9S_MB_2U(SCH_1):PAGE170
     2    GND @S9S_MB_2U_LIB.S9S_MB_2U(SCH_1):GND    I37 @S9S_MB_2U_LIB.S9S_MB_2U(SCH_1):PAGE170

C1879 Q_CAP_0402-0.1UF,25V,10%,X7R,CA
     1 P3V3_AUX @S9S_MB_2U_LIB.S9S_MB_2U(SCH_1):P3V3_AUX    I31 @S9S_MB_2U_LIB.S9S_MB_2U(SCH_1):PAGE170
     2    GND @S9S_MB_2U_LIB.S9S_MB_2U(SCH_1):GND    I31 @S9S_MB_2U_LIB.S9S_MB_2U(SCH_1):PAGE170

C1880 Q_CAP_0402-0.1UF,25V,10%,X7R,CA
     1 P3V3_AUX @S9S_MB_2U_LIB.S9S_MB_2U(SCH_1):P3V3_AUX    I27 @S9S_MB_2U_LIB.S9S_MB_2U(SCH_1):PAGE170
     2    GND @S9S_MB_2U_LIB.S9S_MB_2U(SCH_1):GND    I27 @S9S_MB_2U_LIB.S9S_MB_2U(SCH_1):PAGE170

C1881 Q_CAP_0402-1000PF,50V,5%,EMPTYA
     1 GPU_FPGA_READY_ISO @S9S_MB_2U_LIB.S9S_MB_2U(SCH_1):GPU_FPGA_READY_ISO   I156 @S9S_MB_2U_LIB.S9S_MB_2U(SCH_1):PAGE145
     2    GND @S9S_MB_2U_LIB.S9S_MB_2U(SCH_1):GND   I156 @S9S_MB_2U_LIB.S9S_MB_2U(SCH_1):PAGE145

C1882 Q_CAP_0402-0.1UF,25V,10%,X7R,CA
     1 P3V3_AUX @S9S_MB_2U_LIB.S9S_MB_2U(SCH_1):P3V3_AUX    I80 @S9S_MB_2U_LIB.S9S_MB_2U(SCH_1):PAGE201
     2    GND @S9S_MB_2U_LIB.S9S_MB_2U(SCH_1):GND    I80 @S9S_MB_2U_LIB.S9S_MB_2U(SCH_1):PAGE201

C1883 Q_CAP_C0805-10UF,25V,10%,X6S,CA
     1 VFG3P3_CLK_GEN @S9S_MB_2U_LIB.S9S_MB_2U(SCH_1):VFG3P3_CLK_GEN    I16 @S9S_MB_2U_LIB.S9S_MB_2U(SCH_1):PAGE201
     2    GND @S9S_MB_2U_LIB.S9S_MB_2U(SCH_1):GND    I16 @S9S_MB_2U_LIB.S9S_MB_2U(SCH_1):PAGE201

C1884 Q_CAP_C0402-1UF,25V,10%,X6S,CHA
     1 VFG_3P3A_CLK_GEN @S9S_MB_2U_LIB.S9S_MB_2U(SCH_1):VFG_3P3A_CLK_GEN   I103 @S9S_MB_2U_LIB.S9S_MB_2U(SCH_1):PAGE201
     2    GND @S9S_MB_2U_LIB.S9S_MB_2U(SCH_1):GND   I103 @S9S_MB_2U_LIB.S9S_MB_2U(SCH_1):PAGE201

C1886 Q_CAP_0402-0.1UF,25V,10%,X7R,CA
     1 VFG3P3_CLK_GEN @S9S_MB_2U_LIB.S9S_MB_2U(SCH_1):VFG3P3_CLK_GEN    I18 @S9S_MB_2U_LIB.S9S_MB_2U(SCH_1):PAGE201
     2    GND @S9S_MB_2U_LIB.S9S_MB_2U(SCH_1):GND    I18 @S9S_MB_2U_LIB.S9S_MB_2U(SCH_1):PAGE201

C1889 Q_CAP_0402-0.1UF,25V,10%,X7R,CA
     1 VFG3P3_CLK_GEN @S9S_MB_2U_LIB.S9S_MB_2U(SCH_1):VFG3P3_CLK_GEN    I19 @S9S_MB_2U_LIB.S9S_MB_2U(SCH_1):PAGE201
     2    GND @S9S_MB_2U_LIB.S9S_MB_2U(SCH_1):GND    I19 @S9S_MB_2U_LIB.S9S_MB_2U(SCH_1):PAGE201

C1893 Q_CAP_C0402-0.01UF,50V,10%,X7RA
     1 P3V3_AUX_FPGA_VCCIO4 @S9S_MB_2U_LIB.S9S_MB_2U(SCH_1):P3V3_AUX_FPGA_VCCIO4    I76 @S9S_MB_2U_LIB.S9S_MB_2U(SCH_1):PAGE202
     2    GND @S9S_MB_2U_LIB.S9S_MB_2U(SCH_1):GND    I76 @S9S_MB_2U_LIB.S9S_MB_2U(SCH_1):PAGE202

C1894 Q_CAP_C0402-0.01UF,50V,10%,X7RA
     1 P3V3_AUX_FPGA_VCCIO2 @S9S_MB_2U_LIB.S9S_MB_2U(SCH_1):P3V3_AUX_FPGA_VCCIO2    I58 @S9S_MB_2U_LIB.S9S_MB_2U(SCH_1):PAGE202
     2    GND @S9S_MB_2U_LIB.S9S_MB_2U(SCH_1):GND    I58 @S9S_MB_2U_LIB.S9S_MB_2U(SCH_1):PAGE202

C1895 Q_CAP_C0402-0.01UF,50V,10%,X7RA
     1 P3V3_AUX_FPGA_VCCIO0 @S9S_MB_2U_LIB.S9S_MB_2U(SCH_1):P3V3_AUX_FPGA_VCCIO0    I43 @S9S_MB_2U_LIB.S9S_MB_2U(SCH_1):PAGE202
     2    GND @S9S_MB_2U_LIB.S9S_MB_2U(SCH_1):GND    I43 @S9S_MB_2U_LIB.S9S_MB_2U(SCH_1):PAGE202

C1896 Q_CAP_C0402-0.01UF,50V,10%,X7RA
     1 P3V3_AUX_FPGA_VCCIO1 @S9S_MB_2U_LIB.S9S_MB_2U(SCH_1):P3V3_AUX_FPGA_VCCIO1    I47 @S9S_MB_2U_LIB.S9S_MB_2U(SCH_1):PAGE202
     2    GND @S9S_MB_2U_LIB.S9S_MB_2U(SCH_1):GND    I47 @S9S_MB_2U_LIB.S9S_MB_2U(SCH_1):PAGE202

C1897 Q_CAP_C0402-0.01UF,50V,10%,X7RA
     1 VCC_PLD_CORE @S9S_MB_2U_LIB.S9S_MB_2U(SCH_1):VCC_PLD_CORE    I27 @S9S_MB_2U_LIB.S9S_MB_2U(SCH_1):PAGE202
     2    GND @S9S_MB_2U_LIB.S9S_MB_2U(SCH_1):GND    I27 @S9S_MB_2U_LIB.S9S_MB_2U(SCH_1):PAGE202

C1898 Q_CAP_C0402-0.01UF,50V,10%,X7RA
     1 P3V3_AUX_FPGA_VCCIO5 @S9S_MB_2U_LIB.S9S_MB_2U(SCH_1):P3V3_AUX_FPGA_VCCIO5    I20 @S9S_MB_2U_LIB.S9S_MB_2U(SCH_1):PAGE202
     2    GND @S9S_MB_2U_LIB.S9S_MB_2U(SCH_1):GND    I20 @S9S_MB_2U_LIB.S9S_MB_2U(SCH_1):PAGE202

C1899 Q_CAP_C0402-0.01UF,50V,10%,X7RA
     1 P3V3_AUX_FPGA_VCCIO4 @S9S_MB_2U_LIB.S9S_MB_2U(SCH_1):P3V3_AUX_FPGA_VCCIO4    I74 @S9S_MB_2U_LIB.S9S_MB_2U(SCH_1):PAGE202
     2    GND @S9S_MB_2U_LIB.S9S_MB_2U(SCH_1):GND    I74 @S9S_MB_2U_LIB.S9S_MB_2U(SCH_1):PAGE202

C1900 Q_CAP_C0402-0.01UF,50V,10%,X7RA
     1 P3V3_AUX_FPGA_VCCIO2 @S9S_MB_2U_LIB.S9S_MB_2U(SCH_1):P3V3_AUX_FPGA_VCCIO2    I57 @S9S_MB_2U_LIB.S9S_MB_2U(SCH_1):PAGE202
     2    GND @S9S_MB_2U_LIB.S9S_MB_2U(SCH_1):GND    I57 @S9S_MB_2U_LIB.S9S_MB_2U(SCH_1):PAGE202

C1901 Q_CAP_C0402-0.01UF,50V,10%,X7RA
     1 P3V3_AUX_FPGA_VCCIO0 @S9S_MB_2U_LIB.S9S_MB_2U(SCH_1):P3V3_AUX_FPGA_VCCIO0    I42 @S9S_MB_2U_LIB.S9S_MB_2U(SCH_1):PAGE202
     2    GND @S9S_MB_2U_LIB.S9S_MB_2U(SCH_1):GND    I42 @S9S_MB_2U_LIB.S9S_MB_2U(SCH_1):PAGE202

C1902 Q_CAP_C0402-0.01UF,50V,10%,X7RA
     1 P3V3_AUX_FPGA_VCCIO1 @S9S_MB_2U_LIB.S9S_MB_2U(SCH_1):P3V3_AUX_FPGA_VCCIO1    I46 @S9S_MB_2U_LIB.S9S_MB_2U(SCH_1):PAGE202
     2    GND @S9S_MB_2U_LIB.S9S_MB_2U(SCH_1):GND    I46 @S9S_MB_2U_LIB.S9S_MB_2U(SCH_1):PAGE202

C1903 Q_CAP_C0402-0.01UF,50V,10%,X7RA
     1 VCC_PLD_CORE @S9S_MB_2U_LIB.S9S_MB_2U(SCH_1):VCC_PLD_CORE    I26 @S9S_MB_2U_LIB.S9S_MB_2U(SCH_1):PAGE202
     2    GND @S9S_MB_2U_LIB.S9S_MB_2U(SCH_1):GND    I26 @S9S_MB_2U_LIB.S9S_MB_2U(SCH_1):PAGE202

C1904 Q_CAP_C0402-0.01UF,50V,10%,X7RA
     1 P3V3_AUX_FPGA_VCCIO5 @S9S_MB_2U_LIB.S9S_MB_2U(SCH_1):P3V3_AUX_FPGA_VCCIO5    I18 @S9S_MB_2U_LIB.S9S_MB_2U(SCH_1):PAGE202
     2    GND @S9S_MB_2U_LIB.S9S_MB_2U(SCH_1):GND    I18 @S9S_MB_2U_LIB.S9S_MB_2U(SCH_1):PAGE202

C1905 Q_CAP_0402-0.1UF,25V,10%,X7R,CA
     1 P3V3_AUX_FPGA_VCCIO0 @S9S_MB_2U_LIB.S9S_MB_2U(SCH_1):P3V3_AUX_FPGA_VCCIO0    I41 @S9S_MB_2U_LIB.S9S_MB_2U(SCH_1):PAGE202
     2    GND @S9S_MB_2U_LIB.S9S_MB_2U(SCH_1):GND    I41 @S9S_MB_2U_LIB.S9S_MB_2U(SCH_1):PAGE202

C1906 Q_CAP_0402-0.1UF,25V,10%,X7R,CA
     1 P3V3_AUX_FPGA_VCCIO1 @S9S_MB_2U_LIB.S9S_MB_2U(SCH_1):P3V3_AUX_FPGA_VCCIO1    I45 @S9S_MB_2U_LIB.S9S_MB_2U(SCH_1):PAGE202
     2    GND @S9S_MB_2U_LIB.S9S_MB_2U(SCH_1):GND    I45 @S9S_MB_2U_LIB.S9S_MB_2U(SCH_1):PAGE202

C1907 Q_CAP_0402-0.1UF,25V,10%,X7R,CA
     1 VCC_PLD_CORE @S9S_MB_2U_LIB.S9S_MB_2U(SCH_1):VCC_PLD_CORE    I25 @S9S_MB_2U_LIB.S9S_MB_2U(SCH_1):PAGE202
     2    GND @S9S_MB_2U_LIB.S9S_MB_2U(SCH_1):GND    I25 @S9S_MB_2U_LIB.S9S_MB_2U(SCH_1):PAGE202

C1908 Q_CAP_C0402-0.01UF,50V,10%,X7RA
     1 P3V3_AUX_FPGA_VCCIO4 @S9S_MB_2U_LIB.S9S_MB_2U(SCH_1):P3V3_AUX_FPGA_VCCIO4    I77 @S9S_MB_2U_LIB.S9S_MB_2U(SCH_1):PAGE202
     2    GND @S9S_MB_2U_LIB.S9S_MB_2U(SCH_1):GND    I77 @S9S_MB_2U_LIB.S9S_MB_2U(SCH_1):PAGE202

C1909 Q_CAP_C0402-0.01UF,50V,10%,X7RA
     1 P3V3_AUX_FPGA_VCCIO2 @S9S_MB_2U_LIB.S9S_MB_2U(SCH_1):P3V3_AUX_FPGA_VCCIO2    I59 @S9S_MB_2U_LIB.S9S_MB_2U(SCH_1):PAGE202
     2    GND @S9S_MB_2U_LIB.S9S_MB_2U(SCH_1):GND    I59 @S9S_MB_2U_LIB.S9S_MB_2U(SCH_1):PAGE202

C1910 Q_CAP_C0402-0.01UF,50V,10%,X7RA
     1 P3V3_AUX_FPGA_VCCIO0 @S9S_MB_2U_LIB.S9S_MB_2U(SCH_1):P3V3_AUX_FPGA_VCCIO0    I44 @S9S_MB_2U_LIB.S9S_MB_2U(SCH_1):PAGE202
     2    GND @S9S_MB_2U_LIB.S9S_MB_2U(SCH_1):GND    I44 @S9S_MB_2U_LIB.S9S_MB_2U(SCH_1):PAGE202

C1911 Q_CAP_C0402-0.01UF,50V,10%,X7RA
     1 P3V3_AUX_FPGA_VCCIO1 @S9S_MB_2U_LIB.S9S_MB_2U(SCH_1):P3V3_AUX_FPGA_VCCIO1    I48 @S9S_MB_2U_LIB.S9S_MB_2U(SCH_1):PAGE202
     2    GND @S9S_MB_2U_LIB.S9S_MB_2U(SCH_1):GND    I48 @S9S_MB_2U_LIB.S9S_MB_2U(SCH_1):PAGE202

C1912 Q_CAP_C0402-0.01UF,50V,10%,X7RA
     1 VCC_PLD_CORE @S9S_MB_2U_LIB.S9S_MB_2U(SCH_1):VCC_PLD_CORE    I28 @S9S_MB_2U_LIB.S9S_MB_2U(SCH_1):PAGE202
     2    GND @S9S_MB_2U_LIB.S9S_MB_2U(SCH_1):GND    I28 @S9S_MB_2U_LIB.S9S_MB_2U(SCH_1):PAGE202

C1913 Q_CAP_C0402-0.01UF,50V,10%,X7RA
     1 P3V3_AUX_FPGA_VCCIO5 @S9S_MB_2U_LIB.S9S_MB_2U(SCH_1):P3V3_AUX_FPGA_VCCIO5    I53 @S9S_MB_2U_LIB.S9S_MB_2U(SCH_1):PAGE202
     2    GND @S9S_MB_2U_LIB.S9S_MB_2U(SCH_1):GND    I53 @S9S_MB_2U_LIB.S9S_MB_2U(SCH_1):PAGE202

C1914 Q_CAP_C0402-0.01UF,50V,10%,X7RA
     1 P3V3_AUX_FPGA_VCCIO0 @S9S_MB_2U_LIB.S9S_MB_2U(SCH_1):P3V3_AUX_FPGA_VCCIO0    I36 @S9S_MB_2U_LIB.S9S_MB_2U(SCH_1):PAGE202
     2    GND @S9S_MB_2U_LIB.S9S_MB_2U(SCH_1):GND    I36 @S9S_MB_2U_LIB.S9S_MB_2U(SCH_1):PAGE202

C1915 Q_CAP_C0402-0.01UF,50V,10%,X7RA
     1 P3V3_AUX_FPGA_VCCIO1 @S9S_MB_2U_LIB.S9S_MB_2U(SCH_1):P3V3_AUX_FPGA_VCCIO1    I40 @S9S_MB_2U_LIB.S9S_MB_2U(SCH_1):PAGE202
     2    GND @S9S_MB_2U_LIB.S9S_MB_2U(SCH_1):GND    I40 @S9S_MB_2U_LIB.S9S_MB_2U(SCH_1):PAGE202

C1916 Q_CAP_C0402-0.01UF,50V,10%,X7RA
     1 VCC_PLD_CORE @S9S_MB_2U_LIB.S9S_MB_2U(SCH_1):VCC_PLD_CORE    I24 @S9S_MB_2U_LIB.S9S_MB_2U(SCH_1):PAGE202
     2    GND @S9S_MB_2U_LIB.S9S_MB_2U(SCH_1):GND    I24 @S9S_MB_2U_LIB.S9S_MB_2U(SCH_1):PAGE202

C1917 Q_CAP_C0402-0.01UF,50V,10%,X7RA
     1 P3V3_AUX_FPGA_VCCIO0 @S9S_MB_2U_LIB.S9S_MB_2U(SCH_1):P3V3_AUX_FPGA_VCCIO0    I35 @S9S_MB_2U_LIB.S9S_MB_2U(SCH_1):PAGE202
     2    GND @S9S_MB_2U_LIB.S9S_MB_2U(SCH_1):GND    I35 @S9S_MB_2U_LIB.S9S_MB_2U(SCH_1):PAGE202

C1918 Q_CAP_C0402-0.01UF,50V,10%,X7RA
     1 P3V3_AUX_FPGA_VCCIO1 @S9S_MB_2U_LIB.S9S_MB_2U(SCH_1):P3V3_AUX_FPGA_VCCIO1    I39 @S9S_MB_2U_LIB.S9S_MB_2U(SCH_1):PAGE202
     2    GND @S9S_MB_2U_LIB.S9S_MB_2U(SCH_1):GND    I39 @S9S_MB_2U_LIB.S9S_MB_2U(SCH_1):PAGE202

C1919 Q_CAP_C0402-0.01UF,50V,10%,X7RA
     1 VCC_PLD_CORE @S9S_MB_2U_LIB.S9S_MB_2U(SCH_1):VCC_PLD_CORE    I23 @S9S_MB_2U_LIB.S9S_MB_2U(SCH_1):PAGE202
     2    GND @S9S_MB_2U_LIB.S9S_MB_2U(SCH_1):GND    I23 @S9S_MB_2U_LIB.S9S_MB_2U(SCH_1):PAGE202

C1920 Q_CAP_C0603-22UF,6.3V,20%,X6S,A
     1 P3V3_M2_0 @S9S_MB_2U_LIB.S9S_MB_2U(SCH_1):P3V3_M2_0    I88 @S9S_MB_2U_LIB.S9S_MB_2U(SCH_1):PAGE182
     2    GND @S9S_MB_2U_LIB.S9S_MB_2U(SCH_1):GND    I88 @S9S_MB_2U_LIB.S9S_MB_2U(SCH_1):PAGE182

C1921 Q_CAP_C0603-22UF,6.3V,20%,X6S,A
     1 P3V3_M2_0 @S9S_MB_2U_LIB.S9S_MB_2U(SCH_1):P3V3_M2_0    I90 @S9S_MB_2U_LIB.S9S_MB_2U(SCH_1):PAGE182
     2    GND @S9S_MB_2U_LIB.S9S_MB_2U(SCH_1):GND    I90 @S9S_MB_2U_LIB.S9S_MB_2U(SCH_1):PAGE182

C1922 Q_CAP_C0603-22UF,6.3V,20%,X6S,A
     1 P3V3_M2_0 @S9S_MB_2U_LIB.S9S_MB_2U(SCH_1):P3V3_M2_0    I96 @S9S_MB_2U_LIB.S9S_MB_2U(SCH_1):PAGE182
     2    GND @S9S_MB_2U_LIB.S9S_MB_2U(SCH_1):GND    I96 @S9S_MB_2U_LIB.S9S_MB_2U(SCH_1):PAGE182

C1923 Q_CAP_0402-0.1UF,25V,10%,X7R,CA
     1 P3V3_M2_0 @S9S_MB_2U_LIB.S9S_MB_2U(SCH_1):P3V3_M2_0    I97 @S9S_MB_2U_LIB.S9S_MB_2U(SCH_1):PAGE182
     2    GND @S9S_MB_2U_LIB.S9S_MB_2U(SCH_1):GND    I97 @S9S_MB_2U_LIB.S9S_MB_2U(SCH_1):PAGE182

C1924 Q_CAP_0402-0.1UF,25V,10%,X7R,CA
     1 P3V3_M2_0 @S9S_MB_2U_LIB.S9S_MB_2U(SCH_1):P3V3_M2_0    I98 @S9S_MB_2U_LIB.S9S_MB_2U(SCH_1):PAGE182
     2    GND @S9S_MB_2U_LIB.S9S_MB_2U(SCH_1):GND    I98 @S9S_MB_2U_LIB.S9S_MB_2U(SCH_1):PAGE182

C1925 Q_CAP_0402-0.1UF,25V,10%,X7R,CA
     1 P3V3_M2_0 @S9S_MB_2U_LIB.S9S_MB_2U(SCH_1):P3V3_M2_0   I100 @S9S_MB_2U_LIB.S9S_MB_2U(SCH_1):PAGE182
     2    GND @S9S_MB_2U_LIB.S9S_MB_2U(SCH_1):GND   I100 @S9S_MB_2U_LIB.S9S_MB_2U(SCH_1):PAGE182

C1926 Q_CAP_C0402-0.01UF,50V,10%,X7RA
     1 P3V3_AUX_FPGA_VCCIO0 @S9S_MB_2U_LIB.S9S_MB_2U(SCH_1):P3V3_AUX_FPGA_VCCIO0    I34 @S9S_MB_2U_LIB.S9S_MB_2U(SCH_1):PAGE202
     2    GND @S9S_MB_2U_LIB.S9S_MB_2U(SCH_1):GND    I34 @S9S_MB_2U_LIB.S9S_MB_2U(SCH_1):PAGE202

C1927 Q_CAP_C0402-0.01UF,50V,10%,X7RA
     1 P3V3_AUX_FPGA_VCCIO1 @S9S_MB_2U_LIB.S9S_MB_2U(SCH_1):P3V3_AUX_FPGA_VCCIO1    I38 @S9S_MB_2U_LIB.S9S_MB_2U(SCH_1):PAGE202
     2    GND @S9S_MB_2U_LIB.S9S_MB_2U(SCH_1):GND    I38 @S9S_MB_2U_LIB.S9S_MB_2U(SCH_1):PAGE202

C1928 Q_CAP_C0402-0.01UF,50V,10%,X7RA
     1 VCC_PLD_CORE @S9S_MB_2U_LIB.S9S_MB_2U(SCH_1):VCC_PLD_CORE    I22 @S9S_MB_2U_LIB.S9S_MB_2U(SCH_1):PAGE202
     2    GND @S9S_MB_2U_LIB.S9S_MB_2U(SCH_1):GND    I22 @S9S_MB_2U_LIB.S9S_MB_2U(SCH_1):PAGE202

C1929 Q_CAP_C0402-0.01UF,50V,10%,X7RA
     1 P3V3_AUX_FPGA_VCCIO0 @S9S_MB_2U_LIB.S9S_MB_2U(SCH_1):P3V3_AUX_FPGA_VCCIO0    I33 @S9S_MB_2U_LIB.S9S_MB_2U(SCH_1):PAGE202
     2    GND @S9S_MB_2U_LIB.S9S_MB_2U(SCH_1):GND    I33 @S9S_MB_2U_LIB.S9S_MB_2U(SCH_1):PAGE202

C1930 Q_CAP_C0402-0.01UF,50V,10%,X7RA
     1 P3V3_AUX_FPGA_VCCIO1 @S9S_MB_2U_LIB.S9S_MB_2U(SCH_1):P3V3_AUX_FPGA_VCCIO1    I37 @S9S_MB_2U_LIB.S9S_MB_2U(SCH_1):PAGE202
     2    GND @S9S_MB_2U_LIB.S9S_MB_2U(SCH_1):GND    I37 @S9S_MB_2U_LIB.S9S_MB_2U(SCH_1):PAGE202

C1931 Q_CAP_C0402-0.01UF,50V,10%,X7RA
     1 VCC_PLD_CORE @S9S_MB_2U_LIB.S9S_MB_2U(SCH_1):VCC_PLD_CORE    I21 @S9S_MB_2U_LIB.S9S_MB_2U(SCH_1):PAGE202
     2    GND @S9S_MB_2U_LIB.S9S_MB_2U(SCH_1):GND    I21 @S9S_MB_2U_LIB.S9S_MB_2U(SCH_1):PAGE202

C1932 Q_CAP_C0402-0.01UF,50V,10%,X7RA
     1 P3V3_AUX_FPGA_VCCIO0 @S9S_MB_2U_LIB.S9S_MB_2U(SCH_1):P3V3_AUX_FPGA_VCCIO0     I9 @S9S_MB_2U_LIB.S9S_MB_2U(SCH_1):PAGE202
     2    GND @S9S_MB_2U_LIB.S9S_MB_2U(SCH_1):GND     I9 @S9S_MB_2U_LIB.S9S_MB_2U(SCH_1):PAGE202

C1933 Q_CAP_C0402-0.01UF,50V,10%,X7RA
     1 P3V3_AUX_FPGA_VCCIO1 @S9S_MB_2U_LIB.S9S_MB_2U(SCH_1):P3V3_AUX_FPGA_VCCIO1    I12 @S9S_MB_2U_LIB.S9S_MB_2U(SCH_1):PAGE202
     2    GND @S9S_MB_2U_LIB.S9S_MB_2U(SCH_1):GND    I12 @S9S_MB_2U_LIB.S9S_MB_2U(SCH_1):PAGE202

C1934 Q_CAP_C0402-0.01UF,50V,10%,X7RA
     1 VCC_PLD_CORE @S9S_MB_2U_LIB.S9S_MB_2U(SCH_1):VCC_PLD_CORE   I120 @S9S_MB_2U_LIB.S9S_MB_2U(SCH_1):PAGE202
     2    GND @S9S_MB_2U_LIB.S9S_MB_2U(SCH_1):GND   I120 @S9S_MB_2U_LIB.S9S_MB_2U(SCH_1):PAGE202

C1935 Q_CAP_C0402-10UF,6.3V,20%,X6S,A
     1 P3V3_AUX_FPGA_VCCIO4 @S9S_MB_2U_LIB.S9S_MB_2U(SCH_1):P3V3_AUX_FPGA_VCCIO4    I82 @S9S_MB_2U_LIB.S9S_MB_2U(SCH_1):PAGE202
     2    GND @S9S_MB_2U_LIB.S9S_MB_2U(SCH_1):GND    I82 @S9S_MB_2U_LIB.S9S_MB_2U(SCH_1):PAGE202

C1936 Q_CAP_C0402-10UF,6.3V,20%,X6S,A
     1 VCC_PLD_CORE @S9S_MB_2U_LIB.S9S_MB_2U(SCH_1):VCC_PLD_CORE    I30 @S9S_MB_2U_LIB.S9S_MB_2U(SCH_1):PAGE202
     2    GND @S9S_MB_2U_LIB.S9S_MB_2U(SCH_1):GND    I30 @S9S_MB_2U_LIB.S9S_MB_2U(SCH_1):PAGE202

C1937 Q_CAP_C0402-10UF,6.3V,20%,X6S,A
     1 P3V3_AUX_FPGA_VCCIO2 @S9S_MB_2U_LIB.S9S_MB_2U(SCH_1):P3V3_AUX_FPGA_VCCIO2    I71 @S9S_MB_2U_LIB.S9S_MB_2U(SCH_1):PAGE202
     2    GND @S9S_MB_2U_LIB.S9S_MB_2U(SCH_1):GND    I71 @S9S_MB_2U_LIB.S9S_MB_2U(SCH_1):PAGE202

C1938 Q_CAP_C0402-10UF,6.3V,20%,X6S,A
     1 P3V3_AUX_FPGA_VCCIO0 @S9S_MB_2U_LIB.S9S_MB_2U(SCH_1):P3V3_AUX_FPGA_VCCIO0    I64 @S9S_MB_2U_LIB.S9S_MB_2U(SCH_1):PAGE202
     2    GND @S9S_MB_2U_LIB.S9S_MB_2U(SCH_1):GND    I64 @S9S_MB_2U_LIB.S9S_MB_2U(SCH_1):PAGE202

C1939 Q_CAP_C0402-10UF,6.3V,20%,X6S,A
     1 P3V3_AUX_FPGA_VCCIO1 @S9S_MB_2U_LIB.S9S_MB_2U(SCH_1):P3V3_AUX_FPGA_VCCIO1    I66 @S9S_MB_2U_LIB.S9S_MB_2U(SCH_1):PAGE202
     2    GND @S9S_MB_2U_LIB.S9S_MB_2U(SCH_1):GND    I66 @S9S_MB_2U_LIB.S9S_MB_2U(SCH_1):PAGE202

C1940 Q_CAP_C0402-10UF,6.3V,20%,X6S,A
     1 P3V3_AUX_FPGA_VCCIO5 @S9S_MB_2U_LIB.S9S_MB_2U(SCH_1):P3V3_AUX_FPGA_VCCIO5    I55 @S9S_MB_2U_LIB.S9S_MB_2U(SCH_1):PAGE202
     2    GND @S9S_MB_2U_LIB.S9S_MB_2U(SCH_1):GND    I55 @S9S_MB_2U_LIB.S9S_MB_2U(SCH_1):PAGE202

C1941 Q_CAP_0402-0.1UF,25V,10%,X7R,CA
     1 P3V3_AUX_FPGA_VCCIO3 @S9S_MB_2U_LIB.S9S_MB_2U(SCH_1):P3V3_AUX_FPGA_VCCIO3   I101 @S9S_MB_2U_LIB.S9S_MB_2U(SCH_1):PAGE202
     2    GND @S9S_MB_2U_LIB.S9S_MB_2U(SCH_1):GND   I101 @S9S_MB_2U_LIB.S9S_MB_2U(SCH_1):PAGE202

C1942 Q_CAP_0402-0.1UF,25V,10%,X7R,CA
     1 P3V3_AUX_FPGA_VCCIO4 @S9S_MB_2U_LIB.S9S_MB_2U(SCH_1):P3V3_AUX_FPGA_VCCIO4    I80 @S9S_MB_2U_LIB.S9S_MB_2U(SCH_1):PAGE202
     2    GND @S9S_MB_2U_LIB.S9S_MB_2U(SCH_1):GND    I80 @S9S_MB_2U_LIB.S9S_MB_2U(SCH_1):PAGE202

C1943 Q_CAP_0402-0.1UF,25V,10%,X7R,CA
     1 VCC_PLD_CORE @S9S_MB_2U_LIB.S9S_MB_2U(SCH_1):VCC_PLD_CORE    I29 @S9S_MB_2U_LIB.S9S_MB_2U(SCH_1):PAGE202
     2    GND @S9S_MB_2U_LIB.S9S_MB_2U(SCH_1):GND    I29 @S9S_MB_2U_LIB.S9S_MB_2U(SCH_1):PAGE202

C1944 Q_CAP_0402-0.1UF,25V,10%,X7R,CA
     1 P3V3_AUX_FPGA_VCCIO2 @S9S_MB_2U_LIB.S9S_MB_2U(SCH_1):P3V3_AUX_FPGA_VCCIO2    I70 @S9S_MB_2U_LIB.S9S_MB_2U(SCH_1):PAGE202
     2    GND @S9S_MB_2U_LIB.S9S_MB_2U(SCH_1):GND    I70 @S9S_MB_2U_LIB.S9S_MB_2U(SCH_1):PAGE202

C1945 Q_CAP_0402-0.1UF,25V,10%,X7R,CA
     1 P3V3_AUX_FPGA_VCCIO0 @S9S_MB_2U_LIB.S9S_MB_2U(SCH_1):P3V3_AUX_FPGA_VCCIO0    I62 @S9S_MB_2U_LIB.S9S_MB_2U(SCH_1):PAGE202
     2    GND @S9S_MB_2U_LIB.S9S_MB_2U(SCH_1):GND    I62 @S9S_MB_2U_LIB.S9S_MB_2U(SCH_1):PAGE202

C1946 Q_CAP_0402-0.1UF,25V,10%,X7R,CA
     1 P3V3_AUX_FPGA_VCCIO1 @S9S_MB_2U_LIB.S9S_MB_2U(SCH_1):P3V3_AUX_FPGA_VCCIO1    I65 @S9S_MB_2U_LIB.S9S_MB_2U(SCH_1):PAGE202
     2    GND @S9S_MB_2U_LIB.S9S_MB_2U(SCH_1):GND    I65 @S9S_MB_2U_LIB.S9S_MB_2U(SCH_1):PAGE202

C1947 Q_CAP_0402-0.1UF,25V,10%,X7R,CA
     1 P3V3_AUX_FPGA_VCCIO5 @S9S_MB_2U_LIB.S9S_MB_2U(SCH_1):P3V3_AUX_FPGA_VCCIO5    I54 @S9S_MB_2U_LIB.S9S_MB_2U(SCH_1):PAGE202
     2    GND @S9S_MB_2U_LIB.S9S_MB_2U(SCH_1):GND    I54 @S9S_MB_2U_LIB.S9S_MB_2U(SCH_1):PAGE202

C1957 Q_CAP_0402-0.1UF,25V,10%,X7R,CA
     1 P3V3_AUX @S9S_MB_2U_LIB.S9S_MB_2U(SCH_1):P3V3_AUX   I148 @S9S_MB_2U_LIB.S9S_MB_2U(SCH_1):PAGE160
     2    GND @S9S_MB_2U_LIB.S9S_MB_2U(SCH_1):GND   I148 @S9S_MB_2U_LIB.S9S_MB_2U(SCH_1):PAGE160

C1958 Q_CAP_0402-0.1UF,25V,10%,X7R,CA
     1 P3V3_AUX @S9S_MB_2U_LIB.S9S_MB_2U(SCH_1):P3V3_AUX    I29 @S9S_MB_2U_LIB.S9S_MB_2U(SCH_1):PAGE160
     2    GND @S9S_MB_2U_LIB.S9S_MB_2U(SCH_1):GND    I29 @S9S_MB_2U_LIB.S9S_MB_2U(SCH_1):PAGE160

C1963 Q_CAP_0402-0.1UF,25V,10%,X7R,CA
     1 P3V3_AUX @S9S_MB_2U_LIB.S9S_MB_2U(SCH_1):P3V3_AUX    I13 @S9S_MB_2U_LIB.S9S_MB_2U(SCH_1):PAGE296
     2    GND @S9S_MB_2U_LIB.S9S_MB_2U(SCH_1):GND    I13 @S9S_MB_2U_LIB.S9S_MB_2U(SCH_1):PAGE296

C1973 Q_CAP_0402-1000PF,50V,5%,EMPTYA
     1 GPU_BASE_HMC_READY_ISO @S9S_MB_2U_LIB.S9S_MB_2U(SCH_1):GPU_BASE_HMC_READY_ISO    I71 @S9S_MB_2U_LIB.S9S_MB_2U(SCH_1):PAGE299
     2    GND @S9S_MB_2U_LIB.S9S_MB_2U(SCH_1):GND    I71 @S9S_MB_2U_LIB.S9S_MB_2U(SCH_1):PAGE299

C1974 Q_CAP_0402-1000PF,50V,5%,EMPTYA
     1 GPU_FPGA_THERM_OVERT_ISO_N @S9S_MB_2U_LIB.S9S_MB_2U(SCH_1):GPU_FPGA_THERM_OVERT_ISO_N    I74 @S9S_MB_2U_LIB.S9S_MB_2U(SCH_1):PAGE299
     2    GND @S9S_MB_2U_LIB.S9S_MB_2U(SCH_1):GND    I74 @S9S_MB_2U_LIB.S9S_MB_2U(SCH_1):PAGE299

C1975 Q_CAP_0402-1000PF,50V,5%,EMPTYA
     1 GPU_HMC_PRSNT_ISO_N @S9S_MB_2U_LIB.S9S_MB_2U(SCH_1):GPU_HMC_PRSNT_ISO_N   I129 @S9S_MB_2U_LIB.S9S_MB_2U(SCH_1):PAGE299
     2    GND @S9S_MB_2U_LIB.S9S_MB_2U(SCH_1):GND   I129 @S9S_MB_2U_LIB.S9S_MB_2U(SCH_1):PAGE299

C1976 Q_CAP_0402-1000PF,50V,5%,EMPTYA
     1 GPU_FPGA_OVERT_ISO_N @S9S_MB_2U_LIB.S9S_MB_2U(SCH_1):GPU_FPGA_OVERT_ISO_N    I30 @S9S_MB_2U_LIB.S9S_MB_2U(SCH_1):PAGE299
     2    GND @S9S_MB_2U_LIB.S9S_MB_2U(SCH_1):GND    I30 @S9S_MB_2U_LIB.S9S_MB_2U(SCH_1):PAGE299

C1977 Q_CAP_0402-0.1UF,25V,10%,X7R,CA
     1 P3V3_AUX @S9S_MB_2U_LIB.S9S_MB_2U(SCH_1):P3V3_AUX   I175 @S9S_MB_2U_LIB.S9S_MB_2U(SCH_1):PAGE160
     2    GND @S9S_MB_2U_LIB.S9S_MB_2U(SCH_1):GND   I175 @S9S_MB_2U_LIB.S9S_MB_2U(SCH_1):PAGE160

C1978 Q_CAP_0402-1000PF,50V,5%,EMPTYA
     1 GPU_PRSNT_N_ISO @S9S_MB_2U_LIB.S9S_MB_2U(SCH_1):GPU_PRSNT_N_ISO   I152 @S9S_MB_2U_LIB.S9S_MB_2U(SCH_1):PAGE299
     2    GND @S9S_MB_2U_LIB.S9S_MB_2U(SCH_1):GND   I152 @S9S_MB_2U_LIB.S9S_MB_2U(SCH_1):PAGE299

C1979 Q_CAP_0402-0.1UF,25V,10%,X7R,CA
     1 P3V3_AUX @S9S_MB_2U_LIB.S9S_MB_2U(SCH_1):P3V3_AUX    I67 @S9S_MB_2U_LIB.S9S_MB_2U(SCH_1):PAGE296
     2    GND @S9S_MB_2U_LIB.S9S_MB_2U(SCH_1):GND    I67 @S9S_MB_2U_LIB.S9S_MB_2U(SCH_1):PAGE296

C1988 Q_CAP_0402-1000PF,50V,5%,EMPTYA
     1 GPU_FPGA_EROT_FATALERR_ISO_N @S9S_MB_2U_LIB.S9S_MB_2U(SCH_1):GPU_FPGA_EROT_FATALERR_ISO_N   I171 @S9S_MB_2U_LIB.S9S_MB_2U(SCH_1):PAGE299
     2    GND @S9S_MB_2U_LIB.S9S_MB_2U(SCH_1):GND   I171 @S9S_MB_2U_LIB.S9S_MB_2U(SCH_1):PAGE299

C1989 Q_CAP_DIFFBUS_C0201-DIFF BUS_0A
     1 P3E_PCH_E1S_TX_DP<3> @S9S_MB_2U_LIB.S9S_MB_2U(SCH_1):P3E_PCH_E1S_TX_DP(3)    I75 @S9S_MB_2U_LIB.S9S_MB_2U(SCH_1):PAGE173
     2 P3E_PCH_E1S_TX_C_DP<3> @S9S_MB_2U_LIB.S9S_MB_2U(SCH_1):P3E_PCH_E1S_TX_C_DP(3)    I75 @S9S_MB_2U_LIB.S9S_MB_2U(SCH_1):PAGE173

C1990 Q_CAP_DIFFBUS_C0201-DIFF BUS_0A
     1 P3E_PCH_E1S_TX_DN<3> @S9S_MB_2U_LIB.S9S_MB_2U(SCH_1):P3E_PCH_E1S_TX_DN(3)    I74 @S9S_MB_2U_LIB.S9S_MB_2U(SCH_1):PAGE173
     2 P3E_PCH_E1S_TX_C_DN<3> @S9S_MB_2U_LIB.S9S_MB_2U(SCH_1):P3E_PCH_E1S_TX_C_DN(3)    I74 @S9S_MB_2U_LIB.S9S_MB_2U(SCH_1):PAGE173

C1991 Q_CAP_DIFFBUS_C0201-DIFF BUS_0A
     1 P3E_PCH_E1S_TX_DP<2> @S9S_MB_2U_LIB.S9S_MB_2U(SCH_1):P3E_PCH_E1S_TX_DP(2)    I73 @S9S_MB_2U_LIB.S9S_MB_2U(SCH_1):PAGE173
     2 P3E_PCH_E1S_TX_C_DP<2> @S9S_MB_2U_LIB.S9S_MB_2U(SCH_1):P3E_PCH_E1S_TX_C_DP(2)    I73 @S9S_MB_2U_LIB.S9S_MB_2U(SCH_1):PAGE173

C1992 Q_CAP_DIFFBUS_C0201-DIFF BUS_0A
     1 P3E_PCH_E1S_TX_DN<2> @S9S_MB_2U_LIB.S9S_MB_2U(SCH_1):P3E_PCH_E1S_TX_DN(2)    I72 @S9S_MB_2U_LIB.S9S_MB_2U(SCH_1):PAGE173
     2 P3E_PCH_E1S_TX_C_DN<2> @S9S_MB_2U_LIB.S9S_MB_2U(SCH_1):P3E_PCH_E1S_TX_C_DN(2)    I72 @S9S_MB_2U_LIB.S9S_MB_2U(SCH_1):PAGE173

C1993 Q_CAP_DIFFBUS_C0201-DIFF BUS_0A
     1 P3E_PCH_E1S_TX_DP<1> @S9S_MB_2U_LIB.S9S_MB_2U(SCH_1):P3E_PCH_E1S_TX_DP(1)    I71 @S9S_MB_2U_LIB.S9S_MB_2U(SCH_1):PAGE173
     2 P3E_PCH_E1S_TX_C_DP<1> @S9S_MB_2U_LIB.S9S_MB_2U(SCH_1):P3E_PCH_E1S_TX_C_DP(1)    I71 @S9S_MB_2U_LIB.S9S_MB_2U(SCH_1):PAGE173

C1994 Q_CAP_DIFFBUS_C0201-DIFF BUS_0A
     1 P3E_PCH_E1S_TX_DN<1> @S9S_MB_2U_LIB.S9S_MB_2U(SCH_1):P3E_PCH_E1S_TX_DN(1)    I70 @S9S_MB_2U_LIB.S9S_MB_2U(SCH_1):PAGE173
     2 P3E_PCH_E1S_TX_C_DN<1> @S9S_MB_2U_LIB.S9S_MB_2U(SCH_1):P3E_PCH_E1S_TX_C_DN(1)    I70 @S9S_MB_2U_LIB.S9S_MB_2U(SCH_1):PAGE173

C1995 Q_CAP_DIFFBUS_C0201-DIFF BUS_0A
     1 P3E_PCH_E1S_TX_DP<0> @S9S_MB_2U_LIB.S9S_MB_2U(SCH_1):P3E_PCH_E1S_TX_DP(0)    I69 @S9S_MB_2U_LIB.S9S_MB_2U(SCH_1):PAGE173
     2 P3E_PCH_E1S_TX_C_DP<0> @S9S_MB_2U_LIB.S9S_MB_2U(SCH_1):P3E_PCH_E1S_TX_C_DP(0)    I69 @S9S_MB_2U_LIB.S9S_MB_2U(SCH_1):PAGE173

C1996 Q_CAP_DIFFBUS_C0201-DIFF BUS_0A
     1 P3E_PCH_E1S_TX_DN<0> @S9S_MB_2U_LIB.S9S_MB_2U(SCH_1):P3E_PCH_E1S_TX_DN(0)    I68 @S9S_MB_2U_LIB.S9S_MB_2U(SCH_1):PAGE173
     2 P3E_PCH_E1S_TX_C_DN<0> @S9S_MB_2U_LIB.S9S_MB_2U(SCH_1):P3E_PCH_E1S_TX_C_DN(0)    I68 @S9S_MB_2U_LIB.S9S_MB_2U(SCH_1):PAGE173

C1997 Q_CAP_0402-0.1UF,25V,10%,X7R,CA
     1 P3V3_AUX @S9S_MB_2U_LIB.S9S_MB_2U(SCH_1):P3V3_AUX    I89 @S9S_MB_2U_LIB.S9S_MB_2U(SCH_1):PAGE183
     2    GND @S9S_MB_2U_LIB.S9S_MB_2U(SCH_1):GND    I89 @S9S_MB_2U_LIB.S9S_MB_2U(SCH_1):PAGE183

C1998 Q_CAP_0402-0.1UF,25V,10%,X7R,CA
     1 P3V3_E1S_0 @S9S_MB_2U_LIB.S9S_MB_2U(SCH_1):P3V3_E1S_0    I82 @S9S_MB_2U_LIB.S9S_MB_2U(SCH_1):PAGE183
     2    GND @S9S_MB_2U_LIB.S9S_MB_2U(SCH_1):GND    I82 @S9S_MB_2U_LIB.S9S_MB_2U(SCH_1):PAGE183

C2007 Q_CAP_C0402-1UF,25V,10%,X6S,CHA
     1 P3V3_AUX @S9S_MB_2U_LIB.S9S_MB_2U(SCH_1):P3V3_AUX   I326 @S9S_MB_2U_LIB.S9S_MB_2U(SCH_1):PAGE182
     2    GND @S9S_MB_2U_LIB.S9S_MB_2U(SCH_1):GND   I326 @S9S_MB_2U_LIB.S9S_MB_2U(SCH_1):PAGE182

C2010 Q_CAP_0402-0.1UF,25V,10%,X7R,CA
     1 P3V3_AUX @S9S_MB_2U_LIB.S9S_MB_2U(SCH_1):P3V3_AUX    I16 @S9S_MB_2U_LIB.S9S_MB_2U(SCH_1):PAGE161
     2    GND @S9S_MB_2U_LIB.S9S_MB_2U(SCH_1):GND    I16 @S9S_MB_2U_LIB.S9S_MB_2U(SCH_1):PAGE161

C2012 Q_CAP_0402-0.1UF,25V,10%,X7R,CA
     1 P3V3_AUX @S9S_MB_2U_LIB.S9S_MB_2U(SCH_1):P3V3_AUX    I98 @S9S_MB_2U_LIB.S9S_MB_2U(SCH_1):PAGE163
     2    GND @S9S_MB_2U_LIB.S9S_MB_2U(SCH_1):GND    I98 @S9S_MB_2U_LIB.S9S_MB_2U(SCH_1):PAGE163

C2013 Q_CAP_0402-0.1UF,25V,10%,X7R,CA
     1 P3V3_AUX @S9S_MB_2U_LIB.S9S_MB_2U(SCH_1):P3V3_AUX    I42 @S9S_MB_2U_LIB.S9S_MB_2U(SCH_1):PAGE163
     2    GND @S9S_MB_2U_LIB.S9S_MB_2U(SCH_1):GND    I42 @S9S_MB_2U_LIB.S9S_MB_2U(SCH_1):PAGE163

C2014 Q_CAP_0402-0.1UF,25V,10%,X7R,CA
     1 P3V3_AUX @S9S_MB_2U_LIB.S9S_MB_2U(SCH_1):P3V3_AUX    I65 @S9S_MB_2U_LIB.S9S_MB_2U(SCH_1):PAGE163
     2    GND @S9S_MB_2U_LIB.S9S_MB_2U(SCH_1):GND    I65 @S9S_MB_2U_LIB.S9S_MB_2U(SCH_1):PAGE163

C2015 Q_CAP_0402-0.1UF,25V,10%,X7R,CA
     1 P3V3_AUX @S9S_MB_2U_LIB.S9S_MB_2U(SCH_1):P3V3_AUX    I34 @S9S_MB_2U_LIB.S9S_MB_2U(SCH_1):PAGE295
     2    GND @S9S_MB_2U_LIB.S9S_MB_2U(SCH_1):GND    I34 @S9S_MB_2U_LIB.S9S_MB_2U(SCH_1):PAGE295

C2017 Q_CAP_0402-0.1UF,25V,10%,X7R,CA
     1 P3V3_OCP_V3_2_R @S9S_MB_2U_LIB.S9S_MB_2U(SCH_1):P3V3_OCP_V3_2_R   I114 @S9S_MB_2U_LIB.S9S_MB_2U(SCH_1):PAGE163
     2    GND @S9S_MB_2U_LIB.S9S_MB_2U(SCH_1):GND   I114 @S9S_MB_2U_LIB.S9S_MB_2U(SCH_1):PAGE163

C2018 Q_CAP_0402-0.1UF,25V,10%,X7R,CA
     1   P3V3 @S9S_MB_2U_LIB.S9S_MB_2U(SCH_1):P3V3    I26 @S9S_MB_2U_LIB.S9S_MB_2U(SCH_1):PAGE163
     2    GND @S9S_MB_2U_LIB.S9S_MB_2U(SCH_1):GND    I26 @S9S_MB_2U_LIB.S9S_MB_2U(SCH_1):PAGE163

C2019 Q_CAP_0402-0.1UF,25V,10%,X7R,CA
     1 P12V_SCM_R @S9S_MB_2U_LIB.S9S_MB_2U(SCH_1):P12V_SCM_R    I49 @S9S_MB_2U_LIB.S9S_MB_2U(SCH_1):PAGE163
     2    GND @S9S_MB_2U_LIB.S9S_MB_2U(SCH_1):GND    I49 @S9S_MB_2U_LIB.S9S_MB_2U(SCH_1):PAGE163

C2020 Q_CAP_0402-0.1UF,25V,10%,X7R,CA
     1 VSENSE_P12V_INA230_3_INP @S9S_MB_2U_LIB.S9S_MB_2U(SCH_1):VSENSE_P12V_INA230_3_INP   I108 @S9S_MB_2U_LIB.S9S_MB_2U(SCH_1):PAGE163
     2 VSENSE_P12V_INA230_3_INN @S9S_MB_2U_LIB.S9S_MB_2U(SCH_1):VSENSE_P12V_INA230_3_INN   I108 @S9S_MB_2U_LIB.S9S_MB_2U(SCH_1):PAGE163

C2021 Q_CAP_0402-0.1UF,25V,10%,X7R,CA
     1 VSENSE_P12V_INA230_4_INP @S9S_MB_2U_LIB.S9S_MB_2U(SCH_1):VSENSE_P12V_INA230_4_INP    I71 @S9S_MB_2U_LIB.S9S_MB_2U(SCH_1):PAGE163
     2 VSENSE_P12V_INA230_4_INN @S9S_MB_2U_LIB.S9S_MB_2U(SCH_1):VSENSE_P12V_INA230_4_INN    I71 @S9S_MB_2U_LIB.S9S_MB_2U(SCH_1):PAGE163

C2022 Q_CAP_0402-0.1UF,25V,10%,X7R,CA
     1 VSENSE_P12V_INA230_5_INP @S9S_MB_2U_LIB.S9S_MB_2U(SCH_1):VSENSE_P12V_INA230_5_INP    I72 @S9S_MB_2U_LIB.S9S_MB_2U(SCH_1):PAGE163
     2 VSENSE_P12V_INA230_5_INN @S9S_MB_2U_LIB.S9S_MB_2U(SCH_1):VSENSE_P12V_INA230_5_INN    I72 @S9S_MB_2U_LIB.S9S_MB_2U(SCH_1):PAGE163

C2024 Q_CAP_0402-0.1UF,25V,10%,X7R,CA
     1 P3V3_OCP_SFF_R @S9S_MB_2U_LIB.S9S_MB_2U(SCH_1):P3V3_OCP_SFF_R    I50 @S9S_MB_2U_LIB.S9S_MB_2U(SCH_1):PAGE295
     2    GND @S9S_MB_2U_LIB.S9S_MB_2U(SCH_1):GND    I50 @S9S_MB_2U_LIB.S9S_MB_2U(SCH_1):PAGE295

C2027 Q_CAP_0402-0.1UF,25V,10%,X7R,CA
     1 VSENSE_P3V3_INA230_1_INP @S9S_MB_2U_LIB.S9S_MB_2U(SCH_1):VSENSE_P3V3_INA230_1_INP    I77 @S9S_MB_2U_LIB.S9S_MB_2U(SCH_1):PAGE295
     2 VSENSE_P3V3_INA230_1_INN @S9S_MB_2U_LIB.S9S_MB_2U(SCH_1):VSENSE_P3V3_INA230_1_INN    I77 @S9S_MB_2U_LIB.S9S_MB_2U(SCH_1):PAGE295

C2029 Q_CAP_0402-18PF,50V,5%,C0G,CH0A
     1 USB_HUB_XTAL_IN @S9S_MB_2U_LIB.S9S_MB_2U(SCH_1):USB_HUB_XTAL_IN   I210 @S9S_MB_2U_LIB.S9S_MB_2U(SCH_1):PAGE155
     2    GND @S9S_MB_2U_LIB.S9S_MB_2U(SCH_1):GND   I210 @S9S_MB_2U_LIB.S9S_MB_2U(SCH_1):PAGE155

C2030 Q_CAP_0402-18PF,50V,5%,C0G,CH0A
     1 USB_HUB_XTAL_OUT @S9S_MB_2U_LIB.S9S_MB_2U(SCH_1):USB_HUB_XTAL_OUT   I211 @S9S_MB_2U_LIB.S9S_MB_2U(SCH_1):PAGE155
     2    GND @S9S_MB_2U_LIB.S9S_MB_2U(SCH_1):GND   I211 @S9S_MB_2U_LIB.S9S_MB_2U(SCH_1):PAGE155

C2031 Q_CAP_C0402-1UF,25V,10%,X6S,CHA
     1 P3V3_AUX_USB_HUB @S9S_MB_2U_LIB.S9S_MB_2U(SCH_1):P3V3_AUX_USB_HUB   I148 @S9S_MB_2U_LIB.S9S_MB_2U(SCH_1):PAGE155
     2    GND @S9S_MB_2U_LIB.S9S_MB_2U(SCH_1):GND   I148 @S9S_MB_2U_LIB.S9S_MB_2U(SCH_1):PAGE155

C2032 Q_CAP_0402-0.1UF,25V,10%,X7R,CA
     1 P3V3_AUX_USB_HUB @S9S_MB_2U_LIB.S9S_MB_2U(SCH_1):P3V3_AUX_USB_HUB   I145 @S9S_MB_2U_LIB.S9S_MB_2U(SCH_1):PAGE155
     2    GND @S9S_MB_2U_LIB.S9S_MB_2U(SCH_1):GND   I145 @S9S_MB_2U_LIB.S9S_MB_2U(SCH_1):PAGE155

C2033 Q_CAP_0402-0.1UF,25V,10%,X7R,CA
     1 P3V3_AUX_USB_HUB @S9S_MB_2U_LIB.S9S_MB_2U(SCH_1):P3V3_AUX_USB_HUB   I143 @S9S_MB_2U_LIB.S9S_MB_2U(SCH_1):PAGE155
     2    GND @S9S_MB_2U_LIB.S9S_MB_2U(SCH_1):GND   I143 @S9S_MB_2U_LIB.S9S_MB_2U(SCH_1):PAGE155

C2034 Q_CAP_0402-0.1UF,25V,10%,X7R,CA
     1 P3V3_AUX_USB_HUB @S9S_MB_2U_LIB.S9S_MB_2U(SCH_1):P3V3_AUX_USB_HUB   I142 @S9S_MB_2U_LIB.S9S_MB_2U(SCH_1):PAGE155
     2    GND @S9S_MB_2U_LIB.S9S_MB_2U(SCH_1):GND   I142 @S9S_MB_2U_LIB.S9S_MB_2U(SCH_1):PAGE155

C2035 Q_CAP_C0402-1UF,25V,10%,X6S,CHA
     1 P3V3_AUX_USB_HUB @S9S_MB_2U_LIB.S9S_MB_2U(SCH_1):P3V3_AUX_USB_HUB   I147 @S9S_MB_2U_LIB.S9S_MB_2U(SCH_1):PAGE155
     2    GND @S9S_MB_2U_LIB.S9S_MB_2U(SCH_1):GND   I147 @S9S_MB_2U_LIB.S9S_MB_2U(SCH_1):PAGE155

C2036 Q_CAP_C0402-8.2PF,50V,0.1P,NP0A
     1 XTAL_CLK_GEN1_25M_X1_R @S9S_MB_2U_LIB.S9S_MB_2U(SCH_1):XTAL_CLK_GEN1_25M_X1_R   I393 @S9S_MB_2U_LIB.S9S_MB_2U(SCH_1):PAGE197
     2    GND @S9S_MB_2U_LIB.S9S_MB_2U(SCH_1):GND   I393 @S9S_MB_2U_LIB.S9S_MB_2U(SCH_1):PAGE197

C2037 Q_CAP_C0402-8.2PF,50V,0.1P,NP0A
     1 XTAL_CLK_GEN1_25M_X2 @S9S_MB_2U_LIB.S9S_MB_2U(SCH_1):XTAL_CLK_GEN1_25M_X2   I394 @S9S_MB_2U_LIB.S9S_MB_2U(SCH_1):PAGE197
     2    GND @S9S_MB_2U_LIB.S9S_MB_2U(SCH_1):GND   I394 @S9S_MB_2U_LIB.S9S_MB_2U(SCH_1):PAGE197

C2038 Q_CAP_C0402-10UF,6.3V,20%,X6S,A
     1 P3V3_AUX_USB_HUB @S9S_MB_2U_LIB.S9S_MB_2U(SCH_1):P3V3_AUX_USB_HUB   I164 @S9S_MB_2U_LIB.S9S_MB_2U(SCH_1):PAGE155
     2    GND @S9S_MB_2U_LIB.S9S_MB_2U(SCH_1):GND   I164 @S9S_MB_2U_LIB.S9S_MB_2U(SCH_1):PAGE155

C2039 Q_CAP_0402-0.1UF,25V,10%,X7R,CA
     1 P3V3_AUX_USB_HUB @S9S_MB_2U_LIB.S9S_MB_2U(SCH_1):P3V3_AUX_USB_HUB   I163 @S9S_MB_2U_LIB.S9S_MB_2U(SCH_1):PAGE155
     2    GND @S9S_MB_2U_LIB.S9S_MB_2U(SCH_1):GND   I163 @S9S_MB_2U_LIB.S9S_MB_2U(SCH_1):PAGE155

C2040 Q_CAP_0402-0.1UF,25V,10%,X7R,CA
     1 P3V3_AUX_USB_HUB @S9S_MB_2U_LIB.S9S_MB_2U(SCH_1):P3V3_AUX_USB_HUB   I162 @S9S_MB_2U_LIB.S9S_MB_2U(SCH_1):PAGE155
     2    GND @S9S_MB_2U_LIB.S9S_MB_2U(SCH_1):GND   I162 @S9S_MB_2U_LIB.S9S_MB_2U(SCH_1):PAGE155

C2041 Q_CAP_C0402-1UF,25V,10%,X6S,CHA
     1 RST_USB_HUB_R_N @S9S_MB_2U_LIB.S9S_MB_2U(SCH_1):RST_USB_HUB_R_N   I158 @S9S_MB_2U_LIB.S9S_MB_2U(SCH_1):PAGE155
     2    GND @S9S_MB_2U_LIB.S9S_MB_2U(SCH_1):GND   I158 @S9S_MB_2U_LIB.S9S_MB_2U(SCH_1):PAGE155

C2042 Q_CAP_0402-100PF,50V,5%,EMPTY,A
     1 P3V3_AUX_ADC_MAM @S9S_MB_2U_LIB.S9S_MB_2U(SCH_1):P3V3_AUX_ADC_MAM   I180 @S9S_MB_2U_LIB.S9S_MB_2U(SCH_1):PAGE239
     2    GND @S9S_MB_2U_LIB.S9S_MB_2U(SCH_1):GND   I180 @S9S_MB_2U_LIB.S9S_MB_2U(SCH_1):PAGE239

C2043 Q_CAP_0402-100PF,50V,5%,EMPTY,A
     1 P3V3_ADC_MAM @S9S_MB_2U_LIB.S9S_MB_2U(SCH_1):P3V3_ADC_MAM   I196 @S9S_MB_2U_LIB.S9S_MB_2U(SCH_1):PAGE239
     2    GND @S9S_MB_2U_LIB.S9S_MB_2U(SCH_1):GND   I196 @S9S_MB_2U_LIB.S9S_MB_2U(SCH_1):PAGE239

C2044 Q_CAP_0402-100PF,50V,5%,EMPTY,A
     1 P5V_ADC_MAM @S9S_MB_2U_LIB.S9S_MB_2U(SCH_1):P5V_ADC_MAM   I187 @S9S_MB_2U_LIB.S9S_MB_2U(SCH_1):PAGE239
     2    GND @S9S_MB_2U_LIB.S9S_MB_2U(SCH_1):GND   I187 @S9S_MB_2U_LIB.S9S_MB_2U(SCH_1):PAGE239

C2045 Q_CAP_0402-100PF,50V,5%,EMPTY,A
     1 P3V3_PDB_AUX_ADC_MAM @S9S_MB_2U_LIB.S9S_MB_2U(SCH_1):P3V3_PDB_AUX_ADC_MAM   I236 @S9S_MB_2U_LIB.S9S_MB_2U(SCH_1):PAGE239
     2    GND @S9S_MB_2U_LIB.S9S_MB_2U(SCH_1):GND   I236 @S9S_MB_2U_LIB.S9S_MB_2U(SCH_1):PAGE239

C2046 Q_CAP_0402-0.1UF,25V,10%,X7R,CA
     1 P12V_AUX_ADC_TIC @S9S_MB_2U_LIB.S9S_MB_2U(SCH_1):P12V_AUX_ADC_TIC   I207 @S9S_MB_2U_LIB.S9S_MB_2U(SCH_1):PAGE239
     2    GND @S9S_MB_2U_LIB.S9S_MB_2U(SCH_1):GND   I207 @S9S_MB_2U_LIB.S9S_MB_2U(SCH_1):PAGE239

C2047 Q_CAP_0402-0.1UF,25V,10%,X7R,CA
     1 P3V3_AUX_ADC_TIC @S9S_MB_2U_LIB.S9S_MB_2U(SCH_1):P3V3_AUX_ADC_TIC   I181 @S9S_MB_2U_LIB.S9S_MB_2U(SCH_1):PAGE239
     2    GND @S9S_MB_2U_LIB.S9S_MB_2U(SCH_1):GND   I181 @S9S_MB_2U_LIB.S9S_MB_2U(SCH_1):PAGE239

C2048 Q_CAP_0402-0.1UF,25V,10%,X7R,CA
     1 P3V3_ADC_TIC @S9S_MB_2U_LIB.S9S_MB_2U(SCH_1):P3V3_ADC_TIC   I197 @S9S_MB_2U_LIB.S9S_MB_2U(SCH_1):PAGE239
     2    GND @S9S_MB_2U_LIB.S9S_MB_2U(SCH_1):GND   I197 @S9S_MB_2U_LIB.S9S_MB_2U(SCH_1):PAGE239

C2049 Q_CAP_0402-0.1UF,25V,10%,X7R,CA
     1 P5V_ADC_TIC @S9S_MB_2U_LIB.S9S_MB_2U(SCH_1):P5V_ADC_TIC   I188 @S9S_MB_2U_LIB.S9S_MB_2U(SCH_1):PAGE239
     2    GND @S9S_MB_2U_LIB.S9S_MB_2U(SCH_1):GND   I188 @S9S_MB_2U_LIB.S9S_MB_2U(SCH_1):PAGE239

C2050 Q_CAP_0402-0.1UF,25V,10%,X7R,CA
     1 P3V3_PDB_AUX_ADC_TIC @S9S_MB_2U_LIB.S9S_MB_2U(SCH_1):P3V3_PDB_AUX_ADC_TIC   I238 @S9S_MB_2U_LIB.S9S_MB_2U(SCH_1):PAGE239
     2    GND @S9S_MB_2U_LIB.S9S_MB_2U(SCH_1):GND   I238 @S9S_MB_2U_LIB.S9S_MB_2U(SCH_1):PAGE239

C2051 Q_CAP_0402-0.1UF,25V,10%,X7R,CA
     1 P3V3_ADC128_VCC @S9S_MB_2U_LIB.S9S_MB_2U(SCH_1):P3V3_ADC128_VCC   I127 @S9S_MB_2U_LIB.S9S_MB_2U(SCH_1):PAGE239
     2    GND @S9S_MB_2U_LIB.S9S_MB_2U(SCH_1):GND   I127 @S9S_MB_2U_LIB.S9S_MB_2U(SCH_1):PAGE239

C2052 Q_CAP_0402-0.1UF,25V,10%,X7R,CA
     1 P3V3_ADC128_VCC @S9S_MB_2U_LIB.S9S_MB_2U(SCH_1):P3V3_ADC128_VCC   I128 @S9S_MB_2U_LIB.S9S_MB_2U(SCH_1):PAGE239
     2    GND @S9S_MB_2U_LIB.S9S_MB_2U(SCH_1):GND   I128 @S9S_MB_2U_LIB.S9S_MB_2U(SCH_1):PAGE239

C2056 Q_CAP_0402-0.1UF,25V,10%,X7R,CA
     1 P3V3_AUX @S9S_MB_2U_LIB.S9S_MB_2U(SCH_1):P3V3_AUX   I106 @S9S_MB_2U_LIB.S9S_MB_2U(SCH_1):PAGE221
     2    GND @S9S_MB_2U_LIB.S9S_MB_2U(SCH_1):GND   I106 @S9S_MB_2U_LIB.S9S_MB_2U(SCH_1):PAGE221

C2067 Q_CAP_0402-0.1UF,25V,10%,X7R,CA
     1 P3V3_AUX @S9S_MB_2U_LIB.S9S_MB_2U(SCH_1):P3V3_AUX   I125 @S9S_MB_2U_LIB.S9S_MB_2U(SCH_1):PAGE295
     2    GND @S9S_MB_2U_LIB.S9S_MB_2U(SCH_1):GND   I125 @S9S_MB_2U_LIB.S9S_MB_2U(SCH_1):PAGE295

C2069 Q_CAP_0402-0.1UF,25V,10%,X7R,CA
     1 P3V3_E1S_0_R @S9S_MB_2U_LIB.S9S_MB_2U(SCH_1):P3V3_E1S_0_R   I142 @S9S_MB_2U_LIB.S9S_MB_2U(SCH_1):PAGE295
     2    GND @S9S_MB_2U_LIB.S9S_MB_2U(SCH_1):GND   I142 @S9S_MB_2U_LIB.S9S_MB_2U(SCH_1):PAGE295

C2071 Q_CAP_0402-0.1UF,25V,10%,X7R,CA
     1 VSENSE_P3V3_INA230_2_INP @S9S_MB_2U_LIB.S9S_MB_2U(SCH_1):VSENSE_P3V3_INA230_2_INP   I133 @S9S_MB_2U_LIB.S9S_MB_2U(SCH_1):PAGE295
     2 VSENSE_P3V3_INA230_2_INN @S9S_MB_2U_LIB.S9S_MB_2U(SCH_1):VSENSE_P3V3_INA230_2_INN   I133 @S9S_MB_2U_LIB.S9S_MB_2U(SCH_1):PAGE295

C2073 Q_CAP_DIFFBUS_C0201-DIFF BUS_0A
     1 P3E_PCH_NVS_TX_DP<1> @S9S_MB_2U_LIB.S9S_MB_2U(SCH_1):P3E_PCH_NVS_TX_DP(1)    I83 @S9S_MB_2U_LIB.S9S_MB_2U(SCH_1):PAGE173
     2 P3E_PCH_NVS_TX_C_DP<1> @S9S_MB_2U_LIB.S9S_MB_2U(SCH_1):P3E_PCH_NVS_TX_C_DP(1)    I83 @S9S_MB_2U_LIB.S9S_MB_2U(SCH_1):PAGE173

C2074 Q_CAP_DIFFBUS_C0201-DIFF BUS_0A
     1 P3E_PCH_NVS_TX_DN<1> @S9S_MB_2U_LIB.S9S_MB_2U(SCH_1):P3E_PCH_NVS_TX_DN(1)    I82 @S9S_MB_2U_LIB.S9S_MB_2U(SCH_1):PAGE173
     2 P3E_PCH_NVS_TX_C_DN<1> @S9S_MB_2U_LIB.S9S_MB_2U(SCH_1):P3E_PCH_NVS_TX_C_DN(1)    I82 @S9S_MB_2U_LIB.S9S_MB_2U(SCH_1):PAGE173

C2075 Q_CAP_DIFFBUS_C0201-DIFF BUS_0A
     1 P3E_PCH_NVS_TX_DP<0> @S9S_MB_2U_LIB.S9S_MB_2U(SCH_1):P3E_PCH_NVS_TX_DP(0)    I81 @S9S_MB_2U_LIB.S9S_MB_2U(SCH_1):PAGE173
     2 P3E_PCH_NVS_TX_C_DP<0> @S9S_MB_2U_LIB.S9S_MB_2U(SCH_1):P3E_PCH_NVS_TX_C_DP(0)    I81 @S9S_MB_2U_LIB.S9S_MB_2U(SCH_1):PAGE173

C2076 Q_CAP_DIFFBUS_C0201-DIFF BUS_0A
     1 P3E_PCH_NVS_TX_DN<0> @S9S_MB_2U_LIB.S9S_MB_2U(SCH_1):P3E_PCH_NVS_TX_DN(0)    I79 @S9S_MB_2U_LIB.S9S_MB_2U(SCH_1):PAGE173
     2 P3E_PCH_NVS_TX_C_DN<0> @S9S_MB_2U_LIB.S9S_MB_2U(SCH_1):P3E_PCH_NVS_TX_C_DN(0)    I79 @S9S_MB_2U_LIB.S9S_MB_2U(SCH_1):PAGE173

C2077 Q_CAP_DIFFBUS_C0201-DIFF BUS_0A
     1 P3E_PCH_BMC_TX_DP @S9S_MB_2U_LIB.S9S_MB_2U(SCH_1):P3E_PCH_BMC_TX_DP    I77 @S9S_MB_2U_LIB.S9S_MB_2U(SCH_1):PAGE173
     2 P3E_PCH_BMC_TX_C_DP @S9S_MB_2U_LIB.S9S_MB_2U(SCH_1):P3E_PCH_BMC_TX_C_DP    I77 @S9S_MB_2U_LIB.S9S_MB_2U(SCH_1):PAGE173

C2078 Q_CAP_DIFFBUS_C0201-DIFF BUS_0A
     1 P3E_PCH_BMC_TX_DN @S9S_MB_2U_LIB.S9S_MB_2U(SCH_1):P3E_PCH_BMC_TX_DN    I76 @S9S_MB_2U_LIB.S9S_MB_2U(SCH_1):PAGE173
     2 P3E_PCH_BMC_TX_C_DN @S9S_MB_2U_LIB.S9S_MB_2U(SCH_1):P3E_PCH_BMC_TX_C_DN    I76 @S9S_MB_2U_LIB.S9S_MB_2U(SCH_1):PAGE173

C2148 Q_CAP_C0402-0.01UF,50V,10%,EMPA
     1 P12V_OCP_V3_2 @S9S_MB_2U_LIB.S9S_MB_2U(SCH_1):P12V_OCP_V3_2    I73 @S9S_MB_2U_LIB.S9S_MB_2U(SCH_1):PAGE131
     2 P12V_OCP_GATE_2 @S9S_MB_2U_LIB.S9S_MB_2U(SCH_1):P12V_OCP_GATE_2    I73 @S9S_MB_2U_LIB.S9S_MB_2U(SCH_1):PAGE131

C2175 Q_CAP_0402-100PF,50V,5%,EMPTY,A
     1 P12V_OCP_V3_2_ISENSE_MAM @S9S_MB_2U_LIB.S9S_MB_2U(SCH_1):P12V_OCP_V3_2_ISENSE_MAM   I309 @S9S_MB_2U_LIB.S9S_MB_2U(SCH_1):PAGE239
     2    GND @S9S_MB_2U_LIB.S9S_MB_2U(SCH_1):GND   I309 @S9S_MB_2U_LIB.S9S_MB_2U(SCH_1):PAGE239

C2176 Q_CAP_0402-100PF,50V,5%,EMPTY,A
     1 P12V_OCP_SFF_ISENSE_MAM @S9S_MB_2U_LIB.S9S_MB_2U(SCH_1):P12V_OCP_SFF_ISENSE_MAM   I304 @S9S_MB_2U_LIB.S9S_MB_2U(SCH_1):PAGE239
     2    GND @S9S_MB_2U_LIB.S9S_MB_2U(SCH_1):GND   I304 @S9S_MB_2U_LIB.S9S_MB_2U(SCH_1):PAGE239

C2177 Q_CAP_0402-0.1UF,25V,10%,X7R,CA
     1 P12V_OCP_V3_2_ISENSE_TIC @S9S_MB_2U_LIB.S9S_MB_2U(SCH_1):P12V_OCP_V3_2_ISENSE_TIC   I311 @S9S_MB_2U_LIB.S9S_MB_2U(SCH_1):PAGE239
     2    GND @S9S_MB_2U_LIB.S9S_MB_2U(SCH_1):GND   I311 @S9S_MB_2U_LIB.S9S_MB_2U(SCH_1):PAGE239

C2178 Q_CAP_0402-0.1UF,25V,10%,X7R,CA
     1 P12V_OCP_SFF_ISENSE_TIC @S9S_MB_2U_LIB.S9S_MB_2U(SCH_1):P12V_OCP_SFF_ISENSE_TIC   I305 @S9S_MB_2U_LIB.S9S_MB_2U(SCH_1):PAGE239
     2    GND @S9S_MB_2U_LIB.S9S_MB_2U(SCH_1):GND   I305 @S9S_MB_2U_LIB.S9S_MB_2U(SCH_1):PAGE239

C2179 Q_CAP_C0402-100NF,50V,10%,X7R,A
     1 HSC_EN @S9S_MB_2U_LIB.S9S_MB_2U(SCH_1):HSC_EN    I29 @S9S_MB_2U_LIB.S9S_MB_2U(SCH_1):PAGE303
     2 AGND_HSC @S9S_MB_2U_LIB.S9S_MB_2U(SCH_1):AGND_HSC    I29 @S9S_MB_2U_LIB.S9S_MB_2U(SCH_1):PAGE303

C2194 Q_CAP_0402-0.1UF,25V,10%,X7R,CA
     1 P12V_E1S_0_ISENSE_TIC @S9S_MB_2U_LIB.S9S_MB_2U(SCH_1):P12V_E1S_0_ISENSE_TIC   I336 @S9S_MB_2U_LIB.S9S_MB_2U(SCH_1):PAGE239
     2    GND @S9S_MB_2U_LIB.S9S_MB_2U(SCH_1):GND   I336 @S9S_MB_2U_LIB.S9S_MB_2U(SCH_1):PAGE239

C2195 Q_CAP_0402-100PF,50V,5%,EMPTY,A
     1 P12V_E1S_0_ISENSE_MAM @S9S_MB_2U_LIB.S9S_MB_2U(SCH_1):P12V_E1S_0_ISENSE_MAM   I333 @S9S_MB_2U_LIB.S9S_MB_2U(SCH_1):PAGE239
     2    GND @S9S_MB_2U_LIB.S9S_MB_2U(SCH_1):GND   I333 @S9S_MB_2U_LIB.S9S_MB_2U(SCH_1):PAGE239

C2243 Q_CAP_C0402-1UF,25V,10%,X6S,CHA
     1   P3V3 @S9S_MB_2U_LIB.S9S_MB_2U(SCH_1):P3V3    I85 @S9S_MB_2U_LIB.S9S_MB_2U(SCH_1):PAGE321
     2    GND @S9S_MB_2U_LIB.S9S_MB_2U(SCH_1):GND    I85 @S9S_MB_2U_LIB.S9S_MB_2U(SCH_1):PAGE321

C2246 Q_CAP_C0402-1UF,25V,10%,X6S,CHA
     1 P3V3_AUX @S9S_MB_2U_LIB.S9S_MB_2U(SCH_1):P3V3_AUX     I9 @S9S_MB_2U_LIB.S9S_MB_2U(SCH_1):PAGE322
     2    GND @S9S_MB_2U_LIB.S9S_MB_2U(SCH_1):GND     I9 @S9S_MB_2U_LIB.S9S_MB_2U(SCH_1):PAGE322

C2247 Q_CAP_C0402-1UF,25V,10%,X6S,CHA
     1 P3V3_AUX @S9S_MB_2U_LIB.S9S_MB_2U(SCH_1):P3V3_AUX    I59 @S9S_MB_2U_LIB.S9S_MB_2U(SCH_1):PAGE322
     2    GND @S9S_MB_2U_LIB.S9S_MB_2U(SCH_1):GND    I59 @S9S_MB_2U_LIB.S9S_MB_2U(SCH_1):PAGE322

C2248 Q_CAP_C0402-1UF,25V,10%,X6S,CHA
     1   P3V3 @S9S_MB_2U_LIB.S9S_MB_2U(SCH_1):P3V3    I83 @S9S_MB_2U_LIB.S9S_MB_2U(SCH_1):PAGE322
     2    GND @S9S_MB_2U_LIB.S9S_MB_2U(SCH_1):GND    I83 @S9S_MB_2U_LIB.S9S_MB_2U(SCH_1):PAGE322

C2249 Q_CAP_0402-0.1UF,25V,10%,X7R,CA
     1 P0V62_CPU0_ERRS_VREF @S9S_MB_2U_LIB.S9S_MB_2U(SCH_1):P0V62_CPU0_ERRS_VREF    I83 @S9S_MB_2U_LIB.S9S_MB_2U(SCH_1):PAGE321
     2    GND @S9S_MB_2U_LIB.S9S_MB_2U(SCH_1):GND    I83 @S9S_MB_2U_LIB.S9S_MB_2U(SCH_1):PAGE321

C2252 Q_CAP_0402-0.1UF,25V,10%,X7R,CA
     1 P0V62_CPU0_RST_DDR_VREF @S9S_MB_2U_LIB.S9S_MB_2U(SCH_1):P0V62_CPU0_RST_DDR_VREF   I101 @S9S_MB_2U_LIB.S9S_MB_2U(SCH_1):PAGE322
     2    GND @S9S_MB_2U_LIB.S9S_MB_2U(SCH_1):GND   I101 @S9S_MB_2U_LIB.S9S_MB_2U(SCH_1):PAGE322

C2253 Q_CAP_0402-0.1UF,25V,10%,X7R,CA
     1 P0V62_CPU1_RST_DDR_VREF @S9S_MB_2U_LIB.S9S_MB_2U(SCH_1):P0V62_CPU1_RST_DDR_VREF   I106 @S9S_MB_2U_LIB.S9S_MB_2U(SCH_1):PAGE322
     2    GND @S9S_MB_2U_LIB.S9S_MB_2U(SCH_1):GND   I106 @S9S_MB_2U_LIB.S9S_MB_2U(SCH_1):PAGE322

C2254 Q_CAP_0402-0.1UF,25V,10%,X7R,CA
     1 P0V62_CPU0_ERRS_U306_VREF @S9S_MB_2U_LIB.S9S_MB_2U(SCH_1):P0V62_CPU0_ERRS_U306_VREF   I111 @S9S_MB_2U_LIB.S9S_MB_2U(SCH_1):PAGE322
     2    GND @S9S_MB_2U_LIB.S9S_MB_2U(SCH_1):GND   I111 @S9S_MB_2U_LIB.S9S_MB_2U(SCH_1):PAGE322

C2255 Q_CAP_C0402-8.2PF,50V,0.1P,NP0A
     1 CLK_GEN2_XTAL_IN_R @S9S_MB_2U_LIB.S9S_MB_2U(SCH_1):CLK_GEN2_XTAL_IN_R   I165 @S9S_MB_2U_LIB.S9S_MB_2U(SCH_1):PAGE201
     2    GND @S9S_MB_2U_LIB.S9S_MB_2U(SCH_1):GND   I165 @S9S_MB_2U_LIB.S9S_MB_2U(SCH_1):PAGE201

C2256 Q_CAP_C0402-8.2PF,50V,0.1P,NP0A
     1 CLK_GEN2_XTAL_OUT @S9S_MB_2U_LIB.S9S_MB_2U(SCH_1):CLK_GEN2_XTAL_OUT   I166 @S9S_MB_2U_LIB.S9S_MB_2U(SCH_1):PAGE201
     2    GND @S9S_MB_2U_LIB.S9S_MB_2U(SCH_1):GND   I166 @S9S_MB_2U_LIB.S9S_MB_2U(SCH_1):PAGE201

C2257 Q_CAP_0402-0.1UF,25V,10%,X7R,CA
     1 VFG3P3_CLK_GEN @S9S_MB_2U_LIB.S9S_MB_2U(SCH_1):VFG3P3_CLK_GEN   I104 @S9S_MB_2U_LIB.S9S_MB_2U(SCH_1):PAGE201
     2    GND @S9S_MB_2U_LIB.S9S_MB_2U(SCH_1):GND   I104 @S9S_MB_2U_LIB.S9S_MB_2U(SCH_1):PAGE201

C2258 Q_CAP_0402-0.1UF,25V,10%,X7R,CA
     1 VFG3P3_CLK_GEN @S9S_MB_2U_LIB.S9S_MB_2U(SCH_1):VFG3P3_CLK_GEN   I105 @S9S_MB_2U_LIB.S9S_MB_2U(SCH_1):PAGE201
     2    GND @S9S_MB_2U_LIB.S9S_MB_2U(SCH_1):GND   I105 @S9S_MB_2U_LIB.S9S_MB_2U(SCH_1):PAGE201

C2259 Q_CAP_0402-0.1UF,25V,10%,X7R,CA
     1 VFG_3P3A_CLK_GEN @S9S_MB_2U_LIB.S9S_MB_2U(SCH_1):VFG_3P3A_CLK_GEN   I106 @S9S_MB_2U_LIB.S9S_MB_2U(SCH_1):PAGE201
     2    GND @S9S_MB_2U_LIB.S9S_MB_2U(SCH_1):GND   I106 @S9S_MB_2U_LIB.S9S_MB_2U(SCH_1):PAGE201

C2264 Q_CAP_0402-1000PF,50V,5%,EMPTYA
     1 GPU_3V3IO_RSVD0_FFU_ISO @S9S_MB_2U_LIB.S9S_MB_2U(SCH_1):GPU_3V3IO_RSVD0_FFU_ISO     I2 @S9S_MB_2U_LIB.S9S_MB_2U(SCH_1):PAGE143
     2    GND @S9S_MB_2U_LIB.S9S_MB_2U(SCH_1):GND     I2 @S9S_MB_2U_LIB.S9S_MB_2U(SCH_1):PAGE143

C2265 Q_CAP_0402-1000PF,50V,5%,EMPTYA
     1 PRSNT_CABLE_GPU_B3_ISO_N @S9S_MB_2U_LIB.S9S_MB_2U(SCH_1):PRSNT_CABLE_GPU_B3_ISO_N    I40 @S9S_MB_2U_LIB.S9S_MB_2U(SCH_1):PAGE143
     2    GND @S9S_MB_2U_LIB.S9S_MB_2U(SCH_1):GND    I40 @S9S_MB_2U_LIB.S9S_MB_2U(SCH_1):PAGE143

C2266 Q_CAP_0402-1000PF,50V,5%,EMPTYA
     1 GPU_3V3IO_RSVD1_FFU_ISO @S9S_MB_2U_LIB.S9S_MB_2U(SCH_1):GPU_3V3IO_RSVD1_FFU_ISO    I23 @S9S_MB_2U_LIB.S9S_MB_2U(SCH_1):PAGE143
     2    GND @S9S_MB_2U_LIB.S9S_MB_2U(SCH_1):GND    I23 @S9S_MB_2U_LIB.S9S_MB_2U(SCH_1):PAGE143

C2267 Q_CAP_0402-1000PF,50V,5%,EMPTYA
     1 GPU_3V3IO_RSVD3_FFU_ISO @S9S_MB_2U_LIB.S9S_MB_2U(SCH_1):GPU_3V3IO_RSVD3_FFU_ISO    I55 @S9S_MB_2U_LIB.S9S_MB_2U(SCH_1):PAGE143
     2    GND @S9S_MB_2U_LIB.S9S_MB_2U(SCH_1):GND    I55 @S9S_MB_2U_LIB.S9S_MB_2U(SCH_1):PAGE143

C2268 Q_CAP_0402-1000PF,50V,5%,EMPTYA
     1 GPU_3V3IO_RSVD5_FFU_ISO @S9S_MB_2U_LIB.S9S_MB_2U(SCH_1):GPU_3V3IO_RSVD5_FFU_ISO    I66 @S9S_MB_2U_LIB.S9S_MB_2U(SCH_1):PAGE143
     2    GND @S9S_MB_2U_LIB.S9S_MB_2U(SCH_1):GND    I66 @S9S_MB_2U_LIB.S9S_MB_2U(SCH_1):PAGE143

C2269 Q_CAP_0402-1000PF,50V,5%,EMPTYA
     1 PRSNT_CABLE_GPU_A2_ISO_N @S9S_MB_2U_LIB.S9S_MB_2U(SCH_1):PRSNT_CABLE_GPU_A2_ISO_N    I57 @S9S_MB_2U_LIB.S9S_MB_2U(SCH_1):PAGE143
     2    GND @S9S_MB_2U_LIB.S9S_MB_2U(SCH_1):GND    I57 @S9S_MB_2U_LIB.S9S_MB_2U(SCH_1):PAGE143

C2270 Q_CAP_0402-1000PF,50V,5%,EMPTYA
     1 PRSNT_CABLE_GPU_A1_ISO_N @S9S_MB_2U_LIB.S9S_MB_2U(SCH_1):PRSNT_CABLE_GPU_A1_ISO_N   I105 @S9S_MB_2U_LIB.S9S_MB_2U(SCH_1):PAGE143
     2    GND @S9S_MB_2U_LIB.S9S_MB_2U(SCH_1):GND   I105 @S9S_MB_2U_LIB.S9S_MB_2U(SCH_1):PAGE143

C2271 Q_CAP_0402-1000PF,50V,5%,EMPTYA
     1 GPU_3V3IO_RSVD1_ISO @S9S_MB_2U_LIB.S9S_MB_2U(SCH_1):GPU_3V3IO_RSVD1_ISO    I44 @S9S_MB_2U_LIB.S9S_MB_2U(SCH_1):PAGE139
     2    GND @S9S_MB_2U_LIB.S9S_MB_2U(SCH_1):GND    I44 @S9S_MB_2U_LIB.S9S_MB_2U(SCH_1):PAGE139

C2272 Q_CAP_0402-1000PF,50V,5%,EMPTYA
     1 GPU_3V3IO_RSVD4_ISO @S9S_MB_2U_LIB.S9S_MB_2U(SCH_1):GPU_3V3IO_RSVD4_ISO    I33 @S9S_MB_2U_LIB.S9S_MB_2U(SCH_1):PAGE139
     2    GND @S9S_MB_2U_LIB.S9S_MB_2U(SCH_1):GND    I33 @S9S_MB_2U_LIB.S9S_MB_2U(SCH_1):PAGE139

C2273 Q_CAP_0402-1000PF,50V,5%,EMPTYA
     1 GPU_3V3IO_RSVD3_ISO @S9S_MB_2U_LIB.S9S_MB_2U(SCH_1):GPU_3V3IO_RSVD3_ISO    I42 @S9S_MB_2U_LIB.S9S_MB_2U(SCH_1):PAGE139
     2    GND @S9S_MB_2U_LIB.S9S_MB_2U(SCH_1):GND    I42 @S9S_MB_2U_LIB.S9S_MB_2U(SCH_1):PAGE139

C2274 Q_CAP_0402-0.1UF,25V,10%,X7R,CA
     1 P3V3_AUX @S9S_MB_2U_LIB.S9S_MB_2U(SCH_1):P3V3_AUX   I139 @S9S_MB_2U_LIB.S9S_MB_2U(SCH_1):PAGE161
     2    GND @S9S_MB_2U_LIB.S9S_MB_2U(SCH_1):GND   I139 @S9S_MB_2U_LIB.S9S_MB_2U(SCH_1):PAGE161

C2275 Q_CAP_0402-0.1UF,25V,10%,X7R,CA
     1 P3V3_AUX @S9S_MB_2U_LIB.S9S_MB_2U(SCH_1):P3V3_AUX   I119 @S9S_MB_2U_LIB.S9S_MB_2U(SCH_1):PAGE161
     2    GND @S9S_MB_2U_LIB.S9S_MB_2U(SCH_1):GND   I119 @S9S_MB_2U_LIB.S9S_MB_2U(SCH_1):PAGE161

C2276 Q_CAP_0402-0.1UF,25V,10%,X7R,CA
     1 P3V3_AUX @S9S_MB_2U_LIB.S9S_MB_2U(SCH_1):P3V3_AUX   I104 @S9S_MB_2U_LIB.S9S_MB_2U(SCH_1):PAGE161
     2    GND @S9S_MB_2U_LIB.S9S_MB_2U(SCH_1):GND   I104 @S9S_MB_2U_LIB.S9S_MB_2U(SCH_1):PAGE161

C2283 Q_CAP_0402-0.1UF,25V,10%,X7R,CA
     1 P3V3_AUX @S9S_MB_2U_LIB.S9S_MB_2U(SCH_1):P3V3_AUX    I40 @S9S_MB_2U_LIB.S9S_MB_2U(SCH_1):PAGE230
     2    GND @S9S_MB_2U_LIB.S9S_MB_2U(SCH_1):GND    I40 @S9S_MB_2U_LIB.S9S_MB_2U(SCH_1):PAGE230

C2284 Q_CAP_C0805-22UF,16V,20%,X6S,CB
     1 P3V3_AUX_USB_BUF @S9S_MB_2U_LIB.S9S_MB_2U(SCH_1):P3V3_AUX_USB_BUF    I37 @S9S_MB_2U_LIB.S9S_MB_2U(SCH_1):PAGE162
     2    GND @S9S_MB_2U_LIB.S9S_MB_2U(SCH_1):GND    I37 @S9S_MB_2U_LIB.S9S_MB_2U(SCH_1):PAGE162

C2285 Q_CAP_0402-0.1UF,25V,10%,X7R,CA
     1 P3V3_AUX_USB_BUF @S9S_MB_2U_LIB.S9S_MB_2U(SCH_1):P3V3_AUX_USB_BUF    I44 @S9S_MB_2U_LIB.S9S_MB_2U(SCH_1):PAGE162
     2    GND @S9S_MB_2U_LIB.S9S_MB_2U(SCH_1):GND    I44 @S9S_MB_2U_LIB.S9S_MB_2U(SCH_1):PAGE162

C2286 Q_CAP_0402-0.1UF,25V,10%,X7R,CA
     1 P3V3_AUX_USB_BUF @S9S_MB_2U_LIB.S9S_MB_2U(SCH_1):P3V3_AUX_USB_BUF    I45 @S9S_MB_2U_LIB.S9S_MB_2U(SCH_1):PAGE162
     2    GND @S9S_MB_2U_LIB.S9S_MB_2U(SCH_1):GND    I45 @S9S_MB_2U_LIB.S9S_MB_2U(SCH_1):PAGE162

C2287 Q_CAP_C0402-0.01UF,50V,10%,X7RA
     1 PWRGD_P1V8_PCH_AUX @S9S_MB_2U_LIB.S9S_MB_2U(SCH_1):PWRGD_P1V8_PCH_AUX    I36 @S9S_MB_2U_LIB.S9S_MB_2U(SCH_1):PAGE249
     2    GND @S9S_MB_2U_LIB.S9S_MB_2U(SCH_1):GND    I36 @S9S_MB_2U_LIB.S9S_MB_2U(SCH_1):PAGE249

C2289 Q_CAP_C0201-0.1UF,6.3V,10%,X6SA
     1 USB3_PCH_TX_BUF_DP<4> @S9S_MB_2U_LIB.S9S_MB_2U(SCH_1):USB3_PCH_TX_BUF_DP(4)    I57 @S9S_MB_2U_LIB.S9S_MB_2U(SCH_1):PAGE162
     2 USB3_PCH_TX_BUF_C_DP<4> @S9S_MB_2U_LIB.S9S_MB_2U(SCH_1):USB3_PCH_TX_BUF_C_DP(4)    I57 @S9S_MB_2U_LIB.S9S_MB_2U(SCH_1):PAGE162

C2290 Q_CAP_C0201-0.1UF,6.3V,10%,X6SA
     1 USB3_PCH_TX_BUF_DN<4> @S9S_MB_2U_LIB.S9S_MB_2U(SCH_1):USB3_PCH_TX_BUF_DN(4)    I56 @S9S_MB_2U_LIB.S9S_MB_2U(SCH_1):PAGE162
     2 USB3_PCH_TX_BUF_C_DN<4> @S9S_MB_2U_LIB.S9S_MB_2U(SCH_1):USB3_PCH_TX_BUF_C_DN(4)    I56 @S9S_MB_2U_LIB.S9S_MB_2U(SCH_1):PAGE162

C2291 Q_CAP_C0201-0.1UF,6.3V,10%,X6SA
     1 USB3_PCH_RX_BUF_C_DP<4> @S9S_MB_2U_LIB.S9S_MB_2U(SCH_1):USB3_PCH_RX_BUF_C_DP(4)    I55 @S9S_MB_2U_LIB.S9S_MB_2U(SCH_1):PAGE162
     2 USB3_PCH_RX_BUF_DP<4> @S9S_MB_2U_LIB.S9S_MB_2U(SCH_1):USB3_PCH_RX_BUF_DP(4)    I55 @S9S_MB_2U_LIB.S9S_MB_2U(SCH_1):PAGE162

C2292 Q_CAP_C0201-0.1UF,6.3V,10%,X6SA
     1 USB3_PCH_RX_BUF_C_DN<4> @S9S_MB_2U_LIB.S9S_MB_2U(SCH_1):USB3_PCH_RX_BUF_C_DN(4)    I54 @S9S_MB_2U_LIB.S9S_MB_2U(SCH_1):PAGE162
     2 USB3_PCH_RX_BUF_DN<4> @S9S_MB_2U_LIB.S9S_MB_2U(SCH_1):USB3_PCH_RX_BUF_DN(4)    I54 @S9S_MB_2U_LIB.S9S_MB_2U(SCH_1):PAGE162

C2293 Q_CAP_0402-0.1UF,25V,10%,EMPTYA
     1 RST_SMB_SWITCH_R_N @S9S_MB_2U_LIB.S9S_MB_2U(SCH_1):RST_SMB_SWITCH_R_N    I57 @S9S_MB_2U_LIB.S9S_MB_2U(SCH_1):PAGE233
     2    GND @S9S_MB_2U_LIB.S9S_MB_2U(SCH_1):GND    I57 @S9S_MB_2U_LIB.S9S_MB_2U(SCH_1):PAGE233

C2294 Q_CAP_0402-0.1UF,25V,10%,EMPTYA
     1 PDB_PRSNT_N @S9S_MB_2U_LIB.S9S_MB_2U(SCH_1):PDB_PRSNT_N    I55 @S9S_MB_2U_LIB.S9S_MB_2U(SCH_1):PAGE233
     2    GND @S9S_MB_2U_LIB.S9S_MB_2U(SCH_1):GND    I55 @S9S_MB_2U_LIB.S9S_MB_2U(SCH_1):PAGE233

C2295 Q_CAP_0402-0.1UF,25V,10%,EMPTYA
     1 HPDB_HSC_PWRGD_R @S9S_MB_2U_LIB.S9S_MB_2U(SCH_1):HPDB_HSC_PWRGD_R    I54 @S9S_MB_2U_LIB.S9S_MB_2U(SCH_1):PAGE233
     2    GND @S9S_MB_2U_LIB.S9S_MB_2U(SCH_1):GND    I54 @S9S_MB_2U_LIB.S9S_MB_2U(SCH_1):PAGE233

C2296 Q_CAP_0402-0.1UF,25V,10%,EMPTYA
     1 FM_FAN_PWR_EN_R @S9S_MB_2U_LIB.S9S_MB_2U(SCH_1):FM_FAN_PWR_EN_R    I53 @S9S_MB_2U_LIB.S9S_MB_2U(SCH_1):PAGE233
     2    GND @S9S_MB_2U_LIB.S9S_MB_2U(SCH_1):GND    I53 @S9S_MB_2U_LIB.S9S_MB_2U(SCH_1):PAGE233

C2297 Q_CAP_0402-0.1UF,25V,10%,EMPTYA
     1 FM_GPU_HSC_EN_BUF_R1 @S9S_MB_2U_LIB.S9S_MB_2U(SCH_1):FM_GPU_HSC_EN_BUF_R1    I52 @S9S_MB_2U_LIB.S9S_MB_2U(SCH_1):PAGE233
     2    GND @S9S_MB_2U_LIB.S9S_MB_2U(SCH_1):GND    I52 @S9S_MB_2U_LIB.S9S_MB_2U(SCH_1):PAGE233

C2313 Q_CAP_C0402-10UF,6.3V,20%,EMPTA
     1 P3V3_AUX_USB_HUB_2 @S9S_MB_2U_LIB.S9S_MB_2U(SCH_1):P3V3_AUX_USB_HUB_2    I43 @S9S_MB_2U_LIB.S9S_MB_2U(SCH_1):PAGE194
     2    GND @S9S_MB_2U_LIB.S9S_MB_2U(SCH_1):GND    I43 @S9S_MB_2U_LIB.S9S_MB_2U(SCH_1):PAGE194

C2314 Q_CAP_0402-0.1UF,25V,10%,EMPTYA
     1 P3V3_AUX_USB_HUB_2 @S9S_MB_2U_LIB.S9S_MB_2U(SCH_1):P3V3_AUX_USB_HUB_2    I45 @S9S_MB_2U_LIB.S9S_MB_2U(SCH_1):PAGE194
     2    GND @S9S_MB_2U_LIB.S9S_MB_2U(SCH_1):GND    I45 @S9S_MB_2U_LIB.S9S_MB_2U(SCH_1):PAGE194

C2315 Q_CAP_0402-0.1UF,25V,10%,EMPTYA
     1 P3V3_AUX_USB_HUB_2 @S9S_MB_2U_LIB.S9S_MB_2U(SCH_1):P3V3_AUX_USB_HUB_2    I46 @S9S_MB_2U_LIB.S9S_MB_2U(SCH_1):PAGE194
     2    GND @S9S_MB_2U_LIB.S9S_MB_2U(SCH_1):GND    I46 @S9S_MB_2U_LIB.S9S_MB_2U(SCH_1):PAGE194

C2316 Q_CAP_C0402-1UF,25V,10%,EMPTY,A
     1 P3V3_AUX_USB_HUB_2 @S9S_MB_2U_LIB.S9S_MB_2U(SCH_1):P3V3_AUX_USB_HUB_2    I47 @S9S_MB_2U_LIB.S9S_MB_2U(SCH_1):PAGE194
     2    GND @S9S_MB_2U_LIB.S9S_MB_2U(SCH_1):GND    I47 @S9S_MB_2U_LIB.S9S_MB_2U(SCH_1):PAGE194

C2317 Q_CAP_C0402-1UF,25V,10%,EMPTY,A
     1 RST_USB_HUB_2_R_N @S9S_MB_2U_LIB.S9S_MB_2U(SCH_1):RST_USB_HUB_2_R_N    I15 @S9S_MB_2U_LIB.S9S_MB_2U(SCH_1):PAGE194
     2    GND @S9S_MB_2U_LIB.S9S_MB_2U(SCH_1):GND    I15 @S9S_MB_2U_LIB.S9S_MB_2U(SCH_1):PAGE194

C2318 Q_CAP_0402-0.1UF,25V,10%,EMPTYA
     1 P3V3_AUX_USB_HUB_2 @S9S_MB_2U_LIB.S9S_MB_2U(SCH_1):P3V3_AUX_USB_HUB_2    I49 @S9S_MB_2U_LIB.S9S_MB_2U(SCH_1):PAGE194
     2    GND @S9S_MB_2U_LIB.S9S_MB_2U(SCH_1):GND    I49 @S9S_MB_2U_LIB.S9S_MB_2U(SCH_1):PAGE194

C2319 Q_CAP_0402-0.1UF,25V,10%,EMPTYA
     1 P3V3_AUX_USB_HUB_2 @S9S_MB_2U_LIB.S9S_MB_2U(SCH_1):P3V3_AUX_USB_HUB_2    I51 @S9S_MB_2U_LIB.S9S_MB_2U(SCH_1):PAGE194
     2    GND @S9S_MB_2U_LIB.S9S_MB_2U(SCH_1):GND    I51 @S9S_MB_2U_LIB.S9S_MB_2U(SCH_1):PAGE194

C2320 Q_CAP_0402-0.1UF,25V,10%,EMPTYA
     1 P3V3_AUX_USB_HUB_2 @S9S_MB_2U_LIB.S9S_MB_2U(SCH_1):P3V3_AUX_USB_HUB_2    I52 @S9S_MB_2U_LIB.S9S_MB_2U(SCH_1):PAGE194
     2    GND @S9S_MB_2U_LIB.S9S_MB_2U(SCH_1):GND    I52 @S9S_MB_2U_LIB.S9S_MB_2U(SCH_1):PAGE194

C2321 Q_CAP_0402-0.1UF,25V,10%,EMPTYA
     1 PD_USB_HUB_2_RSTN @S9S_MB_2U_LIB.S9S_MB_2U(SCH_1):PD_USB_HUB_2_RSTN     I2 @S9S_MB_2U_LIB.S9S_MB_2U(SCH_1):PAGE194
     2    GND @S9S_MB_2U_LIB.S9S_MB_2U(SCH_1):GND     I2 @S9S_MB_2U_LIB.S9S_MB_2U(SCH_1):PAGE194

C2322 Q_CAP_C0402-1UF,25V,10%,EMPTY,A
     1 P3V3_AUX_USB_HUB_2 @S9S_MB_2U_LIB.S9S_MB_2U(SCH_1):P3V3_AUX_USB_HUB_2    I53 @S9S_MB_2U_LIB.S9S_MB_2U(SCH_1):PAGE194
     2    GND @S9S_MB_2U_LIB.S9S_MB_2U(SCH_1):GND    I53 @S9S_MB_2U_LIB.S9S_MB_2U(SCH_1):PAGE194

C2323 Q_CAP_C0402-1UF,25V,10%,EMPTY,A
     1 P3V3_AUX @S9S_MB_2U_LIB.S9S_MB_2U(SCH_1):P3V3_AUX    I56 @S9S_MB_2U_LIB.S9S_MB_2U(SCH_1):PAGE194
     2    GND @S9S_MB_2U_LIB.S9S_MB_2U(SCH_1):GND    I56 @S9S_MB_2U_LIB.S9S_MB_2U(SCH_1):PAGE194

C2324 Q_CAP_0402-0.1UF,25V,10%,EMPTYA
     1 P3V3_AUX @S9S_MB_2U_LIB.S9S_MB_2U(SCH_1):P3V3_AUX    I58 @S9S_MB_2U_LIB.S9S_MB_2U(SCH_1):PAGE194
     2    GND @S9S_MB_2U_LIB.S9S_MB_2U(SCH_1):GND    I58 @S9S_MB_2U_LIB.S9S_MB_2U(SCH_1):PAGE194

C2325 Q_CAP_0402-0.1UF,25V,10%,EMPTYA
     1 PD_USB_HUB_2_VREG @S9S_MB_2U_LIB.S9S_MB_2U(SCH_1):PD_USB_HUB_2_VREG    I55 @S9S_MB_2U_LIB.S9S_MB_2U(SCH_1):PAGE194
     2    GND @S9S_MB_2U_LIB.S9S_MB_2U(SCH_1):GND    I55 @S9S_MB_2U_LIB.S9S_MB_2U(SCH_1):PAGE194

C2326 Q_CAP_C0402-12PF,50V,5%,EMPTY,A
     1 USB_HUB_2_XTAL_IN @S9S_MB_2U_LIB.S9S_MB_2U(SCH_1):USB_HUB_2_XTAL_IN    I81 @S9S_MB_2U_LIB.S9S_MB_2U(SCH_1):PAGE194
     2    GND @S9S_MB_2U_LIB.S9S_MB_2U(SCH_1):GND    I81 @S9S_MB_2U_LIB.S9S_MB_2U(SCH_1):PAGE194

C2327 Q_CAP_C0402-12PF,50V,5%,EMPTY,A
     1 USB_HUB_2_XTAL_OUT @S9S_MB_2U_LIB.S9S_MB_2U(SCH_1):USB_HUB_2_XTAL_OUT    I85 @S9S_MB_2U_LIB.S9S_MB_2U(SCH_1):PAGE194
     2    GND @S9S_MB_2U_LIB.S9S_MB_2U(SCH_1):GND    I85 @S9S_MB_2U_LIB.S9S_MB_2U(SCH_1):PAGE194

C2328 Q_CAP_C0603-10UF,6.3V,20%,X6S,A
     1 P3V3_9ZXL045_VDD @S9S_MB_2U_LIB.S9S_MB_2U(SCH_1):P3V3_9ZXL045_VDD    I17 @S9S_MB_2U_LIB.S9S_MB_2U(SCH_1):PAGE200
     2    GND @S9S_MB_2U_LIB.S9S_MB_2U(SCH_1):GND    I17 @S9S_MB_2U_LIB.S9S_MB_2U(SCH_1):PAGE200

C2329 Q_CAP_0402-0.1UF,25V,10%,X7R,CA
     1 P3V3_9ZXL045_VDD @S9S_MB_2U_LIB.S9S_MB_2U(SCH_1):P3V3_9ZXL045_VDD    I54 @S9S_MB_2U_LIB.S9S_MB_2U(SCH_1):PAGE200
     2    GND @S9S_MB_2U_LIB.S9S_MB_2U(SCH_1):GND    I54 @S9S_MB_2U_LIB.S9S_MB_2U(SCH_1):PAGE200

C2330 Q_CAP_0402-0.1UF,25V,10%,X7R,CA
     1 P3V3_9ZXL045_VDD @S9S_MB_2U_LIB.S9S_MB_2U(SCH_1):P3V3_9ZXL045_VDD    I55 @S9S_MB_2U_LIB.S9S_MB_2U(SCH_1):PAGE200
     2    GND @S9S_MB_2U_LIB.S9S_MB_2U(SCH_1):GND    I55 @S9S_MB_2U_LIB.S9S_MB_2U(SCH_1):PAGE200

C2331 Q_CAP_C0603-10UF,6.3V,20%,X6S,A
     1 P3V3_9ZXL045_VDDA @S9S_MB_2U_LIB.S9S_MB_2U(SCH_1):P3V3_9ZXL045_VDDA     I5 @S9S_MB_2U_LIB.S9S_MB_2U(SCH_1):PAGE200
     2    GND @S9S_MB_2U_LIB.S9S_MB_2U(SCH_1):GND     I5 @S9S_MB_2U_LIB.S9S_MB_2U(SCH_1):PAGE200

C2332 Q_CAP_C0603-10UF,6.3V,20%,X6S,A
     1 P3V3_9ZXL045_VDDR @S9S_MB_2U_LIB.S9S_MB_2U(SCH_1):P3V3_9ZXL045_VDDR    I10 @S9S_MB_2U_LIB.S9S_MB_2U(SCH_1):PAGE200
     2    GND @S9S_MB_2U_LIB.S9S_MB_2U(SCH_1):GND    I10 @S9S_MB_2U_LIB.S9S_MB_2U(SCH_1):PAGE200

C2333 Q_CAP_0402-0.1UF,25V,10%,X7R,CA
     1 P3V3_9ZXL045_VDD @S9S_MB_2U_LIB.S9S_MB_2U(SCH_1):P3V3_9ZXL045_VDD    I56 @S9S_MB_2U_LIB.S9S_MB_2U(SCH_1):PAGE200
     2    GND @S9S_MB_2U_LIB.S9S_MB_2U(SCH_1):GND    I56 @S9S_MB_2U_LIB.S9S_MB_2U(SCH_1):PAGE200

C2334 Q_CAP_0402-0.1UF,25V,10%,X7R,CA
     1 P3V3_9ZXL045_VDDA @S9S_MB_2U_LIB.S9S_MB_2U(SCH_1):P3V3_9ZXL045_VDDA    I58 @S9S_MB_2U_LIB.S9S_MB_2U(SCH_1):PAGE200
     2    GND @S9S_MB_2U_LIB.S9S_MB_2U(SCH_1):GND    I58 @S9S_MB_2U_LIB.S9S_MB_2U(SCH_1):PAGE200

C2335 Q_CAP_0402-0.1UF,25V,10%,X7R,CA
     1 P3V3_9ZXL045_VDDR @S9S_MB_2U_LIB.S9S_MB_2U(SCH_1):P3V3_9ZXL045_VDDR    I59 @S9S_MB_2U_LIB.S9S_MB_2U(SCH_1):PAGE200
     2    GND @S9S_MB_2U_LIB.S9S_MB_2U(SCH_1):GND    I59 @S9S_MB_2U_LIB.S9S_MB_2U(SCH_1):PAGE200

C2336 Q_CAP_0402-0.1UF,25V,10%,X7R,CA
     1 P3V3_9ZXL045_VDD @S9S_MB_2U_LIB.S9S_MB_2U(SCH_1):P3V3_9ZXL045_VDD    I57 @S9S_MB_2U_LIB.S9S_MB_2U(SCH_1):PAGE200
     2    GND @S9S_MB_2U_LIB.S9S_MB_2U(SCH_1):GND    I57 @S9S_MB_2U_LIB.S9S_MB_2U(SCH_1):PAGE200

C2337 Q_CAP_0402-0.1UF,25V,10%,X7R,CA
     1 P3V3_AUX @S9S_MB_2U_LIB.S9S_MB_2U(SCH_1):P3V3_AUX     I5 @S9S_MB_2U_LIB.S9S_MB_2U(SCH_1):PAGE225
     2    GND @S9S_MB_2U_LIB.S9S_MB_2U(SCH_1):GND     I5 @S9S_MB_2U_LIB.S9S_MB_2U(SCH_1):PAGE225

C2338 Q_CAP_0402-0.1UF,25V,10%,X7R,CA
     1   P3V3 @S9S_MB_2U_LIB.S9S_MB_2U(SCH_1):P3V3     I8 @S9S_MB_2U_LIB.S9S_MB_2U(SCH_1):PAGE225
     2    GND @S9S_MB_2U_LIB.S9S_MB_2U(SCH_1):GND     I8 @S9S_MB_2U_LIB.S9S_MB_2U(SCH_1):PAGE225

C2339 Q_CAP_0402-0.1UF,25V,10%,X7R,CA
     1 P3V3_9ZXL045_VDD @S9S_MB_2U_LIB.S9S_MB_2U(SCH_1):P3V3_9ZXL045_VDD    I71 @S9S_MB_2U_LIB.S9S_MB_2U(SCH_1):PAGE200
     2    GND @S9S_MB_2U_LIB.S9S_MB_2U(SCH_1):GND    I71 @S9S_MB_2U_LIB.S9S_MB_2U(SCH_1):PAGE200

C2340 Q_CAP_0402-1000PF,50V,5%,EMPTYA
     1 HGX_DETECT_N_ISO @S9S_MB_2U_LIB.S9S_MB_2U(SCH_1):HGX_DETECT_N_ISO    I52 @S9S_MB_2U_LIB.S9S_MB_2U(SCH_1):PAGE139
     2    GND @S9S_MB_2U_LIB.S9S_MB_2U(SCH_1):GND    I52 @S9S_MB_2U_LIB.S9S_MB_2U(SCH_1):PAGE139

C2341 Q_CAP_0402-0.1UF,25V,10%,X7R,CA
     1 P3V3_AUX @S9S_MB_2U_LIB.S9S_MB_2U(SCH_1):P3V3_AUX    I93 @S9S_MB_2U_LIB.S9S_MB_2U(SCH_1):PAGE139
     2    GND @S9S_MB_2U_LIB.S9S_MB_2U(SCH_1):GND    I93 @S9S_MB_2U_LIB.S9S_MB_2U(SCH_1):PAGE139

C2342 Q_CAP_0402-1000PF,50V,5%,EMPTYA
     1 HPDB_HSC_PWRGD_ISO @S9S_MB_2U_LIB.S9S_MB_2U(SCH_1):HPDB_HSC_PWRGD_ISO    I62 @S9S_MB_2U_LIB.S9S_MB_2U(SCH_1):PAGE230
     2    GND @S9S_MB_2U_LIB.S9S_MB_2U(SCH_1):GND    I62 @S9S_MB_2U_LIB.S9S_MB_2U(SCH_1):PAGE230

C2343 Q_CAP_0402-1000PF,50V,5%,EMPTYA
     1 SWB_HSC_PWRGD_ISO @S9S_MB_2U_LIB.S9S_MB_2U(SCH_1):SWB_HSC_PWRGD_ISO   I118 @S9S_MB_2U_LIB.S9S_MB_2U(SCH_1):PAGE143
     2    GND @S9S_MB_2U_LIB.S9S_MB_2U(SCH_1):GND   I118 @S9S_MB_2U_LIB.S9S_MB_2U(SCH_1):PAGE143

C2344 Q_CAP_0402-0.1UF,25V,10%,X7R,CA
     1 P3V3_AUX @S9S_MB_2U_LIB.S9S_MB_2U(SCH_1):P3V3_AUX    I87 @S9S_MB_2U_LIB.S9S_MB_2U(SCH_1):PAGE152
     2    GND @S9S_MB_2U_LIB.S9S_MB_2U(SCH_1):GND    I87 @S9S_MB_2U_LIB.S9S_MB_2U(SCH_1):PAGE152

C2345 Q_CAP_0402-0.1UF,25V,10%,X7R,CA
     1 P3V3_AUX @S9S_MB_2U_LIB.S9S_MB_2U(SCH_1):P3V3_AUX    I81 @S9S_MB_2U_LIB.S9S_MB_2U(SCH_1):PAGE156
     2    GND @S9S_MB_2U_LIB.S9S_MB_2U(SCH_1):GND    I81 @S9S_MB_2U_LIB.S9S_MB_2U(SCH_1):PAGE156

C2346 Q_CAP_0402-0.1UF,25V,10%,X7R,CA
     1 P3V3_AUX @S9S_MB_2U_LIB.S9S_MB_2U(SCH_1):P3V3_AUX   I223 @S9S_MB_2U_LIB.S9S_MB_2U(SCH_1):PAGE154
     2    GND @S9S_MB_2U_LIB.S9S_MB_2U(SCH_1):GND   I223 @S9S_MB_2U_LIB.S9S_MB_2U(SCH_1):PAGE154

C2347 Q_CAP_0402-0.1UF,25V,10%,X7R,CA
     1 P3V3_AUX @S9S_MB_2U_LIB.S9S_MB_2U(SCH_1):P3V3_AUX    I90 @S9S_MB_2U_LIB.S9S_MB_2U(SCH_1):PAGE132
     2    GND @S9S_MB_2U_LIB.S9S_MB_2U(SCH_1):GND    I90 @S9S_MB_2U_LIB.S9S_MB_2U(SCH_1):PAGE132

C2348 Q_CAP_0402-0.1UF,25V,10%,X7R,CA
     1 P3V3_AUX @S9S_MB_2U_LIB.S9S_MB_2U(SCH_1):P3V3_AUX    I23 @S9S_MB_2U_LIB.S9S_MB_2U(SCH_1):PAGE235
     2    GND @S9S_MB_2U_LIB.S9S_MB_2U(SCH_1):GND    I23 @S9S_MB_2U_LIB.S9S_MB_2U(SCH_1):PAGE235

C2349 Q_CAP_DIFFBUS_C0402-DIFF BUS_0A
     1 USB3_PCH_RX_DP<4> @S9S_MB_2U_LIB.S9S_MB_2U(SCH_1):USB3_PCH_RX_DP(4)    I26 @S9S_MB_2U_LIB.S9S_MB_2U(SCH_1):PAGE162
     2 USB3_PCH_RX_C_DP<4> @S9S_MB_2U_LIB.S9S_MB_2U(SCH_1):USB3_PCH_RX_C_DP(4)    I26 @S9S_MB_2U_LIB.S9S_MB_2U(SCH_1):PAGE162

C2350 Q_CAP_DIFFBUS_C0402-DIFF BUS_0A
     1 USB3_PCH_RX_DN<4> @S9S_MB_2U_LIB.S9S_MB_2U(SCH_1):USB3_PCH_RX_DN(4)    I25 @S9S_MB_2U_LIB.S9S_MB_2U(SCH_1):PAGE162
     2 USB3_PCH_RX_C_DN<4> @S9S_MB_2U_LIB.S9S_MB_2U(SCH_1):USB3_PCH_RX_C_DN(4)    I25 @S9S_MB_2U_LIB.S9S_MB_2U(SCH_1):PAGE162

C2351 Q_CAP_0402-0.1UF,25V,10%,EMPTYA
     1 P2E_MB_BMC_TX_BUF2_DP<0> @S9S_MB_2U_LIB.S9S_MB_2U(SCH_1):P2E_MB_BMC_TX_BUF2_DP(0)    I31 @S9S_MB_2U_LIB.S9S_MB_2U(SCH_1):PAGE159
     2 P2E_MB_BMC_TX_BUF_C_DP<0> @S9S_MB_2U_LIB.S9S_MB_2U(SCH_1):P2E_MB_BMC_TX_BUF_C_DP(0)    I31 @S9S_MB_2U_LIB.S9S_MB_2U(SCH_1):PAGE159

C2352 Q_CAP_0402-0.1UF,25V,10%,EMPTYA
     1 P2E_MB_BMC_TX_BUF2_DN<0> @S9S_MB_2U_LIB.S9S_MB_2U(SCH_1):P2E_MB_BMC_TX_BUF2_DN(0)    I32 @S9S_MB_2U_LIB.S9S_MB_2U(SCH_1):PAGE159
     2 P2E_MB_BMC_TX_BUF_C_DN<0> @S9S_MB_2U_LIB.S9S_MB_2U(SCH_1):P2E_MB_BMC_TX_BUF_C_DN(0)    I32 @S9S_MB_2U_LIB.S9S_MB_2U(SCH_1):PAGE159

C2353 Q_CAP_0402-0.1UF,25V,10%,EMPTYA
     1 P2E_MB_BMC_RX_BUF2_C_DP<0> @S9S_MB_2U_LIB.S9S_MB_2U(SCH_1):P2E_MB_BMC_RX_BUF2_C_DP(0)    I27 @S9S_MB_2U_LIB.S9S_MB_2U(SCH_1):PAGE159
     2 P2E_MB_BMC_RX_BUF_DP<0> @S9S_MB_2U_LIB.S9S_MB_2U(SCH_1):P2E_MB_BMC_RX_BUF_DP(0)    I27 @S9S_MB_2U_LIB.S9S_MB_2U(SCH_1):PAGE159

C2354 Q_CAP_0402-0.1UF,25V,10%,EMPTYA
     1 P2E_MB_BMC_RX_BUF2_C_DN<0> @S9S_MB_2U_LIB.S9S_MB_2U(SCH_1):P2E_MB_BMC_RX_BUF2_C_DN(0)    I28 @S9S_MB_2U_LIB.S9S_MB_2U(SCH_1):PAGE159
     2 P2E_MB_BMC_RX_BUF_DN<0> @S9S_MB_2U_LIB.S9S_MB_2U(SCH_1):P2E_MB_BMC_RX_BUF_DN(0)    I28 @S9S_MB_2U_LIB.S9S_MB_2U(SCH_1):PAGE159

C2355 Q_CAP_C0402-1UF,25V,10%,X6S,CHA
     1 P3V3_AUX @S9S_MB_2U_LIB.S9S_MB_2U(SCH_1):P3V3_AUX    I96 @S9S_MB_2U_LIB.S9S_MB_2U(SCH_1):PAGE159
     2    GND @S9S_MB_2U_LIB.S9S_MB_2U(SCH_1):GND    I96 @S9S_MB_2U_LIB.S9S_MB_2U(SCH_1):PAGE159

C2356 Q_CAP_C0805-10UF,16V,10%,X6S,CA
     1 P3V3_AUX @S9S_MB_2U_LIB.S9S_MB_2U(SCH_1):P3V3_AUX    I98 @S9S_MB_2U_LIB.S9S_MB_2U(SCH_1):PAGE159
     2    GND @S9S_MB_2U_LIB.S9S_MB_2U(SCH_1):GND    I98 @S9S_MB_2U_LIB.S9S_MB_2U(SCH_1):PAGE159

C2357 Q_CAP_0402-0.1UF,25V,10%,X7R,CA
     1 P2E_BUF2_VDD @S9S_MB_2U_LIB.S9S_MB_2U(SCH_1):P2E_BUF2_VDD    I99 @S9S_MB_2U_LIB.S9S_MB_2U(SCH_1):PAGE159
     2    GND @S9S_MB_2U_LIB.S9S_MB_2U(SCH_1):GND    I99 @S9S_MB_2U_LIB.S9S_MB_2U(SCH_1):PAGE159

C2358 Q_CAP_0402-0.1UF,25V,10%,X7R,CA
     1 P2E_BUF2_VDD @S9S_MB_2U_LIB.S9S_MB_2U(SCH_1):P2E_BUF2_VDD   I100 @S9S_MB_2U_LIB.S9S_MB_2U(SCH_1):PAGE159
     2    GND @S9S_MB_2U_LIB.S9S_MB_2U(SCH_1):GND   I100 @S9S_MB_2U_LIB.S9S_MB_2U(SCH_1):PAGE159

C2359 Q_CAP_C0402-0.22UF,25V,10%,X7RA
     1 PWRGD_P5V_ISO_R @S9S_MB_2U_LIB.S9S_MB_2U(SCH_1):PWRGD_P5V_ISO_R    I94 @S9S_MB_2U_LIB.S9S_MB_2U(SCH_1):PAGE246
     2    GND @S9S_MB_2U_LIB.S9S_MB_2U(SCH_1):GND    I94 @S9S_MB_2U_LIB.S9S_MB_2U(SCH_1):PAGE246

C2360 Q_CAP_0402-0.1UF,25V,10%,X7R,CA
     1   P3V3 @S9S_MB_2U_LIB.S9S_MB_2U(SCH_1):P3V3   I107 @S9S_MB_2U_LIB.S9S_MB_2U(SCH_1):PAGE246
     2    GND @S9S_MB_2U_LIB.S9S_MB_2U(SCH_1):GND   I107 @S9S_MB_2U_LIB.S9S_MB_2U(SCH_1):PAGE246

C2363 Q_CAP_0402-0.1UF,25V,10%,EMPTYA
     1 HSC_TYPE_ADC @S9S_MB_2U_LIB.S9S_MB_2U(SCH_1):HSC_TYPE_ADC    I15 @S9S_MB_2U_LIB.S9S_MB_2U(SCH_1):PAGE240
     2    GND @S9S_MB_2U_LIB.S9S_MB_2U(SCH_1):GND    I15 @S9S_MB_2U_LIB.S9S_MB_2U(SCH_1):PAGE240

C2364 Q_CAP_0402-0.1UF,25V,10%,EMPTYA
     1 P3V3_AUX @S9S_MB_2U_LIB.S9S_MB_2U(SCH_1):P3V3_AUX    I33 @S9S_MB_2U_LIB.S9S_MB_2U(SCH_1):PAGE240
     2    GND @S9S_MB_2U_LIB.S9S_MB_2U(SCH_1):GND    I33 @S9S_MB_2U_LIB.S9S_MB_2U(SCH_1):PAGE240

C2369 Q_CAP_C0402-1UF,25V,10%,EMPTY,A
     1 FM_AC_PWR_BTN_R_N @S9S_MB_2U_LIB.S9S_MB_2U(SCH_1):FM_AC_PWR_BTN_R_N    I42 @S9S_MB_2U_LIB.S9S_MB_2U(SCH_1):PAGE213
     2    GND @S9S_MB_2U_LIB.S9S_MB_2U(SCH_1):GND    I42 @S9S_MB_2U_LIB.S9S_MB_2U(SCH_1):PAGE213

C2370 Q_CAP_0402-0.1UF,25V,10%,EMPTYA
     1 P3V3_AUX @S9S_MB_2U_LIB.S9S_MB_2U(SCH_1):P3V3_AUX    I35 @S9S_MB_2U_LIB.S9S_MB_2U(SCH_1):PAGE213
     2    GND @S9S_MB_2U_LIB.S9S_MB_2U(SCH_1):GND    I35 @S9S_MB_2U_LIB.S9S_MB_2U(SCH_1):PAGE213

C2371 Q_CAP_0402-0.1UF,25V,10%,EMPTYA
     1 FM_AC_PWR_BTN_PDB_N @S9S_MB_2U_LIB.S9S_MB_2U(SCH_1):FM_AC_PWR_BTN_PDB_N    I51 @S9S_MB_2U_LIB.S9S_MB_2U(SCH_1):PAGE233
     2    GND @S9S_MB_2U_LIB.S9S_MB_2U(SCH_1):GND    I51 @S9S_MB_2U_LIB.S9S_MB_2U(SCH_1):PAGE233

C2372 Q_CAP_0402-1000PF,50V,5%,EMPTYA
     1 PRSNT_SWB_ISO_N @S9S_MB_2U_LIB.S9S_MB_2U(SCH_1):PRSNT_SWB_ISO_N    I15 @S9S_MB_2U_LIB.S9S_MB_2U(SCH_1):PAGE147
     2    GND @S9S_MB_2U_LIB.S9S_MB_2U(SCH_1):GND    I15 @S9S_MB_2U_LIB.S9S_MB_2U(SCH_1):PAGE147

C2373 Q_CAP_0402-1000PF,50V,5%,EMPTYA
     1 PRSNT_CABLE_SWB_B2_ISO_N @S9S_MB_2U_LIB.S9S_MB_2U(SCH_1):PRSNT_CABLE_SWB_B2_ISO_N    I22 @S9S_MB_2U_LIB.S9S_MB_2U(SCH_1):PAGE147
     2    GND @S9S_MB_2U_LIB.S9S_MB_2U(SCH_1):GND    I22 @S9S_MB_2U_LIB.S9S_MB_2U(SCH_1):PAGE147

C2374 Q_CAP_0402-1000PF,50V,5%,EMPTYA
     1 PRSNT_CABLE_SWB_B1_ISO_N @S9S_MB_2U_LIB.S9S_MB_2U(SCH_1):PRSNT_CABLE_SWB_B1_ISO_N    I47 @S9S_MB_2U_LIB.S9S_MB_2U(SCH_1):PAGE147
     2    GND @S9S_MB_2U_LIB.S9S_MB_2U(SCH_1):GND    I47 @S9S_MB_2U_LIB.S9S_MB_2U(SCH_1):PAGE147

C2376 Q_CAP_0402-0.1UF,25V,10%,X7R,CA
     1 P3V3_AUX @S9S_MB_2U_LIB.S9S_MB_2U(SCH_1):P3V3_AUX   I241 @S9S_MB_2U_LIB.S9S_MB_2U(SCH_1):PAGE154
     2    GND @S9S_MB_2U_LIB.S9S_MB_2U(SCH_1):GND   I241 @S9S_MB_2U_LIB.S9S_MB_2U(SCH_1):PAGE154

C2377 Q_CAP_0402-0.1UF,25V,10%,X7R,CA
     1 P3V3_AUX @S9S_MB_2U_LIB.S9S_MB_2U(SCH_1):P3V3_AUX   I110 @S9S_MB_2U_LIB.S9S_MB_2U(SCH_1):PAGE132
     2    GND @S9S_MB_2U_LIB.S9S_MB_2U(SCH_1):GND   I110 @S9S_MB_2U_LIB.S9S_MB_2U(SCH_1):PAGE132

C2378 Q_CAP_0402-0.1UF,25V,10%,X7R,CA
     1 P3V3_E1S_0 @S9S_MB_2U_LIB.S9S_MB_2U(SCH_1):P3V3_E1S_0   I327 @S9S_MB_2U_LIB.S9S_MB_2U(SCH_1):PAGE297
     2    GND @S9S_MB_2U_LIB.S9S_MB_2U(SCH_1):GND   I327 @S9S_MB_2U_LIB.S9S_MB_2U(SCH_1):PAGE297

C2379 Q_CAP_C0402-100NF,50V,10%,EMPTA
     1 UV_ADR_P2V5_COMP @S9S_MB_2U_LIB.S9S_MB_2U(SCH_1):UV_ADR_P2V5_COMP     I1 @S9S_MB_2U_LIB.S9S_MB_2U(SCH_1):PAGE329
     2    GND @S9S_MB_2U_LIB.S9S_MB_2U(SCH_1):GND     I1 @S9S_MB_2U_LIB.S9S_MB_2U(SCH_1):PAGE329

C2380 Q_CAP_C0402-100NF,50V,10%,EMPTA
     1 UV_P2V5_COMP @S9S_MB_2U_LIB.S9S_MB_2U(SCH_1):UV_P2V5_COMP    I35 @S9S_MB_2U_LIB.S9S_MB_2U(SCH_1):PAGE329
     2    GND @S9S_MB_2U_LIB.S9S_MB_2U(SCH_1):GND    I35 @S9S_MB_2U_LIB.S9S_MB_2U(SCH_1):PAGE329

C2381 Q_CAP_C0402-100NF,50V,10%,EMPTA
     1 P12V_AUX_UV_ADR_TRIGGER @S9S_MB_2U_LIB.S9S_MB_2U(SCH_1):P12V_AUX_UV_ADR_TRIGGER    I14 @S9S_MB_2U_LIB.S9S_MB_2U(SCH_1):PAGE329
     2    GND @S9S_MB_2U_LIB.S9S_MB_2U(SCH_1):GND    I14 @S9S_MB_2U_LIB.S9S_MB_2U(SCH_1):PAGE329

C2382 Q_CAP_C0402-100NF,50V,10%,EMPTA
     1 P12V_AUX_UV_TRIGGER @S9S_MB_2U_LIB.S9S_MB_2U(SCH_1):P12V_AUX_UV_TRIGGER    I33 @S9S_MB_2U_LIB.S9S_MB_2U(SCH_1):PAGE329
     2    GND @S9S_MB_2U_LIB.S9S_MB_2U(SCH_1):GND    I33 @S9S_MB_2U_LIB.S9S_MB_2U(SCH_1):PAGE329

C2383 Q_CAP_C0402-100NF,50V,10%,EMPTA
     1 P12V_AUX @S9S_MB_2U_LIB.S9S_MB_2U(SCH_1):P12V_AUX    I11 @S9S_MB_2U_LIB.S9S_MB_2U(SCH_1):PAGE329
     2    GND @S9S_MB_2U_LIB.S9S_MB_2U(SCH_1):GND    I11 @S9S_MB_2U_LIB.S9S_MB_2U(SCH_1):PAGE329

C2384 Q_CAP_C0402-100NF,50V,10%,EMPTA
     1 P12V_AUX @S9S_MB_2U_LIB.S9S_MB_2U(SCH_1):P12V_AUX    I29 @S9S_MB_2U_LIB.S9S_MB_2U(SCH_1):PAGE329
     2    GND @S9S_MB_2U_LIB.S9S_MB_2U(SCH_1):GND    I29 @S9S_MB_2U_LIB.S9S_MB_2U(SCH_1):PAGE329

C2385 Q_CAP_C0402-100NF,50V,10%,EMPTA
     1 DSW_PWROK_P2V5_COMP @S9S_MB_2U_LIB.S9S_MB_2U(SCH_1):DSW_PWROK_P2V5_COMP    I57 @S9S_MB_2U_LIB.S9S_MB_2U(SCH_1):PAGE329
     2    GND @S9S_MB_2U_LIB.S9S_MB_2U(SCH_1):GND    I57 @S9S_MB_2U_LIB.S9S_MB_2U(SCH_1):PAGE329

C2386 Q_CAP_C0402-100NF,50V,10%,EMPTA
     1 PWRGD_DSW_PWROK_TRIGGER @S9S_MB_2U_LIB.S9S_MB_2U(SCH_1):PWRGD_DSW_PWROK_TRIGGER    I55 @S9S_MB_2U_LIB.S9S_MB_2U(SCH_1):PAGE329
     2    GND @S9S_MB_2U_LIB.S9S_MB_2U(SCH_1):GND    I55 @S9S_MB_2U_LIB.S9S_MB_2U(SCH_1):PAGE329

C2387 Q_CAP_C0402-100NF,50V,10%,EMPTA
     1 P12V_AUX @S9S_MB_2U_LIB.S9S_MB_2U(SCH_1):P12V_AUX    I51 @S9S_MB_2U_LIB.S9S_MB_2U(SCH_1):PAGE329
     2    GND @S9S_MB_2U_LIB.S9S_MB_2U(SCH_1):GND    I51 @S9S_MB_2U_LIB.S9S_MB_2U(SCH_1):PAGE329

C2388 Q_CAP_C0402-100NF,50V,10%,EMPTA
     1 OC_P2V5_COMP @S9S_MB_2U_LIB.S9S_MB_2U(SCH_1):OC_P2V5_COMP    I64 @S9S_MB_2U_LIB.S9S_MB_2U(SCH_1):PAGE326
     2    GND @S9S_MB_2U_LIB.S9S_MB_2U(SCH_1):GND    I64 @S9S_MB_2U_LIB.S9S_MB_2U(SCH_1):PAGE326

C2389 Q_CAP_C0402-100NF,50V,10%,EMPTA
     1 HSC_OC_VOL @S9S_MB_2U_LIB.S9S_MB_2U(SCH_1):HSC_OC_VOL    I76 @S9S_MB_2U_LIB.S9S_MB_2U(SCH_1):PAGE326
     2    GND @S9S_MB_2U_LIB.S9S_MB_2U(SCH_1):GND    I76 @S9S_MB_2U_LIB.S9S_MB_2U(SCH_1):PAGE326

C2390 Q_CAP_C0402-100NF,50V,10%,EMPTA
     1 P12V_AUX @S9S_MB_2U_LIB.S9S_MB_2U(SCH_1):P12V_AUX    I71 @S9S_MB_2U_LIB.S9S_MB_2U(SCH_1):PAGE326
     2    GND @S9S_MB_2U_LIB.S9S_MB_2U(SCH_1):GND    I71 @S9S_MB_2U_LIB.S9S_MB_2U(SCH_1):PAGE326

C2391 Q_CAP_0402-1000PF,50V,5%,EMPTYA
     1 PRSNT_CABLE_GPU_A3_ISO_N @S9S_MB_2U_LIB.S9S_MB_2U(SCH_1):PRSNT_CABLE_GPU_A3_ISO_N    I66 @S9S_MB_2U_LIB.S9S_MB_2U(SCH_1):PAGE147
     2    GND @S9S_MB_2U_LIB.S9S_MB_2U(SCH_1):GND    I66 @S9S_MB_2U_LIB.S9S_MB_2U(SCH_1):PAGE147

C2392 Q_CAP_0402-0.1UF,25V,10%,EMPTYA
     1 U205_VDD @S9S_MB_2U_LIB.S9S_MB_2U(SCH_1):U205_VDD    I95 @S9S_MB_2U_LIB.S9S_MB_2U(SCH_1):PAGE326
     2    GND @S9S_MB_2U_LIB.S9S_MB_2U(SCH_1):GND    I95 @S9S_MB_2U_LIB.S9S_MB_2U(SCH_1):PAGE326

C2393 Q_CAP_0402-0.1UF,25V,10%,EMPTYA
     1 U369_VDD @S9S_MB_2U_LIB.S9S_MB_2U(SCH_1):U369_VDD    I92 @S9S_MB_2U_LIB.S9S_MB_2U(SCH_1):PAGE326
     2    GND @S9S_MB_2U_LIB.S9S_MB_2U(SCH_1):GND    I92 @S9S_MB_2U_LIB.S9S_MB_2U(SCH_1):PAGE326

C2394 Q_CAP_0402-0.1UF,25V,10%,X7R,CA
     1 U206_VDD @S9S_MB_2U_LIB.S9S_MB_2U(SCH_1):U206_VDD    I93 @S9S_MB_2U_LIB.S9S_MB_2U(SCH_1):PAGE326
     2    GND @S9S_MB_2U_LIB.S9S_MB_2U(SCH_1):GND    I93 @S9S_MB_2U_LIB.S9S_MB_2U(SCH_1):PAGE326

C2443 Q_CAP_C0402-10UF,6.3V,20%,X6S,B
     1 PVNN_TERM_CPU0 @S9S_MB_2U_LIB.S9S_MB_2U(SCH_1):PVNN_TERM_CPU0    I18 @S9S_MB_2U_LIB.S9S_MB_2U(SCH_1):PAGE264
     2    GND @S9S_MB_2U_LIB.S9S_MB_2U(SCH_1):GND    I18 @S9S_MB_2U_LIB.S9S_MB_2U(SCH_1):PAGE264

C2444 Q_CAP_0402-0.1UF,25V,10%,X7R,CA
     1 PVNN_TERM_CPU0 @S9S_MB_2U_LIB.S9S_MB_2U(SCH_1):PVNN_TERM_CPU0    I19 @S9S_MB_2U_LIB.S9S_MB_2U(SCH_1):PAGE264
     2    GND @S9S_MB_2U_LIB.S9S_MB_2U(SCH_1):GND    I19 @S9S_MB_2U_LIB.S9S_MB_2U(SCH_1):PAGE264

C2445 Q_CAP_0402-1000PF,50V,5%,EMPTYA
     1 FM_PVPP_HBM_CPU1_EN @S9S_MB_2U_LIB.S9S_MB_2U(SCH_1):FM_PVPP_HBM_CPU1_EN    I11 @S9S_MB_2U_LIB.S9S_MB_2U(SCH_1):PAGE285
     2    GND @S9S_MB_2U_LIB.S9S_MB_2U(SCH_1):GND    I11 @S9S_MB_2U_LIB.S9S_MB_2U(SCH_1):PAGE285

C2446 Q_CAP_0402-1000PF,50V,5%,X7R,TA
     1 PVCCFA_EHV_FIVRA_CPU1_EN_R @S9S_MB_2U_LIB.S9S_MB_2U(SCH_1):PVCCFA_EHV_FIVRA_CPU1_EN_R    I34 @S9S_MB_2U_LIB.S9S_MB_2U(SCH_1):PAGE270
     2    GND @S9S_MB_2U_LIB.S9S_MB_2U(SCH_1):GND    I34 @S9S_MB_2U_LIB.S9S_MB_2U(SCH_1):PAGE270

C2447 Q_CAP_0402-1000PF,50V,5%,EMPTYA
     1 PWRGD_PVCCFA_EHV_FIVRA_CPU1_R @S9S_MB_2U_LIB.S9S_MB_2U(SCH_1):PWRGD_PVCCFA_EHV_FIVRA_CPU1_R    I35 @S9S_MB_2U_LIB.S9S_MB_2U(SCH_1):PAGE270
     2    GND @S9S_MB_2U_LIB.S9S_MB_2U(SCH_1):GND    I35 @S9S_MB_2U_LIB.S9S_MB_2U(SCH_1):PAGE270

C2448 Q_CAP_C0603-10UF,4V,20%,EMPTY,A
     1 PVNN_TERM_CPU1 @S9S_MB_2U_LIB.S9S_MB_2U(SCH_1):PVNN_TERM_CPU1   I103 @S9S_MB_2U_LIB.S9S_MB_2U(SCH_1):PAGE270
     2    GND @S9S_MB_2U_LIB.S9S_MB_2U(SCH_1):GND   I103 @S9S_MB_2U_LIB.S9S_MB_2U(SCH_1):PAGE270

C2449 Q_CAP_C0402-100NF,50V,10%,X7R,A
     1 PVNN_TERM_CPU1 @S9S_MB_2U_LIB.S9S_MB_2U(SCH_1):PVNN_TERM_CPU1   I104 @S9S_MB_2U_LIB.S9S_MB_2U(SCH_1):PAGE270
     2    GND @S9S_MB_2U_LIB.S9S_MB_2U(SCH_1):GND   I104 @S9S_MB_2U_LIB.S9S_MB_2U(SCH_1):PAGE270

C2450 Q_CAP_0402-1000PF,50V,5%,EMPTYA
     1 PWRGD_PVCCINFAON_CPU1_R @S9S_MB_2U_LIB.S9S_MB_2U(SCH_1):PWRGD_PVCCINFAON_CPU1_R   I106 @S9S_MB_2U_LIB.S9S_MB_2U(SCH_1):PAGE278
     2    GND @S9S_MB_2U_LIB.S9S_MB_2U(SCH_1):GND   I106 @S9S_MB_2U_LIB.S9S_MB_2U(SCH_1):PAGE278

C2451 Q_CAP_0402-1000PF,50V,5%,X7R,TA
     1 PVCCINFAON_CPU1_EN_R @S9S_MB_2U_LIB.S9S_MB_2U(SCH_1):PVCCINFAON_CPU1_EN_R    I63 @S9S_MB_2U_LIB.S9S_MB_2U(SCH_1):PAGE278
     2    GND @S9S_MB_2U_LIB.S9S_MB_2U(SCH_1):GND    I63 @S9S_MB_2U_LIB.S9S_MB_2U(SCH_1):PAGE278

C2452 Q_CAP_0402-1000PF,50V,5%,X7R,TA
     1 PVCCFA_EHV_CPU1_EN_R @S9S_MB_2U_LIB.S9S_MB_2U(SCH_1):PVCCFA_EHV_CPU1_EN_R    I33 @S9S_MB_2U_LIB.S9S_MB_2U(SCH_1):PAGE278
     2    GND @S9S_MB_2U_LIB.S9S_MB_2U(SCH_1):GND    I33 @S9S_MB_2U_LIB.S9S_MB_2U(SCH_1):PAGE278

C2453 Q_CAP_0402-1000PF,50V,5%,EMPTYA
     1 PWRGD_PVCCFA_EHV_CPU1_R @S9S_MB_2U_LIB.S9S_MB_2U(SCH_1):PWRGD_PVCCFA_EHV_CPU1_R    I32 @S9S_MB_2U_LIB.S9S_MB_2U(SCH_1):PAGE278
     2    GND @S9S_MB_2U_LIB.S9S_MB_2U(SCH_1):GND    I32 @S9S_MB_2U_LIB.S9S_MB_2U(SCH_1):PAGE278

C2454 Q_CAP_0402-1000PF,50V,5%,EMPTYA
     1 PWRGD_PVCCD_HV_CPU1_R @S9S_MB_2U_LIB.S9S_MB_2U(SCH_1):PWRGD_PVCCD_HV_CPU1_R    I45 @S9S_MB_2U_LIB.S9S_MB_2U(SCH_1):PAGE282
     2    GND @S9S_MB_2U_LIB.S9S_MB_2U(SCH_1):GND    I45 @S9S_MB_2U_LIB.S9S_MB_2U(SCH_1):PAGE282

C2458 Q_CAP_0402-0.1UF,25V,10%,EMPTYA
     1 P3V3_AUX @S9S_MB_2U_LIB.S9S_MB_2U(SCH_1):P3V3_AUX     I8 @S9S_MB_2U_LIB.S9S_MB_2U(SCH_1):PAGE327
     2    GND @S9S_MB_2U_LIB.S9S_MB_2U(SCH_1):GND     I8 @S9S_MB_2U_LIB.S9S_MB_2U(SCH_1):PAGE327

C2459 Q_CAP_0603-1000PF,50V,10%,EMPTA
     1 P12V_HSC_TEMP_D+ @S9S_MB_2U_LIB.S9S_MB_2U(SCH_1):P12V_HSC_TEMP_D+     I6 @S9S_MB_2U_LIB.S9S_MB_2U(SCH_1):PAGE327
     2 P12V_HSC_TEMP_D- @S9S_MB_2U_LIB.S9S_MB_2U(SCH_1):P12V_HSC_TEMP_D-     I6 @S9S_MB_2U_LIB.S9S_MB_2U(SCH_1):PAGE327

C2460 Q_CAP_0402-1000PF,50V,5%,X7R,TA
     1 PWRGD_PVPP_HBM_CPU1_R @S9S_MB_2U_LIB.S9S_MB_2U(SCH_1):PWRGD_PVPP_HBM_CPU1_R    I36 @S9S_MB_2U_LIB.S9S_MB_2U(SCH_1):PAGE285
     2    GND @S9S_MB_2U_LIB.S9S_MB_2U(SCH_1):GND    I36 @S9S_MB_2U_LIB.S9S_MB_2U(SCH_1):PAGE285

C2541 Q_CAP_C0402-0.22UF,25V,10%,X7RA
     1 P3V3_AUX_EN @S9S_MB_2U_LIB.S9S_MB_2U(SCH_1):P3V3_AUX_EN    I73 @S9S_MB_2U_LIB.S9S_MB_2U(SCH_1):PAGE245
     2    GND @S9S_MB_2U_LIB.S9S_MB_2U(SCH_1):GND    I73 @S9S_MB_2U_LIB.S9S_MB_2U(SCH_1):PAGE245

C2859 Q_CAP_0402-1000PF,50V,5%,EMPTYA
     1 PWRGD_PVCCIN_CPU1_R @S9S_MB_2U_LIB.S9S_MB_2U(SCH_1):PWRGD_PVCCIN_CPU1_R    I68 @S9S_MB_2U_LIB.S9S_MB_2U(SCH_1):PAGE270
     2    GND @S9S_MB_2U_LIB.S9S_MB_2U(SCH_1):GND    I68 @S9S_MB_2U_LIB.S9S_MB_2U(SCH_1):PAGE270

C2860 Q_CAP_0402-1000PF,50V,5%,X7R,TA
     1 PVCCIN_CPU1_EN_R @S9S_MB_2U_LIB.S9S_MB_2U(SCH_1):PVCCIN_CPU1_EN_R    I67 @S9S_MB_2U_LIB.S9S_MB_2U(SCH_1):PAGE270
     2    GND @S9S_MB_2U_LIB.S9S_MB_2U(SCH_1):GND    I67 @S9S_MB_2U_LIB.S9S_MB_2U(SCH_1):PAGE270

C3266 Q_CAP_0402-1000PF,50V,5%,EMPTYA
     1 PWRGD_PVCCIN_CPU0_R @S9S_MB_2U_LIB.S9S_MB_2U(SCH_1):PWRGD_PVCCIN_CPU0_R    I84 @S9S_MB_2U_LIB.S9S_MB_2U(SCH_1):PAGE252
     2    GND @S9S_MB_2U_LIB.S9S_MB_2U(SCH_1):GND    I84 @S9S_MB_2U_LIB.S9S_MB_2U(SCH_1):PAGE252

C3267 Q_CAP_0402-1000PF,50V,5%,X7R,TA
     1 PVCCIN_CPU0_EN_R @S9S_MB_2U_LIB.S9S_MB_2U(SCH_1):PVCCIN_CPU0_EN_R    I82 @S9S_MB_2U_LIB.S9S_MB_2U(SCH_1):PAGE252
     2    GND @S9S_MB_2U_LIB.S9S_MB_2U(SCH_1):GND    I82 @S9S_MB_2U_LIB.S9S_MB_2U(SCH_1):PAGE252

C3268 Q_CAP_0402-1000PF,50V,5%,X7R,TA
     1 PVCCFA_EHV_FIVRA_CPU0_EN_R @S9S_MB_2U_LIB.S9S_MB_2U(SCH_1):PVCCFA_EHV_FIVRA_CPU0_EN_R    I58 @S9S_MB_2U_LIB.S9S_MB_2U(SCH_1):PAGE252
     2    GND @S9S_MB_2U_LIB.S9S_MB_2U(SCH_1):GND    I58 @S9S_MB_2U_LIB.S9S_MB_2U(SCH_1):PAGE252

C3269 Q_CAP_0402-1000PF,50V,5%,EMPTYA
     1 PWRGD_PVCCFA_EHV_FIVRA_CPU0_R @S9S_MB_2U_LIB.S9S_MB_2U(SCH_1):PWRGD_PVCCFA_EHV_FIVRA_CPU0_R    I57 @S9S_MB_2U_LIB.S9S_MB_2U(SCH_1):PAGE252
     2    GND @S9S_MB_2U_LIB.S9S_MB_2U(SCH_1):GND    I57 @S9S_MB_2U_LIB.S9S_MB_2U(SCH_1):PAGE252

C3270 Q_CAP_C0603-10UF,4V,20%,EMPTY,A
     1 PVNN_TERM_CPU0 @S9S_MB_2U_LIB.S9S_MB_2U(SCH_1):PVNN_TERM_CPU0   I127 @S9S_MB_2U_LIB.S9S_MB_2U(SCH_1):PAGE252
     2    GND @S9S_MB_2U_LIB.S9S_MB_2U(SCH_1):GND   I127 @S9S_MB_2U_LIB.S9S_MB_2U(SCH_1):PAGE252

C3271 Q_CAP_C0402-100NF,50V,10%,X7R,A
     1 PVNN_TERM_CPU0 @S9S_MB_2U_LIB.S9S_MB_2U(SCH_1):PVNN_TERM_CPU0   I128 @S9S_MB_2U_LIB.S9S_MB_2U(SCH_1):PAGE252
     2    GND @S9S_MB_2U_LIB.S9S_MB_2U(SCH_1):GND   I128 @S9S_MB_2U_LIB.S9S_MB_2U(SCH_1):PAGE252

C3273 Q_CAP_0402-1000PF,50V,5%,EMPTYA
     1 PWRGD_PVCCINFAON_CPU0_R @S9S_MB_2U_LIB.S9S_MB_2U(SCH_1):PWRGD_PVCCINFAON_CPU0_R    I61 @S9S_MB_2U_LIB.S9S_MB_2U(SCH_1):PAGE260
     2    GND @S9S_MB_2U_LIB.S9S_MB_2U(SCH_1):GND    I61 @S9S_MB_2U_LIB.S9S_MB_2U(SCH_1):PAGE260

C3274 Q_CAP_0402-1000PF,50V,5%,X7R,TA
     1 PVCCINFAON_CPU0_EN_R @S9S_MB_2U_LIB.S9S_MB_2U(SCH_1):PVCCINFAON_CPU0_EN_R    I60 @S9S_MB_2U_LIB.S9S_MB_2U(SCH_1):PAGE260
     2    GND @S9S_MB_2U_LIB.S9S_MB_2U(SCH_1):GND    I60 @S9S_MB_2U_LIB.S9S_MB_2U(SCH_1):PAGE260

C3275 Q_CAP_0402-1000PF,50V,5%,X7R,TA
     1 PVCCFA_EHV_CPU0_EN_R @S9S_MB_2U_LIB.S9S_MB_2U(SCH_1):PVCCFA_EHV_CPU0_EN_R    I23 @S9S_MB_2U_LIB.S9S_MB_2U(SCH_1):PAGE260
     2    GND @S9S_MB_2U_LIB.S9S_MB_2U(SCH_1):GND    I23 @S9S_MB_2U_LIB.S9S_MB_2U(SCH_1):PAGE260

C3276 Q_CAP_0402-1000PF,50V,5%,EMPTYA
     1 PWRGD_PVCCFA_EHV_CPU0_R @S9S_MB_2U_LIB.S9S_MB_2U(SCH_1):PWRGD_PVCCFA_EHV_CPU0_R    I22 @S9S_MB_2U_LIB.S9S_MB_2U(SCH_1):PAGE260
     2    GND @S9S_MB_2U_LIB.S9S_MB_2U(SCH_1):GND    I22 @S9S_MB_2U_LIB.S9S_MB_2U(SCH_1):PAGE260

C4562 Q_CAP_C0402-1UF,25V,10%,EMPTY,A
     1 U369_VDD @S9S_MB_2U_LIB.S9S_MB_2U(SCH_1):U369_VDD    I91 @S9S_MB_2U_LIB.S9S_MB_2U(SCH_1):PAGE326
     2    GND @S9S_MB_2U_LIB.S9S_MB_2U(SCH_1):GND    I91 @S9S_MB_2U_LIB.S9S_MB_2U(SCH_1):PAGE326

C5229 Q_CAP_C0402-1UF,25V,10%,EMPTY,A
     1 P3V3_AUX @S9S_MB_2U_LIB.S9S_MB_2U(SCH_1):P3V3_AUX    I88 @S9S_MB_2U_LIB.S9S_MB_2U(SCH_1):PAGE155
     2    GND @S9S_MB_2U_LIB.S9S_MB_2U(SCH_1):GND    I88 @S9S_MB_2U_LIB.S9S_MB_2U(SCH_1):PAGE155

C5232 Q_CAP_0402-0.1UF,25V,10%,EMPTYA
     1 PD_U5201_RSTN @S9S_MB_2U_LIB.S9S_MB_2U(SCH_1):PD_U5201_RSTN    I81 @S9S_MB_2U_LIB.S9S_MB_2U(SCH_1):PAGE155
     2    GND @S9S_MB_2U_LIB.S9S_MB_2U(SCH_1):GND    I81 @S9S_MB_2U_LIB.S9S_MB_2U(SCH_1):PAGE155

C5234 Q_CAP_0402-0.1UF,25V,10%,EMPTYA
     1 P3V3_AUX @S9S_MB_2U_LIB.S9S_MB_2U(SCH_1):P3V3_AUX    I92 @S9S_MB_2U_LIB.S9S_MB_2U(SCH_1):PAGE155
     2    GND @S9S_MB_2U_LIB.S9S_MB_2U(SCH_1):GND    I92 @S9S_MB_2U_LIB.S9S_MB_2U(SCH_1):PAGE155

C5236 Q_CAP_0402-0.1UF,25V,10%,EMPTYA
     1 PD_U5201_VREG @S9S_MB_2U_LIB.S9S_MB_2U(SCH_1):PD_U5201_VREG    I87 @S9S_MB_2U_LIB.S9S_MB_2U(SCH_1):PAGE155
     2    GND @S9S_MB_2U_LIB.S9S_MB_2U(SCH_1):GND    I87 @S9S_MB_2U_LIB.S9S_MB_2U(SCH_1):PAGE155

  D0 Q_LED_SMLF-LED_BLUE,LTST-C281TA
     A PU_PLD_HEARTBEAT_LVC3 @S9S_MB_2U_LIB.S9S_MB_2U(SCH_1):PU_PLD_HEARTBEAT_LVC3   I277 @S9S_MB_2U_LIB.S9S_MB_2U(SCH_1):PAGE207
     C FM_PLD_HEARTBEAT_LVC3_D @S9S_MB_2U_LIB.S9S_MB_2U(SCH_1):FM_PLD_HEARTBEAT_LVC3_D   I277 @S9S_MB_2U_LIB.S9S_MB_2U(SCH_1):PAGE207

  D6 Q_LED_SMLF-LED_YELLOW,LTST-C19A
     A LED_CPU_RMCA_CATERR @S9S_MB_2U_LIB.S9S_MB_2U(SCH_1):LED_CPU_RMCA_CATERR   I279 @S9S_MB_2U_LIB.S9S_MB_2U(SCH_1):PAGE207
     C    GND @S9S_MB_2U_LIB.S9S_MB_2U(SCH_1):GND   I279 @S9S_MB_2U_LIB.S9S_MB_2U(SCH_1):PAGE207

  D7 BAT547F-BAT547F,SMLF,IC,BC0BATA
     1   P3V3 @S9S_MB_2U_LIB.S9S_MB_2U(SCH_1):P3V3    I32 @S9S_MB_2U_LIB.S9S_MB_2U(SCH_1):PAGE246
     3    P5V @S9S_MB_2U_LIB.S9S_MB_2U(SCH_1):P5V    I32 @S9S_MB_2U_LIB.S9S_MB_2U(SCH_1):PAGE246

 D42 SCHOTTKY_12-B0530WS7F,SMLF,IC,A
     1 PWRGD_FAIL_CPU0_AB_R1 @S9S_MB_2U_LIB.S9S_MB_2U(SCH_1):PWRGD_FAIL_CPU0_AB_R1    I59 @S9S_MB_2U_LIB.S9S_MB_2U(SCH_1):PAGE115
     2 P3V3_AUX @S9S_MB_2U_LIB.S9S_MB_2U(SCH_1):P3V3_AUX    I59 @S9S_MB_2U_LIB.S9S_MB_2U(SCH_1):PAGE115

 D43 SCHOTTKY_12-B0530WS7F,SMLF,IC,A
     1 PWRGD_FAIL_CPU0_CD_R1 @S9S_MB_2U_LIB.S9S_MB_2U(SCH_1):PWRGD_FAIL_CPU0_CD_R1    I54 @S9S_MB_2U_LIB.S9S_MB_2U(SCH_1):PAGE115
     2 P3V3_AUX @S9S_MB_2U_LIB.S9S_MB_2U(SCH_1):P3V3_AUX    I54 @S9S_MB_2U_LIB.S9S_MB_2U(SCH_1):PAGE115

 D44 SCHOTTKY_12-B0530WS7F,SMLF,IC,A
     1 PWRGD_FAIL_CPU0_EF_R1 @S9S_MB_2U_LIB.S9S_MB_2U(SCH_1):PWRGD_FAIL_CPU0_EF_R1    I52 @S9S_MB_2U_LIB.S9S_MB_2U(SCH_1):PAGE115
     2 P3V3_AUX @S9S_MB_2U_LIB.S9S_MB_2U(SCH_1):P3V3_AUX    I52 @S9S_MB_2U_LIB.S9S_MB_2U(SCH_1):PAGE115

 D45 SCHOTTKY_12-B0530WS7F,SMLF,IC,A
     1 PWRGD_FAIL_CPU0_GH_R1 @S9S_MB_2U_LIB.S9S_MB_2U(SCH_1):PWRGD_FAIL_CPU0_GH_R1    I50 @S9S_MB_2U_LIB.S9S_MB_2U(SCH_1):PAGE115
     2 P3V3_AUX @S9S_MB_2U_LIB.S9S_MB_2U(SCH_1):P3V3_AUX    I50 @S9S_MB_2U_LIB.S9S_MB_2U(SCH_1):PAGE115

 D46 SCHOTTKY_12-B0530WS7F,SMLF,IC,A
     1 PWRGD_FAIL_CPU1_AB_R1 @S9S_MB_2U_LIB.S9S_MB_2U(SCH_1):PWRGD_FAIL_CPU1_AB_R1    I29 @S9S_MB_2U_LIB.S9S_MB_2U(SCH_1):PAGE115
     2 P3V3_AUX @S9S_MB_2U_LIB.S9S_MB_2U(SCH_1):P3V3_AUX    I29 @S9S_MB_2U_LIB.S9S_MB_2U(SCH_1):PAGE115

 D47 SCHOTTKY_12-B0530WS7F,SMLF,IC,A
     1 PWRGD_FAIL_CPU1_CD_R1 @S9S_MB_2U_LIB.S9S_MB_2U(SCH_1):PWRGD_FAIL_CPU1_CD_R1    I27 @S9S_MB_2U_LIB.S9S_MB_2U(SCH_1):PAGE115
     2 P3V3_AUX @S9S_MB_2U_LIB.S9S_MB_2U(SCH_1):P3V3_AUX    I27 @S9S_MB_2U_LIB.S9S_MB_2U(SCH_1):PAGE115

 D48 SCHOTTKY_12-B0530WS7F,SMLF,IC,A
     1 PWRGD_FAIL_CPU1_EF_R1 @S9S_MB_2U_LIB.S9S_MB_2U(SCH_1):PWRGD_FAIL_CPU1_EF_R1    I25 @S9S_MB_2U_LIB.S9S_MB_2U(SCH_1):PAGE115
     2 P3V3_AUX @S9S_MB_2U_LIB.S9S_MB_2U(SCH_1):P3V3_AUX    I25 @S9S_MB_2U_LIB.S9S_MB_2U(SCH_1):PAGE115

 D49 SCHOTTKY_12-B0530WS7F,SMLF,IC,A
     1 PWRGD_FAIL_CPU1_GH_R1 @S9S_MB_2U_LIB.S9S_MB_2U(SCH_1):PWRGD_FAIL_CPU1_GH_R1    I22 @S9S_MB_2U_LIB.S9S_MB_2U(SCH_1):PAGE115
     2 P3V3_AUX @S9S_MB_2U_LIB.S9S_MB_2U(SCH_1):P3V3_AUX    I22 @S9S_MB_2U_LIB.S9S_MB_2U(SCH_1):PAGE115

 D65 Q_LED_SMLF-LED_BLUE,LTST-C281TA
     A LED_RST_PLD_CPU0_DRAM_AB_N @S9S_MB_2U_LIB.S9S_MB_2U(SCH_1):LED_RST_PLD_CPU0_DRAM_AB_N    I21 @S9S_MB_2U_LIB.S9S_MB_2U(SCH_1):PAGE304
     C LED_RST_PLD_CPU0_DRAM_AB_N_D @S9S_MB_2U_LIB.S9S_MB_2U(SCH_1):LED_RST_PLD_CPU0_DRAM_AB_N_D    I21 @S9S_MB_2U_LIB.S9S_MB_2U(SCH_1):PAGE304

 D66 Q_LED_SMLF-LED_BLUE,LTST-C281TA
     A LED_RST_PLD_CPU0_DRAM_CD_N @S9S_MB_2U_LIB.S9S_MB_2U(SCH_1):LED_RST_PLD_CPU0_DRAM_CD_N    I20 @S9S_MB_2U_LIB.S9S_MB_2U(SCH_1):PAGE304
     C LED_RST_PLD_CPU0_DRAM_CD_N_D @S9S_MB_2U_LIB.S9S_MB_2U(SCH_1):LED_RST_PLD_CPU0_DRAM_CD_N_D    I20 @S9S_MB_2U_LIB.S9S_MB_2U(SCH_1):PAGE304

 D67 Q_LED_SMLF-LED_BLUE,LTST-C281TA
     A LED_RST_PLD_CPU0_DRAM_EF_N @S9S_MB_2U_LIB.S9S_MB_2U(SCH_1):LED_RST_PLD_CPU0_DRAM_EF_N    I12 @S9S_MB_2U_LIB.S9S_MB_2U(SCH_1):PAGE304
     C LED_RST_PLD_CPU0_DRAM_EF_N_D @S9S_MB_2U_LIB.S9S_MB_2U(SCH_1):LED_RST_PLD_CPU0_DRAM_EF_N_D    I12 @S9S_MB_2U_LIB.S9S_MB_2U(SCH_1):PAGE304

 D68 Q_LED_SMLF-LED_BLUE,LTST-C281TA
     A LED_RST_PLD_CPU0_DRAM_GH_N @S9S_MB_2U_LIB.S9S_MB_2U(SCH_1):LED_RST_PLD_CPU0_DRAM_GH_N     I9 @S9S_MB_2U_LIB.S9S_MB_2U(SCH_1):PAGE304
     C LED_RST_PLD_CPU0_DRAM_GH_N_D @S9S_MB_2U_LIB.S9S_MB_2U(SCH_1):LED_RST_PLD_CPU0_DRAM_GH_N_D     I9 @S9S_MB_2U_LIB.S9S_MB_2U(SCH_1):PAGE304

 D69 Q_LED_SMLF-LED_BLUE,LTST-C281TA
     A LED_RST_PLD_CPU1_DRAM_AB_N @S9S_MB_2U_LIB.S9S_MB_2U(SCH_1):LED_RST_PLD_CPU1_DRAM_AB_N    I32 @S9S_MB_2U_LIB.S9S_MB_2U(SCH_1):PAGE304
     C LED_RST_PLD_CPU1_DRAM_AB_N_D @S9S_MB_2U_LIB.S9S_MB_2U(SCH_1):LED_RST_PLD_CPU1_DRAM_AB_N_D    I32 @S9S_MB_2U_LIB.S9S_MB_2U(SCH_1):PAGE304

 D70 Q_LED_SMLF-LED_BLUE,LTST-C281TA
     A LED_RST_PLD_CPU1_DRAM_CD_N @S9S_MB_2U_LIB.S9S_MB_2U(SCH_1):LED_RST_PLD_CPU1_DRAM_CD_N    I31 @S9S_MB_2U_LIB.S9S_MB_2U(SCH_1):PAGE304
     C LED_RST_PLD_CPU1_DRAM_CD_N_D @S9S_MB_2U_LIB.S9S_MB_2U(SCH_1):LED_RST_PLD_CPU1_DRAM_CD_N_D    I31 @S9S_MB_2U_LIB.S9S_MB_2U(SCH_1):PAGE304

 D71 Q_LED_SMLF-LED_BLUE,LTST-C281TA
     A LED_RST_PLD_CPU1_DRAM_EF_N @S9S_MB_2U_LIB.S9S_MB_2U(SCH_1):LED_RST_PLD_CPU1_DRAM_EF_N    I58 @S9S_MB_2U_LIB.S9S_MB_2U(SCH_1):PAGE304
     C LED_RST_PLD_CPU1_DRAM_EF_N_D @S9S_MB_2U_LIB.S9S_MB_2U(SCH_1):LED_RST_PLD_CPU1_DRAM_EF_N_D    I58 @S9S_MB_2U_LIB.S9S_MB_2U(SCH_1):PAGE304

 D72 Q_LED_SMLF-LED_BLUE,LTST-C281TA
     A LED_RST_PLD_CPU1_DRAM_GH_N @S9S_MB_2U_LIB.S9S_MB_2U(SCH_1):LED_RST_PLD_CPU1_DRAM_GH_N    I63 @S9S_MB_2U_LIB.S9S_MB_2U(SCH_1):PAGE304
     C LED_RST_PLD_CPU1_DRAM_GH_N_D @S9S_MB_2U_LIB.S9S_MB_2U(SCH_1):LED_RST_PLD_CPU1_DRAM_GH_N_D    I63 @S9S_MB_2U_LIB.S9S_MB_2U(SCH_1):PAGE304

 D73 Q_LED_SMLF-LED_BLUE,LTST-C281TA
     A LED_PWRGD_PVCCD_HV_CPU0 @S9S_MB_2U_LIB.S9S_MB_2U(SCH_1):LED_PWRGD_PVCCD_HV_CPU0    I22 @S9S_MB_2U_LIB.S9S_MB_2U(SCH_1):PAGE305
     C LED_PWRGD_PVCCD_HV_CPU0_D @S9S_MB_2U_LIB.S9S_MB_2U(SCH_1):LED_PWRGD_PVCCD_HV_CPU0_D    I22 @S9S_MB_2U_LIB.S9S_MB_2U(SCH_1):PAGE305

 D74 Q_LED_SMLF-LED_BLUE,LTST-C281TA
     A LED_PWRGD_PVPP_HBM_CPU0 @S9S_MB_2U_LIB.S9S_MB_2U(SCH_1):LED_PWRGD_PVPP_HBM_CPU0    I21 @S9S_MB_2U_LIB.S9S_MB_2U(SCH_1):PAGE305
     C LED_PWRGD_PVPP_HBM_CPU0_D @S9S_MB_2U_LIB.S9S_MB_2U(SCH_1):LED_PWRGD_PVPP_HBM_CPU0_D    I21 @S9S_MB_2U_LIB.S9S_MB_2U(SCH_1):PAGE305

 D75 Q_LED_SMLF-LED_BLUE,LTST-C281TA
     A LED_PWRGD_PVCCFA_EHV_CPU0 @S9S_MB_2U_LIB.S9S_MB_2U(SCH_1):LED_PWRGD_PVCCFA_EHV_CPU0    I13 @S9S_MB_2U_LIB.S9S_MB_2U(SCH_1):PAGE305
     C LED_PWRGD_PVCCFA_EHV_CPU0_D @S9S_MB_2U_LIB.S9S_MB_2U(SCH_1):LED_PWRGD_PVCCFA_EHV_CPU0_D    I13 @S9S_MB_2U_LIB.S9S_MB_2U(SCH_1):PAGE305

 D76 Q_LED_SMLF-LED_BLUE,LTST-C281TA
     A LED_PWRGD_PVCCFA_EHV_FIVRA_CPU0 @S9S_MB_2U_LIB.S9S_MB_2U(SCH_1):LED_PWRGD_PVCCFA_EHV_FIVRA_CPU0    I10 @S9S_MB_2U_LIB.S9S_MB_2U(SCH_1):PAGE305
     C LED_PWRGD_PVCCFA_EHV_FIVRA_CP_1 @S9S_MB_2U_LIB.S9S_MB_2U(SCH_1):LED_PWRGD_PVCCFA_EHV_FIVRA_CPU0_D    I10 @S9S_MB_2U_LIB.S9S_MB_2U(SCH_1):PAGE305

 D77 Q_LED_SMLF-LED_BLUE,LTST-C281TA
     A LED_PWRGD_PVCCINFAON_CPU0 @S9S_MB_2U_LIB.S9S_MB_2U(SCH_1):LED_PWRGD_PVCCINFAON_CPU0    I44 @S9S_MB_2U_LIB.S9S_MB_2U(SCH_1):PAGE305
     C LED_PWRGD_PVCCINFAON_CPU0_D @S9S_MB_2U_LIB.S9S_MB_2U(SCH_1):LED_PWRGD_PVCCINFAON_CPU0_D    I44 @S9S_MB_2U_LIB.S9S_MB_2U(SCH_1):PAGE305

 D78 Q_LED_SMLF-LED_BLUE,LTST-C281TA
     A LED_PWRGD_PVNN_MAIN_CPU0 @S9S_MB_2U_LIB.S9S_MB_2U(SCH_1):LED_PWRGD_PVNN_MAIN_CPU0    I43 @S9S_MB_2U_LIB.S9S_MB_2U(SCH_1):PAGE305
     C LED_PWRGD_PVNN_MAIN_CPU0_D @S9S_MB_2U_LIB.S9S_MB_2U(SCH_1):LED_PWRGD_PVNN_MAIN_CPU0_D    I43 @S9S_MB_2U_LIB.S9S_MB_2U(SCH_1):PAGE305

 D79 Q_LED_SMLF-LED_BLUE,LTST-C281TA
     A LED_PWRGD_PVCCIN_CPU0 @S9S_MB_2U_LIB.S9S_MB_2U(SCH_1):LED_PWRGD_PVCCIN_CPU0    I35 @S9S_MB_2U_LIB.S9S_MB_2U(SCH_1):PAGE305
     C LED_PWRGD_PVCCIN_CPU0_D @S9S_MB_2U_LIB.S9S_MB_2U(SCH_1):LED_PWRGD_PVCCIN_CPU0_D    I35 @S9S_MB_2U_LIB.S9S_MB_2U(SCH_1):PAGE305

 D80 Q_LED_SMLF-LED_BLUE,LTST-C281TA
     A LED_PWRGD_PVCCD_HV_CPU1 @S9S_MB_2U_LIB.S9S_MB_2U(SCH_1):LED_PWRGD_PVCCD_HV_CPU1    I19 @S9S_MB_2U_LIB.S9S_MB_2U(SCH_1):PAGE306
     C LED_PWRGD_PVCCD_HV_CPU1_D @S9S_MB_2U_LIB.S9S_MB_2U(SCH_1):LED_PWRGD_PVCCD_HV_CPU1_D    I19 @S9S_MB_2U_LIB.S9S_MB_2U(SCH_1):PAGE306

 D81 Q_LED_SMLF-LED_BLUE,LTST-C281TA
     A LED_PWRGD_PVPP_HBM_CPU1 @S9S_MB_2U_LIB.S9S_MB_2U(SCH_1):LED_PWRGD_PVPP_HBM_CPU1    I14 @S9S_MB_2U_LIB.S9S_MB_2U(SCH_1):PAGE306
     C LED_PWRGD_PVPP_HBM_CPU1_D @S9S_MB_2U_LIB.S9S_MB_2U(SCH_1):LED_PWRGD_PVPP_HBM_CPU1_D    I14 @S9S_MB_2U_LIB.S9S_MB_2U(SCH_1):PAGE306

 D82 Q_LED_SMLF-LED_BLUE,LTST-C281TA
     A LED_PWRGD_PVCCFA_EHV_CPU1 @S9S_MB_2U_LIB.S9S_MB_2U(SCH_1):LED_PWRGD_PVCCFA_EHV_CPU1    I13 @S9S_MB_2U_LIB.S9S_MB_2U(SCH_1):PAGE306
     C LED_PWRGD_PVCCFA_EHV_CPU1_D @S9S_MB_2U_LIB.S9S_MB_2U(SCH_1):LED_PWRGD_PVCCFA_EHV_CPU1_D    I13 @S9S_MB_2U_LIB.S9S_MB_2U(SCH_1):PAGE306

 D83 Q_LED_SMLF-LED_BLUE,LTST-C281TA
     A LED_PWRGD_PVCCFA_EHV_FIVRA_CPU1 @S9S_MB_2U_LIB.S9S_MB_2U(SCH_1):LED_PWRGD_PVCCFA_EHV_FIVRA_CPU1    I11 @S9S_MB_2U_LIB.S9S_MB_2U(SCH_1):PAGE306
     C LED_PWRGD_PVCCFA_EHV_FIVRA_CP_2 @S9S_MB_2U_LIB.S9S_MB_2U(SCH_1):LED_PWRGD_PVCCFA_EHV_FIVRA_CPU1_D    I11 @S9S_MB_2U_LIB.S9S_MB_2U(SCH_1):PAGE306

 D84 Q_LED_SMLF-LED_BLUE,LTST-C281TA
     A LED_PWRGD_PVCCINFAON_CPU1 @S9S_MB_2U_LIB.S9S_MB_2U(SCH_1):LED_PWRGD_PVCCINFAON_CPU1    I36 @S9S_MB_2U_LIB.S9S_MB_2U(SCH_1):PAGE306
     C LED_PWRGD_PVCCINFAON_CPU1_D @S9S_MB_2U_LIB.S9S_MB_2U(SCH_1):LED_PWRGD_PVCCINFAON_CPU1_D    I36 @S9S_MB_2U_LIB.S9S_MB_2U(SCH_1):PAGE306

 D85 Q_LED_SMLF-LED_BLUE,LTST-C281TA
     A LED_PWRGD_PVNN_MAIN_CPU1 @S9S_MB_2U_LIB.S9S_MB_2U(SCH_1):LED_PWRGD_PVNN_MAIN_CPU1    I32 @S9S_MB_2U_LIB.S9S_MB_2U(SCH_1):PAGE306
     C LED_PWRGD_PVNN_MAIN_CPU1_D @S9S_MB_2U_LIB.S9S_MB_2U(SCH_1):LED_PWRGD_PVNN_MAIN_CPU1_D    I32 @S9S_MB_2U_LIB.S9S_MB_2U(SCH_1):PAGE306

 D86 Q_LED_SMLF-LED_BLUE,LTST-C281TA
     A LED_PWRGD_PVCCIN_CPU1 @S9S_MB_2U_LIB.S9S_MB_2U(SCH_1):LED_PWRGD_PVCCIN_CPU1    I30 @S9S_MB_2U_LIB.S9S_MB_2U(SCH_1):PAGE306
     C LED_PWRGD_PVCCIN_CPU1_D @S9S_MB_2U_LIB.S9S_MB_2U(SCH_1):LED_PWRGD_PVCCIN_CPU1_D    I30 @S9S_MB_2U_LIB.S9S_MB_2U(SCH_1):PAGE306

 D87 Q_LED_SMLF-LED_BLUE,LTST-C281TA
     A LED_PWRGD_PCH_PWROK_R @S9S_MB_2U_LIB.S9S_MB_2U(SCH_1):LED_PWRGD_PCH_PWROK_R    I20 @S9S_MB_2U_LIB.S9S_MB_2U(SCH_1):PAGE241
     C LED_PWRGD_PCH_PWROK_R_D @S9S_MB_2U_LIB.S9S_MB_2U(SCH_1):LED_PWRGD_PCH_PWROK_R_D    I20 @S9S_MB_2U_LIB.S9S_MB_2U(SCH_1):PAGE241

 D88 Q_LED_SMLF-LED_BLUE,LTST-C281TA
     A LED_PWRGD_SYS_PWROK_R @S9S_MB_2U_LIB.S9S_MB_2U(SCH_1):LED_PWRGD_SYS_PWROK_R    I19 @S9S_MB_2U_LIB.S9S_MB_2U(SCH_1):PAGE241
     C LED_PWRGD_SYS_PWROK_R_D @S9S_MB_2U_LIB.S9S_MB_2U(SCH_1):LED_PWRGD_SYS_PWROK_R_D    I19 @S9S_MB_2U_LIB.S9S_MB_2U(SCH_1):PAGE241

 D89 Q_LED_SMLF-LED_BLUE,LTST-C281TA
     A LED_PWRGD_CPUPWRGD_GTL @S9S_MB_2U_LIB.S9S_MB_2U(SCH_1):LED_PWRGD_CPUPWRGD_GTL    I11 @S9S_MB_2U_LIB.S9S_MB_2U(SCH_1):PAGE241
     C LED_PWRGD_CPUPWRGD_GTL_D @S9S_MB_2U_LIB.S9S_MB_2U(SCH_1):LED_PWRGD_CPUPWRGD_GTL_D    I11 @S9S_MB_2U_LIB.S9S_MB_2U(SCH_1):PAGE241

 D90 Q_LED_SMLF-LED_BLUE,LTST-C281TA
     A LED_RST_PLTRST_N @S9S_MB_2U_LIB.S9S_MB_2U(SCH_1):LED_RST_PLTRST_N    I33 @S9S_MB_2U_LIB.S9S_MB_2U(SCH_1):PAGE241
     C LED_RST_PLTRST_N_D @S9S_MB_2U_LIB.S9S_MB_2U(SCH_1):LED_RST_PLTRST_N_D    I33 @S9S_MB_2U_LIB.S9S_MB_2U(SCH_1):PAGE241

 D91 Q_LED_SMLF-LED_BLUE,LTST-C281TA
     A LED_PWRGD_P1V8_PCH_AUX @S9S_MB_2U_LIB.S9S_MB_2U(SCH_1):LED_PWRGD_P1V8_PCH_AUX    I18 @S9S_MB_2U_LIB.S9S_MB_2U(SCH_1):PAGE242
     C LED_PWRGD_P1V8_PCH_AUX_D @S9S_MB_2U_LIB.S9S_MB_2U(SCH_1):LED_PWRGD_P1V8_PCH_AUX_D    I18 @S9S_MB_2U_LIB.S9S_MB_2U(SCH_1):PAGE242

 D92 Q_LED_SMLF-LED_BLUE,LTST-C281TA
     A LED_PWRGD_P1V05_PCH_AUX @S9S_MB_2U_LIB.S9S_MB_2U(SCH_1):LED_PWRGD_P1V05_PCH_AUX    I42 @S9S_MB_2U_LIB.S9S_MB_2U(SCH_1):PAGE242
     C LED_PWRGD_P1V05_PCH_AUX_D @S9S_MB_2U_LIB.S9S_MB_2U(SCH_1):LED_PWRGD_P1V05_PCH_AUX_D    I42 @S9S_MB_2U_LIB.S9S_MB_2U(SCH_1):PAGE242

 D93 Q_LED_SMLF-LED_BLUE,LTST-C281TA
     A LED_RST_RSMRST_PLD_R_N @S9S_MB_2U_LIB.S9S_MB_2U(SCH_1):LED_RST_RSMRST_PLD_R_N    I13 @S9S_MB_2U_LIB.S9S_MB_2U(SCH_1):PAGE242
     C LED_RST_RSMRST_PLD_R_N_D @S9S_MB_2U_LIB.S9S_MB_2U(SCH_1):LED_RST_RSMRST_PLD_R_N_D    I13 @S9S_MB_2U_LIB.S9S_MB_2U(SCH_1):PAGE242

 D94 Q_LED_SMLF-LED_BLUE,LTST-C281TA
     A LED_FM_PCH_SLP_S4_N @S9S_MB_2U_LIB.S9S_MB_2U(SCH_1):LED_FM_PCH_SLP_S4_N    I11 @S9S_MB_2U_LIB.S9S_MB_2U(SCH_1):PAGE242
     C LED_FM_PCH_SLP_S4_N_D @S9S_MB_2U_LIB.S9S_MB_2U(SCH_1):LED_FM_PCH_SLP_S4_N_D    I11 @S9S_MB_2U_LIB.S9S_MB_2U(SCH_1):PAGE242

 D95 Q_LED_SMLF-LED_BLUE,LTST-C281TA
     A LED_FM_PCH_SLP_S3_N @S9S_MB_2U_LIB.S9S_MB_2U(SCH_1):LED_FM_PCH_SLP_S3_N    I35 @S9S_MB_2U_LIB.S9S_MB_2U(SCH_1):PAGE242
     C LED_FM_PCH_SLP_S3_N_D @S9S_MB_2U_LIB.S9S_MB_2U(SCH_1):LED_FM_PCH_SLP_S3_N_D    I35 @S9S_MB_2U_LIB.S9S_MB_2U(SCH_1):PAGE242

 D96 Q_LED_SMLF-LED_BLUE,LTST-C281TA
     A LED_PWRGD_PS_PWROK_PLD @S9S_MB_2U_LIB.S9S_MB_2U(SCH_1):LED_PWRGD_PS_PWROK_PLD    I31 @S9S_MB_2U_LIB.S9S_MB_2U(SCH_1):PAGE242
     C LED_PWRGD_PS_PWROK_PLD_D @S9S_MB_2U_LIB.S9S_MB_2U(SCH_1):LED_PWRGD_PS_PWROK_PLD_D    I31 @S9S_MB_2U_LIB.S9S_MB_2U(SCH_1):PAGE242

 D97 Q_LED_SMLF-LED_BLUE,LTST-C281TA
     A LED_P5V_AUX @S9S_MB_2U_LIB.S9S_MB_2U(SCH_1):LED_P5V_AUX    I52 @S9S_MB_2U_LIB.S9S_MB_2U(SCH_1):PAGE242
     C    GND @S9S_MB_2U_LIB.S9S_MB_2U(SCH_1):GND    I52 @S9S_MB_2U_LIB.S9S_MB_2U(SCH_1):PAGE242

 D98 Q_LED_SMLF-LED_BLUE,LTST-C281TA
     A LED_P5V @S9S_MB_2U_LIB.S9S_MB_2U(SCH_1):LED_P5V    I53 @S9S_MB_2U_LIB.S9S_MB_2U(SCH_1):PAGE242
     C    GND @S9S_MB_2U_LIB.S9S_MB_2U(SCH_1):GND    I53 @S9S_MB_2U_LIB.S9S_MB_2U(SCH_1):PAGE242

 D99 Q_LED_SMLF-LED_BLUE,LTST-C281TA
     A LED_P3V3 @S9S_MB_2U_LIB.S9S_MB_2U(SCH_1):LED_P3V3    I60 @S9S_MB_2U_LIB.S9S_MB_2U(SCH_1):PAGE242
     C    GND @S9S_MB_2U_LIB.S9S_MB_2U(SCH_1):GND    I60 @S9S_MB_2U_LIB.S9S_MB_2U(SCH_1):PAGE242

D141 SCHOTTKY_12-1N5819HW,SMLF,IC,BA
     1 P3V3_AUX @S9S_MB_2U_LIB.S9S_MB_2U(SCH_1):P3V3_AUX    I91 @S9S_MB_2U_LIB.S9S_MB_2U(SCH_1):PAGE210
     2 P3V3_AUX_BMC_D @S9S_MB_2U_LIB.S9S_MB_2U(SCH_1):P3V3_AUX_BMC_D    I91 @S9S_MB_2U_LIB.S9S_MB_2U(SCH_1):PAGE210

D142 Q_LED_SMLF-LED_BLUE,LTST-C281TA
     A LED_P12V_AUX_R1 @S9S_MB_2U_LIB.S9S_MB_2U(SCH_1):LED_P12V_AUX_R1    I58 @S9S_MB_2U_LIB.S9S_MB_2U(SCH_1):PAGE241
     C    GND @S9S_MB_2U_LIB.S9S_MB_2U(SCH_1):GND    I58 @S9S_MB_2U_LIB.S9S_MB_2U(SCH_1):PAGE241

D143 Q_LED_SMLF-LED_BLUE,LTST-C281TA
     A LED_P12V_PSU_R1 @S9S_MB_2U_LIB.S9S_MB_2U(SCH_1):LED_P12V_PSU_R1    I49 @S9S_MB_2U_LIB.S9S_MB_2U(SCH_1):PAGE241
     C    GND @S9S_MB_2U_LIB.S9S_MB_2U(SCH_1):GND    I49 @S9S_MB_2U_LIB.S9S_MB_2U(SCH_1):PAGE241

D144 Q_LED_SMLF-LED_YELLOW,LTST-C19A
     A LED_P12V_SCM_FAULT @S9S_MB_2U_LIB.S9S_MB_2U(SCH_1):LED_P12V_SCM_FAULT    I67 @S9S_MB_2U_LIB.S9S_MB_2U(SCH_1):PAGE241
     C LED_P12V_SCM_FAULT_D2 @S9S_MB_2U_LIB.S9S_MB_2U(SCH_1):LED_P12V_SCM_FAULT_D2    I67 @S9S_MB_2U_LIB.S9S_MB_2U(SCH_1):PAGE241

D145 Q_DIODE_SMLF-SDMK0340L-7-F,IC,A
     1 MB0_P12V_STBY_PWRGD @S9S_MB_2U_LIB.S9S_MB_2U(SCH_1):MB0_P12V_STBY_PWRGD    I71 @S9S_MB_2U_LIB.S9S_MB_2U(SCH_1):PAGE245
     2 P3V3_AUX_EN @S9S_MB_2U_LIB.S9S_MB_2U(SCH_1):P3V3_AUX_EN    I71 @S9S_MB_2U_LIB.S9S_MB_2U(SCH_1):PAGE245

 DB1 TDR_3P_TH2-EMPTY,N_A
     1 T1_GND @S9S_MB_2U_LIB.S9S_MB_2U(SCH_1):T1_GND    I61 @S9S_MB_2U_LIB.S9S_MB_2U(SCH_1):PAGE288
     2 TDR_SE_40_OHM_TOP @S9S_MB_2U_LIB.S9S_MB_2U(SCH_1):TDR_SE_40_OHM_TOP    I61 @S9S_MB_2U_LIB.S9S_MB_2U(SCH_1):PAGE288
     3 TDR_SE_40_OHM_TOP @S9S_MB_2U_LIB.S9S_MB_2U(SCH_1):TDR_SE_40_OHM_TOP    I61 @S9S_MB_2U_LIB.S9S_MB_2U(SCH_1):PAGE288

 DB2 TDR_3P_TH2-EMPTY,N_A
     1 T1_GND @S9S_MB_2U_LIB.S9S_MB_2U(SCH_1):T1_GND    I62 @S9S_MB_2U_LIB.S9S_MB_2U(SCH_1):PAGE288
     2 TDR_SE_40_OHM_IN1 @S9S_MB_2U_LIB.S9S_MB_2U(SCH_1):TDR_SE_40_OHM_IN1    I62 @S9S_MB_2U_LIB.S9S_MB_2U(SCH_1):PAGE288
     3 TDR_SE_40_OHM_IN1 @S9S_MB_2U_LIB.S9S_MB_2U(SCH_1):TDR_SE_40_OHM_IN1    I62 @S9S_MB_2U_LIB.S9S_MB_2U(SCH_1):PAGE288

 DB3 TDR_3P_TH2-EMPTY,N_A
     1 T1_GND @S9S_MB_2U_LIB.S9S_MB_2U(SCH_1):T1_GND    I63 @S9S_MB_2U_LIB.S9S_MB_2U(SCH_1):PAGE288
     2 TDR_SE_40_OHM_IN2 @S9S_MB_2U_LIB.S9S_MB_2U(SCH_1):TDR_SE_40_OHM_IN2    I63 @S9S_MB_2U_LIB.S9S_MB_2U(SCH_1):PAGE288
     3 TDR_SE_40_OHM_IN2 @S9S_MB_2U_LIB.S9S_MB_2U(SCH_1):TDR_SE_40_OHM_IN2    I63 @S9S_MB_2U_LIB.S9S_MB_2U(SCH_1):PAGE288

 DB4 TDR_3P_TH2-EMPTY,N_A
     1 T1_GND @S9S_MB_2U_LIB.S9S_MB_2U(SCH_1):T1_GND    I67 @S9S_MB_2U_LIB.S9S_MB_2U(SCH_1):PAGE288
     2 TDR_SE_40_OHM_IN3 @S9S_MB_2U_LIB.S9S_MB_2U(SCH_1):TDR_SE_40_OHM_IN3    I67 @S9S_MB_2U_LIB.S9S_MB_2U(SCH_1):PAGE288
     3 TDR_SE_40_OHM_IN3 @S9S_MB_2U_LIB.S9S_MB_2U(SCH_1):TDR_SE_40_OHM_IN3    I67 @S9S_MB_2U_LIB.S9S_MB_2U(SCH_1):PAGE288

 DB5 TDR_3P_TH2-EMPTY,N_A
     1 T1_GND @S9S_MB_2U_LIB.S9S_MB_2U(SCH_1):T1_GND    I68 @S9S_MB_2U_LIB.S9S_MB_2U(SCH_1):PAGE288
     2 TDR_SE_40_OHM_IN4 @S9S_MB_2U_LIB.S9S_MB_2U(SCH_1):TDR_SE_40_OHM_IN4    I68 @S9S_MB_2U_LIB.S9S_MB_2U(SCH_1):PAGE288
     3 TDR_SE_40_OHM_IN4 @S9S_MB_2U_LIB.S9S_MB_2U(SCH_1):TDR_SE_40_OHM_IN4    I68 @S9S_MB_2U_LIB.S9S_MB_2U(SCH_1):PAGE288

 DB6 TDR_3P_TH2-EMPTY,N_A
     1 T1_GND @S9S_MB_2U_LIB.S9S_MB_2U(SCH_1):T1_GND    I69 @S9S_MB_2U_LIB.S9S_MB_2U(SCH_1):PAGE288
     2 TDR_SE_40_OHM_BOT @S9S_MB_2U_LIB.S9S_MB_2U(SCH_1):TDR_SE_40_OHM_BOT    I69 @S9S_MB_2U_LIB.S9S_MB_2U(SCH_1):PAGE288
     3 TDR_SE_40_OHM_BOT @S9S_MB_2U_LIB.S9S_MB_2U(SCH_1):TDR_SE_40_OHM_BOT    I69 @S9S_MB_2U_LIB.S9S_MB_2U(SCH_1):PAGE288

 DB7 TDR_3P_TH2-EMPTY,N_A
     1 T1_GND @S9S_MB_2U_LIB.S9S_MB_2U(SCH_1):T1_GND    I49 @S9S_MB_2U_LIB.S9S_MB_2U(SCH_1):PAGE288
     2 TDR_SE_50_OHM_TOP @S9S_MB_2U_LIB.S9S_MB_2U(SCH_1):TDR_SE_50_OHM_TOP    I49 @S9S_MB_2U_LIB.S9S_MB_2U(SCH_1):PAGE288
     3 TDR_SE_50_OHM_TOP @S9S_MB_2U_LIB.S9S_MB_2U(SCH_1):TDR_SE_50_OHM_TOP    I49 @S9S_MB_2U_LIB.S9S_MB_2U(SCH_1):PAGE288

 DB8 TDR_3P_TH2-EMPTY,N_A
     1 T1_GND @S9S_MB_2U_LIB.S9S_MB_2U(SCH_1):T1_GND    I51 @S9S_MB_2U_LIB.S9S_MB_2U(SCH_1):PAGE288
     2 TDR_SE_50_OHM_IN1 @S9S_MB_2U_LIB.S9S_MB_2U(SCH_1):TDR_SE_50_OHM_IN1    I51 @S9S_MB_2U_LIB.S9S_MB_2U(SCH_1):PAGE288
     3 TDR_SE_50_OHM_IN1 @S9S_MB_2U_LIB.S9S_MB_2U(SCH_1):TDR_SE_50_OHM_IN1    I51 @S9S_MB_2U_LIB.S9S_MB_2U(SCH_1):PAGE288

 DB9 TDR_3P_TH2-EMPTY,N_A
     1 T1_GND @S9S_MB_2U_LIB.S9S_MB_2U(SCH_1):T1_GND    I53 @S9S_MB_2U_LIB.S9S_MB_2U(SCH_1):PAGE288
     2 TDR_SE_50_OHM_IN2 @S9S_MB_2U_LIB.S9S_MB_2U(SCH_1):TDR_SE_50_OHM_IN2    I53 @S9S_MB_2U_LIB.S9S_MB_2U(SCH_1):PAGE288
     3 TDR_SE_50_OHM_IN2 @S9S_MB_2U_LIB.S9S_MB_2U(SCH_1):TDR_SE_50_OHM_IN2    I53 @S9S_MB_2U_LIB.S9S_MB_2U(SCH_1):PAGE288

DB10 TDR_3P_TH2-EMPTY,N_A
     1 T1_GND @S9S_MB_2U_LIB.S9S_MB_2U(SCH_1):T1_GND    I55 @S9S_MB_2U_LIB.S9S_MB_2U(SCH_1):PAGE288
     2 TDR_SE_50_OHM_IN3 @S9S_MB_2U_LIB.S9S_MB_2U(SCH_1):TDR_SE_50_OHM_IN3    I55 @S9S_MB_2U_LIB.S9S_MB_2U(SCH_1):PAGE288
     3 TDR_SE_50_OHM_IN3 @S9S_MB_2U_LIB.S9S_MB_2U(SCH_1):TDR_SE_50_OHM_IN3    I55 @S9S_MB_2U_LIB.S9S_MB_2U(SCH_1):PAGE288

DB11 TDR_3P_TH2-EMPTY,N_A
     1 T1_GND @S9S_MB_2U_LIB.S9S_MB_2U(SCH_1):T1_GND    I57 @S9S_MB_2U_LIB.S9S_MB_2U(SCH_1):PAGE288
     2 TDR_SE_50_OHM_IN4 @S9S_MB_2U_LIB.S9S_MB_2U(SCH_1):TDR_SE_50_OHM_IN4    I57 @S9S_MB_2U_LIB.S9S_MB_2U(SCH_1):PAGE288
     3 TDR_SE_50_OHM_IN4 @S9S_MB_2U_LIB.S9S_MB_2U(SCH_1):TDR_SE_50_OHM_IN4    I57 @S9S_MB_2U_LIB.S9S_MB_2U(SCH_1):PAGE288

DB12 TDR_3P_TH2-EMPTY,N_A
     1 T1_GND @S9S_MB_2U_LIB.S9S_MB_2U(SCH_1):T1_GND    I60 @S9S_MB_2U_LIB.S9S_MB_2U(SCH_1):PAGE288
     2 TDR_SE_50_OHM_BOT @S9S_MB_2U_LIB.S9S_MB_2U(SCH_1):TDR_SE_50_OHM_BOT    I60 @S9S_MB_2U_LIB.S9S_MB_2U(SCH_1):PAGE288
     3 TDR_SE_50_OHM_BOT @S9S_MB_2U_LIB.S9S_MB_2U(SCH_1):TDR_SE_50_OHM_BOT    I60 @S9S_MB_2U_LIB.S9S_MB_2U(SCH_1):PAGE288

DB13 TDR_3P_TH2-EMPTY,N_A
     1 T1_GND @S9S_MB_2U_LIB.S9S_MB_2U(SCH_1):T1_GND   I101 @S9S_MB_2U_LIB.S9S_MB_2U(SCH_1):PAGE288
     2 TDR_SE_40_OHM_IN5 @S9S_MB_2U_LIB.S9S_MB_2U(SCH_1):TDR_SE_40_OHM_IN5   I101 @S9S_MB_2U_LIB.S9S_MB_2U(SCH_1):PAGE288
     3 TDR_SE_40_OHM_IN5 @S9S_MB_2U_LIB.S9S_MB_2U(SCH_1):TDR_SE_40_OHM_IN5   I101 @S9S_MB_2U_LIB.S9S_MB_2U(SCH_1):PAGE288

DB14 TDR_3P_TH2-EMPTY,N_A
     1 T1_GND @S9S_MB_2U_LIB.S9S_MB_2U(SCH_1):T1_GND    I96 @S9S_MB_2U_LIB.S9S_MB_2U(SCH_1):PAGE288
     2 TDR_SE_40_OHM_IN6 @S9S_MB_2U_LIB.S9S_MB_2U(SCH_1):TDR_SE_40_OHM_IN6    I96 @S9S_MB_2U_LIB.S9S_MB_2U(SCH_1):PAGE288
     3 TDR_SE_40_OHM_IN6 @S9S_MB_2U_LIB.S9S_MB_2U(SCH_1):TDR_SE_40_OHM_IN6    I96 @S9S_MB_2U_LIB.S9S_MB_2U(SCH_1):PAGE288

DB15 TDR_3P_TH2-EMPTY,N_A
     1 T1_GND @S9S_MB_2U_LIB.S9S_MB_2U(SCH_1):T1_GND    I97 @S9S_MB_2U_LIB.S9S_MB_2U(SCH_1):PAGE288
     2 TDR_SE_50_OHM_IN5 @S9S_MB_2U_LIB.S9S_MB_2U(SCH_1):TDR_SE_50_OHM_IN5    I97 @S9S_MB_2U_LIB.S9S_MB_2U(SCH_1):PAGE288
     3 TDR_SE_50_OHM_IN5 @S9S_MB_2U_LIB.S9S_MB_2U(SCH_1):TDR_SE_50_OHM_IN5    I97 @S9S_MB_2U_LIB.S9S_MB_2U(SCH_1):PAGE288

DB16 TDR_3P_TH2-EMPTY,N_A
     1 T1_GND @S9S_MB_2U_LIB.S9S_MB_2U(SCH_1):T1_GND    I99 @S9S_MB_2U_LIB.S9S_MB_2U(SCH_1):PAGE288
     2 TDR_SE_50_OHM_IN6 @S9S_MB_2U_LIB.S9S_MB_2U(SCH_1):TDR_SE_50_OHM_IN6    I99 @S9S_MB_2U_LIB.S9S_MB_2U(SCH_1):PAGE288
     3 TDR_SE_50_OHM_IN6 @S9S_MB_2U_LIB.S9S_MB_2U(SCH_1):TDR_SE_50_OHM_IN6    I99 @S9S_MB_2U_LIB.S9S_MB_2U(SCH_1):PAGE288

 DM9 DUMMY_SYMBOL-MECHANIC_SYMBOL,MA
     1     NC     NC    I23 @S9S_MB_2U_LIB.S9S_MB_2U(SCH_1):PAGE290

DM13 DUMMY_SYMBOL-BATTERY_SYMBOL,MEA
     1     NC     NC    I17 @S9S_MB_2U_LIB.S9S_MB_2U(SCH_1):PAGE290

 FS1 Q_FUSE_SMLF-20A/125V,IC,DKK00XA
     1 P12V_PSU @S9S_MB_2U_LIB.S9S_MB_2U(SCH_1):P12V_PSU    I54 @S9S_MB_2U_LIB.S9S_MB_2U(SCH_1):PAGE328
     2 P12V_PSU_FUSE @S9S_MB_2U_LIB.S9S_MB_2U(SCH_1):P12V_PSU_FUSE    I54 @S9S_MB_2U_LIB.S9S_MB_2U(SCH_1):PAGE328

 H15 HOLE_TH-EMPTY,HOLE1079
     1     NC     NC    I83 @S9S_MB_2U_LIB.S9S_MB_2U(SCH_1):PAGE289

 H16 HOLE_TH-EMPTY,HOLE1079
     1     NC     NC    I63 @S9S_MB_2U_LIB.S9S_MB_2U(SCH_1):PAGE289

 H17 HOLE_TH-EMPTY,HOLE1079
     1     NC     NC    I75 @S9S_MB_2U_LIB.S9S_MB_2U(SCH_1):PAGE289

 H18 HOLE_TH-EMPTY,HOLE1079
     1     NC     NC    I61 @S9S_MB_2U_LIB.S9S_MB_2U(SCH_1):PAGE289

 H19 HOLE_TH-EMPTY,HOLE1079
     1     NC     NC    I74 @S9S_MB_2U_LIB.S9S_MB_2U(SCH_1):PAGE289

 H20 HOLE_TH-EMPTY,HOLE1079
     1     NC     NC    I60 @S9S_MB_2U_LIB.S9S_MB_2U(SCH_1):PAGE289

 H21 HOLE_TH-EMPTY,HOLE1079
     1     NC     NC    I73 @S9S_MB_2U_LIB.S9S_MB_2U(SCH_1):PAGE289

 H22 HOLE_TH-EMPTY,HOLE1079
     1     NC     NC    I21 @S9S_MB_2U_LIB.S9S_MB_2U(SCH_1):PAGE289

 H23 HOLE_TH-EMPTY,HOLE1079
     1     NC     NC    I72 @S9S_MB_2U_LIB.S9S_MB_2U(SCH_1):PAGE289

 H24 HOLE_TH-EMPTY,HOLE1079
     1     NC     NC    I20 @S9S_MB_2U_LIB.S9S_MB_2U(SCH_1):PAGE289

 H25 HOLE_TH-EMPTY,HOLE1079
     1     NC     NC    I64 @S9S_MB_2U_LIB.S9S_MB_2U(SCH_1):PAGE289

 H26 HOLE_TH-EMPTY,HOLE1079
     1     NC     NC    I19 @S9S_MB_2U_LIB.S9S_MB_2U(SCH_1):PAGE289

 H27 HOLE_TH-EMPTY,DUMMY50
     1     NC     NC    I12 @S9S_MB_2U_LIB.S9S_MB_2U(SCH_1):PAGE289

 H28 HOLE_TH-EMPTY,DUMMY50
     1     NC     NC    I11 @S9S_MB_2U_LIB.S9S_MB_2U(SCH_1):PAGE289

 H29 HOLE_TH-EMPTY,DUMMY50
     1     NC     NC     I8 @S9S_MB_2U_LIB.S9S_MB_2U(SCH_1):PAGE289

 H30 HOLE_TH-EMPTY,DUMMY50
     1     NC     NC     I7 @S9S_MB_2U_LIB.S9S_MB_2U(SCH_1):PAGE289

 H31 HOLE_TH-EMPTY,HOLE1248
     1    GND @S9S_MB_2U_LIB.S9S_MB_2U(SCH_1):GND    I56 @S9S_MB_2U_LIB.S9S_MB_2U(SCH_1):PAGE289

 H32 HOLE_TH-EMPTY,HOLE1248
     1    GND @S9S_MB_2U_LIB.S9S_MB_2U(SCH_1):GND    I54 @S9S_MB_2U_LIB.S9S_MB_2U(SCH_1):PAGE289

 H36 HOLE_TH-EMPTY,TMP-Q_HOLE78
     1     NC     NC    I10 @S9S_MB_2U_LIB.S9S_MB_2U(SCH_1):PAGE289

 H38 HOLE_TH-EMPTY,TMP-Q_HOLE78
     1     NC     NC     I9 @S9S_MB_2U_LIB.S9S_MB_2U(SCH_1):PAGE289

 H44 HOLE_TH-EMPTY,SP_HOLE1199
     1    GND @S9S_MB_2U_LIB.S9S_MB_2U(SCH_1):GND   I216 @S9S_MB_2U_LIB.S9S_MB_2U(SCH_1):PAGE289

 H45 HOLE_TH-EMPTY,SP_HOLE1199
     1    GND @S9S_MB_2U_LIB.S9S_MB_2U(SCH_1):GND   I217 @S9S_MB_2U_LIB.S9S_MB_2U(SCH_1):PAGE289

 H47 HOLE_TH-EMPTY,SP_HOLE1199
     1    GND @S9S_MB_2U_LIB.S9S_MB_2U(SCH_1):GND   I218 @S9S_MB_2U_LIB.S9S_MB_2U(SCH_1):PAGE289

 H49 HOLE_TH-EMPTY,SP_HOLE1199
     1    GND @S9S_MB_2U_LIB.S9S_MB_2U(SCH_1):GND   I219 @S9S_MB_2U_LIB.S9S_MB_2U(SCH_1):PAGE289

 H74 HOLE_TH-EMPTY,HOLE1247
     1     NC     NC    I58 @S9S_MB_2U_LIB.S9S_MB_2U(SCH_1):PAGE289

 H75 HOLE_TH-EMPTY,HOLE1247
     1     NC     NC    I57 @S9S_MB_2U_LIB.S9S_MB_2U(SCH_1):PAGE289

 H76 HOLE_TH-EMPTY,HOLE1187
     1    GND @S9S_MB_2U_LIB.S9S_MB_2U(SCH_1):GND    I18 @S9S_MB_2U_LIB.S9S_MB_2U(SCH_1):PAGE289

 H77 HOLE_TH-EMPTY,HOLE1187
     1    GND @S9S_MB_2U_LIB.S9S_MB_2U(SCH_1):GND    I87 @S9S_MB_2U_LIB.S9S_MB_2U(SCH_1):PAGE289

 H86 HOLE_TH-EMPTY,HOLE596
     1    GND @S9S_MB_2U_LIB.S9S_MB_2U(SCH_1):GND   I140 @S9S_MB_2U_LIB.S9S_MB_2U(SCH_1):PAGE289

 H87 HOLE_TH-EMPTY,HOLE596
     1    GND @S9S_MB_2U_LIB.S9S_MB_2U(SCH_1):GND   I168 @S9S_MB_2U_LIB.S9S_MB_2U(SCH_1):PAGE289

 H88 HOLE_TH-EMPTY,HOLE596
     1    GND @S9S_MB_2U_LIB.S9S_MB_2U(SCH_1):GND   I144 @S9S_MB_2U_LIB.S9S_MB_2U(SCH_1):PAGE289

 H89 HOLE_TH-EMPTY,HOLE596
     1    GND @S9S_MB_2U_LIB.S9S_MB_2U(SCH_1):GND   I167 @S9S_MB_2U_LIB.S9S_MB_2U(SCH_1):PAGE289

 H90 HOLE_TH-EMPTY,HOLE372
     1     NC     NC   I254 @S9S_MB_2U_LIB.S9S_MB_2U(SCH_1):PAGE289

 H91 HOLE_TH-EMPTY,HOLE596
     1    GND @S9S_MB_2U_LIB.S9S_MB_2U(SCH_1):GND   I147 @S9S_MB_2U_LIB.S9S_MB_2U(SCH_1):PAGE289

 H92 HOLE_TH-EMPTY,HOLE596
     1    GND @S9S_MB_2U_LIB.S9S_MB_2U(SCH_1):GND   I166 @S9S_MB_2U_LIB.S9S_MB_2U(SCH_1):PAGE289

 H93 HOLE_TH-EMPTY,HOLE596
     1    GND @S9S_MB_2U_LIB.S9S_MB_2U(SCH_1):GND   I148 @S9S_MB_2U_LIB.S9S_MB_2U(SCH_1):PAGE289

 H94 HOLE_TH-EMPTY,HOLE596
     1    GND @S9S_MB_2U_LIB.S9S_MB_2U(SCH_1):GND   I165 @S9S_MB_2U_LIB.S9S_MB_2U(SCH_1):PAGE289

 H95 HOLE_TH-EMPTY,HOLE596
     1    GND @S9S_MB_2U_LIB.S9S_MB_2U(SCH_1):GND   I150 @S9S_MB_2U_LIB.S9S_MB_2U(SCH_1):PAGE289

 H96 HOLE_TH-EMPTY,HOLE596
     1    GND @S9S_MB_2U_LIB.S9S_MB_2U(SCH_1):GND   I161 @S9S_MB_2U_LIB.S9S_MB_2U(SCH_1):PAGE289

 H97 HOLE_TH-EMPTY,HOLE596
     1    GND @S9S_MB_2U_LIB.S9S_MB_2U(SCH_1):GND   I149 @S9S_MB_2U_LIB.S9S_MB_2U(SCH_1):PAGE289

 H98 HOLE_TH-EMPTY,HOLE596
     1    GND @S9S_MB_2U_LIB.S9S_MB_2U(SCH_1):GND   I160 @S9S_MB_2U_LIB.S9S_MB_2U(SCH_1):PAGE289

 H99 HOLE_TH-EMPTY,HOLE596
     1    GND @S9S_MB_2U_LIB.S9S_MB_2U(SCH_1):GND   I155 @S9S_MB_2U_LIB.S9S_MB_2U(SCH_1):PAGE289

H100 HOLE_TH-EMPTY,HOLE596
     1    GND @S9S_MB_2U_LIB.S9S_MB_2U(SCH_1):GND   I159 @S9S_MB_2U_LIB.S9S_MB_2U(SCH_1):PAGE289

H101 HOLE_TH-EMPTY,HOLE596
     1    GND @S9S_MB_2U_LIB.S9S_MB_2U(SCH_1):GND   I154 @S9S_MB_2U_LIB.S9S_MB_2U(SCH_1):PAGE289

H102 HOLE_TH-EMPTY,HOLE596
     1    GND @S9S_MB_2U_LIB.S9S_MB_2U(SCH_1):GND   I158 @S9S_MB_2U_LIB.S9S_MB_2U(SCH_1):PAGE289

H103 HOLE_TH-EMPTY,HOLE596
     1    GND @S9S_MB_2U_LIB.S9S_MB_2U(SCH_1):GND   I174 @S9S_MB_2U_LIB.S9S_MB_2U(SCH_1):PAGE289

H104 HOLE_TH-EMPTY,HOLE596
     1    GND @S9S_MB_2U_LIB.S9S_MB_2U(SCH_1):GND   I175 @S9S_MB_2U_LIB.S9S_MB_2U(SCH_1):PAGE289

H105 HOLE_TH-EMPTY,HOLE596
     1    GND @S9S_MB_2U_LIB.S9S_MB_2U(SCH_1):GND   I192 @S9S_MB_2U_LIB.S9S_MB_2U(SCH_1):PAGE289

H106 HOLE_TH-EMPTY,HOLE596
     1    GND @S9S_MB_2U_LIB.S9S_MB_2U(SCH_1):GND   I190 @S9S_MB_2U_LIB.S9S_MB_2U(SCH_1):PAGE289

H111 GND_HOLE_TH-EMPTY,GND_HOLE140
     3    GND @S9S_MB_2U_LIB.S9S_MB_2U(SCH_1):GND   I204 @S9S_MB_2U_LIB.S9S_MB_2U(SCH_1):PAGE289
     2    GND @S9S_MB_2U_LIB.S9S_MB_2U(SCH_1):GND   I204 @S9S_MB_2U_LIB.S9S_MB_2U(SCH_1):PAGE289
     9    GND @S9S_MB_2U_LIB.S9S_MB_2U(SCH_1):GND   I204 @S9S_MB_2U_LIB.S9S_MB_2U(SCH_1):PAGE289
     8    GND @S9S_MB_2U_LIB.S9S_MB_2U(SCH_1):GND   I204 @S9S_MB_2U_LIB.S9S_MB_2U(SCH_1):PAGE289
     7    GND @S9S_MB_2U_LIB.S9S_MB_2U(SCH_1):GND   I204 @S9S_MB_2U_LIB.S9S_MB_2U(SCH_1):PAGE289
     6    GND @S9S_MB_2U_LIB.S9S_MB_2U(SCH_1):GND   I204 @S9S_MB_2U_LIB.S9S_MB_2U(SCH_1):PAGE289
     5    GND @S9S_MB_2U_LIB.S9S_MB_2U(SCH_1):GND   I204 @S9S_MB_2U_LIB.S9S_MB_2U(SCH_1):PAGE289
     4    GND @S9S_MB_2U_LIB.S9S_MB_2U(SCH_1):GND   I204 @S9S_MB_2U_LIB.S9S_MB_2U(SCH_1):PAGE289

H112 GND_HOLE_TH-EMPTY,GND_HOLE140
     3    GND @S9S_MB_2U_LIB.S9S_MB_2U(SCH_1):GND   I207 @S9S_MB_2U_LIB.S9S_MB_2U(SCH_1):PAGE289
     2    GND @S9S_MB_2U_LIB.S9S_MB_2U(SCH_1):GND   I207 @S9S_MB_2U_LIB.S9S_MB_2U(SCH_1):PAGE289
     9    GND @S9S_MB_2U_LIB.S9S_MB_2U(SCH_1):GND   I207 @S9S_MB_2U_LIB.S9S_MB_2U(SCH_1):PAGE289
     8    GND @S9S_MB_2U_LIB.S9S_MB_2U(SCH_1):GND   I207 @S9S_MB_2U_LIB.S9S_MB_2U(SCH_1):PAGE289
     7    GND @S9S_MB_2U_LIB.S9S_MB_2U(SCH_1):GND   I207 @S9S_MB_2U_LIB.S9S_MB_2U(SCH_1):PAGE289
     6    GND @S9S_MB_2U_LIB.S9S_MB_2U(SCH_1):GND   I207 @S9S_MB_2U_LIB.S9S_MB_2U(SCH_1):PAGE289
     5    GND @S9S_MB_2U_LIB.S9S_MB_2U(SCH_1):GND   I207 @S9S_MB_2U_LIB.S9S_MB_2U(SCH_1):PAGE289
     4    GND @S9S_MB_2U_LIB.S9S_MB_2U(SCH_1):GND   I207 @S9S_MB_2U_LIB.S9S_MB_2U(SCH_1):PAGE289

H113 GND_HOLE_TH-EMPTY,TMP-QGND_HOLA
     3    GND @S9S_MB_2U_LIB.S9S_MB_2U(SCH_1):GND   I247 @S9S_MB_2U_LIB.S9S_MB_2U(SCH_1):PAGE289
     2    GND @S9S_MB_2U_LIB.S9S_MB_2U(SCH_1):GND   I247 @S9S_MB_2U_LIB.S9S_MB_2U(SCH_1):PAGE289
     9    GND @S9S_MB_2U_LIB.S9S_MB_2U(SCH_1):GND   I247 @S9S_MB_2U_LIB.S9S_MB_2U(SCH_1):PAGE289
     8    GND @S9S_MB_2U_LIB.S9S_MB_2U(SCH_1):GND   I247 @S9S_MB_2U_LIB.S9S_MB_2U(SCH_1):PAGE289
     7    GND @S9S_MB_2U_LIB.S9S_MB_2U(SCH_1):GND   I247 @S9S_MB_2U_LIB.S9S_MB_2U(SCH_1):PAGE289
     6    GND @S9S_MB_2U_LIB.S9S_MB_2U(SCH_1):GND   I247 @S9S_MB_2U_LIB.S9S_MB_2U(SCH_1):PAGE289
     5    GND @S9S_MB_2U_LIB.S9S_MB_2U(SCH_1):GND   I247 @S9S_MB_2U_LIB.S9S_MB_2U(SCH_1):PAGE289
     4    GND @S9S_MB_2U_LIB.S9S_MB_2U(SCH_1):GND   I247 @S9S_MB_2U_LIB.S9S_MB_2U(SCH_1):PAGE289

H114 GND_HOLE_TH-EMPTY,TMP-QGND_HOLA
     3    GND @S9S_MB_2U_LIB.S9S_MB_2U(SCH_1):GND   I248 @S9S_MB_2U_LIB.S9S_MB_2U(SCH_1):PAGE289
     2    GND @S9S_MB_2U_LIB.S9S_MB_2U(SCH_1):GND   I248 @S9S_MB_2U_LIB.S9S_MB_2U(SCH_1):PAGE289
     9    GND @S9S_MB_2U_LIB.S9S_MB_2U(SCH_1):GND   I248 @S9S_MB_2U_LIB.S9S_MB_2U(SCH_1):PAGE289
     8    GND @S9S_MB_2U_LIB.S9S_MB_2U(SCH_1):GND   I248 @S9S_MB_2U_LIB.S9S_MB_2U(SCH_1):PAGE289
     7    GND @S9S_MB_2U_LIB.S9S_MB_2U(SCH_1):GND   I248 @S9S_MB_2U_LIB.S9S_MB_2U(SCH_1):PAGE289
     6    GND @S9S_MB_2U_LIB.S9S_MB_2U(SCH_1):GND   I248 @S9S_MB_2U_LIB.S9S_MB_2U(SCH_1):PAGE289
     5    GND @S9S_MB_2U_LIB.S9S_MB_2U(SCH_1):GND   I248 @S9S_MB_2U_LIB.S9S_MB_2U(SCH_1):PAGE289
     4    GND @S9S_MB_2U_LIB.S9S_MB_2U(SCH_1):GND   I248 @S9S_MB_2U_LIB.S9S_MB_2U(SCH_1):PAGE289

H115 GND_HOLE_TH-EMPTY,GND_HOLE514
     3    GND @S9S_MB_2U_LIB.S9S_MB_2U(SCH_1):GND   I202 @S9S_MB_2U_LIB.S9S_MB_2U(SCH_1):PAGE289
     2    GND @S9S_MB_2U_LIB.S9S_MB_2U(SCH_1):GND   I202 @S9S_MB_2U_LIB.S9S_MB_2U(SCH_1):PAGE289
     9    GND @S9S_MB_2U_LIB.S9S_MB_2U(SCH_1):GND   I202 @S9S_MB_2U_LIB.S9S_MB_2U(SCH_1):PAGE289
     8    GND @S9S_MB_2U_LIB.S9S_MB_2U(SCH_1):GND   I202 @S9S_MB_2U_LIB.S9S_MB_2U(SCH_1):PAGE289
     7    GND @S9S_MB_2U_LIB.S9S_MB_2U(SCH_1):GND   I202 @S9S_MB_2U_LIB.S9S_MB_2U(SCH_1):PAGE289
     6    GND @S9S_MB_2U_LIB.S9S_MB_2U(SCH_1):GND   I202 @S9S_MB_2U_LIB.S9S_MB_2U(SCH_1):PAGE289
     5    GND @S9S_MB_2U_LIB.S9S_MB_2U(SCH_1):GND   I202 @S9S_MB_2U_LIB.S9S_MB_2U(SCH_1):PAGE289
     4    GND @S9S_MB_2U_LIB.S9S_MB_2U(SCH_1):GND   I202 @S9S_MB_2U_LIB.S9S_MB_2U(SCH_1):PAGE289

H120 HOLE_TH-EMPTY,TMP-C_T2I_ALEX_1A
     1     NC     NC   I224 @S9S_MB_2U_LIB.S9S_MB_2U(SCH_1):PAGE289

H122 HOLE_TH-EMPTY,TMP-C_T2I_ALEX_1A
     1     NC     NC   I225 @S9S_MB_2U_LIB.S9S_MB_2U(SCH_1):PAGE289

H124 HOLE_TH-EMPTY,TMP-C_T2I_ALEX_1A
     1     NC     NC   I226 @S9S_MB_2U_LIB.S9S_MB_2U(SCH_1):PAGE289

H125 HOLE_TH-EMPTY,TMP-C_T2I_ALEX_1A
     1     NC     NC   I229 @S9S_MB_2U_LIB.S9S_MB_2U(SCH_1):PAGE289

H126 HOLE_TH-EMPTY,TMP-C_T2I_ALEX_1A
     1     NC     NC   I227 @S9S_MB_2U_LIB.S9S_MB_2U(SCH_1):PAGE289

H127 HOLE_TH-EMPTY,TMP-C_T2I_ALEX_1A
     1     NC     NC   I228 @S9S_MB_2U_LIB.S9S_MB_2U(SCH_1):PAGE289

H128 HOLE_TH-EMPTY,HOLE596
     1    GND @S9S_MB_2U_LIB.S9S_MB_2U(SCH_1):GND   I232 @S9S_MB_2U_LIB.S9S_MB_2U(SCH_1):PAGE289

H129 HOLE_TH-EMPTY,HOLE1195
     1    GND @S9S_MB_2U_LIB.S9S_MB_2U(SCH_1):GND   I249 @S9S_MB_2U_LIB.S9S_MB_2U(SCH_1):PAGE289

  J1 SCONN288_ADR50017P130CC-SCONN2A
     3 P3V3_AUX @S9S_MB_2U_LIB.S9S_MB_2U(SCH_1):P3V3_AUX   I198 @S9S_MB_2U_LIB.S9S_MB_2U(SCH_1):PAGE82
     2 TP_CHA_CPU0_DIMM1_FRU_0 @S9S_MB_2U_LIB.S9S_MB_2U(SCH_1):TP_CHA_CPU0_DIMM1_FRU_0   I198 @S9S_MB_2U_LIB.S9S_MB_2U(SCH_1):PAGE82
   144 TP_CHA_CPU0_DIMM1_FRU_1 @S9S_MB_2U_LIB.S9S_MB_2U(SCH_1):TP_CHA_CPU0_DIMM1_FRU_1   I198 @S9S_MB_2U_LIB.S9S_MB_2U(SCH_1):PAGE82
   149 TP_CHA_CPU0_DIMM1_FRU_2 @S9S_MB_2U_LIB.S9S_MB_2U(SCH_1):TP_CHA_CPU0_DIMM1_FRU_2   I198 @S9S_MB_2U_LIB.S9S_MB_2U(SCH_1):PAGE82
   150 TP_CHA_CPU0_DIMM1_FRU_3 @S9S_MB_2U_LIB.S9S_MB_2U(SCH_1):TP_CHA_CPU0_DIMM1_FRU_3   I198 @S9S_MB_2U_LIB.S9S_MB_2U(SCH_1):PAGE82
   220 TP_CHA_CPU0_DIMM1_FRU_4 @S9S_MB_2U_LIB.S9S_MB_2U(SCH_1):TP_CHA_CPU0_DIMM1_FRU_4   I198 @S9S_MB_2U_LIB.S9S_MB_2U(SCH_1):PAGE82
   231 TP_CHA_CPU0_DIMM1_FRU_5 @S9S_MB_2U_LIB.S9S_MB_2U(SCH_1):TP_CHA_CPU0_DIMM1_FRU_5   I198 @S9S_MB_2U_LIB.S9S_MB_2U(SCH_1):PAGE82
   232 TP_CHA_CPU0_DIMM1_FRU_6 @S9S_MB_2U_LIB.S9S_MB_2U(SCH_1):TP_CHA_CPU0_DIMM1_FRU_6   I198 @S9S_MB_2U_LIB.S9S_MB_2U(SCH_1):PAGE82
   207 RST_M_AB_CPU0_FPGA_N @S9S_MB_2U_LIB.S9S_MB_2U(SCH_1):RST_M_AB_CPU0_FPGA_N   I198 @S9S_MB_2U_LIB.S9S_MB_2U(SCH_1):PAGE82
   147 PWRGD_CHA_CPU0_DIMM1 @S9S_MB_2U_LIB.S9S_MB_2U(SCH_1):PWRGD_CHA_CPU0_DIMM1   I198 @S9S_MB_2U_LIB.S9S_MB_2U(SCH_1):PAGE82
   227 M_A_CPU0_SB_PAR @S9S_MB_2U_LIB.S9S_MB_2U(SCH_1):M_A_CPU0_SB_PAR   I198 @S9S_MB_2U_LIB.S9S_MB_2U(SCH_1):PAGE82
    74 M_A_CPU0_SA_PAR @S9S_MB_2U_LIB.S9S_MB_2U(SCH_1):M_A_CPU0_SA_PAR   I198 @S9S_MB_2U_LIB.S9S_MB_2U(SCH_1):PAGE82
    87 M_A_CPU0_SB_RSP<0> @S9S_MB_2U_LIB.S9S_MB_2U(SCH_1):M_A_CPU0_SB_RSP(0)   I198 @S9S_MB_2U_LIB.S9S_MB_2U(SCH_1):PAGE82
    86 M_A_CPU0_SA_RSP<0> @S9S_MB_2U_LIB.S9S_MB_2U(SCH_1):M_A_CPU0_SA_RSP(0)   I198 @S9S_MB_2U_LIB.S9S_MB_2U(SCH_1):PAGE82
     5 I3C_SPD_DDRABCD_CPU0_LVC1_SDA @S9S_MB_2U_LIB.S9S_MB_2U(SCH_1):I3C_SPD_DDRABCD_CPU0_LVC1_SDA   I198 @S9S_MB_2U_LIB.S9S_MB_2U(SCH_1):PAGE82
     4 I3C_SPD_DDRABCD_CPU0_LVC1_SCL_R @S9S_MB_2U_LIB.S9S_MB_2U(SCH_1):I3C_SPD_DDRABCD_CPU0_LVC1_SCL_R1   I198 @S9S_MB_2U_LIB.S9S_MB_2U(SCH_1):PAGE82
   148 PD_CHA_CPU0_DIMM1_SAA @S9S_MB_2U_LIB.S9S_MB_2U(SCH_1):PD_CHA_CPU0_DIMM1_SAA   I198 @S9S_MB_2U_LIB.S9S_MB_2U(SCH_1):PAGE82
   100 M_A_CPU0_SB_DQ<0> @S9S_MB_2U_LIB.S9S_MB_2U(SCH_1):M_A_CPU0_SB_DQ(0)   I198 @S9S_MB_2U_LIB.S9S_MB_2U(SCH_1):PAGE82
   102 M_A_CPU0_SB_DQ<1> @S9S_MB_2U_LIB.S9S_MB_2U(SCH_1):M_A_CPU0_SB_DQ(1)   I198 @S9S_MB_2U_LIB.S9S_MB_2U(SCH_1):PAGE82
   245 M_A_CPU0_SB_DQ<2> @S9S_MB_2U_LIB.S9S_MB_2U(SCH_1):M_A_CPU0_SB_DQ(2)   I198 @S9S_MB_2U_LIB.S9S_MB_2U(SCH_1):PAGE82
   247 M_A_CPU0_SB_DQ<3> @S9S_MB_2U_LIB.S9S_MB_2U(SCH_1):M_A_CPU0_SB_DQ(3)   I198 @S9S_MB_2U_LIB.S9S_MB_2U(SCH_1):PAGE82
   107 M_A_CPU0_SB_DQ<4> @S9S_MB_2U_LIB.S9S_MB_2U(SCH_1):M_A_CPU0_SB_DQ(4)   I198 @S9S_MB_2U_LIB.S9S_MB_2U(SCH_1):PAGE82
   109 M_A_CPU0_SB_DQ<5> @S9S_MB_2U_LIB.S9S_MB_2U(SCH_1):M_A_CPU0_SB_DQ(5)   I198 @S9S_MB_2U_LIB.S9S_MB_2U(SCH_1):PAGE82
   252 M_A_CPU0_SB_DQ<6> @S9S_MB_2U_LIB.S9S_MB_2U(SCH_1):M_A_CPU0_SB_DQ(6)   I198 @S9S_MB_2U_LIB.S9S_MB_2U(SCH_1):PAGE82
   254 M_A_CPU0_SB_DQ<7> @S9S_MB_2U_LIB.S9S_MB_2U(SCH_1):M_A_CPU0_SB_DQ(7)   I198 @S9S_MB_2U_LIB.S9S_MB_2U(SCH_1):PAGE82
   111 M_A_CPU0_SB_DQ<8> @S9S_MB_2U_LIB.S9S_MB_2U(SCH_1):M_A_CPU0_SB_DQ(8)   I198 @S9S_MB_2U_LIB.S9S_MB_2U(SCH_1):PAGE82
   113 M_A_CPU0_SB_DQ<9> @S9S_MB_2U_LIB.S9S_MB_2U(SCH_1):M_A_CPU0_SB_DQ(9)   I198 @S9S_MB_2U_LIB.S9S_MB_2U(SCH_1):PAGE82
   256 M_A_CPU0_SB_DQ<10> @S9S_MB_2U_LIB.S9S_MB_2U(SCH_1):M_A_CPU0_SB_DQ(10)   I198 @S9S_MB_2U_LIB.S9S_MB_2U(SCH_1):PAGE82
   258 M_A_CPU0_SB_DQ<11> @S9S_MB_2U_LIB.S9S_MB_2U(SCH_1):M_A_CPU0_SB_DQ(11)   I198 @S9S_MB_2U_LIB.S9S_MB_2U(SCH_1):PAGE82
   118 M_A_CPU0_SB_DQ<12> @S9S_MB_2U_LIB.S9S_MB_2U(SCH_1):M_A_CPU0_SB_DQ(12)   I198 @S9S_MB_2U_LIB.S9S_MB_2U(SCH_1):PAGE82
   120 M_A_CPU0_SB_DQ<13> @S9S_MB_2U_LIB.S9S_MB_2U(SCH_1):M_A_CPU0_SB_DQ(13)   I198 @S9S_MB_2U_LIB.S9S_MB_2U(SCH_1):PAGE82
   263 M_A_CPU0_SB_DQ<14> @S9S_MB_2U_LIB.S9S_MB_2U(SCH_1):M_A_CPU0_SB_DQ(14)   I198 @S9S_MB_2U_LIB.S9S_MB_2U(SCH_1):PAGE82
   265 M_A_CPU0_SB_DQ<15> @S9S_MB_2U_LIB.S9S_MB_2U(SCH_1):M_A_CPU0_SB_DQ(15)   I198 @S9S_MB_2U_LIB.S9S_MB_2U(SCH_1):PAGE82
   122 M_A_CPU0_SB_DQ<16> @S9S_MB_2U_LIB.S9S_MB_2U(SCH_1):M_A_CPU0_SB_DQ(16)   I198 @S9S_MB_2U_LIB.S9S_MB_2U(SCH_1):PAGE82
   124 M_A_CPU0_SB_DQ<17> @S9S_MB_2U_LIB.S9S_MB_2U(SCH_1):M_A_CPU0_SB_DQ(17)   I198 @S9S_MB_2U_LIB.S9S_MB_2U(SCH_1):PAGE82
   267 M_A_CPU0_SB_DQ<18> @S9S_MB_2U_LIB.S9S_MB_2U(SCH_1):M_A_CPU0_SB_DQ(18)   I198 @S9S_MB_2U_LIB.S9S_MB_2U(SCH_1):PAGE82
   269 M_A_CPU0_SB_DQ<19> @S9S_MB_2U_LIB.S9S_MB_2U(SCH_1):M_A_CPU0_SB_DQ(19)   I198 @S9S_MB_2U_LIB.S9S_MB_2U(SCH_1):PAGE82
   129 M_A_CPU0_SB_DQ<20> @S9S_MB_2U_LIB.S9S_MB_2U(SCH_1):M_A_CPU0_SB_DQ(20)   I198 @S9S_MB_2U_LIB.S9S_MB_2U(SCH_1):PAGE82
   131 M_A_CPU0_SB_DQ<21> @S9S_MB_2U_LIB.S9S_MB_2U(SCH_1):M_A_CPU0_SB_DQ(21)   I198 @S9S_MB_2U_LIB.S9S_MB_2U(SCH_1):PAGE82
   274 M_A_CPU0_SB_DQ<22> @S9S_MB_2U_LIB.S9S_MB_2U(SCH_1):M_A_CPU0_SB_DQ(22)   I198 @S9S_MB_2U_LIB.S9S_MB_2U(SCH_1):PAGE82
   276 M_A_CPU0_SB_DQ<23> @S9S_MB_2U_LIB.S9S_MB_2U(SCH_1):M_A_CPU0_SB_DQ(23)   I198 @S9S_MB_2U_LIB.S9S_MB_2U(SCH_1):PAGE82
   133 M_A_CPU0_SB_DQ<24> @S9S_MB_2U_LIB.S9S_MB_2U(SCH_1):M_A_CPU0_SB_DQ(24)   I198 @S9S_MB_2U_LIB.S9S_MB_2U(SCH_1):PAGE82
   135 M_A_CPU0_SB_DQ<25> @S9S_MB_2U_LIB.S9S_MB_2U(SCH_1):M_A_CPU0_SB_DQ(25)   I198 @S9S_MB_2U_LIB.S9S_MB_2U(SCH_1):PAGE82
   278 M_A_CPU0_SB_DQ<26> @S9S_MB_2U_LIB.S9S_MB_2U(SCH_1):M_A_CPU0_SB_DQ(26)   I198 @S9S_MB_2U_LIB.S9S_MB_2U(SCH_1):PAGE82
   280 M_A_CPU0_SB_DQ<27> @S9S_MB_2U_LIB.S9S_MB_2U(SCH_1):M_A_CPU0_SB_DQ(27)   I198 @S9S_MB_2U_LIB.S9S_MB_2U(SCH_1):PAGE82
   140 M_A_CPU0_SB_DQ<28> @S9S_MB_2U_LIB.S9S_MB_2U(SCH_1):M_A_CPU0_SB_DQ(28)   I198 @S9S_MB_2U_LIB.S9S_MB_2U(SCH_1):PAGE82
   142 M_A_CPU0_SB_DQ<29> @S9S_MB_2U_LIB.S9S_MB_2U(SCH_1):M_A_CPU0_SB_DQ(29)   I198 @S9S_MB_2U_LIB.S9S_MB_2U(SCH_1):PAGE82
   285 M_A_CPU0_SB_DQ<30> @S9S_MB_2U_LIB.S9S_MB_2U(SCH_1):M_A_CPU0_SB_DQ(30)   I198 @S9S_MB_2U_LIB.S9S_MB_2U(SCH_1):PAGE82
   287 M_A_CPU0_SB_DQ<31> @S9S_MB_2U_LIB.S9S_MB_2U(SCH_1):M_A_CPU0_SB_DQ(31)   I198 @S9S_MB_2U_LIB.S9S_MB_2U(SCH_1):PAGE82
     7 M_A_CPU0_SA_DQ<0> @S9S_MB_2U_LIB.S9S_MB_2U(SCH_1):M_A_CPU0_SA_DQ(0)   I198 @S9S_MB_2U_LIB.S9S_MB_2U(SCH_1):PAGE82
     9 M_A_CPU0_SA_DQ<1> @S9S_MB_2U_LIB.S9S_MB_2U(SCH_1):M_A_CPU0_SA_DQ(1)   I198 @S9S_MB_2U_LIB.S9S_MB_2U(SCH_1):PAGE82
   152 M_A_CPU0_SA_DQ<2> @S9S_MB_2U_LIB.S9S_MB_2U(SCH_1):M_A_CPU0_SA_DQ(2)   I198 @S9S_MB_2U_LIB.S9S_MB_2U(SCH_1):PAGE82
   154 M_A_CPU0_SA_DQ<3> @S9S_MB_2U_LIB.S9S_MB_2U(SCH_1):M_A_CPU0_SA_DQ(3)   I198 @S9S_MB_2U_LIB.S9S_MB_2U(SCH_1):PAGE82
    14 M_A_CPU0_SA_DQ<4> @S9S_MB_2U_LIB.S9S_MB_2U(SCH_1):M_A_CPU0_SA_DQ(4)   I198 @S9S_MB_2U_LIB.S9S_MB_2U(SCH_1):PAGE82
    16 M_A_CPU0_SA_DQ<5> @S9S_MB_2U_LIB.S9S_MB_2U(SCH_1):M_A_CPU0_SA_DQ(5)   I198 @S9S_MB_2U_LIB.S9S_MB_2U(SCH_1):PAGE82
   159 M_A_CPU0_SA_DQ<6> @S9S_MB_2U_LIB.S9S_MB_2U(SCH_1):M_A_CPU0_SA_DQ(6)   I198 @S9S_MB_2U_LIB.S9S_MB_2U(SCH_1):PAGE82
   161 M_A_CPU0_SA_DQ<7> @S9S_MB_2U_LIB.S9S_MB_2U(SCH_1):M_A_CPU0_SA_DQ(7)   I198 @S9S_MB_2U_LIB.S9S_MB_2U(SCH_1):PAGE82
    18 M_A_CPU0_SA_DQ<8> @S9S_MB_2U_LIB.S9S_MB_2U(SCH_1):M_A_CPU0_SA_DQ(8)   I198 @S9S_MB_2U_LIB.S9S_MB_2U(SCH_1):PAGE82
    20 M_A_CPU0_SA_DQ<9> @S9S_MB_2U_LIB.S9S_MB_2U(SCH_1):M_A_CPU0_SA_DQ(9)   I198 @S9S_MB_2U_LIB.S9S_MB_2U(SCH_1):PAGE82
   163 M_A_CPU0_SA_DQ<10> @S9S_MB_2U_LIB.S9S_MB_2U(SCH_1):M_A_CPU0_SA_DQ(10)   I198 @S9S_MB_2U_LIB.S9S_MB_2U(SCH_1):PAGE82
   165 M_A_CPU0_SA_DQ<11> @S9S_MB_2U_LIB.S9S_MB_2U(SCH_1):M_A_CPU0_SA_DQ(11)   I198 @S9S_MB_2U_LIB.S9S_MB_2U(SCH_1):PAGE82
    25 M_A_CPU0_SA_DQ<12> @S9S_MB_2U_LIB.S9S_MB_2U(SCH_1):M_A_CPU0_SA_DQ(12)   I198 @S9S_MB_2U_LIB.S9S_MB_2U(SCH_1):PAGE82
    27 M_A_CPU0_SA_DQ<13> @S9S_MB_2U_LIB.S9S_MB_2U(SCH_1):M_A_CPU0_SA_DQ(13)   I198 @S9S_MB_2U_LIB.S9S_MB_2U(SCH_1):PAGE82
   170 M_A_CPU0_SA_DQ<14> @S9S_MB_2U_LIB.S9S_MB_2U(SCH_1):M_A_CPU0_SA_DQ(14)   I198 @S9S_MB_2U_LIB.S9S_MB_2U(SCH_1):PAGE82
   172 M_A_CPU0_SA_DQ<15> @S9S_MB_2U_LIB.S9S_MB_2U(SCH_1):M_A_CPU0_SA_DQ(15)   I198 @S9S_MB_2U_LIB.S9S_MB_2U(SCH_1):PAGE82
    29 M_A_CPU0_SA_DQ<16> @S9S_MB_2U_LIB.S9S_MB_2U(SCH_1):M_A_CPU0_SA_DQ(16)   I198 @S9S_MB_2U_LIB.S9S_MB_2U(SCH_1):PAGE82
    31 M_A_CPU0_SA_DQ<17> @S9S_MB_2U_LIB.S9S_MB_2U(SCH_1):M_A_CPU0_SA_DQ(17)   I198 @S9S_MB_2U_LIB.S9S_MB_2U(SCH_1):PAGE82
   174 M_A_CPU0_SA_DQ<18> @S9S_MB_2U_LIB.S9S_MB_2U(SCH_1):M_A_CPU0_SA_DQ(18)   I198 @S9S_MB_2U_LIB.S9S_MB_2U(SCH_1):PAGE82
   176 M_A_CPU0_SA_DQ<19> @S9S_MB_2U_LIB.S9S_MB_2U(SCH_1):M_A_CPU0_SA_DQ(19)   I198 @S9S_MB_2U_LIB.S9S_MB_2U(SCH_1):PAGE82
    36 M_A_CPU0_SA_DQ<20> @S9S_MB_2U_LIB.S9S_MB_2U(SCH_1):M_A_CPU0_SA_DQ(20)   I198 @S9S_MB_2U_LIB.S9S_MB_2U(SCH_1):PAGE82
    38 M_A_CPU0_SA_DQ<21> @S9S_MB_2U_LIB.S9S_MB_2U(SCH_1):M_A_CPU0_SA_DQ(21)   I198 @S9S_MB_2U_LIB.S9S_MB_2U(SCH_1):PAGE82
   181 M_A_CPU0_SA_DQ<22> @S9S_MB_2U_LIB.S9S_MB_2U(SCH_1):M_A_CPU0_SA_DQ(22)   I198 @S9S_MB_2U_LIB.S9S_MB_2U(SCH_1):PAGE82
   183 M_A_CPU0_SA_DQ<23> @S9S_MB_2U_LIB.S9S_MB_2U(SCH_1):M_A_CPU0_SA_DQ(23)   I198 @S9S_MB_2U_LIB.S9S_MB_2U(SCH_1):PAGE82
    40 M_A_CPU0_SA_DQ<24> @S9S_MB_2U_LIB.S9S_MB_2U(SCH_1):M_A_CPU0_SA_DQ(24)   I198 @S9S_MB_2U_LIB.S9S_MB_2U(SCH_1):PAGE82
    42 M_A_CPU0_SA_DQ<25> @S9S_MB_2U_LIB.S9S_MB_2U(SCH_1):M_A_CPU0_SA_DQ(25)   I198 @S9S_MB_2U_LIB.S9S_MB_2U(SCH_1):PAGE82
   185 M_A_CPU0_SA_DQ<26> @S9S_MB_2U_LIB.S9S_MB_2U(SCH_1):M_A_CPU0_SA_DQ(26)   I198 @S9S_MB_2U_LIB.S9S_MB_2U(SCH_1):PAGE82
   187 M_A_CPU0_SA_DQ<27> @S9S_MB_2U_LIB.S9S_MB_2U(SCH_1):M_A_CPU0_SA_DQ(27)   I198 @S9S_MB_2U_LIB.S9S_MB_2U(SCH_1):PAGE82
    47 M_A_CPU0_SA_DQ<28> @S9S_MB_2U_LIB.S9S_MB_2U(SCH_1):M_A_CPU0_SA_DQ(28)   I198 @S9S_MB_2U_LIB.S9S_MB_2U(SCH_1):PAGE82
    49 M_A_CPU0_SA_DQ<29> @S9S_MB_2U_LIB.S9S_MB_2U(SCH_1):M_A_CPU0_SA_DQ(29)   I198 @S9S_MB_2U_LIB.S9S_MB_2U(SCH_1):PAGE82
   192 M_A_CPU0_SA_DQ<30> @S9S_MB_2U_LIB.S9S_MB_2U(SCH_1):M_A_CPU0_SA_DQ(30)   I198 @S9S_MB_2U_LIB.S9S_MB_2U(SCH_1):PAGE82
   229 M_A_CPU0_SB_CS_N<1> @S9S_MB_2U_LIB.S9S_MB_2U(SCH_1):M_A_CPU0_SB_CS_N(1)   I198 @S9S_MB_2U_LIB.S9S_MB_2U(SCH_1):PAGE82
   209 M_A_CPU0_SA_CS_N<1> @S9S_MB_2U_LIB.S9S_MB_2U(SCH_1):M_A_CPU0_SA_CS_N(1)   I198 @S9S_MB_2U_LIB.S9S_MB_2U(SCH_1):PAGE82
    84 M_A_CPU0_SB_CS_N<0> @S9S_MB_2U_LIB.S9S_MB_2U(SCH_1):M_A_CPU0_SB_CS_N(0)   I198 @S9S_MB_2U_LIB.S9S_MB_2U(SCH_1):PAGE82
    64 M_A_CPU0_SA_CS_N<0> @S9S_MB_2U_LIB.S9S_MB_2U(SCH_1):M_A_CPU0_SA_CS_N(0)   I198 @S9S_MB_2U_LIB.S9S_MB_2U(SCH_1):PAGE82
   217 M_A_CPU0_CLK_DP<0> @S9S_MB_2U_LIB.S9S_MB_2U(SCH_1):M_A_CPU0_CLK_DP(0)   I198 @S9S_MB_2U_LIB.S9S_MB_2U(SCH_1):PAGE82
   218 M_A_CPU0_CLK_DN<0> @S9S_MB_2U_LIB.S9S_MB_2U(SCH_1):M_A_CPU0_CLK_DN(0)   I198 @S9S_MB_2U_LIB.S9S_MB_2U(SCH_1):PAGE82
    96 M_A_CPU0_SB_CB<0> @S9S_MB_2U_LIB.S9S_MB_2U(SCH_1):M_A_CPU0_SB_CB(0)   I198 @S9S_MB_2U_LIB.S9S_MB_2U(SCH_1):PAGE82
    98 M_A_CPU0_SB_CB<1> @S9S_MB_2U_LIB.S9S_MB_2U(SCH_1):M_A_CPU0_SB_CB(1)   I198 @S9S_MB_2U_LIB.S9S_MB_2U(SCH_1):PAGE82
   241 M_A_CPU0_SB_CB<2> @S9S_MB_2U_LIB.S9S_MB_2U(SCH_1):M_A_CPU0_SB_CB(2)   I198 @S9S_MB_2U_LIB.S9S_MB_2U(SCH_1):PAGE82
   243 M_A_CPU0_SB_CB<3> @S9S_MB_2U_LIB.S9S_MB_2U(SCH_1):M_A_CPU0_SB_CB(3)   I198 @S9S_MB_2U_LIB.S9S_MB_2U(SCH_1):PAGE82
    89 M_A_CPU0_SB_CB<4> @S9S_MB_2U_LIB.S9S_MB_2U(SCH_1):M_A_CPU0_SB_CB(4)   I198 @S9S_MB_2U_LIB.S9S_MB_2U(SCH_1):PAGE82
    91 M_A_CPU0_SB_CB<5> @S9S_MB_2U_LIB.S9S_MB_2U(SCH_1):M_A_CPU0_SB_CB(5)   I198 @S9S_MB_2U_LIB.S9S_MB_2U(SCH_1):PAGE82
   234 M_A_CPU0_SB_CB<6> @S9S_MB_2U_LIB.S9S_MB_2U(SCH_1):M_A_CPU0_SB_CB(6)   I198 @S9S_MB_2U_LIB.S9S_MB_2U(SCH_1):PAGE82
    51 M_A_CPU0_SA_CB<0> @S9S_MB_2U_LIB.S9S_MB_2U(SCH_1):M_A_CPU0_SA_CB(0)   I198 @S9S_MB_2U_LIB.S9S_MB_2U(SCH_1):PAGE82
   196 M_A_CPU0_SA_CB<2> @S9S_MB_2U_LIB.S9S_MB_2U(SCH_1):M_A_CPU0_SA_CB(2)   I198 @S9S_MB_2U_LIB.S9S_MB_2U(SCH_1):PAGE82
   198 M_A_CPU0_SA_CB<3> @S9S_MB_2U_LIB.S9S_MB_2U(SCH_1):M_A_CPU0_SA_CB(3)   I198 @S9S_MB_2U_LIB.S9S_MB_2U(SCH_1):PAGE82
    60 M_A_CPU0_SA_CB<5> @S9S_MB_2U_LIB.S9S_MB_2U(SCH_1):M_A_CPU0_SA_CB(5)   I198 @S9S_MB_2U_LIB.S9S_MB_2U(SCH_1):PAGE82
   203 M_A_CPU0_SA_CB<6> @S9S_MB_2U_LIB.S9S_MB_2U(SCH_1):M_A_CPU0_SA_CB(6)   I198 @S9S_MB_2U_LIB.S9S_MB_2U(SCH_1):PAGE82
    82 M_A_CPU0_SB_CA<6> @S9S_MB_2U_LIB.S9S_MB_2U(SCH_1):M_A_CPU0_SB_CA(6)   I198 @S9S_MB_2U_LIB.S9S_MB_2U(SCH_1):PAGE82
    72 M_A_CPU0_SA_CA<6> @S9S_MB_2U_LIB.S9S_MB_2U(SCH_1):M_A_CPU0_SA_CA(6)   I198 @S9S_MB_2U_LIB.S9S_MB_2U(SCH_1):PAGE82
   225 M_A_CPU0_SB_CA<5> @S9S_MB_2U_LIB.S9S_MB_2U(SCH_1):M_A_CPU0_SB_CA(5)   I198 @S9S_MB_2U_LIB.S9S_MB_2U(SCH_1):PAGE82
   215 M_A_CPU0_SA_CA<5> @S9S_MB_2U_LIB.S9S_MB_2U(SCH_1):M_A_CPU0_SA_CA(5)   I198 @S9S_MB_2U_LIB.S9S_MB_2U(SCH_1):PAGE82
    80 M_A_CPU0_SB_CA<4> @S9S_MB_2U_LIB.S9S_MB_2U(SCH_1):M_A_CPU0_SB_CA(4)   I198 @S9S_MB_2U_LIB.S9S_MB_2U(SCH_1):PAGE82
    70 M_A_CPU0_SA_CA<4> @S9S_MB_2U_LIB.S9S_MB_2U(SCH_1):M_A_CPU0_SA_CA(4)   I198 @S9S_MB_2U_LIB.S9S_MB_2U(SCH_1):PAGE82
   223 M_A_CPU0_SB_CA<3> @S9S_MB_2U_LIB.S9S_MB_2U(SCH_1):M_A_CPU0_SB_CA(3)   I198 @S9S_MB_2U_LIB.S9S_MB_2U(SCH_1):PAGE82
   213 M_A_CPU0_SA_CA<3> @S9S_MB_2U_LIB.S9S_MB_2U(SCH_1):M_A_CPU0_SA_CA(3)   I198 @S9S_MB_2U_LIB.S9S_MB_2U(SCH_1):PAGE82
    78 M_A_CPU0_SB_CA<2> @S9S_MB_2U_LIB.S9S_MB_2U(SCH_1):M_A_CPU0_SB_CA(2)   I198 @S9S_MB_2U_LIB.S9S_MB_2U(SCH_1):PAGE82
    68 M_A_CPU0_SA_CA<2> @S9S_MB_2U_LIB.S9S_MB_2U(SCH_1):M_A_CPU0_SA_CA(2)   I198 @S9S_MB_2U_LIB.S9S_MB_2U(SCH_1):PAGE82
   221 M_A_CPU0_SB_CA<1> @S9S_MB_2U_LIB.S9S_MB_2U(SCH_1):M_A_CPU0_SB_CA(1)   I198 @S9S_MB_2U_LIB.S9S_MB_2U(SCH_1):PAGE82
   211 M_A_CPU0_SA_CA<1> @S9S_MB_2U_LIB.S9S_MB_2U(SCH_1):M_A_CPU0_SA_CA(1)   I198 @S9S_MB_2U_LIB.S9S_MB_2U(SCH_1):PAGE82
    76 M_A_CPU0_SB_CA<0> @S9S_MB_2U_LIB.S9S_MB_2U(SCH_1):M_A_CPU0_SB_CA(0)   I198 @S9S_MB_2U_LIB.S9S_MB_2U(SCH_1):PAGE82
    66 M_A_CPU0_SA_CA<0> @S9S_MB_2U_LIB.S9S_MB_2U(SCH_1):M_A_CPU0_SA_CA(0)   I198 @S9S_MB_2U_LIB.S9S_MB_2U(SCH_1):PAGE82
    62 M_A_CPU0_ALERT_N @S9S_MB_2U_LIB.S9S_MB_2U(SCH_1):M_A_CPU0_ALERT_N   I198 @S9S_MB_2U_LIB.S9S_MB_2U(SCH_1):PAGE82
   236 M_A_CPU0_SB_CB<7> @S9S_MB_2U_LIB.S9S_MB_2U(SCH_1):M_A_CPU0_SB_CB(7)   I198 @S9S_MB_2U_LIB.S9S_MB_2U(SCH_1):PAGE82
    53 M_A_CPU0_SA_CB<1> @S9S_MB_2U_LIB.S9S_MB_2U(SCH_1):M_A_CPU0_SA_CB(1)   I198 @S9S_MB_2U_LIB.S9S_MB_2U(SCH_1):PAGE82
    58 M_A_CPU0_SA_CB<4> @S9S_MB_2U_LIB.S9S_MB_2U(SCH_1):M_A_CPU0_SA_CB(4)   I198 @S9S_MB_2U_LIB.S9S_MB_2U(SCH_1):PAGE82
   205 M_A_CPU0_SA_CB<7> @S9S_MB_2U_LIB.S9S_MB_2U(SCH_1):M_A_CPU0_SA_CB(7)   I198 @S9S_MB_2U_LIB.S9S_MB_2U(SCH_1):PAGE82
   194 M_A_CPU0_SA_DQ<31> @S9S_MB_2U_LIB.S9S_MB_2U(SCH_1):M_A_CPU0_SA_DQ(31)   I198 @S9S_MB_2U_LIB.S9S_MB_2U(SCH_1):PAGE82
    93 M_A_CPU0_SB_DQS_DP<9> @S9S_MB_2U_LIB.S9S_MB_2U(SCH_1):M_A_CPU0_SB_DQS_DP(9)   I202 @S9S_MB_2U_LIB.S9S_MB_2U(SCH_1):PAGE82
    94 M_A_CPU0_SB_DQS_DN<9> @S9S_MB_2U_LIB.S9S_MB_2U(SCH_1):M_A_CPU0_SB_DQS_DN(9)   I202 @S9S_MB_2U_LIB.S9S_MB_2U(SCH_1):PAGE82
   201 M_A_CPU0_SA_DQS_DP<9> @S9S_MB_2U_LIB.S9S_MB_2U(SCH_1):M_A_CPU0_SA_DQS_DP(9)   I202 @S9S_MB_2U_LIB.S9S_MB_2U(SCH_1):PAGE82
   200 M_A_CPU0_SA_DQS_DN<9> @S9S_MB_2U_LIB.S9S_MB_2U(SCH_1):M_A_CPU0_SA_DQS_DN(9)   I202 @S9S_MB_2U_LIB.S9S_MB_2U(SCH_1):PAGE82
   190 M_A_CPU0_SA_DQS_DP<8> @S9S_MB_2U_LIB.S9S_MB_2U(SCH_1):M_A_CPU0_SA_DQS_DP(8)   I202 @S9S_MB_2U_LIB.S9S_MB_2U(SCH_1):PAGE82
   189 M_A_CPU0_SA_DQS_DN<8> @S9S_MB_2U_LIB.S9S_MB_2U(SCH_1):M_A_CPU0_SA_DQS_DN(8)   I202 @S9S_MB_2U_LIB.S9S_MB_2U(SCH_1):PAGE82
   271 M_A_CPU0_SB_DQS_DN<7> @S9S_MB_2U_LIB.S9S_MB_2U(SCH_1):M_A_CPU0_SB_DQS_DN(7)   I202 @S9S_MB_2U_LIB.S9S_MB_2U(SCH_1):PAGE82
   179 M_A_CPU0_SA_DQS_DP<7> @S9S_MB_2U_LIB.S9S_MB_2U(SCH_1):M_A_CPU0_SA_DQS_DP(7)   I202 @S9S_MB_2U_LIB.S9S_MB_2U(SCH_1):PAGE82
   261 M_A_CPU0_SB_DQS_DP<6> @S9S_MB_2U_LIB.S9S_MB_2U(SCH_1):M_A_CPU0_SB_DQS_DP(6)   I202 @S9S_MB_2U_LIB.S9S_MB_2U(SCH_1):PAGE82
   260 M_A_CPU0_SB_DQS_DN<6> @S9S_MB_2U_LIB.S9S_MB_2U(SCH_1):M_A_CPU0_SB_DQS_DN(6)   I202 @S9S_MB_2U_LIB.S9S_MB_2U(SCH_1):PAGE82
   167 M_A_CPU0_SA_DQS_DN<6> @S9S_MB_2U_LIB.S9S_MB_2U(SCH_1):M_A_CPU0_SA_DQS_DN(6)   I202 @S9S_MB_2U_LIB.S9S_MB_2U(SCH_1):PAGE82
   250 M_A_CPU0_SB_DQS_DP<5> @S9S_MB_2U_LIB.S9S_MB_2U(SCH_1):M_A_CPU0_SB_DQS_DP(5)   I202 @S9S_MB_2U_LIB.S9S_MB_2U(SCH_1):PAGE82
   249 M_A_CPU0_SB_DQS_DN<5> @S9S_MB_2U_LIB.S9S_MB_2U(SCH_1):M_A_CPU0_SB_DQS_DN(5)   I202 @S9S_MB_2U_LIB.S9S_MB_2U(SCH_1):PAGE82
   157 M_A_CPU0_SA_DQS_DP<5> @S9S_MB_2U_LIB.S9S_MB_2U(SCH_1):M_A_CPU0_SA_DQS_DP(5)   I202 @S9S_MB_2U_LIB.S9S_MB_2U(SCH_1):PAGE82
   156 M_A_CPU0_SA_DQS_DN<5> @S9S_MB_2U_LIB.S9S_MB_2U(SCH_1):M_A_CPU0_SA_DQS_DN(5)   I202 @S9S_MB_2U_LIB.S9S_MB_2U(SCH_1):PAGE82
   239 M_A_CPU0_SB_DQS_DP<4> @S9S_MB_2U_LIB.S9S_MB_2U(SCH_1):M_A_CPU0_SB_DQS_DP(4)   I202 @S9S_MB_2U_LIB.S9S_MB_2U(SCH_1):PAGE82
   238 M_A_CPU0_SB_DQS_DN<4> @S9S_MB_2U_LIB.S9S_MB_2U(SCH_1):M_A_CPU0_SB_DQS_DN(4)   I202 @S9S_MB_2U_LIB.S9S_MB_2U(SCH_1):PAGE82
    55 M_A_CPU0_SA_DQS_DP<4> @S9S_MB_2U_LIB.S9S_MB_2U(SCH_1):M_A_CPU0_SA_DQS_DP(4)   I202 @S9S_MB_2U_LIB.S9S_MB_2U(SCH_1):PAGE82
    56 M_A_CPU0_SA_DQS_DN<4> @S9S_MB_2U_LIB.S9S_MB_2U(SCH_1):M_A_CPU0_SA_DQS_DN(4)   I202 @S9S_MB_2U_LIB.S9S_MB_2U(SCH_1):PAGE82
   137 M_A_CPU0_SB_DQS_DP<3> @S9S_MB_2U_LIB.S9S_MB_2U(SCH_1):M_A_CPU0_SB_DQS_DP(3)   I202 @S9S_MB_2U_LIB.S9S_MB_2U(SCH_1):PAGE82
   138 M_A_CPU0_SB_DQS_DN<3> @S9S_MB_2U_LIB.S9S_MB_2U(SCH_1):M_A_CPU0_SB_DQS_DN(3)   I202 @S9S_MB_2U_LIB.S9S_MB_2U(SCH_1):PAGE82
    44 M_A_CPU0_SA_DQS_DP<3> @S9S_MB_2U_LIB.S9S_MB_2U(SCH_1):M_A_CPU0_SA_DQS_DP(3)   I202 @S9S_MB_2U_LIB.S9S_MB_2U(SCH_1):PAGE82
    45 M_A_CPU0_SA_DQS_DN<3> @S9S_MB_2U_LIB.S9S_MB_2U(SCH_1):M_A_CPU0_SA_DQS_DN(3)   I202 @S9S_MB_2U_LIB.S9S_MB_2U(SCH_1):PAGE82
   126 M_A_CPU0_SB_DQS_DP<2> @S9S_MB_2U_LIB.S9S_MB_2U(SCH_1):M_A_CPU0_SB_DQS_DP(2)   I202 @S9S_MB_2U_LIB.S9S_MB_2U(SCH_1):PAGE82
   127 M_A_CPU0_SB_DQS_DN<2> @S9S_MB_2U_LIB.S9S_MB_2U(SCH_1):M_A_CPU0_SB_DQS_DN(2)   I202 @S9S_MB_2U_LIB.S9S_MB_2U(SCH_1):PAGE82
    33 M_A_CPU0_SA_DQS_DP<2> @S9S_MB_2U_LIB.S9S_MB_2U(SCH_1):M_A_CPU0_SA_DQS_DP(2)   I202 @S9S_MB_2U_LIB.S9S_MB_2U(SCH_1):PAGE82
    34 M_A_CPU0_SA_DQS_DN<2> @S9S_MB_2U_LIB.S9S_MB_2U(SCH_1):M_A_CPU0_SA_DQS_DN(2)   I202 @S9S_MB_2U_LIB.S9S_MB_2U(SCH_1):PAGE82
   115 M_A_CPU0_SB_DQS_DP<1> @S9S_MB_2U_LIB.S9S_MB_2U(SCH_1):M_A_CPU0_SB_DQS_DP(1)   I202 @S9S_MB_2U_LIB.S9S_MB_2U(SCH_1):PAGE82
   116 M_A_CPU0_SB_DQS_DN<1> @S9S_MB_2U_LIB.S9S_MB_2U(SCH_1):M_A_CPU0_SB_DQS_DN(1)   I202 @S9S_MB_2U_LIB.S9S_MB_2U(SCH_1):PAGE82
    22 M_A_CPU0_SA_DQS_DP<1> @S9S_MB_2U_LIB.S9S_MB_2U(SCH_1):M_A_CPU0_SA_DQS_DP(1)   I202 @S9S_MB_2U_LIB.S9S_MB_2U(SCH_1):PAGE82
    23 M_A_CPU0_SA_DQS_DN<1> @S9S_MB_2U_LIB.S9S_MB_2U(SCH_1):M_A_CPU0_SA_DQS_DN(1)   I202 @S9S_MB_2U_LIB.S9S_MB_2U(SCH_1):PAGE82
   104 M_A_CPU0_SB_DQS_DP<0> @S9S_MB_2U_LIB.S9S_MB_2U(SCH_1):M_A_CPU0_SB_DQS_DP(0)   I202 @S9S_MB_2U_LIB.S9S_MB_2U(SCH_1):PAGE82
   105 M_A_CPU0_SB_DQS_DN<0> @S9S_MB_2U_LIB.S9S_MB_2U(SCH_1):M_A_CPU0_SB_DQS_DN(0)   I202 @S9S_MB_2U_LIB.S9S_MB_2U(SCH_1):PAGE82
    11 M_A_CPU0_SA_DQS_DP<0> @S9S_MB_2U_LIB.S9S_MB_2U(SCH_1):M_A_CPU0_SA_DQS_DP(0)   I202 @S9S_MB_2U_LIB.S9S_MB_2U(SCH_1):PAGE82
    12 M_A_CPU0_SA_DQS_DN<0> @S9S_MB_2U_LIB.S9S_MB_2U(SCH_1):M_A_CPU0_SA_DQS_DN(0)   I202 @S9S_MB_2U_LIB.S9S_MB_2U(SCH_1):PAGE82
   272 M_A_CPU0_SB_DQS_DP<7> @S9S_MB_2U_LIB.S9S_MB_2U(SCH_1):M_A_CPU0_SB_DQS_DP(7)   I202 @S9S_MB_2U_LIB.S9S_MB_2U(SCH_1):PAGE82
   282 M_A_CPU0_SB_DQS_DN<8> @S9S_MB_2U_LIB.S9S_MB_2U(SCH_1):M_A_CPU0_SB_DQS_DN(8)   I202 @S9S_MB_2U_LIB.S9S_MB_2U(SCH_1):PAGE82
   283 M_A_CPU0_SB_DQS_DP<8> @S9S_MB_2U_LIB.S9S_MB_2U(SCH_1):M_A_CPU0_SB_DQS_DP(8)   I202 @S9S_MB_2U_LIB.S9S_MB_2U(SCH_1):PAGE82
   168 M_A_CPU0_SA_DQS_DP<6> @S9S_MB_2U_LIB.S9S_MB_2U(SCH_1):M_A_CPU0_SA_DQS_DP(6)   I202 @S9S_MB_2U_LIB.S9S_MB_2U(SCH_1):PAGE82
   178 M_A_CPU0_SA_DQS_DN<7> @S9S_MB_2U_LIB.S9S_MB_2U(SCH_1):M_A_CPU0_SA_DQS_DN(7)   I202 @S9S_MB_2U_LIB.S9S_MB_2U(SCH_1):PAGE82
     6    GND @S9S_MB_2U_LIB.S9S_MB_2U(SCH_1):GND   I203 @S9S_MB_2U_LIB.S9S_MB_2U(SCH_1):PAGE82
     8    GND @S9S_MB_2U_LIB.S9S_MB_2U(SCH_1):GND   I203 @S9S_MB_2U_LIB.S9S_MB_2U(SCH_1):PAGE82
    10    GND @S9S_MB_2U_LIB.S9S_MB_2U(SCH_1):GND   I203 @S9S_MB_2U_LIB.S9S_MB_2U(SCH_1):PAGE82
    13    GND @S9S_MB_2U_LIB.S9S_MB_2U(SCH_1):GND   I203 @S9S_MB_2U_LIB.S9S_MB_2U(SCH_1):PAGE82
    15    GND @S9S_MB_2U_LIB.S9S_MB_2U(SCH_1):GND   I203 @S9S_MB_2U_LIB.S9S_MB_2U(SCH_1):PAGE82
    17    GND @S9S_MB_2U_LIB.S9S_MB_2U(SCH_1):GND   I203 @S9S_MB_2U_LIB.S9S_MB_2U(SCH_1):PAGE82
    19    GND @S9S_MB_2U_LIB.S9S_MB_2U(SCH_1):GND   I203 @S9S_MB_2U_LIB.S9S_MB_2U(SCH_1):PAGE82
    21    GND @S9S_MB_2U_LIB.S9S_MB_2U(SCH_1):GND   I203 @S9S_MB_2U_LIB.S9S_MB_2U(SCH_1):PAGE82
    24    GND @S9S_MB_2U_LIB.S9S_MB_2U(SCH_1):GND   I203 @S9S_MB_2U_LIB.S9S_MB_2U(SCH_1):PAGE82
    26    GND @S9S_MB_2U_LIB.S9S_MB_2U(SCH_1):GND   I203 @S9S_MB_2U_LIB.S9S_MB_2U(SCH_1):PAGE82
    28    GND @S9S_MB_2U_LIB.S9S_MB_2U(SCH_1):GND   I203 @S9S_MB_2U_LIB.S9S_MB_2U(SCH_1):PAGE82
    30    GND @S9S_MB_2U_LIB.S9S_MB_2U(SCH_1):GND   I203 @S9S_MB_2U_LIB.S9S_MB_2U(SCH_1):PAGE82
    32    GND @S9S_MB_2U_LIB.S9S_MB_2U(SCH_1):GND   I203 @S9S_MB_2U_LIB.S9S_MB_2U(SCH_1):PAGE82
    35    GND @S9S_MB_2U_LIB.S9S_MB_2U(SCH_1):GND   I203 @S9S_MB_2U_LIB.S9S_MB_2U(SCH_1):PAGE82
    37    GND @S9S_MB_2U_LIB.S9S_MB_2U(SCH_1):GND   I203 @S9S_MB_2U_LIB.S9S_MB_2U(SCH_1):PAGE82
    39    GND @S9S_MB_2U_LIB.S9S_MB_2U(SCH_1):GND   I203 @S9S_MB_2U_LIB.S9S_MB_2U(SCH_1):PAGE82
    41    GND @S9S_MB_2U_LIB.S9S_MB_2U(SCH_1):GND   I203 @S9S_MB_2U_LIB.S9S_MB_2U(SCH_1):PAGE82
    43    GND @S9S_MB_2U_LIB.S9S_MB_2U(SCH_1):GND   I203 @S9S_MB_2U_LIB.S9S_MB_2U(SCH_1):PAGE82
    46    GND @S9S_MB_2U_LIB.S9S_MB_2U(SCH_1):GND   I203 @S9S_MB_2U_LIB.S9S_MB_2U(SCH_1):PAGE82
    48    GND @S9S_MB_2U_LIB.S9S_MB_2U(SCH_1):GND   I203 @S9S_MB_2U_LIB.S9S_MB_2U(SCH_1):PAGE82
    50    GND @S9S_MB_2U_LIB.S9S_MB_2U(SCH_1):GND   I203 @S9S_MB_2U_LIB.S9S_MB_2U(SCH_1):PAGE82
    52    GND @S9S_MB_2U_LIB.S9S_MB_2U(SCH_1):GND   I203 @S9S_MB_2U_LIB.S9S_MB_2U(SCH_1):PAGE82
    54    GND @S9S_MB_2U_LIB.S9S_MB_2U(SCH_1):GND   I203 @S9S_MB_2U_LIB.S9S_MB_2U(SCH_1):PAGE82
    57    GND @S9S_MB_2U_LIB.S9S_MB_2U(SCH_1):GND   I203 @S9S_MB_2U_LIB.S9S_MB_2U(SCH_1):PAGE82
    59    GND @S9S_MB_2U_LIB.S9S_MB_2U(SCH_1):GND   I203 @S9S_MB_2U_LIB.S9S_MB_2U(SCH_1):PAGE82
    61    GND @S9S_MB_2U_LIB.S9S_MB_2U(SCH_1):GND   I203 @S9S_MB_2U_LIB.S9S_MB_2U(SCH_1):PAGE82
    63    GND @S9S_MB_2U_LIB.S9S_MB_2U(SCH_1):GND   I203 @S9S_MB_2U_LIB.S9S_MB_2U(SCH_1):PAGE82
    65    GND @S9S_MB_2U_LIB.S9S_MB_2U(SCH_1):GND   I203 @S9S_MB_2U_LIB.S9S_MB_2U(SCH_1):PAGE82
    67    GND @S9S_MB_2U_LIB.S9S_MB_2U(SCH_1):GND   I203 @S9S_MB_2U_LIB.S9S_MB_2U(SCH_1):PAGE82
    69    GND @S9S_MB_2U_LIB.S9S_MB_2U(SCH_1):GND   I203 @S9S_MB_2U_LIB.S9S_MB_2U(SCH_1):PAGE82
    71    GND @S9S_MB_2U_LIB.S9S_MB_2U(SCH_1):GND   I203 @S9S_MB_2U_LIB.S9S_MB_2U(SCH_1):PAGE82
    73    GND @S9S_MB_2U_LIB.S9S_MB_2U(SCH_1):GND   I203 @S9S_MB_2U_LIB.S9S_MB_2U(SCH_1):PAGE82
    75    GND @S9S_MB_2U_LIB.S9S_MB_2U(SCH_1):GND   I203 @S9S_MB_2U_LIB.S9S_MB_2U(SCH_1):PAGE82
    77    GND @S9S_MB_2U_LIB.S9S_MB_2U(SCH_1):GND   I203 @S9S_MB_2U_LIB.S9S_MB_2U(SCH_1):PAGE82
    79    GND @S9S_MB_2U_LIB.S9S_MB_2U(SCH_1):GND   I203 @S9S_MB_2U_LIB.S9S_MB_2U(SCH_1):PAGE82
    81    GND @S9S_MB_2U_LIB.S9S_MB_2U(SCH_1):GND   I203 @S9S_MB_2U_LIB.S9S_MB_2U(SCH_1):PAGE82
    83    GND @S9S_MB_2U_LIB.S9S_MB_2U(SCH_1):GND   I203 @S9S_MB_2U_LIB.S9S_MB_2U(SCH_1):PAGE82
    85    GND @S9S_MB_2U_LIB.S9S_MB_2U(SCH_1):GND   I203 @S9S_MB_2U_LIB.S9S_MB_2U(SCH_1):PAGE82
    88    GND @S9S_MB_2U_LIB.S9S_MB_2U(SCH_1):GND   I203 @S9S_MB_2U_LIB.S9S_MB_2U(SCH_1):PAGE82
    90    GND @S9S_MB_2U_LIB.S9S_MB_2U(SCH_1):GND   I203 @S9S_MB_2U_LIB.S9S_MB_2U(SCH_1):PAGE82
    92    GND @S9S_MB_2U_LIB.S9S_MB_2U(SCH_1):GND   I203 @S9S_MB_2U_LIB.S9S_MB_2U(SCH_1):PAGE82
    95    GND @S9S_MB_2U_LIB.S9S_MB_2U(SCH_1):GND   I203 @S9S_MB_2U_LIB.S9S_MB_2U(SCH_1):PAGE82
    97    GND @S9S_MB_2U_LIB.S9S_MB_2U(SCH_1):GND   I203 @S9S_MB_2U_LIB.S9S_MB_2U(SCH_1):PAGE82
    99    GND @S9S_MB_2U_LIB.S9S_MB_2U(SCH_1):GND   I203 @S9S_MB_2U_LIB.S9S_MB_2U(SCH_1):PAGE82
   101    GND @S9S_MB_2U_LIB.S9S_MB_2U(SCH_1):GND   I203 @S9S_MB_2U_LIB.S9S_MB_2U(SCH_1):PAGE82
   103    GND @S9S_MB_2U_LIB.S9S_MB_2U(SCH_1):GND   I203 @S9S_MB_2U_LIB.S9S_MB_2U(SCH_1):PAGE82
   106    GND @S9S_MB_2U_LIB.S9S_MB_2U(SCH_1):GND   I203 @S9S_MB_2U_LIB.S9S_MB_2U(SCH_1):PAGE82
   108    GND @S9S_MB_2U_LIB.S9S_MB_2U(SCH_1):GND   I203 @S9S_MB_2U_LIB.S9S_MB_2U(SCH_1):PAGE82
   110    GND @S9S_MB_2U_LIB.S9S_MB_2U(SCH_1):GND   I203 @S9S_MB_2U_LIB.S9S_MB_2U(SCH_1):PAGE82
   112    GND @S9S_MB_2U_LIB.S9S_MB_2U(SCH_1):GND   I203 @S9S_MB_2U_LIB.S9S_MB_2U(SCH_1):PAGE82
   114    GND @S9S_MB_2U_LIB.S9S_MB_2U(SCH_1):GND   I203 @S9S_MB_2U_LIB.S9S_MB_2U(SCH_1):PAGE82
   117    GND @S9S_MB_2U_LIB.S9S_MB_2U(SCH_1):GND   I203 @S9S_MB_2U_LIB.S9S_MB_2U(SCH_1):PAGE82
   119    GND @S9S_MB_2U_LIB.S9S_MB_2U(SCH_1):GND   I203 @S9S_MB_2U_LIB.S9S_MB_2U(SCH_1):PAGE82
   121    GND @S9S_MB_2U_LIB.S9S_MB_2U(SCH_1):GND   I203 @S9S_MB_2U_LIB.S9S_MB_2U(SCH_1):PAGE82
   123    GND @S9S_MB_2U_LIB.S9S_MB_2U(SCH_1):GND   I203 @S9S_MB_2U_LIB.S9S_MB_2U(SCH_1):PAGE82
   125    GND @S9S_MB_2U_LIB.S9S_MB_2U(SCH_1):GND   I203 @S9S_MB_2U_LIB.S9S_MB_2U(SCH_1):PAGE82
   128    GND @S9S_MB_2U_LIB.S9S_MB_2U(SCH_1):GND   I203 @S9S_MB_2U_LIB.S9S_MB_2U(SCH_1):PAGE82
   130    GND @S9S_MB_2U_LIB.S9S_MB_2U(SCH_1):GND   I203 @S9S_MB_2U_LIB.S9S_MB_2U(SCH_1):PAGE82
   134    GND @S9S_MB_2U_LIB.S9S_MB_2U(SCH_1):GND   I203 @S9S_MB_2U_LIB.S9S_MB_2U(SCH_1):PAGE82
   143    GND @S9S_MB_2U_LIB.S9S_MB_2U(SCH_1):GND   I203 @S9S_MB_2U_LIB.S9S_MB_2U(SCH_1):PAGE82
   151    GND @S9S_MB_2U_LIB.S9S_MB_2U(SCH_1):GND   I203 @S9S_MB_2U_LIB.S9S_MB_2U(SCH_1):PAGE82
   153    GND @S9S_MB_2U_LIB.S9S_MB_2U(SCH_1):GND   I203 @S9S_MB_2U_LIB.S9S_MB_2U(SCH_1):PAGE82
   155    GND @S9S_MB_2U_LIB.S9S_MB_2U(SCH_1):GND   I203 @S9S_MB_2U_LIB.S9S_MB_2U(SCH_1):PAGE82
   158    GND @S9S_MB_2U_LIB.S9S_MB_2U(SCH_1):GND   I203 @S9S_MB_2U_LIB.S9S_MB_2U(SCH_1):PAGE82
   160    GND @S9S_MB_2U_LIB.S9S_MB_2U(SCH_1):GND   I203 @S9S_MB_2U_LIB.S9S_MB_2U(SCH_1):PAGE82
   162    GND @S9S_MB_2U_LIB.S9S_MB_2U(SCH_1):GND   I203 @S9S_MB_2U_LIB.S9S_MB_2U(SCH_1):PAGE82
   164    GND @S9S_MB_2U_LIB.S9S_MB_2U(SCH_1):GND   I203 @S9S_MB_2U_LIB.S9S_MB_2U(SCH_1):PAGE82
   166    GND @S9S_MB_2U_LIB.S9S_MB_2U(SCH_1):GND   I203 @S9S_MB_2U_LIB.S9S_MB_2U(SCH_1):PAGE82
   169    GND @S9S_MB_2U_LIB.S9S_MB_2U(SCH_1):GND   I203 @S9S_MB_2U_LIB.S9S_MB_2U(SCH_1):PAGE82
   171    GND @S9S_MB_2U_LIB.S9S_MB_2U(SCH_1):GND   I203 @S9S_MB_2U_LIB.S9S_MB_2U(SCH_1):PAGE82
   173    GND @S9S_MB_2U_LIB.S9S_MB_2U(SCH_1):GND   I203 @S9S_MB_2U_LIB.S9S_MB_2U(SCH_1):PAGE82
   175    GND @S9S_MB_2U_LIB.S9S_MB_2U(SCH_1):GND   I203 @S9S_MB_2U_LIB.S9S_MB_2U(SCH_1):PAGE82
   177    GND @S9S_MB_2U_LIB.S9S_MB_2U(SCH_1):GND   I203 @S9S_MB_2U_LIB.S9S_MB_2U(SCH_1):PAGE82
   180    GND @S9S_MB_2U_LIB.S9S_MB_2U(SCH_1):GND   I203 @S9S_MB_2U_LIB.S9S_MB_2U(SCH_1):PAGE82
   182    GND @S9S_MB_2U_LIB.S9S_MB_2U(SCH_1):GND   I203 @S9S_MB_2U_LIB.S9S_MB_2U(SCH_1):PAGE82
   184    GND @S9S_MB_2U_LIB.S9S_MB_2U(SCH_1):GND   I203 @S9S_MB_2U_LIB.S9S_MB_2U(SCH_1):PAGE82
   186    GND @S9S_MB_2U_LIB.S9S_MB_2U(SCH_1):GND   I203 @S9S_MB_2U_LIB.S9S_MB_2U(SCH_1):PAGE82
   188    GND @S9S_MB_2U_LIB.S9S_MB_2U(SCH_1):GND   I203 @S9S_MB_2U_LIB.S9S_MB_2U(SCH_1):PAGE82
   191    GND @S9S_MB_2U_LIB.S9S_MB_2U(SCH_1):GND   I203 @S9S_MB_2U_LIB.S9S_MB_2U(SCH_1):PAGE82
   193    GND @S9S_MB_2U_LIB.S9S_MB_2U(SCH_1):GND   I203 @S9S_MB_2U_LIB.S9S_MB_2U(SCH_1):PAGE82
   195    GND @S9S_MB_2U_LIB.S9S_MB_2U(SCH_1):GND   I203 @S9S_MB_2U_LIB.S9S_MB_2U(SCH_1):PAGE82
   197    GND @S9S_MB_2U_LIB.S9S_MB_2U(SCH_1):GND   I203 @S9S_MB_2U_LIB.S9S_MB_2U(SCH_1):PAGE82
   199    GND @S9S_MB_2U_LIB.S9S_MB_2U(SCH_1):GND   I203 @S9S_MB_2U_LIB.S9S_MB_2U(SCH_1):PAGE82
   202    GND @S9S_MB_2U_LIB.S9S_MB_2U(SCH_1):GND   I203 @S9S_MB_2U_LIB.S9S_MB_2U(SCH_1):PAGE82
   204    GND @S9S_MB_2U_LIB.S9S_MB_2U(SCH_1):GND   I203 @S9S_MB_2U_LIB.S9S_MB_2U(SCH_1):PAGE82
   206    GND @S9S_MB_2U_LIB.S9S_MB_2U(SCH_1):GND   I203 @S9S_MB_2U_LIB.S9S_MB_2U(SCH_1):PAGE82
   208    GND @S9S_MB_2U_LIB.S9S_MB_2U(SCH_1):GND   I203 @S9S_MB_2U_LIB.S9S_MB_2U(SCH_1):PAGE82
   210    GND @S9S_MB_2U_LIB.S9S_MB_2U(SCH_1):GND   I203 @S9S_MB_2U_LIB.S9S_MB_2U(SCH_1):PAGE82
   212    GND @S9S_MB_2U_LIB.S9S_MB_2U(SCH_1):GND   I203 @S9S_MB_2U_LIB.S9S_MB_2U(SCH_1):PAGE82
   214    GND @S9S_MB_2U_LIB.S9S_MB_2U(SCH_1):GND   I203 @S9S_MB_2U_LIB.S9S_MB_2U(SCH_1):PAGE82
   216    GND @S9S_MB_2U_LIB.S9S_MB_2U(SCH_1):GND   I203 @S9S_MB_2U_LIB.S9S_MB_2U(SCH_1):PAGE82
   219    GND @S9S_MB_2U_LIB.S9S_MB_2U(SCH_1):GND   I203 @S9S_MB_2U_LIB.S9S_MB_2U(SCH_1):PAGE82
   222    GND @S9S_MB_2U_LIB.S9S_MB_2U(SCH_1):GND   I203 @S9S_MB_2U_LIB.S9S_MB_2U(SCH_1):PAGE82
   224    GND @S9S_MB_2U_LIB.S9S_MB_2U(SCH_1):GND   I203 @S9S_MB_2U_LIB.S9S_MB_2U(SCH_1):PAGE82
   226    GND @S9S_MB_2U_LIB.S9S_MB_2U(SCH_1):GND   I203 @S9S_MB_2U_LIB.S9S_MB_2U(SCH_1):PAGE82
   228    GND @S9S_MB_2U_LIB.S9S_MB_2U(SCH_1):GND   I203 @S9S_MB_2U_LIB.S9S_MB_2U(SCH_1):PAGE82
   233    GND @S9S_MB_2U_LIB.S9S_MB_2U(SCH_1):GND   I203 @S9S_MB_2U_LIB.S9S_MB_2U(SCH_1):PAGE82
   237    GND @S9S_MB_2U_LIB.S9S_MB_2U(SCH_1):GND   I203 @S9S_MB_2U_LIB.S9S_MB_2U(SCH_1):PAGE82
   242    GND @S9S_MB_2U_LIB.S9S_MB_2U(SCH_1):GND   I203 @S9S_MB_2U_LIB.S9S_MB_2U(SCH_1):PAGE82
   244    GND @S9S_MB_2U_LIB.S9S_MB_2U(SCH_1):GND   I203 @S9S_MB_2U_LIB.S9S_MB_2U(SCH_1):PAGE82
   246    GND @S9S_MB_2U_LIB.S9S_MB_2U(SCH_1):GND   I203 @S9S_MB_2U_LIB.S9S_MB_2U(SCH_1):PAGE82
   248    GND @S9S_MB_2U_LIB.S9S_MB_2U(SCH_1):GND   I203 @S9S_MB_2U_LIB.S9S_MB_2U(SCH_1):PAGE82
   251    GND @S9S_MB_2U_LIB.S9S_MB_2U(SCH_1):GND   I203 @S9S_MB_2U_LIB.S9S_MB_2U(SCH_1):PAGE82
   253    GND @S9S_MB_2U_LIB.S9S_MB_2U(SCH_1):GND   I203 @S9S_MB_2U_LIB.S9S_MB_2U(SCH_1):PAGE82
   255    GND @S9S_MB_2U_LIB.S9S_MB_2U(SCH_1):GND   I203 @S9S_MB_2U_LIB.S9S_MB_2U(SCH_1):PAGE82
   257    GND @S9S_MB_2U_LIB.S9S_MB_2U(SCH_1):GND   I203 @S9S_MB_2U_LIB.S9S_MB_2U(SCH_1):PAGE82
   259    GND @S9S_MB_2U_LIB.S9S_MB_2U(SCH_1):GND   I203 @S9S_MB_2U_LIB.S9S_MB_2U(SCH_1):PAGE82
   262    GND @S9S_MB_2U_LIB.S9S_MB_2U(SCH_1):GND   I203 @S9S_MB_2U_LIB.S9S_MB_2U(SCH_1):PAGE82
   264    GND @S9S_MB_2U_LIB.S9S_MB_2U(SCH_1):GND   I203 @S9S_MB_2U_LIB.S9S_MB_2U(SCH_1):PAGE82
   266    GND @S9S_MB_2U_LIB.S9S_MB_2U(SCH_1):GND   I203 @S9S_MB_2U_LIB.S9S_MB_2U(SCH_1):PAGE82
   268    GND @S9S_MB_2U_LIB.S9S_MB_2U(SCH_1):GND   I203 @S9S_MB_2U_LIB.S9S_MB_2U(SCH_1):PAGE82
   270    GND @S9S_MB_2U_LIB.S9S_MB_2U(SCH_1):GND   I203 @S9S_MB_2U_LIB.S9S_MB_2U(SCH_1):PAGE82
   273    GND @S9S_MB_2U_LIB.S9S_MB_2U(SCH_1):GND   I203 @S9S_MB_2U_LIB.S9S_MB_2U(SCH_1):PAGE82
   275    GND @S9S_MB_2U_LIB.S9S_MB_2U(SCH_1):GND   I203 @S9S_MB_2U_LIB.S9S_MB_2U(SCH_1):PAGE82
   277    GND @S9S_MB_2U_LIB.S9S_MB_2U(SCH_1):GND   I203 @S9S_MB_2U_LIB.S9S_MB_2U(SCH_1):PAGE82
   279    GND @S9S_MB_2U_LIB.S9S_MB_2U(SCH_1):GND   I203 @S9S_MB_2U_LIB.S9S_MB_2U(SCH_1):PAGE82
   281    GND @S9S_MB_2U_LIB.S9S_MB_2U(SCH_1):GND   I203 @S9S_MB_2U_LIB.S9S_MB_2U(SCH_1):PAGE82
   284    GND @S9S_MB_2U_LIB.S9S_MB_2U(SCH_1):GND   I203 @S9S_MB_2U_LIB.S9S_MB_2U(SCH_1):PAGE82
   286    GND @S9S_MB_2U_LIB.S9S_MB_2U(SCH_1):GND   I203 @S9S_MB_2U_LIB.S9S_MB_2U(SCH_1):PAGE82
   288    GND @S9S_MB_2U_LIB.S9S_MB_2U(SCH_1):GND   I203 @S9S_MB_2U_LIB.S9S_MB_2U(SCH_1):PAGE82
     1 P12V_S3_AUX_CPU0_NVDIMM @S9S_MB_2U_LIB.S9S_MB_2U(SCH_1):P12V_S3_AUX_CPU0_NVDIMM   I203 @S9S_MB_2U_LIB.S9S_MB_2U(SCH_1):PAGE82
   145 P12V_S3_AUX_CPU0_NVDIMM @S9S_MB_2U_LIB.S9S_MB_2U(SCH_1):P12V_S3_AUX_CPU0_NVDIMM   I203 @S9S_MB_2U_LIB.S9S_MB_2U(SCH_1):PAGE82
   146 P12V_S3_AUX_CPU0_NVDIMM @S9S_MB_2U_LIB.S9S_MB_2U(SCH_1):P12V_S3_AUX_CPU0_NVDIMM   I203 @S9S_MB_2U_LIB.S9S_MB_2U(SCH_1):PAGE82
   230    GND @S9S_MB_2U_LIB.S9S_MB_2U(SCH_1):GND   I203 @S9S_MB_2U_LIB.S9S_MB_2U(SCH_1):PAGE82
   235    GND @S9S_MB_2U_LIB.S9S_MB_2U(SCH_1):GND   I203 @S9S_MB_2U_LIB.S9S_MB_2U(SCH_1):PAGE82
   240    GND @S9S_MB_2U_LIB.S9S_MB_2U(SCH_1):GND   I203 @S9S_MB_2U_LIB.S9S_MB_2U(SCH_1):PAGE82
   132    GND @S9S_MB_2U_LIB.S9S_MB_2U(SCH_1):GND   I203 @S9S_MB_2U_LIB.S9S_MB_2U(SCH_1):PAGE82
   136    GND @S9S_MB_2U_LIB.S9S_MB_2U(SCH_1):GND   I203 @S9S_MB_2U_LIB.S9S_MB_2U(SCH_1):PAGE82
   139    GND @S9S_MB_2U_LIB.S9S_MB_2U(SCH_1):GND   I203 @S9S_MB_2U_LIB.S9S_MB_2U(SCH_1):PAGE82
   141    GND @S9S_MB_2U_LIB.S9S_MB_2U(SCH_1):GND   I203 @S9S_MB_2U_LIB.S9S_MB_2U(SCH_1):PAGE82
    G1    GND @S9S_MB_2U_LIB.S9S_MB_2U(SCH_1):GND   I203 @S9S_MB_2U_LIB.S9S_MB_2U(SCH_1):PAGE82
    G2    GND @S9S_MB_2U_LIB.S9S_MB_2U(SCH_1):GND   I203 @S9S_MB_2U_LIB.S9S_MB_2U(SCH_1):PAGE82
    G3    GND @S9S_MB_2U_LIB.S9S_MB_2U(SCH_1):GND   I203 @S9S_MB_2U_LIB.S9S_MB_2U(SCH_1):PAGE82

  J2 SCONN288_ADR50017P087CC-SCONN2A
     3 P3V3_AUX @S9S_MB_2U_LIB.S9S_MB_2U(SCH_1):P3V3_AUX   I177 @S9S_MB_2U_LIB.S9S_MB_2U(SCH_1):PAGE83
     2 TP_CHA_CPU0_DIMM2_FRU_0 @S9S_MB_2U_LIB.S9S_MB_2U(SCH_1):TP_CHA_CPU0_DIMM2_FRU_0   I177 @S9S_MB_2U_LIB.S9S_MB_2U(SCH_1):PAGE83
   144 TP_CHA_CPU0_DIMM2_FRU_1 @S9S_MB_2U_LIB.S9S_MB_2U(SCH_1):TP_CHA_CPU0_DIMM2_FRU_1   I177 @S9S_MB_2U_LIB.S9S_MB_2U(SCH_1):PAGE83
   149 TP_CHA_CPU0_DIMM2_FRU_2 @S9S_MB_2U_LIB.S9S_MB_2U(SCH_1):TP_CHA_CPU0_DIMM2_FRU_2   I177 @S9S_MB_2U_LIB.S9S_MB_2U(SCH_1):PAGE83
   150 TP_CHA_CPU0_DIMM2_FRU_3 @S9S_MB_2U_LIB.S9S_MB_2U(SCH_1):TP_CHA_CPU0_DIMM2_FRU_3   I177 @S9S_MB_2U_LIB.S9S_MB_2U(SCH_1):PAGE83
   220 TP_CHA_CPU0_DIMM2_FRU_4 @S9S_MB_2U_LIB.S9S_MB_2U(SCH_1):TP_CHA_CPU0_DIMM2_FRU_4   I177 @S9S_MB_2U_LIB.S9S_MB_2U(SCH_1):PAGE83
   231 TP_CHA_CPU0_DIMM2_FRU_5 @S9S_MB_2U_LIB.S9S_MB_2U(SCH_1):TP_CHA_CPU0_DIMM2_FRU_5   I177 @S9S_MB_2U_LIB.S9S_MB_2U(SCH_1):PAGE83
   232 TP_CHA_CPU0_DIMM2_FRU_6 @S9S_MB_2U_LIB.S9S_MB_2U(SCH_1):TP_CHA_CPU0_DIMM2_FRU_6   I177 @S9S_MB_2U_LIB.S9S_MB_2U(SCH_1):PAGE83
   207 RST_M_AB_CPU0_FPGA_N @S9S_MB_2U_LIB.S9S_MB_2U(SCH_1):RST_M_AB_CPU0_FPGA_N   I177 @S9S_MB_2U_LIB.S9S_MB_2U(SCH_1):PAGE83
   147 PWRGD_CHA_CPU0_DIMM2 @S9S_MB_2U_LIB.S9S_MB_2U(SCH_1):PWRGD_CHA_CPU0_DIMM2   I177 @S9S_MB_2U_LIB.S9S_MB_2U(SCH_1):PAGE83
   227 M_A_CPU0_SB_PAR @S9S_MB_2U_LIB.S9S_MB_2U(SCH_1):M_A_CPU0_SB_PAR   I177 @S9S_MB_2U_LIB.S9S_MB_2U(SCH_1):PAGE83
    74 M_A_CPU0_SA_PAR @S9S_MB_2U_LIB.S9S_MB_2U(SCH_1):M_A_CPU0_SA_PAR   I177 @S9S_MB_2U_LIB.S9S_MB_2U(SCH_1):PAGE83
    87 M_A_CPU0_SB_RSP<1> @S9S_MB_2U_LIB.S9S_MB_2U(SCH_1):M_A_CPU0_SB_RSP(1)   I177 @S9S_MB_2U_LIB.S9S_MB_2U(SCH_1):PAGE83
    86 M_A_CPU0_SA_RSP<1> @S9S_MB_2U_LIB.S9S_MB_2U(SCH_1):M_A_CPU0_SA_RSP(1)   I177 @S9S_MB_2U_LIB.S9S_MB_2U(SCH_1):PAGE83
     5 I3C_SPD_DDRABCD_CPU0_LVC1_SDA @S9S_MB_2U_LIB.S9S_MB_2U(SCH_1):I3C_SPD_DDRABCD_CPU0_LVC1_SDA   I177 @S9S_MB_2U_LIB.S9S_MB_2U(SCH_1):PAGE83
     4 I3C_SPD_DDRABCD_CPU0_LVC1_SCL_1 @S9S_MB_2U_LIB.S9S_MB_2U(SCH_1):I3C_SPD_DDRABCD_CPU0_LVC1_SCL_R2   I177 @S9S_MB_2U_LIB.S9S_MB_2U(SCH_1):PAGE83
   148 PD_CHA_CPU0_DIMM2_SAA @S9S_MB_2U_LIB.S9S_MB_2U(SCH_1):PD_CHA_CPU0_DIMM2_SAA   I177 @S9S_MB_2U_LIB.S9S_MB_2U(SCH_1):PAGE83
   100 M_A_CPU0_SB_DQ<0> @S9S_MB_2U_LIB.S9S_MB_2U(SCH_1):M_A_CPU0_SB_DQ(0)   I177 @S9S_MB_2U_LIB.S9S_MB_2U(SCH_1):PAGE83
   102 M_A_CPU0_SB_DQ<1> @S9S_MB_2U_LIB.S9S_MB_2U(SCH_1):M_A_CPU0_SB_DQ(1)   I177 @S9S_MB_2U_LIB.S9S_MB_2U(SCH_1):PAGE83
   245 M_A_CPU0_SB_DQ<2> @S9S_MB_2U_LIB.S9S_MB_2U(SCH_1):M_A_CPU0_SB_DQ(2)   I177 @S9S_MB_2U_LIB.S9S_MB_2U(SCH_1):PAGE83
   247 M_A_CPU0_SB_DQ<3> @S9S_MB_2U_LIB.S9S_MB_2U(SCH_1):M_A_CPU0_SB_DQ(3)   I177 @S9S_MB_2U_LIB.S9S_MB_2U(SCH_1):PAGE83
   107 M_A_CPU0_SB_DQ<4> @S9S_MB_2U_LIB.S9S_MB_2U(SCH_1):M_A_CPU0_SB_DQ(4)   I177 @S9S_MB_2U_LIB.S9S_MB_2U(SCH_1):PAGE83
   109 M_A_CPU0_SB_DQ<5> @S9S_MB_2U_LIB.S9S_MB_2U(SCH_1):M_A_CPU0_SB_DQ(5)   I177 @S9S_MB_2U_LIB.S9S_MB_2U(SCH_1):PAGE83
   252 M_A_CPU0_SB_DQ<6> @S9S_MB_2U_LIB.S9S_MB_2U(SCH_1):M_A_CPU0_SB_DQ(6)   I177 @S9S_MB_2U_LIB.S9S_MB_2U(SCH_1):PAGE83
   254 M_A_CPU0_SB_DQ<7> @S9S_MB_2U_LIB.S9S_MB_2U(SCH_1):M_A_CPU0_SB_DQ(7)   I177 @S9S_MB_2U_LIB.S9S_MB_2U(SCH_1):PAGE83
   111 M_A_CPU0_SB_DQ<8> @S9S_MB_2U_LIB.S9S_MB_2U(SCH_1):M_A_CPU0_SB_DQ(8)   I177 @S9S_MB_2U_LIB.S9S_MB_2U(SCH_1):PAGE83
   113 M_A_CPU0_SB_DQ<9> @S9S_MB_2U_LIB.S9S_MB_2U(SCH_1):M_A_CPU0_SB_DQ(9)   I177 @S9S_MB_2U_LIB.S9S_MB_2U(SCH_1):PAGE83
   256 M_A_CPU0_SB_DQ<10> @S9S_MB_2U_LIB.S9S_MB_2U(SCH_1):M_A_CPU0_SB_DQ(10)   I177 @S9S_MB_2U_LIB.S9S_MB_2U(SCH_1):PAGE83
   258 M_A_CPU0_SB_DQ<11> @S9S_MB_2U_LIB.S9S_MB_2U(SCH_1):M_A_CPU0_SB_DQ(11)   I177 @S9S_MB_2U_LIB.S9S_MB_2U(SCH_1):PAGE83
   118 M_A_CPU0_SB_DQ<12> @S9S_MB_2U_LIB.S9S_MB_2U(SCH_1):M_A_CPU0_SB_DQ(12)   I177 @S9S_MB_2U_LIB.S9S_MB_2U(SCH_1):PAGE83
   120 M_A_CPU0_SB_DQ<13> @S9S_MB_2U_LIB.S9S_MB_2U(SCH_1):M_A_CPU0_SB_DQ(13)   I177 @S9S_MB_2U_LIB.S9S_MB_2U(SCH_1):PAGE83
   263 M_A_CPU0_SB_DQ<14> @S9S_MB_2U_LIB.S9S_MB_2U(SCH_1):M_A_CPU0_SB_DQ(14)   I177 @S9S_MB_2U_LIB.S9S_MB_2U(SCH_1):PAGE83
   265 M_A_CPU0_SB_DQ<15> @S9S_MB_2U_LIB.S9S_MB_2U(SCH_1):M_A_CPU0_SB_DQ(15)   I177 @S9S_MB_2U_LIB.S9S_MB_2U(SCH_1):PAGE83
   122 M_A_CPU0_SB_DQ<16> @S9S_MB_2U_LIB.S9S_MB_2U(SCH_1):M_A_CPU0_SB_DQ(16)   I177 @S9S_MB_2U_LIB.S9S_MB_2U(SCH_1):PAGE83
   124 M_A_CPU0_SB_DQ<17> @S9S_MB_2U_LIB.S9S_MB_2U(SCH_1):M_A_CPU0_SB_DQ(17)   I177 @S9S_MB_2U_LIB.S9S_MB_2U(SCH_1):PAGE83
   267 M_A_CPU0_SB_DQ<18> @S9S_MB_2U_LIB.S9S_MB_2U(SCH_1):M_A_CPU0_SB_DQ(18)   I177 @S9S_MB_2U_LIB.S9S_MB_2U(SCH_1):PAGE83
   269 M_A_CPU0_SB_DQ<19> @S9S_MB_2U_LIB.S9S_MB_2U(SCH_1):M_A_CPU0_SB_DQ(19)   I177 @S9S_MB_2U_LIB.S9S_MB_2U(SCH_1):PAGE83
   129 M_A_CPU0_SB_DQ<20> @S9S_MB_2U_LIB.S9S_MB_2U(SCH_1):M_A_CPU0_SB_DQ(20)   I177 @S9S_MB_2U_LIB.S9S_MB_2U(SCH_1):PAGE83
   131 M_A_CPU0_SB_DQ<21> @S9S_MB_2U_LIB.S9S_MB_2U(SCH_1):M_A_CPU0_SB_DQ(21)   I177 @S9S_MB_2U_LIB.S9S_MB_2U(SCH_1):PAGE83
   274 M_A_CPU0_SB_DQ<22> @S9S_MB_2U_LIB.S9S_MB_2U(SCH_1):M_A_CPU0_SB_DQ(22)   I177 @S9S_MB_2U_LIB.S9S_MB_2U(SCH_1):PAGE83
   276 M_A_CPU0_SB_DQ<23> @S9S_MB_2U_LIB.S9S_MB_2U(SCH_1):M_A_CPU0_SB_DQ(23)   I177 @S9S_MB_2U_LIB.S9S_MB_2U(SCH_1):PAGE83
   133 M_A_CPU0_SB_DQ<24> @S9S_MB_2U_LIB.S9S_MB_2U(SCH_1):M_A_CPU0_SB_DQ(24)   I177 @S9S_MB_2U_LIB.S9S_MB_2U(SCH_1):PAGE83
   135 M_A_CPU0_SB_DQ<25> @S9S_MB_2U_LIB.S9S_MB_2U(SCH_1):M_A_CPU0_SB_DQ(25)   I177 @S9S_MB_2U_LIB.S9S_MB_2U(SCH_1):PAGE83
   278 M_A_CPU0_SB_DQ<26> @S9S_MB_2U_LIB.S9S_MB_2U(SCH_1):M_A_CPU0_SB_DQ(26)   I177 @S9S_MB_2U_LIB.S9S_MB_2U(SCH_1):PAGE83
   280 M_A_CPU0_SB_DQ<27> @S9S_MB_2U_LIB.S9S_MB_2U(SCH_1):M_A_CPU0_SB_DQ(27)   I177 @S9S_MB_2U_LIB.S9S_MB_2U(SCH_1):PAGE83
   140 M_A_CPU0_SB_DQ<28> @S9S_MB_2U_LIB.S9S_MB_2U(SCH_1):M_A_CPU0_SB_DQ(28)   I177 @S9S_MB_2U_LIB.S9S_MB_2U(SCH_1):PAGE83
   142 M_A_CPU0_SB_DQ<29> @S9S_MB_2U_LIB.S9S_MB_2U(SCH_1):M_A_CPU0_SB_DQ(29)   I177 @S9S_MB_2U_LIB.S9S_MB_2U(SCH_1):PAGE83
   285 M_A_CPU0_SB_DQ<30> @S9S_MB_2U_LIB.S9S_MB_2U(SCH_1):M_A_CPU0_SB_DQ(30)   I177 @S9S_MB_2U_LIB.S9S_MB_2U(SCH_1):PAGE83
   287 M_A_CPU0_SB_DQ<31> @S9S_MB_2U_LIB.S9S_MB_2U(SCH_1):M_A_CPU0_SB_DQ(31)   I177 @S9S_MB_2U_LIB.S9S_MB_2U(SCH_1):PAGE83
     7 M_A_CPU0_SA_DQ<0> @S9S_MB_2U_LIB.S9S_MB_2U(SCH_1):M_A_CPU0_SA_DQ(0)   I177 @S9S_MB_2U_LIB.S9S_MB_2U(SCH_1):PAGE83
     9 M_A_CPU0_SA_DQ<1> @S9S_MB_2U_LIB.S9S_MB_2U(SCH_1):M_A_CPU0_SA_DQ(1)   I177 @S9S_MB_2U_LIB.S9S_MB_2U(SCH_1):PAGE83
   152 M_A_CPU0_SA_DQ<2> @S9S_MB_2U_LIB.S9S_MB_2U(SCH_1):M_A_CPU0_SA_DQ(2)   I177 @S9S_MB_2U_LIB.S9S_MB_2U(SCH_1):PAGE83
   154 M_A_CPU0_SA_DQ<3> @S9S_MB_2U_LIB.S9S_MB_2U(SCH_1):M_A_CPU0_SA_DQ(3)   I177 @S9S_MB_2U_LIB.S9S_MB_2U(SCH_1):PAGE83
    14 M_A_CPU0_SA_DQ<4> @S9S_MB_2U_LIB.S9S_MB_2U(SCH_1):M_A_CPU0_SA_DQ(4)   I177 @S9S_MB_2U_LIB.S9S_MB_2U(SCH_1):PAGE83
    16 M_A_CPU0_SA_DQ<5> @S9S_MB_2U_LIB.S9S_MB_2U(SCH_1):M_A_CPU0_SA_DQ(5)   I177 @S9S_MB_2U_LIB.S9S_MB_2U(SCH_1):PAGE83
   159 M_A_CPU0_SA_DQ<6> @S9S_MB_2U_LIB.S9S_MB_2U(SCH_1):M_A_CPU0_SA_DQ(6)   I177 @S9S_MB_2U_LIB.S9S_MB_2U(SCH_1):PAGE83
   161 M_A_CPU0_SA_DQ<7> @S9S_MB_2U_LIB.S9S_MB_2U(SCH_1):M_A_CPU0_SA_DQ(7)   I177 @S9S_MB_2U_LIB.S9S_MB_2U(SCH_1):PAGE83
    18 M_A_CPU0_SA_DQ<8> @S9S_MB_2U_LIB.S9S_MB_2U(SCH_1):M_A_CPU0_SA_DQ(8)   I177 @S9S_MB_2U_LIB.S9S_MB_2U(SCH_1):PAGE83
    20 M_A_CPU0_SA_DQ<9> @S9S_MB_2U_LIB.S9S_MB_2U(SCH_1):M_A_CPU0_SA_DQ(9)   I177 @S9S_MB_2U_LIB.S9S_MB_2U(SCH_1):PAGE83
   163 M_A_CPU0_SA_DQ<10> @S9S_MB_2U_LIB.S9S_MB_2U(SCH_1):M_A_CPU0_SA_DQ(10)   I177 @S9S_MB_2U_LIB.S9S_MB_2U(SCH_1):PAGE83
   165 M_A_CPU0_SA_DQ<11> @S9S_MB_2U_LIB.S9S_MB_2U(SCH_1):M_A_CPU0_SA_DQ(11)   I177 @S9S_MB_2U_LIB.S9S_MB_2U(SCH_1):PAGE83
    25 M_A_CPU0_SA_DQ<12> @S9S_MB_2U_LIB.S9S_MB_2U(SCH_1):M_A_CPU0_SA_DQ(12)   I177 @S9S_MB_2U_LIB.S9S_MB_2U(SCH_1):PAGE83
    27 M_A_CPU0_SA_DQ<13> @S9S_MB_2U_LIB.S9S_MB_2U(SCH_1):M_A_CPU0_SA_DQ(13)   I177 @S9S_MB_2U_LIB.S9S_MB_2U(SCH_1):PAGE83
   170 M_A_CPU0_SA_DQ<14> @S9S_MB_2U_LIB.S9S_MB_2U(SCH_1):M_A_CPU0_SA_DQ(14)   I177 @S9S_MB_2U_LIB.S9S_MB_2U(SCH_1):PAGE83
   172 M_A_CPU0_SA_DQ<15> @S9S_MB_2U_LIB.S9S_MB_2U(SCH_1):M_A_CPU0_SA_DQ(15)   I177 @S9S_MB_2U_LIB.S9S_MB_2U(SCH_1):PAGE83
    29 M_A_CPU0_SA_DQ<16> @S9S_MB_2U_LIB.S9S_MB_2U(SCH_1):M_A_CPU0_SA_DQ(16)   I177 @S9S_MB_2U_LIB.S9S_MB_2U(SCH_1):PAGE83
    31 M_A_CPU0_SA_DQ<17> @S9S_MB_2U_LIB.S9S_MB_2U(SCH_1):M_A_CPU0_SA_DQ(17)   I177 @S9S_MB_2U_LIB.S9S_MB_2U(SCH_1):PAGE83
   174 M_A_CPU0_SA_DQ<18> @S9S_MB_2U_LIB.S9S_MB_2U(SCH_1):M_A_CPU0_SA_DQ(18)   I177 @S9S_MB_2U_LIB.S9S_MB_2U(SCH_1):PAGE83
   176 M_A_CPU0_SA_DQ<19> @S9S_MB_2U_LIB.S9S_MB_2U(SCH_1):M_A_CPU0_SA_DQ(19)   I177 @S9S_MB_2U_LIB.S9S_MB_2U(SCH_1):PAGE83
    36 M_A_CPU0_SA_DQ<20> @S9S_MB_2U_LIB.S9S_MB_2U(SCH_1):M_A_CPU0_SA_DQ(20)   I177 @S9S_MB_2U_LIB.S9S_MB_2U(SCH_1):PAGE83
    38 M_A_CPU0_SA_DQ<21> @S9S_MB_2U_LIB.S9S_MB_2U(SCH_1):M_A_CPU0_SA_DQ(21)   I177 @S9S_MB_2U_LIB.S9S_MB_2U(SCH_1):PAGE83
   181 M_A_CPU0_SA_DQ<22> @S9S_MB_2U_LIB.S9S_MB_2U(SCH_1):M_A_CPU0_SA_DQ(22)   I177 @S9S_MB_2U_LIB.S9S_MB_2U(SCH_1):PAGE83
   183 M_A_CPU0_SA_DQ<23> @S9S_MB_2U_LIB.S9S_MB_2U(SCH_1):M_A_CPU0_SA_DQ(23)   I177 @S9S_MB_2U_LIB.S9S_MB_2U(SCH_1):PAGE83
    40 M_A_CPU0_SA_DQ<24> @S9S_MB_2U_LIB.S9S_MB_2U(SCH_1):M_A_CPU0_SA_DQ(24)   I177 @S9S_MB_2U_LIB.S9S_MB_2U(SCH_1):PAGE83
    42 M_A_CPU0_SA_DQ<25> @S9S_MB_2U_LIB.S9S_MB_2U(SCH_1):M_A_CPU0_SA_DQ(25)   I177 @S9S_MB_2U_LIB.S9S_MB_2U(SCH_1):PAGE83
   185 M_A_CPU0_SA_DQ<26> @S9S_MB_2U_LIB.S9S_MB_2U(SCH_1):M_A_CPU0_SA_DQ(26)   I177 @S9S_MB_2U_LIB.S9S_MB_2U(SCH_1):PAGE83
   187 M_A_CPU0_SA_DQ<27> @S9S_MB_2U_LIB.S9S_MB_2U(SCH_1):M_A_CPU0_SA_DQ(27)   I177 @S9S_MB_2U_LIB.S9S_MB_2U(SCH_1):PAGE83
    47 M_A_CPU0_SA_DQ<28> @S9S_MB_2U_LIB.S9S_MB_2U(SCH_1):M_A_CPU0_SA_DQ(28)   I177 @S9S_MB_2U_LIB.S9S_MB_2U(SCH_1):PAGE83
    49 M_A_CPU0_SA_DQ<29> @S9S_MB_2U_LIB.S9S_MB_2U(SCH_1):M_A_CPU0_SA_DQ(29)   I177 @S9S_MB_2U_LIB.S9S_MB_2U(SCH_1):PAGE83
   192 M_A_CPU0_SA_DQ<30> @S9S_MB_2U_LIB.S9S_MB_2U(SCH_1):M_A_CPU0_SA_DQ(30)   I177 @S9S_MB_2U_LIB.S9S_MB_2U(SCH_1):PAGE83
   229 M_A_CPU0_SB_CS_N<3> @S9S_MB_2U_LIB.S9S_MB_2U(SCH_1):M_A_CPU0_SB_CS_N(3)   I177 @S9S_MB_2U_LIB.S9S_MB_2U(SCH_1):PAGE83
   209 M_A_CPU0_SA_CS_N<3> @S9S_MB_2U_LIB.S9S_MB_2U(SCH_1):M_A_CPU0_SA_CS_N(3)   I177 @S9S_MB_2U_LIB.S9S_MB_2U(SCH_1):PAGE83
    84 M_A_CPU0_SB_CS_N<2> @S9S_MB_2U_LIB.S9S_MB_2U(SCH_1):M_A_CPU0_SB_CS_N(2)   I177 @S9S_MB_2U_LIB.S9S_MB_2U(SCH_1):PAGE83
    64 M_A_CPU0_SA_CS_N<2> @S9S_MB_2U_LIB.S9S_MB_2U(SCH_1):M_A_CPU0_SA_CS_N(2)   I177 @S9S_MB_2U_LIB.S9S_MB_2U(SCH_1):PAGE83
   217 M_A_CPU0_CLK_DP<1> @S9S_MB_2U_LIB.S9S_MB_2U(SCH_1):M_A_CPU0_CLK_DP(1)   I177 @S9S_MB_2U_LIB.S9S_MB_2U(SCH_1):PAGE83
   218 M_A_CPU0_CLK_DN<1> @S9S_MB_2U_LIB.S9S_MB_2U(SCH_1):M_A_CPU0_CLK_DN(1)   I177 @S9S_MB_2U_LIB.S9S_MB_2U(SCH_1):PAGE83
    96 M_A_CPU0_SB_CB<0> @S9S_MB_2U_LIB.S9S_MB_2U(SCH_1):M_A_CPU0_SB_CB(0)   I177 @S9S_MB_2U_LIB.S9S_MB_2U(SCH_1):PAGE83
    98 M_A_CPU0_SB_CB<1> @S9S_MB_2U_LIB.S9S_MB_2U(SCH_1):M_A_CPU0_SB_CB(1)   I177 @S9S_MB_2U_LIB.S9S_MB_2U(SCH_1):PAGE83
   241 M_A_CPU0_SB_CB<2> @S9S_MB_2U_LIB.S9S_MB_2U(SCH_1):M_A_CPU0_SB_CB(2)   I177 @S9S_MB_2U_LIB.S9S_MB_2U(SCH_1):PAGE83
   243 M_A_CPU0_SB_CB<3> @S9S_MB_2U_LIB.S9S_MB_2U(SCH_1):M_A_CPU0_SB_CB(3)   I177 @S9S_MB_2U_LIB.S9S_MB_2U(SCH_1):PAGE83
    89 M_A_CPU0_SB_CB<4> @S9S_MB_2U_LIB.S9S_MB_2U(SCH_1):M_A_CPU0_SB_CB(4)   I177 @S9S_MB_2U_LIB.S9S_MB_2U(SCH_1):PAGE83
    91 M_A_CPU0_SB_CB<5> @S9S_MB_2U_LIB.S9S_MB_2U(SCH_1):M_A_CPU0_SB_CB(5)   I177 @S9S_MB_2U_LIB.S9S_MB_2U(SCH_1):PAGE83
   234 M_A_CPU0_SB_CB<6> @S9S_MB_2U_LIB.S9S_MB_2U(SCH_1):M_A_CPU0_SB_CB(6)   I177 @S9S_MB_2U_LIB.S9S_MB_2U(SCH_1):PAGE83
    51 M_A_CPU0_SA_CB<0> @S9S_MB_2U_LIB.S9S_MB_2U(SCH_1):M_A_CPU0_SA_CB(0)   I177 @S9S_MB_2U_LIB.S9S_MB_2U(SCH_1):PAGE83
   196 M_A_CPU0_SA_CB<2> @S9S_MB_2U_LIB.S9S_MB_2U(SCH_1):M_A_CPU0_SA_CB(2)   I177 @S9S_MB_2U_LIB.S9S_MB_2U(SCH_1):PAGE83
   198 M_A_CPU0_SA_CB<3> @S9S_MB_2U_LIB.S9S_MB_2U(SCH_1):M_A_CPU0_SA_CB(3)   I177 @S9S_MB_2U_LIB.S9S_MB_2U(SCH_1):PAGE83
    60 M_A_CPU0_SA_CB<5> @S9S_MB_2U_LIB.S9S_MB_2U(SCH_1):M_A_CPU0_SA_CB(5)   I177 @S9S_MB_2U_LIB.S9S_MB_2U(SCH_1):PAGE83
   203 M_A_CPU0_SA_CB<6> @S9S_MB_2U_LIB.S9S_MB_2U(SCH_1):M_A_CPU0_SA_CB(6)   I177 @S9S_MB_2U_LIB.S9S_MB_2U(SCH_1):PAGE83
    82 M_A_CPU0_SB_CA<6> @S9S_MB_2U_LIB.S9S_MB_2U(SCH_1):M_A_CPU0_SB_CA(6)   I177 @S9S_MB_2U_LIB.S9S_MB_2U(SCH_1):PAGE83
    72 M_A_CPU0_SA_CA<6> @S9S_MB_2U_LIB.S9S_MB_2U(SCH_1):M_A_CPU0_SA_CA(6)   I177 @S9S_MB_2U_LIB.S9S_MB_2U(SCH_1):PAGE83
   225 M_A_CPU0_SB_CA<5> @S9S_MB_2U_LIB.S9S_MB_2U(SCH_1):M_A_CPU0_SB_CA(5)   I177 @S9S_MB_2U_LIB.S9S_MB_2U(SCH_1):PAGE83
   215 M_A_CPU0_SA_CA<5> @S9S_MB_2U_LIB.S9S_MB_2U(SCH_1):M_A_CPU0_SA_CA(5)   I177 @S9S_MB_2U_LIB.S9S_MB_2U(SCH_1):PAGE83
    80 M_A_CPU0_SB_CA<4> @S9S_MB_2U_LIB.S9S_MB_2U(SCH_1):M_A_CPU0_SB_CA(4)   I177 @S9S_MB_2U_LIB.S9S_MB_2U(SCH_1):PAGE83
    70 M_A_CPU0_SA_CA<4> @S9S_MB_2U_LIB.S9S_MB_2U(SCH_1):M_A_CPU0_SA_CA(4)   I177 @S9S_MB_2U_LIB.S9S_MB_2U(SCH_1):PAGE83
   223 M_A_CPU0_SB_CA<3> @S9S_MB_2U_LIB.S9S_MB_2U(SCH_1):M_A_CPU0_SB_CA(3)   I177 @S9S_MB_2U_LIB.S9S_MB_2U(SCH_1):PAGE83
   213 M_A_CPU0_SA_CA<3> @S9S_MB_2U_LIB.S9S_MB_2U(SCH_1):M_A_CPU0_SA_CA(3)   I177 @S9S_MB_2U_LIB.S9S_MB_2U(SCH_1):PAGE83
    78 M_A_CPU0_SB_CA<2> @S9S_MB_2U_LIB.S9S_MB_2U(SCH_1):M_A_CPU0_SB_CA(2)   I177 @S9S_MB_2U_LIB.S9S_MB_2U(SCH_1):PAGE83
    68 M_A_CPU0_SA_CA<2> @S9S_MB_2U_LIB.S9S_MB_2U(SCH_1):M_A_CPU0_SA_CA(2)   I177 @S9S_MB_2U_LIB.S9S_MB_2U(SCH_1):PAGE83
   221 M_A_CPU0_SB_CA<1> @S9S_MB_2U_LIB.S9S_MB_2U(SCH_1):M_A_CPU0_SB_CA(1)   I177 @S9S_MB_2U_LIB.S9S_MB_2U(SCH_1):PAGE83
   211 M_A_CPU0_SA_CA<1> @S9S_MB_2U_LIB.S9S_MB_2U(SCH_1):M_A_CPU0_SA_CA(1)   I177 @S9S_MB_2U_LIB.S9S_MB_2U(SCH_1):PAGE83
    76 M_A_CPU0_SB_CA<0> @S9S_MB_2U_LIB.S9S_MB_2U(SCH_1):M_A_CPU0_SB_CA(0)   I177 @S9S_MB_2U_LIB.S9S_MB_2U(SCH_1):PAGE83
    66 M_A_CPU0_SA_CA<0> @S9S_MB_2U_LIB.S9S_MB_2U(SCH_1):M_A_CPU0_SA_CA(0)   I177 @S9S_MB_2U_LIB.S9S_MB_2U(SCH_1):PAGE83
    62 M_A_CPU0_ALERT_N @S9S_MB_2U_LIB.S9S_MB_2U(SCH_1):M_A_CPU0_ALERT_N   I177 @S9S_MB_2U_LIB.S9S_MB_2U(SCH_1):PAGE83
   236 M_A_CPU0_SB_CB<7> @S9S_MB_2U_LIB.S9S_MB_2U(SCH_1):M_A_CPU0_SB_CB(7)   I177 @S9S_MB_2U_LIB.S9S_MB_2U(SCH_1):PAGE83
    53 M_A_CPU0_SA_CB<1> @S9S_MB_2U_LIB.S9S_MB_2U(SCH_1):M_A_CPU0_SA_CB(1)   I177 @S9S_MB_2U_LIB.S9S_MB_2U(SCH_1):PAGE83
    58 M_A_CPU0_SA_CB<4> @S9S_MB_2U_LIB.S9S_MB_2U(SCH_1):M_A_CPU0_SA_CB(4)   I177 @S9S_MB_2U_LIB.S9S_MB_2U(SCH_1):PAGE83
   205 M_A_CPU0_SA_CB<7> @S9S_MB_2U_LIB.S9S_MB_2U(SCH_1):M_A_CPU0_SA_CB(7)   I177 @S9S_MB_2U_LIB.S9S_MB_2U(SCH_1):PAGE83
   194 M_A_CPU0_SA_DQ<31> @S9S_MB_2U_LIB.S9S_MB_2U(SCH_1):M_A_CPU0_SA_DQ(31)   I177 @S9S_MB_2U_LIB.S9S_MB_2U(SCH_1):PAGE83
    93 M_A_CPU0_SB_DQS_DP<9> @S9S_MB_2U_LIB.S9S_MB_2U(SCH_1):M_A_CPU0_SB_DQS_DP(9)   I181 @S9S_MB_2U_LIB.S9S_MB_2U(SCH_1):PAGE83
    94 M_A_CPU0_SB_DQS_DN<9> @S9S_MB_2U_LIB.S9S_MB_2U(SCH_1):M_A_CPU0_SB_DQS_DN(9)   I181 @S9S_MB_2U_LIB.S9S_MB_2U(SCH_1):PAGE83
   201 M_A_CPU0_SA_DQS_DP<9> @S9S_MB_2U_LIB.S9S_MB_2U(SCH_1):M_A_CPU0_SA_DQS_DP(9)   I181 @S9S_MB_2U_LIB.S9S_MB_2U(SCH_1):PAGE83
   200 M_A_CPU0_SA_DQS_DN<9> @S9S_MB_2U_LIB.S9S_MB_2U(SCH_1):M_A_CPU0_SA_DQS_DN(9)   I181 @S9S_MB_2U_LIB.S9S_MB_2U(SCH_1):PAGE83
   190 M_A_CPU0_SA_DQS_DP<8> @S9S_MB_2U_LIB.S9S_MB_2U(SCH_1):M_A_CPU0_SA_DQS_DP(8)   I181 @S9S_MB_2U_LIB.S9S_MB_2U(SCH_1):PAGE83
   189 M_A_CPU0_SA_DQS_DN<8> @S9S_MB_2U_LIB.S9S_MB_2U(SCH_1):M_A_CPU0_SA_DQS_DN(8)   I181 @S9S_MB_2U_LIB.S9S_MB_2U(SCH_1):PAGE83
   271 M_A_CPU0_SB_DQS_DN<7> @S9S_MB_2U_LIB.S9S_MB_2U(SCH_1):M_A_CPU0_SB_DQS_DN(7)   I181 @S9S_MB_2U_LIB.S9S_MB_2U(SCH_1):PAGE83
   179 M_A_CPU0_SA_DQS_DP<7> @S9S_MB_2U_LIB.S9S_MB_2U(SCH_1):M_A_CPU0_SA_DQS_DP(7)   I181 @S9S_MB_2U_LIB.S9S_MB_2U(SCH_1):PAGE83
   261 M_A_CPU0_SB_DQS_DP<6> @S9S_MB_2U_LIB.S9S_MB_2U(SCH_1):M_A_CPU0_SB_DQS_DP(6)   I181 @S9S_MB_2U_LIB.S9S_MB_2U(SCH_1):PAGE83
   260 M_A_CPU0_SB_DQS_DN<6> @S9S_MB_2U_LIB.S9S_MB_2U(SCH_1):M_A_CPU0_SB_DQS_DN(6)   I181 @S9S_MB_2U_LIB.S9S_MB_2U(SCH_1):PAGE83
   167 M_A_CPU0_SA_DQS_DN<6> @S9S_MB_2U_LIB.S9S_MB_2U(SCH_1):M_A_CPU0_SA_DQS_DN(6)   I181 @S9S_MB_2U_LIB.S9S_MB_2U(SCH_1):PAGE83
   250 M_A_CPU0_SB_DQS_DP<5> @S9S_MB_2U_LIB.S9S_MB_2U(SCH_1):M_A_CPU0_SB_DQS_DP(5)   I181 @S9S_MB_2U_LIB.S9S_MB_2U(SCH_1):PAGE83
   249 M_A_CPU0_SB_DQS_DN<5> @S9S_MB_2U_LIB.S9S_MB_2U(SCH_1):M_A_CPU0_SB_DQS_DN(5)   I181 @S9S_MB_2U_LIB.S9S_MB_2U(SCH_1):PAGE83
   157 M_A_CPU0_SA_DQS_DP<5> @S9S_MB_2U_LIB.S9S_MB_2U(SCH_1):M_A_CPU0_SA_DQS_DP(5)   I181 @S9S_MB_2U_LIB.S9S_MB_2U(SCH_1):PAGE83
   156 M_A_CPU0_SA_DQS_DN<5> @S9S_MB_2U_LIB.S9S_MB_2U(SCH_1):M_A_CPU0_SA_DQS_DN(5)   I181 @S9S_MB_2U_LIB.S9S_MB_2U(SCH_1):PAGE83
   239 M_A_CPU0_SB_DQS_DP<4> @S9S_MB_2U_LIB.S9S_MB_2U(SCH_1):M_A_CPU0_SB_DQS_DP(4)   I181 @S9S_MB_2U_LIB.S9S_MB_2U(SCH_1):PAGE83
   238 M_A_CPU0_SB_DQS_DN<4> @S9S_MB_2U_LIB.S9S_MB_2U(SCH_1):M_A_CPU0_SB_DQS_DN(4)   I181 @S9S_MB_2U_LIB.S9S_MB_2U(SCH_1):PAGE83
    55 M_A_CPU0_SA_DQS_DP<4> @S9S_MB_2U_LIB.S9S_MB_2U(SCH_1):M_A_CPU0_SA_DQS_DP(4)   I181 @S9S_MB_2U_LIB.S9S_MB_2U(SCH_1):PAGE83
    56 M_A_CPU0_SA_DQS_DN<4> @S9S_MB_2U_LIB.S9S_MB_2U(SCH_1):M_A_CPU0_SA_DQS_DN(4)   I181 @S9S_MB_2U_LIB.S9S_MB_2U(SCH_1):PAGE83
   137 M_A_CPU0_SB_DQS_DP<3> @S9S_MB_2U_LIB.S9S_MB_2U(SCH_1):M_A_CPU0_SB_DQS_DP(3)   I181 @S9S_MB_2U_LIB.S9S_MB_2U(SCH_1):PAGE83
   138 M_A_CPU0_SB_DQS_DN<3> @S9S_MB_2U_LIB.S9S_MB_2U(SCH_1):M_A_CPU0_SB_DQS_DN(3)   I181 @S9S_MB_2U_LIB.S9S_MB_2U(SCH_1):PAGE83
    44 M_A_CPU0_SA_DQS_DP<3> @S9S_MB_2U_LIB.S9S_MB_2U(SCH_1):M_A_CPU0_SA_DQS_DP(3)   I181 @S9S_MB_2U_LIB.S9S_MB_2U(SCH_1):PAGE83
    45 M_A_CPU0_SA_DQS_DN<3> @S9S_MB_2U_LIB.S9S_MB_2U(SCH_1):M_A_CPU0_SA_DQS_DN(3)   I181 @S9S_MB_2U_LIB.S9S_MB_2U(SCH_1):PAGE83
   126 M_A_CPU0_SB_DQS_DP<2> @S9S_MB_2U_LIB.S9S_MB_2U(SCH_1):M_A_CPU0_SB_DQS_DP(2)   I181 @S9S_MB_2U_LIB.S9S_MB_2U(SCH_1):PAGE83
   127 M_A_CPU0_SB_DQS_DN<2> @S9S_MB_2U_LIB.S9S_MB_2U(SCH_1):M_A_CPU0_SB_DQS_DN(2)   I181 @S9S_MB_2U_LIB.S9S_MB_2U(SCH_1):PAGE83
    33 M_A_CPU0_SA_DQS_DP<2> @S9S_MB_2U_LIB.S9S_MB_2U(SCH_1):M_A_CPU0_SA_DQS_DP(2)   I181 @S9S_MB_2U_LIB.S9S_MB_2U(SCH_1):PAGE83
    34 M_A_CPU0_SA_DQS_DN<2> @S9S_MB_2U_LIB.S9S_MB_2U(SCH_1):M_A_CPU0_SA_DQS_DN(2)   I181 @S9S_MB_2U_LIB.S9S_MB_2U(SCH_1):PAGE83
   115 M_A_CPU0_SB_DQS_DP<1> @S9S_MB_2U_LIB.S9S_MB_2U(SCH_1):M_A_CPU0_SB_DQS_DP(1)   I181 @S9S_MB_2U_LIB.S9S_MB_2U(SCH_1):PAGE83
   116 M_A_CPU0_SB_DQS_DN<1> @S9S_MB_2U_LIB.S9S_MB_2U(SCH_1):M_A_CPU0_SB_DQS_DN(1)   I181 @S9S_MB_2U_LIB.S9S_MB_2U(SCH_1):PAGE83
    22 M_A_CPU0_SA_DQS_DP<1> @S9S_MB_2U_LIB.S9S_MB_2U(SCH_1):M_A_CPU0_SA_DQS_DP(1)   I181 @S9S_MB_2U_LIB.S9S_MB_2U(SCH_1):PAGE83
    23 M_A_CPU0_SA_DQS_DN<1> @S9S_MB_2U_LIB.S9S_MB_2U(SCH_1):M_A_CPU0_SA_DQS_DN(1)   I181 @S9S_MB_2U_LIB.S9S_MB_2U(SCH_1):PAGE83
   104 M_A_CPU0_SB_DQS_DP<0> @S9S_MB_2U_LIB.S9S_MB_2U(SCH_1):M_A_CPU0_SB_DQS_DP(0)   I181 @S9S_MB_2U_LIB.S9S_MB_2U(SCH_1):PAGE83
   105 M_A_CPU0_SB_DQS_DN<0> @S9S_MB_2U_LIB.S9S_MB_2U(SCH_1):M_A_CPU0_SB_DQS_DN(0)   I181 @S9S_MB_2U_LIB.S9S_MB_2U(SCH_1):PAGE83
    11 M_A_CPU0_SA_DQS_DP<0> @S9S_MB_2U_LIB.S9S_MB_2U(SCH_1):M_A_CPU0_SA_DQS_DP(0)   I181 @S9S_MB_2U_LIB.S9S_MB_2U(SCH_1):PAGE83
    12 M_A_CPU0_SA_DQS_DN<0> @S9S_MB_2U_LIB.S9S_MB_2U(SCH_1):M_A_CPU0_SA_DQS_DN(0)   I181 @S9S_MB_2U_LIB.S9S_MB_2U(SCH_1):PAGE83
   272 M_A_CPU0_SB_DQS_DP<7> @S9S_MB_2U_LIB.S9S_MB_2U(SCH_1):M_A_CPU0_SB_DQS_DP(7)   I181 @S9S_MB_2U_LIB.S9S_MB_2U(SCH_1):PAGE83
   282 M_A_CPU0_SB_DQS_DN<8> @S9S_MB_2U_LIB.S9S_MB_2U(SCH_1):M_A_CPU0_SB_DQS_DN(8)   I181 @S9S_MB_2U_LIB.S9S_MB_2U(SCH_1):PAGE83
   283 M_A_CPU0_SB_DQS_DP<8> @S9S_MB_2U_LIB.S9S_MB_2U(SCH_1):M_A_CPU0_SB_DQS_DP(8)   I181 @S9S_MB_2U_LIB.S9S_MB_2U(SCH_1):PAGE83
   168 M_A_CPU0_SA_DQS_DP<6> @S9S_MB_2U_LIB.S9S_MB_2U(SCH_1):M_A_CPU0_SA_DQS_DP(6)   I181 @S9S_MB_2U_LIB.S9S_MB_2U(SCH_1):PAGE83
   178 M_A_CPU0_SA_DQS_DN<7> @S9S_MB_2U_LIB.S9S_MB_2U(SCH_1):M_A_CPU0_SA_DQS_DN(7)   I181 @S9S_MB_2U_LIB.S9S_MB_2U(SCH_1):PAGE83
     6    GND @S9S_MB_2U_LIB.S9S_MB_2U(SCH_1):GND   I179 @S9S_MB_2U_LIB.S9S_MB_2U(SCH_1):PAGE83
     8    GND @S9S_MB_2U_LIB.S9S_MB_2U(SCH_1):GND   I179 @S9S_MB_2U_LIB.S9S_MB_2U(SCH_1):PAGE83
    10    GND @S9S_MB_2U_LIB.S9S_MB_2U(SCH_1):GND   I179 @S9S_MB_2U_LIB.S9S_MB_2U(SCH_1):PAGE83
    13    GND @S9S_MB_2U_LIB.S9S_MB_2U(SCH_1):GND   I179 @S9S_MB_2U_LIB.S9S_MB_2U(SCH_1):PAGE83
    15    GND @S9S_MB_2U_LIB.S9S_MB_2U(SCH_1):GND   I179 @S9S_MB_2U_LIB.S9S_MB_2U(SCH_1):PAGE83
    17    GND @S9S_MB_2U_LIB.S9S_MB_2U(SCH_1):GND   I179 @S9S_MB_2U_LIB.S9S_MB_2U(SCH_1):PAGE83
    19    GND @S9S_MB_2U_LIB.S9S_MB_2U(SCH_1):GND   I179 @S9S_MB_2U_LIB.S9S_MB_2U(SCH_1):PAGE83
    21    GND @S9S_MB_2U_LIB.S9S_MB_2U(SCH_1):GND   I179 @S9S_MB_2U_LIB.S9S_MB_2U(SCH_1):PAGE83
    24    GND @S9S_MB_2U_LIB.S9S_MB_2U(SCH_1):GND   I179 @S9S_MB_2U_LIB.S9S_MB_2U(SCH_1):PAGE83
    26    GND @S9S_MB_2U_LIB.S9S_MB_2U(SCH_1):GND   I179 @S9S_MB_2U_LIB.S9S_MB_2U(SCH_1):PAGE83
    28    GND @S9S_MB_2U_LIB.S9S_MB_2U(SCH_1):GND   I179 @S9S_MB_2U_LIB.S9S_MB_2U(SCH_1):PAGE83
    30    GND @S9S_MB_2U_LIB.S9S_MB_2U(SCH_1):GND   I179 @S9S_MB_2U_LIB.S9S_MB_2U(SCH_1):PAGE83
    32    GND @S9S_MB_2U_LIB.S9S_MB_2U(SCH_1):GND   I179 @S9S_MB_2U_LIB.S9S_MB_2U(SCH_1):PAGE83
    35    GND @S9S_MB_2U_LIB.S9S_MB_2U(SCH_1):GND   I179 @S9S_MB_2U_LIB.S9S_MB_2U(SCH_1):PAGE83
    37    GND @S9S_MB_2U_LIB.S9S_MB_2U(SCH_1):GND   I179 @S9S_MB_2U_LIB.S9S_MB_2U(SCH_1):PAGE83
    39    GND @S9S_MB_2U_LIB.S9S_MB_2U(SCH_1):GND   I179 @S9S_MB_2U_LIB.S9S_MB_2U(SCH_1):PAGE83
    41    GND @S9S_MB_2U_LIB.S9S_MB_2U(SCH_1):GND   I179 @S9S_MB_2U_LIB.S9S_MB_2U(SCH_1):PAGE83
    43    GND @S9S_MB_2U_LIB.S9S_MB_2U(SCH_1):GND   I179 @S9S_MB_2U_LIB.S9S_MB_2U(SCH_1):PAGE83
    46    GND @S9S_MB_2U_LIB.S9S_MB_2U(SCH_1):GND   I179 @S9S_MB_2U_LIB.S9S_MB_2U(SCH_1):PAGE83
    48    GND @S9S_MB_2U_LIB.S9S_MB_2U(SCH_1):GND   I179 @S9S_MB_2U_LIB.S9S_MB_2U(SCH_1):PAGE83
    50    GND @S9S_MB_2U_LIB.S9S_MB_2U(SCH_1):GND   I179 @S9S_MB_2U_LIB.S9S_MB_2U(SCH_1):PAGE83
    52    GND @S9S_MB_2U_LIB.S9S_MB_2U(SCH_1):GND   I179 @S9S_MB_2U_LIB.S9S_MB_2U(SCH_1):PAGE83
    54    GND @S9S_MB_2U_LIB.S9S_MB_2U(SCH_1):GND   I179 @S9S_MB_2U_LIB.S9S_MB_2U(SCH_1):PAGE83
    57    GND @S9S_MB_2U_LIB.S9S_MB_2U(SCH_1):GND   I179 @S9S_MB_2U_LIB.S9S_MB_2U(SCH_1):PAGE83
    59    GND @S9S_MB_2U_LIB.S9S_MB_2U(SCH_1):GND   I179 @S9S_MB_2U_LIB.S9S_MB_2U(SCH_1):PAGE83
    61    GND @S9S_MB_2U_LIB.S9S_MB_2U(SCH_1):GND   I179 @S9S_MB_2U_LIB.S9S_MB_2U(SCH_1):PAGE83
    63    GND @S9S_MB_2U_LIB.S9S_MB_2U(SCH_1):GND   I179 @S9S_MB_2U_LIB.S9S_MB_2U(SCH_1):PAGE83
    65    GND @S9S_MB_2U_LIB.S9S_MB_2U(SCH_1):GND   I179 @S9S_MB_2U_LIB.S9S_MB_2U(SCH_1):PAGE83
    67    GND @S9S_MB_2U_LIB.S9S_MB_2U(SCH_1):GND   I179 @S9S_MB_2U_LIB.S9S_MB_2U(SCH_1):PAGE83
    69    GND @S9S_MB_2U_LIB.S9S_MB_2U(SCH_1):GND   I179 @S9S_MB_2U_LIB.S9S_MB_2U(SCH_1):PAGE83
    71    GND @S9S_MB_2U_LIB.S9S_MB_2U(SCH_1):GND   I179 @S9S_MB_2U_LIB.S9S_MB_2U(SCH_1):PAGE83
    73    GND @S9S_MB_2U_LIB.S9S_MB_2U(SCH_1):GND   I179 @S9S_MB_2U_LIB.S9S_MB_2U(SCH_1):PAGE83
    75    GND @S9S_MB_2U_LIB.S9S_MB_2U(SCH_1):GND   I179 @S9S_MB_2U_LIB.S9S_MB_2U(SCH_1):PAGE83
    77    GND @S9S_MB_2U_LIB.S9S_MB_2U(SCH_1):GND   I179 @S9S_MB_2U_LIB.S9S_MB_2U(SCH_1):PAGE83
    79    GND @S9S_MB_2U_LIB.S9S_MB_2U(SCH_1):GND   I179 @S9S_MB_2U_LIB.S9S_MB_2U(SCH_1):PAGE83
    81    GND @S9S_MB_2U_LIB.S9S_MB_2U(SCH_1):GND   I179 @S9S_MB_2U_LIB.S9S_MB_2U(SCH_1):PAGE83
    83    GND @S9S_MB_2U_LIB.S9S_MB_2U(SCH_1):GND   I179 @S9S_MB_2U_LIB.S9S_MB_2U(SCH_1):PAGE83
    85    GND @S9S_MB_2U_LIB.S9S_MB_2U(SCH_1):GND   I179 @S9S_MB_2U_LIB.S9S_MB_2U(SCH_1):PAGE83
    88    GND @S9S_MB_2U_LIB.S9S_MB_2U(SCH_1):GND   I179 @S9S_MB_2U_LIB.S9S_MB_2U(SCH_1):PAGE83
    90    GND @S9S_MB_2U_LIB.S9S_MB_2U(SCH_1):GND   I179 @S9S_MB_2U_LIB.S9S_MB_2U(SCH_1):PAGE83
    92    GND @S9S_MB_2U_LIB.S9S_MB_2U(SCH_1):GND   I179 @S9S_MB_2U_LIB.S9S_MB_2U(SCH_1):PAGE83
    95    GND @S9S_MB_2U_LIB.S9S_MB_2U(SCH_1):GND   I179 @S9S_MB_2U_LIB.S9S_MB_2U(SCH_1):PAGE83
    97    GND @S9S_MB_2U_LIB.S9S_MB_2U(SCH_1):GND   I179 @S9S_MB_2U_LIB.S9S_MB_2U(SCH_1):PAGE83
    99    GND @S9S_MB_2U_LIB.S9S_MB_2U(SCH_1):GND   I179 @S9S_MB_2U_LIB.S9S_MB_2U(SCH_1):PAGE83
   101    GND @S9S_MB_2U_LIB.S9S_MB_2U(SCH_1):GND   I179 @S9S_MB_2U_LIB.S9S_MB_2U(SCH_1):PAGE83
   103    GND @S9S_MB_2U_LIB.S9S_MB_2U(SCH_1):GND   I179 @S9S_MB_2U_LIB.S9S_MB_2U(SCH_1):PAGE83
   106    GND @S9S_MB_2U_LIB.S9S_MB_2U(SCH_1):GND   I179 @S9S_MB_2U_LIB.S9S_MB_2U(SCH_1):PAGE83
   108    GND @S9S_MB_2U_LIB.S9S_MB_2U(SCH_1):GND   I179 @S9S_MB_2U_LIB.S9S_MB_2U(SCH_1):PAGE83
   110    GND @S9S_MB_2U_LIB.S9S_MB_2U(SCH_1):GND   I179 @S9S_MB_2U_LIB.S9S_MB_2U(SCH_1):PAGE83
   112    GND @S9S_MB_2U_LIB.S9S_MB_2U(SCH_1):GND   I179 @S9S_MB_2U_LIB.S9S_MB_2U(SCH_1):PAGE83
   114    GND @S9S_MB_2U_LIB.S9S_MB_2U(SCH_1):GND   I179 @S9S_MB_2U_LIB.S9S_MB_2U(SCH_1):PAGE83
   117    GND @S9S_MB_2U_LIB.S9S_MB_2U(SCH_1):GND   I179 @S9S_MB_2U_LIB.S9S_MB_2U(SCH_1):PAGE83
   119    GND @S9S_MB_2U_LIB.S9S_MB_2U(SCH_1):GND   I179 @S9S_MB_2U_LIB.S9S_MB_2U(SCH_1):PAGE83
   121    GND @S9S_MB_2U_LIB.S9S_MB_2U(SCH_1):GND   I179 @S9S_MB_2U_LIB.S9S_MB_2U(SCH_1):PAGE83
   123    GND @S9S_MB_2U_LIB.S9S_MB_2U(SCH_1):GND   I179 @S9S_MB_2U_LIB.S9S_MB_2U(SCH_1):PAGE83
   125    GND @S9S_MB_2U_LIB.S9S_MB_2U(SCH_1):GND   I179 @S9S_MB_2U_LIB.S9S_MB_2U(SCH_1):PAGE83
   128    GND @S9S_MB_2U_LIB.S9S_MB_2U(SCH_1):GND   I179 @S9S_MB_2U_LIB.S9S_MB_2U(SCH_1):PAGE83
   130    GND @S9S_MB_2U_LIB.S9S_MB_2U(SCH_1):GND   I179 @S9S_MB_2U_LIB.S9S_MB_2U(SCH_1):PAGE83
   134    GND @S9S_MB_2U_LIB.S9S_MB_2U(SCH_1):GND   I179 @S9S_MB_2U_LIB.S9S_MB_2U(SCH_1):PAGE83
   143    GND @S9S_MB_2U_LIB.S9S_MB_2U(SCH_1):GND   I179 @S9S_MB_2U_LIB.S9S_MB_2U(SCH_1):PAGE83
   151    GND @S9S_MB_2U_LIB.S9S_MB_2U(SCH_1):GND   I179 @S9S_MB_2U_LIB.S9S_MB_2U(SCH_1):PAGE83
   153    GND @S9S_MB_2U_LIB.S9S_MB_2U(SCH_1):GND   I179 @S9S_MB_2U_LIB.S9S_MB_2U(SCH_1):PAGE83
   155    GND @S9S_MB_2U_LIB.S9S_MB_2U(SCH_1):GND   I179 @S9S_MB_2U_LIB.S9S_MB_2U(SCH_1):PAGE83
   158    GND @S9S_MB_2U_LIB.S9S_MB_2U(SCH_1):GND   I179 @S9S_MB_2U_LIB.S9S_MB_2U(SCH_1):PAGE83
   160    GND @S9S_MB_2U_LIB.S9S_MB_2U(SCH_1):GND   I179 @S9S_MB_2U_LIB.S9S_MB_2U(SCH_1):PAGE83
   162    GND @S9S_MB_2U_LIB.S9S_MB_2U(SCH_1):GND   I179 @S9S_MB_2U_LIB.S9S_MB_2U(SCH_1):PAGE83
   164    GND @S9S_MB_2U_LIB.S9S_MB_2U(SCH_1):GND   I179 @S9S_MB_2U_LIB.S9S_MB_2U(SCH_1):PAGE83
   166    GND @S9S_MB_2U_LIB.S9S_MB_2U(SCH_1):GND   I179 @S9S_MB_2U_LIB.S9S_MB_2U(SCH_1):PAGE83
   169    GND @S9S_MB_2U_LIB.S9S_MB_2U(SCH_1):GND   I179 @S9S_MB_2U_LIB.S9S_MB_2U(SCH_1):PAGE83
   171    GND @S9S_MB_2U_LIB.S9S_MB_2U(SCH_1):GND   I179 @S9S_MB_2U_LIB.S9S_MB_2U(SCH_1):PAGE83
   173    GND @S9S_MB_2U_LIB.S9S_MB_2U(SCH_1):GND   I179 @S9S_MB_2U_LIB.S9S_MB_2U(SCH_1):PAGE83
   175    GND @S9S_MB_2U_LIB.S9S_MB_2U(SCH_1):GND   I179 @S9S_MB_2U_LIB.S9S_MB_2U(SCH_1):PAGE83
   177    GND @S9S_MB_2U_LIB.S9S_MB_2U(SCH_1):GND   I179 @S9S_MB_2U_LIB.S9S_MB_2U(SCH_1):PAGE83
   180    GND @S9S_MB_2U_LIB.S9S_MB_2U(SCH_1):GND   I179 @S9S_MB_2U_LIB.S9S_MB_2U(SCH_1):PAGE83
   182    GND @S9S_MB_2U_LIB.S9S_MB_2U(SCH_1):GND   I179 @S9S_MB_2U_LIB.S9S_MB_2U(SCH_1):PAGE83
   184    GND @S9S_MB_2U_LIB.S9S_MB_2U(SCH_1):GND   I179 @S9S_MB_2U_LIB.S9S_MB_2U(SCH_1):PAGE83
   186    GND @S9S_MB_2U_LIB.S9S_MB_2U(SCH_1):GND   I179 @S9S_MB_2U_LIB.S9S_MB_2U(SCH_1):PAGE83
   188    GND @S9S_MB_2U_LIB.S9S_MB_2U(SCH_1):GND   I179 @S9S_MB_2U_LIB.S9S_MB_2U(SCH_1):PAGE83
   191    GND @S9S_MB_2U_LIB.S9S_MB_2U(SCH_1):GND   I179 @S9S_MB_2U_LIB.S9S_MB_2U(SCH_1):PAGE83
   193    GND @S9S_MB_2U_LIB.S9S_MB_2U(SCH_1):GND   I179 @S9S_MB_2U_LIB.S9S_MB_2U(SCH_1):PAGE83
   195    GND @S9S_MB_2U_LIB.S9S_MB_2U(SCH_1):GND   I179 @S9S_MB_2U_LIB.S9S_MB_2U(SCH_1):PAGE83
   197    GND @S9S_MB_2U_LIB.S9S_MB_2U(SCH_1):GND   I179 @S9S_MB_2U_LIB.S9S_MB_2U(SCH_1):PAGE83
   199    GND @S9S_MB_2U_LIB.S9S_MB_2U(SCH_1):GND   I179 @S9S_MB_2U_LIB.S9S_MB_2U(SCH_1):PAGE83
   202    GND @S9S_MB_2U_LIB.S9S_MB_2U(SCH_1):GND   I179 @S9S_MB_2U_LIB.S9S_MB_2U(SCH_1):PAGE83
   204    GND @S9S_MB_2U_LIB.S9S_MB_2U(SCH_1):GND   I179 @S9S_MB_2U_LIB.S9S_MB_2U(SCH_1):PAGE83
   206    GND @S9S_MB_2U_LIB.S9S_MB_2U(SCH_1):GND   I179 @S9S_MB_2U_LIB.S9S_MB_2U(SCH_1):PAGE83
   208    GND @S9S_MB_2U_LIB.S9S_MB_2U(SCH_1):GND   I179 @S9S_MB_2U_LIB.S9S_MB_2U(SCH_1):PAGE83
   210    GND @S9S_MB_2U_LIB.S9S_MB_2U(SCH_1):GND   I179 @S9S_MB_2U_LIB.S9S_MB_2U(SCH_1):PAGE83
   212    GND @S9S_MB_2U_LIB.S9S_MB_2U(SCH_1):GND   I179 @S9S_MB_2U_LIB.S9S_MB_2U(SCH_1):PAGE83
   214    GND @S9S_MB_2U_LIB.S9S_MB_2U(SCH_1):GND   I179 @S9S_MB_2U_LIB.S9S_MB_2U(SCH_1):PAGE83
   216    GND @S9S_MB_2U_LIB.S9S_MB_2U(SCH_1):GND   I179 @S9S_MB_2U_LIB.S9S_MB_2U(SCH_1):PAGE83
   219    GND @S9S_MB_2U_LIB.S9S_MB_2U(SCH_1):GND   I179 @S9S_MB_2U_LIB.S9S_MB_2U(SCH_1):PAGE83
   222    GND @S9S_MB_2U_LIB.S9S_MB_2U(SCH_1):GND   I179 @S9S_MB_2U_LIB.S9S_MB_2U(SCH_1):PAGE83
   224    GND @S9S_MB_2U_LIB.S9S_MB_2U(SCH_1):GND   I179 @S9S_MB_2U_LIB.S9S_MB_2U(SCH_1):PAGE83
   226    GND @S9S_MB_2U_LIB.S9S_MB_2U(SCH_1):GND   I179 @S9S_MB_2U_LIB.S9S_MB_2U(SCH_1):PAGE83
   228    GND @S9S_MB_2U_LIB.S9S_MB_2U(SCH_1):GND   I179 @S9S_MB_2U_LIB.S9S_MB_2U(SCH_1):PAGE83
   233    GND @S9S_MB_2U_LIB.S9S_MB_2U(SCH_1):GND   I179 @S9S_MB_2U_LIB.S9S_MB_2U(SCH_1):PAGE83
   237    GND @S9S_MB_2U_LIB.S9S_MB_2U(SCH_1):GND   I179 @S9S_MB_2U_LIB.S9S_MB_2U(SCH_1):PAGE83
   242    GND @S9S_MB_2U_LIB.S9S_MB_2U(SCH_1):GND   I179 @S9S_MB_2U_LIB.S9S_MB_2U(SCH_1):PAGE83
   244    GND @S9S_MB_2U_LIB.S9S_MB_2U(SCH_1):GND   I179 @S9S_MB_2U_LIB.S9S_MB_2U(SCH_1):PAGE83
   246    GND @S9S_MB_2U_LIB.S9S_MB_2U(SCH_1):GND   I179 @S9S_MB_2U_LIB.S9S_MB_2U(SCH_1):PAGE83
   248    GND @S9S_MB_2U_LIB.S9S_MB_2U(SCH_1):GND   I179 @S9S_MB_2U_LIB.S9S_MB_2U(SCH_1):PAGE83
   251    GND @S9S_MB_2U_LIB.S9S_MB_2U(SCH_1):GND   I179 @S9S_MB_2U_LIB.S9S_MB_2U(SCH_1):PAGE83
   253    GND @S9S_MB_2U_LIB.S9S_MB_2U(SCH_1):GND   I179 @S9S_MB_2U_LIB.S9S_MB_2U(SCH_1):PAGE83
   255    GND @S9S_MB_2U_LIB.S9S_MB_2U(SCH_1):GND   I179 @S9S_MB_2U_LIB.S9S_MB_2U(SCH_1):PAGE83
   257    GND @S9S_MB_2U_LIB.S9S_MB_2U(SCH_1):GND   I179 @S9S_MB_2U_LIB.S9S_MB_2U(SCH_1):PAGE83
   259    GND @S9S_MB_2U_LIB.S9S_MB_2U(SCH_1):GND   I179 @S9S_MB_2U_LIB.S9S_MB_2U(SCH_1):PAGE83
   262    GND @S9S_MB_2U_LIB.S9S_MB_2U(SCH_1):GND   I179 @S9S_MB_2U_LIB.S9S_MB_2U(SCH_1):PAGE83
   264    GND @S9S_MB_2U_LIB.S9S_MB_2U(SCH_1):GND   I179 @S9S_MB_2U_LIB.S9S_MB_2U(SCH_1):PAGE83
   266    GND @S9S_MB_2U_LIB.S9S_MB_2U(SCH_1):GND   I179 @S9S_MB_2U_LIB.S9S_MB_2U(SCH_1):PAGE83
   268    GND @S9S_MB_2U_LIB.S9S_MB_2U(SCH_1):GND   I179 @S9S_MB_2U_LIB.S9S_MB_2U(SCH_1):PAGE83
   270    GND @S9S_MB_2U_LIB.S9S_MB_2U(SCH_1):GND   I179 @S9S_MB_2U_LIB.S9S_MB_2U(SCH_1):PAGE83
   273    GND @S9S_MB_2U_LIB.S9S_MB_2U(SCH_1):GND   I179 @S9S_MB_2U_LIB.S9S_MB_2U(SCH_1):PAGE83
   275    GND @S9S_MB_2U_LIB.S9S_MB_2U(SCH_1):GND   I179 @S9S_MB_2U_LIB.S9S_MB_2U(SCH_1):PAGE83
   277    GND @S9S_MB_2U_LIB.S9S_MB_2U(SCH_1):GND   I179 @S9S_MB_2U_LIB.S9S_MB_2U(SCH_1):PAGE83
   279    GND @S9S_MB_2U_LIB.S9S_MB_2U(SCH_1):GND   I179 @S9S_MB_2U_LIB.S9S_MB_2U(SCH_1):PAGE83
   281    GND @S9S_MB_2U_LIB.S9S_MB_2U(SCH_1):GND   I179 @S9S_MB_2U_LIB.S9S_MB_2U(SCH_1):PAGE83
   284    GND @S9S_MB_2U_LIB.S9S_MB_2U(SCH_1):GND   I179 @S9S_MB_2U_LIB.S9S_MB_2U(SCH_1):PAGE83
   286    GND @S9S_MB_2U_LIB.S9S_MB_2U(SCH_1):GND   I179 @S9S_MB_2U_LIB.S9S_MB_2U(SCH_1):PAGE83
   288    GND @S9S_MB_2U_LIB.S9S_MB_2U(SCH_1):GND   I179 @S9S_MB_2U_LIB.S9S_MB_2U(SCH_1):PAGE83
     1 P12V_S3_AUX_CPU0_NVDIMM @S9S_MB_2U_LIB.S9S_MB_2U(SCH_1):P12V_S3_AUX_CPU0_NVDIMM   I179 @S9S_MB_2U_LIB.S9S_MB_2U(SCH_1):PAGE83
   145 P12V_S3_AUX_CPU0_NVDIMM @S9S_MB_2U_LIB.S9S_MB_2U(SCH_1):P12V_S3_AUX_CPU0_NVDIMM   I179 @S9S_MB_2U_LIB.S9S_MB_2U(SCH_1):PAGE83
   146 P12V_S3_AUX_CPU0_NVDIMM @S9S_MB_2U_LIB.S9S_MB_2U(SCH_1):P12V_S3_AUX_CPU0_NVDIMM   I179 @S9S_MB_2U_LIB.S9S_MB_2U(SCH_1):PAGE83
   230    GND @S9S_MB_2U_LIB.S9S_MB_2U(SCH_1):GND   I179 @S9S_MB_2U_LIB.S9S_MB_2U(SCH_1):PAGE83
   235    GND @S9S_MB_2U_LIB.S9S_MB_2U(SCH_1):GND   I179 @S9S_MB_2U_LIB.S9S_MB_2U(SCH_1):PAGE83
   240    GND @S9S_MB_2U_LIB.S9S_MB_2U(SCH_1):GND   I179 @S9S_MB_2U_LIB.S9S_MB_2U(SCH_1):PAGE83
   132    GND @S9S_MB_2U_LIB.S9S_MB_2U(SCH_1):GND   I179 @S9S_MB_2U_LIB.S9S_MB_2U(SCH_1):PAGE83
   136    GND @S9S_MB_2U_LIB.S9S_MB_2U(SCH_1):GND   I179 @S9S_MB_2U_LIB.S9S_MB_2U(SCH_1):PAGE83
   139    GND @S9S_MB_2U_LIB.S9S_MB_2U(SCH_1):GND   I179 @S9S_MB_2U_LIB.S9S_MB_2U(SCH_1):PAGE83
   141    GND @S9S_MB_2U_LIB.S9S_MB_2U(SCH_1):GND   I179 @S9S_MB_2U_LIB.S9S_MB_2U(SCH_1):PAGE83
    G1    GND @S9S_MB_2U_LIB.S9S_MB_2U(SCH_1):GND   I179 @S9S_MB_2U_LIB.S9S_MB_2U(SCH_1):PAGE83
    G2    GND @S9S_MB_2U_LIB.S9S_MB_2U(SCH_1):GND   I179 @S9S_MB_2U_LIB.S9S_MB_2U(SCH_1):PAGE83
    G3    GND @S9S_MB_2U_LIB.S9S_MB_2U(SCH_1):GND   I179 @S9S_MB_2U_LIB.S9S_MB_2U(SCH_1):PAGE83

  J3 SCONN288_ADR50017P130CC-SCONN2A
     3 P3V3_AUX @S9S_MB_2U_LIB.S9S_MB_2U(SCH_1):P3V3_AUX   I180 @S9S_MB_2U_LIB.S9S_MB_2U(SCH_1):PAGE84
     2 TP_CHB_CPU0_DIMM1_FRU_0 @S9S_MB_2U_LIB.S9S_MB_2U(SCH_1):TP_CHB_CPU0_DIMM1_FRU_0   I180 @S9S_MB_2U_LIB.S9S_MB_2U(SCH_1):PAGE84
   144 TP_CHB_CPU0_DIMM1_FRU_1 @S9S_MB_2U_LIB.S9S_MB_2U(SCH_1):TP_CHB_CPU0_DIMM1_FRU_1   I180 @S9S_MB_2U_LIB.S9S_MB_2U(SCH_1):PAGE84
   149 TP_CHB_CPU0_DIMM1_FRU_2 @S9S_MB_2U_LIB.S9S_MB_2U(SCH_1):TP_CHB_CPU0_DIMM1_FRU_2   I180 @S9S_MB_2U_LIB.S9S_MB_2U(SCH_1):PAGE84
   150 TP_CHB_CPU0_DIMM1_FRU_3 @S9S_MB_2U_LIB.S9S_MB_2U(SCH_1):TP_CHB_CPU0_DIMM1_FRU_3   I180 @S9S_MB_2U_LIB.S9S_MB_2U(SCH_1):PAGE84
   220 TP_CHB_CPU0_DIMM1_FRU_4 @S9S_MB_2U_LIB.S9S_MB_2U(SCH_1):TP_CHB_CPU0_DIMM1_FRU_4   I180 @S9S_MB_2U_LIB.S9S_MB_2U(SCH_1):PAGE84
   231 TP_CHB_CPU0_DIMM1_FRU_5 @S9S_MB_2U_LIB.S9S_MB_2U(SCH_1):TP_CHB_CPU0_DIMM1_FRU_5   I180 @S9S_MB_2U_LIB.S9S_MB_2U(SCH_1):PAGE84
   232 TP_CHB_CPU0_DIMM1_FRU_6 @S9S_MB_2U_LIB.S9S_MB_2U(SCH_1):TP_CHB_CPU0_DIMM1_FRU_6   I180 @S9S_MB_2U_LIB.S9S_MB_2U(SCH_1):PAGE84
   207 RST_M_AB_CPU0_FPGA_N @S9S_MB_2U_LIB.S9S_MB_2U(SCH_1):RST_M_AB_CPU0_FPGA_N   I180 @S9S_MB_2U_LIB.S9S_MB_2U(SCH_1):PAGE84
   147 PWRGD_CHB_CPU0_DIMM1 @S9S_MB_2U_LIB.S9S_MB_2U(SCH_1):PWRGD_CHB_CPU0_DIMM1   I180 @S9S_MB_2U_LIB.S9S_MB_2U(SCH_1):PAGE84
   227 M_B_CPU0_SB_PAR @S9S_MB_2U_LIB.S9S_MB_2U(SCH_1):M_B_CPU0_SB_PAR   I180 @S9S_MB_2U_LIB.S9S_MB_2U(SCH_1):PAGE84
    74 M_B_CPU0_SA_PAR @S9S_MB_2U_LIB.S9S_MB_2U(SCH_1):M_B_CPU0_SA_PAR   I180 @S9S_MB_2U_LIB.S9S_MB_2U(SCH_1):PAGE84
    87 M_B_CPU0_SB_RSP<0> @S9S_MB_2U_LIB.S9S_MB_2U(SCH_1):M_B_CPU0_SB_RSP(0)   I180 @S9S_MB_2U_LIB.S9S_MB_2U(SCH_1):PAGE84
    86 M_B_CPU0_SA_RSP<0> @S9S_MB_2U_LIB.S9S_MB_2U(SCH_1):M_B_CPU0_SA_RSP(0)   I180 @S9S_MB_2U_LIB.S9S_MB_2U(SCH_1):PAGE84
     5 I3C_SPD_DDRABCD_CPU0_LVC1_SDA @S9S_MB_2U_LIB.S9S_MB_2U(SCH_1):I3C_SPD_DDRABCD_CPU0_LVC1_SDA   I180 @S9S_MB_2U_LIB.S9S_MB_2U(SCH_1):PAGE84
     4 I3C_SPD_DDRABCD_CPU0_LVC1_SCL_2 @S9S_MB_2U_LIB.S9S_MB_2U(SCH_1):I3C_SPD_DDRABCD_CPU0_LVC1_SCL_R3   I180 @S9S_MB_2U_LIB.S9S_MB_2U(SCH_1):PAGE84
   148 PD_CHB_CPU0_DIMM1_SAA @S9S_MB_2U_LIB.S9S_MB_2U(SCH_1):PD_CHB_CPU0_DIMM1_SAA   I180 @S9S_MB_2U_LIB.S9S_MB_2U(SCH_1):PAGE84
   100 M_B_CPU0_SB_DQ<0> @S9S_MB_2U_LIB.S9S_MB_2U(SCH_1):M_B_CPU0_SB_DQ(0)   I180 @S9S_MB_2U_LIB.S9S_MB_2U(SCH_1):PAGE84
   102 M_B_CPU0_SB_DQ<1> @S9S_MB_2U_LIB.S9S_MB_2U(SCH_1):M_B_CPU0_SB_DQ(1)   I180 @S9S_MB_2U_LIB.S9S_MB_2U(SCH_1):PAGE84
   245 M_B_CPU0_SB_DQ<2> @S9S_MB_2U_LIB.S9S_MB_2U(SCH_1):M_B_CPU0_SB_DQ(2)   I180 @S9S_MB_2U_LIB.S9S_MB_2U(SCH_1):PAGE84
   247 M_B_CPU0_SB_DQ<3> @S9S_MB_2U_LIB.S9S_MB_2U(SCH_1):M_B_CPU0_SB_DQ(3)   I180 @S9S_MB_2U_LIB.S9S_MB_2U(SCH_1):PAGE84
   107 M_B_CPU0_SB_DQ<4> @S9S_MB_2U_LIB.S9S_MB_2U(SCH_1):M_B_CPU0_SB_DQ(4)   I180 @S9S_MB_2U_LIB.S9S_MB_2U(SCH_1):PAGE84
   109 M_B_CPU0_SB_DQ<5> @S9S_MB_2U_LIB.S9S_MB_2U(SCH_1):M_B_CPU0_SB_DQ(5)   I180 @S9S_MB_2U_LIB.S9S_MB_2U(SCH_1):PAGE84
   252 M_B_CPU0_SB_DQ<6> @S9S_MB_2U_LIB.S9S_MB_2U(SCH_1):M_B_CPU0_SB_DQ(6)   I180 @S9S_MB_2U_LIB.S9S_MB_2U(SCH_1):PAGE84
   254 M_B_CPU0_SB_DQ<7> @S9S_MB_2U_LIB.S9S_MB_2U(SCH_1):M_B_CPU0_SB_DQ(7)   I180 @S9S_MB_2U_LIB.S9S_MB_2U(SCH_1):PAGE84
   111 M_B_CPU0_SB_DQ<8> @S9S_MB_2U_LIB.S9S_MB_2U(SCH_1):M_B_CPU0_SB_DQ(8)   I180 @S9S_MB_2U_LIB.S9S_MB_2U(SCH_1):PAGE84
   113 M_B_CPU0_SB_DQ<9> @S9S_MB_2U_LIB.S9S_MB_2U(SCH_1):M_B_CPU0_SB_DQ(9)   I180 @S9S_MB_2U_LIB.S9S_MB_2U(SCH_1):PAGE84
   256 M_B_CPU0_SB_DQ<10> @S9S_MB_2U_LIB.S9S_MB_2U(SCH_1):M_B_CPU0_SB_DQ(10)   I180 @S9S_MB_2U_LIB.S9S_MB_2U(SCH_1):PAGE84
   258 M_B_CPU0_SB_DQ<11> @S9S_MB_2U_LIB.S9S_MB_2U(SCH_1):M_B_CPU0_SB_DQ(11)   I180 @S9S_MB_2U_LIB.S9S_MB_2U(SCH_1):PAGE84
   118 M_B_CPU0_SB_DQ<12> @S9S_MB_2U_LIB.S9S_MB_2U(SCH_1):M_B_CPU0_SB_DQ(12)   I180 @S9S_MB_2U_LIB.S9S_MB_2U(SCH_1):PAGE84
   120 M_B_CPU0_SB_DQ<13> @S9S_MB_2U_LIB.S9S_MB_2U(SCH_1):M_B_CPU0_SB_DQ(13)   I180 @S9S_MB_2U_LIB.S9S_MB_2U(SCH_1):PAGE84
   263 M_B_CPU0_SB_DQ<14> @S9S_MB_2U_LIB.S9S_MB_2U(SCH_1):M_B_CPU0_SB_DQ(14)   I180 @S9S_MB_2U_LIB.S9S_MB_2U(SCH_1):PAGE84
   265 M_B_CPU0_SB_DQ<15> @S9S_MB_2U_LIB.S9S_MB_2U(SCH_1):M_B_CPU0_SB_DQ(15)   I180 @S9S_MB_2U_LIB.S9S_MB_2U(SCH_1):PAGE84
   122 M_B_CPU0_SB_DQ<16> @S9S_MB_2U_LIB.S9S_MB_2U(SCH_1):M_B_CPU0_SB_DQ(16)   I180 @S9S_MB_2U_LIB.S9S_MB_2U(SCH_1):PAGE84
   124 M_B_CPU0_SB_DQ<17> @S9S_MB_2U_LIB.S9S_MB_2U(SCH_1):M_B_CPU0_SB_DQ(17)   I180 @S9S_MB_2U_LIB.S9S_MB_2U(SCH_1):PAGE84
   267 M_B_CPU0_SB_DQ<18> @S9S_MB_2U_LIB.S9S_MB_2U(SCH_1):M_B_CPU0_SB_DQ(18)   I180 @S9S_MB_2U_LIB.S9S_MB_2U(SCH_1):PAGE84
   269 M_B_CPU0_SB_DQ<19> @S9S_MB_2U_LIB.S9S_MB_2U(SCH_1):M_B_CPU0_SB_DQ(19)   I180 @S9S_MB_2U_LIB.S9S_MB_2U(SCH_1):PAGE84
   129 M_B_CPU0_SB_DQ<20> @S9S_MB_2U_LIB.S9S_MB_2U(SCH_1):M_B_CPU0_SB_DQ(20)   I180 @S9S_MB_2U_LIB.S9S_MB_2U(SCH_1):PAGE84
   131 M_B_CPU0_SB_DQ<21> @S9S_MB_2U_LIB.S9S_MB_2U(SCH_1):M_B_CPU0_SB_DQ(21)   I180 @S9S_MB_2U_LIB.S9S_MB_2U(SCH_1):PAGE84
   274 M_B_CPU0_SB_DQ<22> @S9S_MB_2U_LIB.S9S_MB_2U(SCH_1):M_B_CPU0_SB_DQ(22)   I180 @S9S_MB_2U_LIB.S9S_MB_2U(SCH_1):PAGE84
   276 M_B_CPU0_SB_DQ<23> @S9S_MB_2U_LIB.S9S_MB_2U(SCH_1):M_B_CPU0_SB_DQ(23)   I180 @S9S_MB_2U_LIB.S9S_MB_2U(SCH_1):PAGE84
   133 M_B_CPU0_SB_DQ<24> @S9S_MB_2U_LIB.S9S_MB_2U(SCH_1):M_B_CPU0_SB_DQ(24)   I180 @S9S_MB_2U_LIB.S9S_MB_2U(SCH_1):PAGE84
   135 M_B_CPU0_SB_DQ<25> @S9S_MB_2U_LIB.S9S_MB_2U(SCH_1):M_B_CPU0_SB_DQ(25)   I180 @S9S_MB_2U_LIB.S9S_MB_2U(SCH_1):PAGE84
   278 M_B_CPU0_SB_DQ<26> @S9S_MB_2U_LIB.S9S_MB_2U(SCH_1):M_B_CPU0_SB_DQ(26)   I180 @S9S_MB_2U_LIB.S9S_MB_2U(SCH_1):PAGE84
   280 M_B_CPU0_SB_DQ<27> @S9S_MB_2U_LIB.S9S_MB_2U(SCH_1):M_B_CPU0_SB_DQ(27)   I180 @S9S_MB_2U_LIB.S9S_MB_2U(SCH_1):PAGE84
   140 M_B_CPU0_SB_DQ<28> @S9S_MB_2U_LIB.S9S_MB_2U(SCH_1):M_B_CPU0_SB_DQ(28)   I180 @S9S_MB_2U_LIB.S9S_MB_2U(SCH_1):PAGE84
   142 M_B_CPU0_SB_DQ<29> @S9S_MB_2U_LIB.S9S_MB_2U(SCH_1):M_B_CPU0_SB_DQ(29)   I180 @S9S_MB_2U_LIB.S9S_MB_2U(SCH_1):PAGE84
   285 M_B_CPU0_SB_DQ<30> @S9S_MB_2U_LIB.S9S_MB_2U(SCH_1):M_B_CPU0_SB_DQ(30)   I180 @S9S_MB_2U_LIB.S9S_MB_2U(SCH_1):PAGE84
   287 M_B_CPU0_SB_DQ<31> @S9S_MB_2U_LIB.S9S_MB_2U(SCH_1):M_B_CPU0_SB_DQ(31)   I180 @S9S_MB_2U_LIB.S9S_MB_2U(SCH_1):PAGE84
     7 M_B_CPU0_SA_DQ<0> @S9S_MB_2U_LIB.S9S_MB_2U(SCH_1):M_B_CPU0_SA_DQ(0)   I180 @S9S_MB_2U_LIB.S9S_MB_2U(SCH_1):PAGE84
     9 M_B_CPU0_SA_DQ<1> @S9S_MB_2U_LIB.S9S_MB_2U(SCH_1):M_B_CPU0_SA_DQ(1)   I180 @S9S_MB_2U_LIB.S9S_MB_2U(SCH_1):PAGE84
   152 M_B_CPU0_SA_DQ<2> @S9S_MB_2U_LIB.S9S_MB_2U(SCH_1):M_B_CPU0_SA_DQ(2)   I180 @S9S_MB_2U_LIB.S9S_MB_2U(SCH_1):PAGE84
   154 M_B_CPU0_SA_DQ<3> @S9S_MB_2U_LIB.S9S_MB_2U(SCH_1):M_B_CPU0_SA_DQ(3)   I180 @S9S_MB_2U_LIB.S9S_MB_2U(SCH_1):PAGE84
    14 M_B_CPU0_SA_DQ<4> @S9S_MB_2U_LIB.S9S_MB_2U(SCH_1):M_B_CPU0_SA_DQ(4)   I180 @S9S_MB_2U_LIB.S9S_MB_2U(SCH_1):PAGE84
    16 M_B_CPU0_SA_DQ<5> @S9S_MB_2U_LIB.S9S_MB_2U(SCH_1):M_B_CPU0_SA_DQ(5)   I180 @S9S_MB_2U_LIB.S9S_MB_2U(SCH_1):PAGE84
   159 M_B_CPU0_SA_DQ<6> @S9S_MB_2U_LIB.S9S_MB_2U(SCH_1):M_B_CPU0_SA_DQ(6)   I180 @S9S_MB_2U_LIB.S9S_MB_2U(SCH_1):PAGE84
   161 M_B_CPU0_SA_DQ<7> @S9S_MB_2U_LIB.S9S_MB_2U(SCH_1):M_B_CPU0_SA_DQ(7)   I180 @S9S_MB_2U_LIB.S9S_MB_2U(SCH_1):PAGE84
    18 M_B_CPU0_SA_DQ<8> @S9S_MB_2U_LIB.S9S_MB_2U(SCH_1):M_B_CPU0_SA_DQ(8)   I180 @S9S_MB_2U_LIB.S9S_MB_2U(SCH_1):PAGE84
    20 M_B_CPU0_SA_DQ<9> @S9S_MB_2U_LIB.S9S_MB_2U(SCH_1):M_B_CPU0_SA_DQ(9)   I180 @S9S_MB_2U_LIB.S9S_MB_2U(SCH_1):PAGE84
   163 M_B_CPU0_SA_DQ<10> @S9S_MB_2U_LIB.S9S_MB_2U(SCH_1):M_B_CPU0_SA_DQ(10)   I180 @S9S_MB_2U_LIB.S9S_MB_2U(SCH_1):PAGE84
   165 M_B_CPU0_SA_DQ<11> @S9S_MB_2U_LIB.S9S_MB_2U(SCH_1):M_B_CPU0_SA_DQ(11)   I180 @S9S_MB_2U_LIB.S9S_MB_2U(SCH_1):PAGE84
    25 M_B_CPU0_SA_DQ<12> @S9S_MB_2U_LIB.S9S_MB_2U(SCH_1):M_B_CPU0_SA_DQ(12)   I180 @S9S_MB_2U_LIB.S9S_MB_2U(SCH_1):PAGE84
    27 M_B_CPU0_SA_DQ<13> @S9S_MB_2U_LIB.S9S_MB_2U(SCH_1):M_B_CPU0_SA_DQ(13)   I180 @S9S_MB_2U_LIB.S9S_MB_2U(SCH_1):PAGE84
   170 M_B_CPU0_SA_DQ<14> @S9S_MB_2U_LIB.S9S_MB_2U(SCH_1):M_B_CPU0_SA_DQ(14)   I180 @S9S_MB_2U_LIB.S9S_MB_2U(SCH_1):PAGE84
   172 M_B_CPU0_SA_DQ<15> @S9S_MB_2U_LIB.S9S_MB_2U(SCH_1):M_B_CPU0_SA_DQ(15)   I180 @S9S_MB_2U_LIB.S9S_MB_2U(SCH_1):PAGE84
    29 M_B_CPU0_SA_DQ<16> @S9S_MB_2U_LIB.S9S_MB_2U(SCH_1):M_B_CPU0_SA_DQ(16)   I180 @S9S_MB_2U_LIB.S9S_MB_2U(SCH_1):PAGE84
    31 M_B_CPU0_SA_DQ<17> @S9S_MB_2U_LIB.S9S_MB_2U(SCH_1):M_B_CPU0_SA_DQ(17)   I180 @S9S_MB_2U_LIB.S9S_MB_2U(SCH_1):PAGE84
   174 M_B_CPU0_SA_DQ<18> @S9S_MB_2U_LIB.S9S_MB_2U(SCH_1):M_B_CPU0_SA_DQ(18)   I180 @S9S_MB_2U_LIB.S9S_MB_2U(SCH_1):PAGE84
   176 M_B_CPU0_SA_DQ<19> @S9S_MB_2U_LIB.S9S_MB_2U(SCH_1):M_B_CPU0_SA_DQ(19)   I180 @S9S_MB_2U_LIB.S9S_MB_2U(SCH_1):PAGE84
    36 M_B_CPU0_SA_DQ<20> @S9S_MB_2U_LIB.S9S_MB_2U(SCH_1):M_B_CPU0_SA_DQ(20)   I180 @S9S_MB_2U_LIB.S9S_MB_2U(SCH_1):PAGE84
    38 M_B_CPU0_SA_DQ<21> @S9S_MB_2U_LIB.S9S_MB_2U(SCH_1):M_B_CPU0_SA_DQ(21)   I180 @S9S_MB_2U_LIB.S9S_MB_2U(SCH_1):PAGE84
   181 M_B_CPU0_SA_DQ<22> @S9S_MB_2U_LIB.S9S_MB_2U(SCH_1):M_B_CPU0_SA_DQ(22)   I180 @S9S_MB_2U_LIB.S9S_MB_2U(SCH_1):PAGE84
   183 M_B_CPU0_SA_DQ<23> @S9S_MB_2U_LIB.S9S_MB_2U(SCH_1):M_B_CPU0_SA_DQ(23)   I180 @S9S_MB_2U_LIB.S9S_MB_2U(SCH_1):PAGE84
    40 M_B_CPU0_SA_DQ<24> @S9S_MB_2U_LIB.S9S_MB_2U(SCH_1):M_B_CPU0_SA_DQ(24)   I180 @S9S_MB_2U_LIB.S9S_MB_2U(SCH_1):PAGE84
    42 M_B_CPU0_SA_DQ<25> @S9S_MB_2U_LIB.S9S_MB_2U(SCH_1):M_B_CPU0_SA_DQ(25)   I180 @S9S_MB_2U_LIB.S9S_MB_2U(SCH_1):PAGE84
   185 M_B_CPU0_SA_DQ<26> @S9S_MB_2U_LIB.S9S_MB_2U(SCH_1):M_B_CPU0_SA_DQ(26)   I180 @S9S_MB_2U_LIB.S9S_MB_2U(SCH_1):PAGE84
   187 M_B_CPU0_SA_DQ<27> @S9S_MB_2U_LIB.S9S_MB_2U(SCH_1):M_B_CPU0_SA_DQ(27)   I180 @S9S_MB_2U_LIB.S9S_MB_2U(SCH_1):PAGE84
    47 M_B_CPU0_SA_DQ<28> @S9S_MB_2U_LIB.S9S_MB_2U(SCH_1):M_B_CPU0_SA_DQ(28)   I180 @S9S_MB_2U_LIB.S9S_MB_2U(SCH_1):PAGE84
    49 M_B_CPU0_SA_DQ<29> @S9S_MB_2U_LIB.S9S_MB_2U(SCH_1):M_B_CPU0_SA_DQ(29)   I180 @S9S_MB_2U_LIB.S9S_MB_2U(SCH_1):PAGE84
   192 M_B_CPU0_SA_DQ<30> @S9S_MB_2U_LIB.S9S_MB_2U(SCH_1):M_B_CPU0_SA_DQ(30)   I180 @S9S_MB_2U_LIB.S9S_MB_2U(SCH_1):PAGE84
   229 M_B_CPU0_SB_CS_N<1> @S9S_MB_2U_LIB.S9S_MB_2U(SCH_1):M_B_CPU0_SB_CS_N(1)   I180 @S9S_MB_2U_LIB.S9S_MB_2U(SCH_1):PAGE84
   209 M_B_CPU0_SA_CS_N<1> @S9S_MB_2U_LIB.S9S_MB_2U(SCH_1):M_B_CPU0_SA_CS_N(1)   I180 @S9S_MB_2U_LIB.S9S_MB_2U(SCH_1):PAGE84
    84 M_B_CPU0_SB_CS_N<0> @S9S_MB_2U_LIB.S9S_MB_2U(SCH_1):M_B_CPU0_SB_CS_N(0)   I180 @S9S_MB_2U_LIB.S9S_MB_2U(SCH_1):PAGE84
    64 M_B_CPU0_SA_CS_N<0> @S9S_MB_2U_LIB.S9S_MB_2U(SCH_1):M_B_CPU0_SA_CS_N(0)   I180 @S9S_MB_2U_LIB.S9S_MB_2U(SCH_1):PAGE84
   217 M_B_CPU0_CLK_DP<0> @S9S_MB_2U_LIB.S9S_MB_2U(SCH_1):M_B_CPU0_CLK_DP(0)   I180 @S9S_MB_2U_LIB.S9S_MB_2U(SCH_1):PAGE84
   218 M_B_CPU0_CLK_DN<0> @S9S_MB_2U_LIB.S9S_MB_2U(SCH_1):M_B_CPU0_CLK_DN(0)   I180 @S9S_MB_2U_LIB.S9S_MB_2U(SCH_1):PAGE84
    96 M_B_CPU0_SB_CB<0> @S9S_MB_2U_LIB.S9S_MB_2U(SCH_1):M_B_CPU0_SB_CB(0)   I180 @S9S_MB_2U_LIB.S9S_MB_2U(SCH_1):PAGE84
    98 M_B_CPU0_SB_CB<1> @S9S_MB_2U_LIB.S9S_MB_2U(SCH_1):M_B_CPU0_SB_CB(1)   I180 @S9S_MB_2U_LIB.S9S_MB_2U(SCH_1):PAGE84
   241 M_B_CPU0_SB_CB<2> @S9S_MB_2U_LIB.S9S_MB_2U(SCH_1):M_B_CPU0_SB_CB(2)   I180 @S9S_MB_2U_LIB.S9S_MB_2U(SCH_1):PAGE84
   243 M_B_CPU0_SB_CB<3> @S9S_MB_2U_LIB.S9S_MB_2U(SCH_1):M_B_CPU0_SB_CB(3)   I180 @S9S_MB_2U_LIB.S9S_MB_2U(SCH_1):PAGE84
    89 M_B_CPU0_SB_CB<4> @S9S_MB_2U_LIB.S9S_MB_2U(SCH_1):M_B_CPU0_SB_CB(4)   I180 @S9S_MB_2U_LIB.S9S_MB_2U(SCH_1):PAGE84
    91 M_B_CPU0_SB_CB<5> @S9S_MB_2U_LIB.S9S_MB_2U(SCH_1):M_B_CPU0_SB_CB(5)   I180 @S9S_MB_2U_LIB.S9S_MB_2U(SCH_1):PAGE84
   234 M_B_CPU0_SB_CB<6> @S9S_MB_2U_LIB.S9S_MB_2U(SCH_1):M_B_CPU0_SB_CB(6)   I180 @S9S_MB_2U_LIB.S9S_MB_2U(SCH_1):PAGE84
    51 M_B_CPU0_SA_CB<0> @S9S_MB_2U_LIB.S9S_MB_2U(SCH_1):M_B_CPU0_SA_CB(0)   I180 @S9S_MB_2U_LIB.S9S_MB_2U(SCH_1):PAGE84
   196 M_B_CPU0_SA_CB<2> @S9S_MB_2U_LIB.S9S_MB_2U(SCH_1):M_B_CPU0_SA_CB(2)   I180 @S9S_MB_2U_LIB.S9S_MB_2U(SCH_1):PAGE84
   198 M_B_CPU0_SA_CB<3> @S9S_MB_2U_LIB.S9S_MB_2U(SCH_1):M_B_CPU0_SA_CB(3)   I180 @S9S_MB_2U_LIB.S9S_MB_2U(SCH_1):PAGE84
    60 M_B_CPU0_SA_CB<5> @S9S_MB_2U_LIB.S9S_MB_2U(SCH_1):M_B_CPU0_SA_CB(5)   I180 @S9S_MB_2U_LIB.S9S_MB_2U(SCH_1):PAGE84
   203 M_B_CPU0_SA_CB<6> @S9S_MB_2U_LIB.S9S_MB_2U(SCH_1):M_B_CPU0_SA_CB(6)   I180 @S9S_MB_2U_LIB.S9S_MB_2U(SCH_1):PAGE84
    82 M_B_CPU0_SB_CA<6> @S9S_MB_2U_LIB.S9S_MB_2U(SCH_1):M_B_CPU0_SB_CA(6)   I180 @S9S_MB_2U_LIB.S9S_MB_2U(SCH_1):PAGE84
    72 M_B_CPU0_SA_CA<6> @S9S_MB_2U_LIB.S9S_MB_2U(SCH_1):M_B_CPU0_SA_CA(6)   I180 @S9S_MB_2U_LIB.S9S_MB_2U(SCH_1):PAGE84
   225 M_B_CPU0_SB_CA<5> @S9S_MB_2U_LIB.S9S_MB_2U(SCH_1):M_B_CPU0_SB_CA(5)   I180 @S9S_MB_2U_LIB.S9S_MB_2U(SCH_1):PAGE84
   215 M_B_CPU0_SA_CA<5> @S9S_MB_2U_LIB.S9S_MB_2U(SCH_1):M_B_CPU0_SA_CA(5)   I180 @S9S_MB_2U_LIB.S9S_MB_2U(SCH_1):PAGE84
    80 M_B_CPU0_SB_CA<4> @S9S_MB_2U_LIB.S9S_MB_2U(SCH_1):M_B_CPU0_SB_CA(4)   I180 @S9S_MB_2U_LIB.S9S_MB_2U(SCH_1):PAGE84
    70 M_B_CPU0_SA_CA<4> @S9S_MB_2U_LIB.S9S_MB_2U(SCH_1):M_B_CPU0_SA_CA(4)   I180 @S9S_MB_2U_LIB.S9S_MB_2U(SCH_1):PAGE84
   223 M_B_CPU0_SB_CA<3> @S9S_MB_2U_LIB.S9S_MB_2U(SCH_1):M_B_CPU0_SB_CA(3)   I180 @S9S_MB_2U_LIB.S9S_MB_2U(SCH_1):PAGE84
   213 M_B_CPU0_SA_CA<3> @S9S_MB_2U_LIB.S9S_MB_2U(SCH_1):M_B_CPU0_SA_CA(3)   I180 @S9S_MB_2U_LIB.S9S_MB_2U(SCH_1):PAGE84
    78 M_B_CPU0_SB_CA<2> @S9S_MB_2U_LIB.S9S_MB_2U(SCH_1):M_B_CPU0_SB_CA(2)   I180 @S9S_MB_2U_LIB.S9S_MB_2U(SCH_1):PAGE84
    68 M_B_CPU0_SA_CA<2> @S9S_MB_2U_LIB.S9S_MB_2U(SCH_1):M_B_CPU0_SA_CA(2)   I180 @S9S_MB_2U_LIB.S9S_MB_2U(SCH_1):PAGE84
   221 M_B_CPU0_SB_CA<1> @S9S_MB_2U_LIB.S9S_MB_2U(SCH_1):M_B_CPU0_SB_CA(1)   I180 @S9S_MB_2U_LIB.S9S_MB_2U(SCH_1):PAGE84
   211 M_B_CPU0_SA_CA<1> @S9S_MB_2U_LIB.S9S_MB_2U(SCH_1):M_B_CPU0_SA_CA(1)   I180 @S9S_MB_2U_LIB.S9S_MB_2U(SCH_1):PAGE84
    76 M_B_CPU0_SB_CA<0> @S9S_MB_2U_LIB.S9S_MB_2U(SCH_1):M_B_CPU0_SB_CA(0)   I180 @S9S_MB_2U_LIB.S9S_MB_2U(SCH_1):PAGE84
    66 M_B_CPU0_SA_CA<0> @S9S_MB_2U_LIB.S9S_MB_2U(SCH_1):M_B_CPU0_SA_CA(0)   I180 @S9S_MB_2U_LIB.S9S_MB_2U(SCH_1):PAGE84
    62 M_B_CPU0_ALERT_N @S9S_MB_2U_LIB.S9S_MB_2U(SCH_1):M_B_CPU0_ALERT_N   I180 @S9S_MB_2U_LIB.S9S_MB_2U(SCH_1):PAGE84
   236 M_B_CPU0_SB_CB<7> @S9S_MB_2U_LIB.S9S_MB_2U(SCH_1):M_B_CPU0_SB_CB(7)   I180 @S9S_MB_2U_LIB.S9S_MB_2U(SCH_1):PAGE84
    53 M_B_CPU0_SA_CB<1> @S9S_MB_2U_LIB.S9S_MB_2U(SCH_1):M_B_CPU0_SA_CB(1)   I180 @S9S_MB_2U_LIB.S9S_MB_2U(SCH_1):PAGE84
    58 M_B_CPU0_SA_CB<4> @S9S_MB_2U_LIB.S9S_MB_2U(SCH_1):M_B_CPU0_SA_CB(4)   I180 @S9S_MB_2U_LIB.S9S_MB_2U(SCH_1):PAGE84
   205 M_B_CPU0_SA_CB<7> @S9S_MB_2U_LIB.S9S_MB_2U(SCH_1):M_B_CPU0_SA_CB(7)   I180 @S9S_MB_2U_LIB.S9S_MB_2U(SCH_1):PAGE84
   194 M_B_CPU0_SA_DQ<31> @S9S_MB_2U_LIB.S9S_MB_2U(SCH_1):M_B_CPU0_SA_DQ(31)   I180 @S9S_MB_2U_LIB.S9S_MB_2U(SCH_1):PAGE84
    93 M_B_CPU0_SB_DQS_DP<9> @S9S_MB_2U_LIB.S9S_MB_2U(SCH_1):M_B_CPU0_SB_DQS_DP(9)   I179 @S9S_MB_2U_LIB.S9S_MB_2U(SCH_1):PAGE84
    94 M_B_CPU0_SB_DQS_DN<9> @S9S_MB_2U_LIB.S9S_MB_2U(SCH_1):M_B_CPU0_SB_DQS_DN(9)   I179 @S9S_MB_2U_LIB.S9S_MB_2U(SCH_1):PAGE84
   201 M_B_CPU0_SA_DQS_DP<9> @S9S_MB_2U_LIB.S9S_MB_2U(SCH_1):M_B_CPU0_SA_DQS_DP(9)   I179 @S9S_MB_2U_LIB.S9S_MB_2U(SCH_1):PAGE84
   200 M_B_CPU0_SA_DQS_DN<9> @S9S_MB_2U_LIB.S9S_MB_2U(SCH_1):M_B_CPU0_SA_DQS_DN(9)   I179 @S9S_MB_2U_LIB.S9S_MB_2U(SCH_1):PAGE84
   190 M_B_CPU0_SA_DQS_DP<8> @S9S_MB_2U_LIB.S9S_MB_2U(SCH_1):M_B_CPU0_SA_DQS_DP(8)   I179 @S9S_MB_2U_LIB.S9S_MB_2U(SCH_1):PAGE84
   189 M_B_CPU0_SA_DQS_DN<8> @S9S_MB_2U_LIB.S9S_MB_2U(SCH_1):M_B_CPU0_SA_DQS_DN(8)   I179 @S9S_MB_2U_LIB.S9S_MB_2U(SCH_1):PAGE84
   271 M_B_CPU0_SB_DQS_DN<7> @S9S_MB_2U_LIB.S9S_MB_2U(SCH_1):M_B_CPU0_SB_DQS_DN(7)   I179 @S9S_MB_2U_LIB.S9S_MB_2U(SCH_1):PAGE84
   179 M_B_CPU0_SA_DQS_DP<7> @S9S_MB_2U_LIB.S9S_MB_2U(SCH_1):M_B_CPU0_SA_DQS_DP(7)   I179 @S9S_MB_2U_LIB.S9S_MB_2U(SCH_1):PAGE84
   261 M_B_CPU0_SB_DQS_DP<6> @S9S_MB_2U_LIB.S9S_MB_2U(SCH_1):M_B_CPU0_SB_DQS_DP(6)   I179 @S9S_MB_2U_LIB.S9S_MB_2U(SCH_1):PAGE84
   260 M_B_CPU0_SB_DQS_DN<6> @S9S_MB_2U_LIB.S9S_MB_2U(SCH_1):M_B_CPU0_SB_DQS_DN(6)   I179 @S9S_MB_2U_LIB.S9S_MB_2U(SCH_1):PAGE84
   167 M_B_CPU0_SA_DQS_DN<6> @S9S_MB_2U_LIB.S9S_MB_2U(SCH_1):M_B_CPU0_SA_DQS_DN(6)   I179 @S9S_MB_2U_LIB.S9S_MB_2U(SCH_1):PAGE84
   250 M_B_CPU0_SB_DQS_DP<5> @S9S_MB_2U_LIB.S9S_MB_2U(SCH_1):M_B_CPU0_SB_DQS_DP(5)   I179 @S9S_MB_2U_LIB.S9S_MB_2U(SCH_1):PAGE84
   249 M_B_CPU0_SB_DQS_DN<5> @S9S_MB_2U_LIB.S9S_MB_2U(SCH_1):M_B_CPU0_SB_DQS_DN(5)   I179 @S9S_MB_2U_LIB.S9S_MB_2U(SCH_1):PAGE84
   157 M_B_CPU0_SA_DQS_DP<5> @S9S_MB_2U_LIB.S9S_MB_2U(SCH_1):M_B_CPU0_SA_DQS_DP(5)   I179 @S9S_MB_2U_LIB.S9S_MB_2U(SCH_1):PAGE84
   156 M_B_CPU0_SA_DQS_DN<5> @S9S_MB_2U_LIB.S9S_MB_2U(SCH_1):M_B_CPU0_SA_DQS_DN(5)   I179 @S9S_MB_2U_LIB.S9S_MB_2U(SCH_1):PAGE84
   239 M_B_CPU0_SB_DQS_DP<4> @S9S_MB_2U_LIB.S9S_MB_2U(SCH_1):M_B_CPU0_SB_DQS_DP(4)   I179 @S9S_MB_2U_LIB.S9S_MB_2U(SCH_1):PAGE84
   238 M_B_CPU0_SB_DQS_DN<4> @S9S_MB_2U_LIB.S9S_MB_2U(SCH_1):M_B_CPU0_SB_DQS_DN(4)   I179 @S9S_MB_2U_LIB.S9S_MB_2U(SCH_1):PAGE84
    55 M_B_CPU0_SA_DQS_DP<4> @S9S_MB_2U_LIB.S9S_MB_2U(SCH_1):M_B_CPU0_SA_DQS_DP(4)   I179 @S9S_MB_2U_LIB.S9S_MB_2U(SCH_1):PAGE84
    56 M_B_CPU0_SA_DQS_DN<4> @S9S_MB_2U_LIB.S9S_MB_2U(SCH_1):M_B_CPU0_SA_DQS_DN(4)   I179 @S9S_MB_2U_LIB.S9S_MB_2U(SCH_1):PAGE84
   137 M_B_CPU0_SB_DQS_DP<3> @S9S_MB_2U_LIB.S9S_MB_2U(SCH_1):M_B_CPU0_SB_DQS_DP(3)   I179 @S9S_MB_2U_LIB.S9S_MB_2U(SCH_1):PAGE84
   138 M_B_CPU0_SB_DQS_DN<3> @S9S_MB_2U_LIB.S9S_MB_2U(SCH_1):M_B_CPU0_SB_DQS_DN(3)   I179 @S9S_MB_2U_LIB.S9S_MB_2U(SCH_1):PAGE84
    44 M_B_CPU0_SA_DQS_DP<3> @S9S_MB_2U_LIB.S9S_MB_2U(SCH_1):M_B_CPU0_SA_DQS_DP(3)   I179 @S9S_MB_2U_LIB.S9S_MB_2U(SCH_1):PAGE84
    45 M_B_CPU0_SA_DQS_DN<3> @S9S_MB_2U_LIB.S9S_MB_2U(SCH_1):M_B_CPU0_SA_DQS_DN(3)   I179 @S9S_MB_2U_LIB.S9S_MB_2U(SCH_1):PAGE84
   126 M_B_CPU0_SB_DQS_DP<2> @S9S_MB_2U_LIB.S9S_MB_2U(SCH_1):M_B_CPU0_SB_DQS_DP(2)   I179 @S9S_MB_2U_LIB.S9S_MB_2U(SCH_1):PAGE84
   127 M_B_CPU0_SB_DQS_DN<2> @S9S_MB_2U_LIB.S9S_MB_2U(SCH_1):M_B_CPU0_SB_DQS_DN(2)   I179 @S9S_MB_2U_LIB.S9S_MB_2U(SCH_1):PAGE84
    33 M_B_CPU0_SA_DQS_DP<2> @S9S_MB_2U_LIB.S9S_MB_2U(SCH_1):M_B_CPU0_SA_DQS_DP(2)   I179 @S9S_MB_2U_LIB.S9S_MB_2U(SCH_1):PAGE84
    34 M_B_CPU0_SA_DQS_DN<2> @S9S_MB_2U_LIB.S9S_MB_2U(SCH_1):M_B_CPU0_SA_DQS_DN(2)   I179 @S9S_MB_2U_LIB.S9S_MB_2U(SCH_1):PAGE84
   115 M_B_CPU0_SB_DQS_DP<1> @S9S_MB_2U_LIB.S9S_MB_2U(SCH_1):M_B_CPU0_SB_DQS_DP(1)   I179 @S9S_MB_2U_LIB.S9S_MB_2U(SCH_1):PAGE84
   116 M_B_CPU0_SB_DQS_DN<1> @S9S_MB_2U_LIB.S9S_MB_2U(SCH_1):M_B_CPU0_SB_DQS_DN(1)   I179 @S9S_MB_2U_LIB.S9S_MB_2U(SCH_1):PAGE84
    22 M_B_CPU0_SA_DQS_DP<1> @S9S_MB_2U_LIB.S9S_MB_2U(SCH_1):M_B_CPU0_SA_DQS_DP(1)   I179 @S9S_MB_2U_LIB.S9S_MB_2U(SCH_1):PAGE84
    23 M_B_CPU0_SA_DQS_DN<1> @S9S_MB_2U_LIB.S9S_MB_2U(SCH_1):M_B_CPU0_SA_DQS_DN(1)   I179 @S9S_MB_2U_LIB.S9S_MB_2U(SCH_1):PAGE84
   104 M_B_CPU0_SB_DQS_DP<0> @S9S_MB_2U_LIB.S9S_MB_2U(SCH_1):M_B_CPU0_SB_DQS_DP(0)   I179 @S9S_MB_2U_LIB.S9S_MB_2U(SCH_1):PAGE84
   105 M_B_CPU0_SB_DQS_DN<0> @S9S_MB_2U_LIB.S9S_MB_2U(SCH_1):M_B_CPU0_SB_DQS_DN(0)   I179 @S9S_MB_2U_LIB.S9S_MB_2U(SCH_1):PAGE84
    11 M_B_CPU0_SA_DQS_DP<0> @S9S_MB_2U_LIB.S9S_MB_2U(SCH_1):M_B_CPU0_SA_DQS_DP(0)   I179 @S9S_MB_2U_LIB.S9S_MB_2U(SCH_1):PAGE84
    12 M_B_CPU0_SA_DQS_DN<0> @S9S_MB_2U_LIB.S9S_MB_2U(SCH_1):M_B_CPU0_SA_DQS_DN(0)   I179 @S9S_MB_2U_LIB.S9S_MB_2U(SCH_1):PAGE84
   272 M_B_CPU0_SB_DQS_DP<7> @S9S_MB_2U_LIB.S9S_MB_2U(SCH_1):M_B_CPU0_SB_DQS_DP(7)   I179 @S9S_MB_2U_LIB.S9S_MB_2U(SCH_1):PAGE84
   282 M_B_CPU0_SB_DQS_DN<8> @S9S_MB_2U_LIB.S9S_MB_2U(SCH_1):M_B_CPU0_SB_DQS_DN(8)   I179 @S9S_MB_2U_LIB.S9S_MB_2U(SCH_1):PAGE84
   283 M_B_CPU0_SB_DQS_DP<8> @S9S_MB_2U_LIB.S9S_MB_2U(SCH_1):M_B_CPU0_SB_DQS_DP(8)   I179 @S9S_MB_2U_LIB.S9S_MB_2U(SCH_1):PAGE84
   168 M_B_CPU0_SA_DQS_DP<6> @S9S_MB_2U_LIB.S9S_MB_2U(SCH_1):M_B_CPU0_SA_DQS_DP(6)   I179 @S9S_MB_2U_LIB.S9S_MB_2U(SCH_1):PAGE84
   178 M_B_CPU0_SA_DQS_DN<7> @S9S_MB_2U_LIB.S9S_MB_2U(SCH_1):M_B_CPU0_SA_DQS_DN(7)   I179 @S9S_MB_2U_LIB.S9S_MB_2U(SCH_1):PAGE84
     6    GND @S9S_MB_2U_LIB.S9S_MB_2U(SCH_1):GND   I178 @S9S_MB_2U_LIB.S9S_MB_2U(SCH_1):PAGE84
     8    GND @S9S_MB_2U_LIB.S9S_MB_2U(SCH_1):GND   I178 @S9S_MB_2U_LIB.S9S_MB_2U(SCH_1):PAGE84
    10    GND @S9S_MB_2U_LIB.S9S_MB_2U(SCH_1):GND   I178 @S9S_MB_2U_LIB.S9S_MB_2U(SCH_1):PAGE84
    13    GND @S9S_MB_2U_LIB.S9S_MB_2U(SCH_1):GND   I178 @S9S_MB_2U_LIB.S9S_MB_2U(SCH_1):PAGE84
    15    GND @S9S_MB_2U_LIB.S9S_MB_2U(SCH_1):GND   I178 @S9S_MB_2U_LIB.S9S_MB_2U(SCH_1):PAGE84
    17    GND @S9S_MB_2U_LIB.S9S_MB_2U(SCH_1):GND   I178 @S9S_MB_2U_LIB.S9S_MB_2U(SCH_1):PAGE84
    19    GND @S9S_MB_2U_LIB.S9S_MB_2U(SCH_1):GND   I178 @S9S_MB_2U_LIB.S9S_MB_2U(SCH_1):PAGE84
    21    GND @S9S_MB_2U_LIB.S9S_MB_2U(SCH_1):GND   I178 @S9S_MB_2U_LIB.S9S_MB_2U(SCH_1):PAGE84
    24    GND @S9S_MB_2U_LIB.S9S_MB_2U(SCH_1):GND   I178 @S9S_MB_2U_LIB.S9S_MB_2U(SCH_1):PAGE84
    26    GND @S9S_MB_2U_LIB.S9S_MB_2U(SCH_1):GND   I178 @S9S_MB_2U_LIB.S9S_MB_2U(SCH_1):PAGE84
    28    GND @S9S_MB_2U_LIB.S9S_MB_2U(SCH_1):GND   I178 @S9S_MB_2U_LIB.S9S_MB_2U(SCH_1):PAGE84
    30    GND @S9S_MB_2U_LIB.S9S_MB_2U(SCH_1):GND   I178 @S9S_MB_2U_LIB.S9S_MB_2U(SCH_1):PAGE84
    32    GND @S9S_MB_2U_LIB.S9S_MB_2U(SCH_1):GND   I178 @S9S_MB_2U_LIB.S9S_MB_2U(SCH_1):PAGE84
    35    GND @S9S_MB_2U_LIB.S9S_MB_2U(SCH_1):GND   I178 @S9S_MB_2U_LIB.S9S_MB_2U(SCH_1):PAGE84
    37    GND @S9S_MB_2U_LIB.S9S_MB_2U(SCH_1):GND   I178 @S9S_MB_2U_LIB.S9S_MB_2U(SCH_1):PAGE84
    39    GND @S9S_MB_2U_LIB.S9S_MB_2U(SCH_1):GND   I178 @S9S_MB_2U_LIB.S9S_MB_2U(SCH_1):PAGE84
    41    GND @S9S_MB_2U_LIB.S9S_MB_2U(SCH_1):GND   I178 @S9S_MB_2U_LIB.S9S_MB_2U(SCH_1):PAGE84
    43    GND @S9S_MB_2U_LIB.S9S_MB_2U(SCH_1):GND   I178 @S9S_MB_2U_LIB.S9S_MB_2U(SCH_1):PAGE84
    46    GND @S9S_MB_2U_LIB.S9S_MB_2U(SCH_1):GND   I178 @S9S_MB_2U_LIB.S9S_MB_2U(SCH_1):PAGE84
    48    GND @S9S_MB_2U_LIB.S9S_MB_2U(SCH_1):GND   I178 @S9S_MB_2U_LIB.S9S_MB_2U(SCH_1):PAGE84
    50    GND @S9S_MB_2U_LIB.S9S_MB_2U(SCH_1):GND   I178 @S9S_MB_2U_LIB.S9S_MB_2U(SCH_1):PAGE84
    52    GND @S9S_MB_2U_LIB.S9S_MB_2U(SCH_1):GND   I178 @S9S_MB_2U_LIB.S9S_MB_2U(SCH_1):PAGE84
    54    GND @S9S_MB_2U_LIB.S9S_MB_2U(SCH_1):GND   I178 @S9S_MB_2U_LIB.S9S_MB_2U(SCH_1):PAGE84
    57    GND @S9S_MB_2U_LIB.S9S_MB_2U(SCH_1):GND   I178 @S9S_MB_2U_LIB.S9S_MB_2U(SCH_1):PAGE84
    59    GND @S9S_MB_2U_LIB.S9S_MB_2U(SCH_1):GND   I178 @S9S_MB_2U_LIB.S9S_MB_2U(SCH_1):PAGE84
    61    GND @S9S_MB_2U_LIB.S9S_MB_2U(SCH_1):GND   I178 @S9S_MB_2U_LIB.S9S_MB_2U(SCH_1):PAGE84
    63    GND @S9S_MB_2U_LIB.S9S_MB_2U(SCH_1):GND   I178 @S9S_MB_2U_LIB.S9S_MB_2U(SCH_1):PAGE84
    65    GND @S9S_MB_2U_LIB.S9S_MB_2U(SCH_1):GND   I178 @S9S_MB_2U_LIB.S9S_MB_2U(SCH_1):PAGE84
    67    GND @S9S_MB_2U_LIB.S9S_MB_2U(SCH_1):GND   I178 @S9S_MB_2U_LIB.S9S_MB_2U(SCH_1):PAGE84
    69    GND @S9S_MB_2U_LIB.S9S_MB_2U(SCH_1):GND   I178 @S9S_MB_2U_LIB.S9S_MB_2U(SCH_1):PAGE84
    71    GND @S9S_MB_2U_LIB.S9S_MB_2U(SCH_1):GND   I178 @S9S_MB_2U_LIB.S9S_MB_2U(SCH_1):PAGE84
    73    GND @S9S_MB_2U_LIB.S9S_MB_2U(SCH_1):GND   I178 @S9S_MB_2U_LIB.S9S_MB_2U(SCH_1):PAGE84
    75    GND @S9S_MB_2U_LIB.S9S_MB_2U(SCH_1):GND   I178 @S9S_MB_2U_LIB.S9S_MB_2U(SCH_1):PAGE84
    77    GND @S9S_MB_2U_LIB.S9S_MB_2U(SCH_1):GND   I178 @S9S_MB_2U_LIB.S9S_MB_2U(SCH_1):PAGE84
    79    GND @S9S_MB_2U_LIB.S9S_MB_2U(SCH_1):GND   I178 @S9S_MB_2U_LIB.S9S_MB_2U(SCH_1):PAGE84
    81    GND @S9S_MB_2U_LIB.S9S_MB_2U(SCH_1):GND   I178 @S9S_MB_2U_LIB.S9S_MB_2U(SCH_1):PAGE84
    83    GND @S9S_MB_2U_LIB.S9S_MB_2U(SCH_1):GND   I178 @S9S_MB_2U_LIB.S9S_MB_2U(SCH_1):PAGE84
    85    GND @S9S_MB_2U_LIB.S9S_MB_2U(SCH_1):GND   I178 @S9S_MB_2U_LIB.S9S_MB_2U(SCH_1):PAGE84
    88    GND @S9S_MB_2U_LIB.S9S_MB_2U(SCH_1):GND   I178 @S9S_MB_2U_LIB.S9S_MB_2U(SCH_1):PAGE84
    90    GND @S9S_MB_2U_LIB.S9S_MB_2U(SCH_1):GND   I178 @S9S_MB_2U_LIB.S9S_MB_2U(SCH_1):PAGE84
    92    GND @S9S_MB_2U_LIB.S9S_MB_2U(SCH_1):GND   I178 @S9S_MB_2U_LIB.S9S_MB_2U(SCH_1):PAGE84
    95    GND @S9S_MB_2U_LIB.S9S_MB_2U(SCH_1):GND   I178 @S9S_MB_2U_LIB.S9S_MB_2U(SCH_1):PAGE84
    97    GND @S9S_MB_2U_LIB.S9S_MB_2U(SCH_1):GND   I178 @S9S_MB_2U_LIB.S9S_MB_2U(SCH_1):PAGE84
    99    GND @S9S_MB_2U_LIB.S9S_MB_2U(SCH_1):GND   I178 @S9S_MB_2U_LIB.S9S_MB_2U(SCH_1):PAGE84
   101    GND @S9S_MB_2U_LIB.S9S_MB_2U(SCH_1):GND   I178 @S9S_MB_2U_LIB.S9S_MB_2U(SCH_1):PAGE84
   103    GND @S9S_MB_2U_LIB.S9S_MB_2U(SCH_1):GND   I178 @S9S_MB_2U_LIB.S9S_MB_2U(SCH_1):PAGE84
   106    GND @S9S_MB_2U_LIB.S9S_MB_2U(SCH_1):GND   I178 @S9S_MB_2U_LIB.S9S_MB_2U(SCH_1):PAGE84
   108    GND @S9S_MB_2U_LIB.S9S_MB_2U(SCH_1):GND   I178 @S9S_MB_2U_LIB.S9S_MB_2U(SCH_1):PAGE84
   110    GND @S9S_MB_2U_LIB.S9S_MB_2U(SCH_1):GND   I178 @S9S_MB_2U_LIB.S9S_MB_2U(SCH_1):PAGE84
   112    GND @S9S_MB_2U_LIB.S9S_MB_2U(SCH_1):GND   I178 @S9S_MB_2U_LIB.S9S_MB_2U(SCH_1):PAGE84
   114    GND @S9S_MB_2U_LIB.S9S_MB_2U(SCH_1):GND   I178 @S9S_MB_2U_LIB.S9S_MB_2U(SCH_1):PAGE84
   117    GND @S9S_MB_2U_LIB.S9S_MB_2U(SCH_1):GND   I178 @S9S_MB_2U_LIB.S9S_MB_2U(SCH_1):PAGE84
   119    GND @S9S_MB_2U_LIB.S9S_MB_2U(SCH_1):GND   I178 @S9S_MB_2U_LIB.S9S_MB_2U(SCH_1):PAGE84
   121    GND @S9S_MB_2U_LIB.S9S_MB_2U(SCH_1):GND   I178 @S9S_MB_2U_LIB.S9S_MB_2U(SCH_1):PAGE84
   123    GND @S9S_MB_2U_LIB.S9S_MB_2U(SCH_1):GND   I178 @S9S_MB_2U_LIB.S9S_MB_2U(SCH_1):PAGE84
   125    GND @S9S_MB_2U_LIB.S9S_MB_2U(SCH_1):GND   I178 @S9S_MB_2U_LIB.S9S_MB_2U(SCH_1):PAGE84
   128    GND @S9S_MB_2U_LIB.S9S_MB_2U(SCH_1):GND   I178 @S9S_MB_2U_LIB.S9S_MB_2U(SCH_1):PAGE84
   130    GND @S9S_MB_2U_LIB.S9S_MB_2U(SCH_1):GND   I178 @S9S_MB_2U_LIB.S9S_MB_2U(SCH_1):PAGE84
   134    GND @S9S_MB_2U_LIB.S9S_MB_2U(SCH_1):GND   I178 @S9S_MB_2U_LIB.S9S_MB_2U(SCH_1):PAGE84
   143    GND @S9S_MB_2U_LIB.S9S_MB_2U(SCH_1):GND   I178 @S9S_MB_2U_LIB.S9S_MB_2U(SCH_1):PAGE84
   151    GND @S9S_MB_2U_LIB.S9S_MB_2U(SCH_1):GND   I178 @S9S_MB_2U_LIB.S9S_MB_2U(SCH_1):PAGE84
   153    GND @S9S_MB_2U_LIB.S9S_MB_2U(SCH_1):GND   I178 @S9S_MB_2U_LIB.S9S_MB_2U(SCH_1):PAGE84
   155    GND @S9S_MB_2U_LIB.S9S_MB_2U(SCH_1):GND   I178 @S9S_MB_2U_LIB.S9S_MB_2U(SCH_1):PAGE84
   158    GND @S9S_MB_2U_LIB.S9S_MB_2U(SCH_1):GND   I178 @S9S_MB_2U_LIB.S9S_MB_2U(SCH_1):PAGE84
   160    GND @S9S_MB_2U_LIB.S9S_MB_2U(SCH_1):GND   I178 @S9S_MB_2U_LIB.S9S_MB_2U(SCH_1):PAGE84
   162    GND @S9S_MB_2U_LIB.S9S_MB_2U(SCH_1):GND   I178 @S9S_MB_2U_LIB.S9S_MB_2U(SCH_1):PAGE84
   164    GND @S9S_MB_2U_LIB.S9S_MB_2U(SCH_1):GND   I178 @S9S_MB_2U_LIB.S9S_MB_2U(SCH_1):PAGE84
   166    GND @S9S_MB_2U_LIB.S9S_MB_2U(SCH_1):GND   I178 @S9S_MB_2U_LIB.S9S_MB_2U(SCH_1):PAGE84
   169    GND @S9S_MB_2U_LIB.S9S_MB_2U(SCH_1):GND   I178 @S9S_MB_2U_LIB.S9S_MB_2U(SCH_1):PAGE84
   171    GND @S9S_MB_2U_LIB.S9S_MB_2U(SCH_1):GND   I178 @S9S_MB_2U_LIB.S9S_MB_2U(SCH_1):PAGE84
   173    GND @S9S_MB_2U_LIB.S9S_MB_2U(SCH_1):GND   I178 @S9S_MB_2U_LIB.S9S_MB_2U(SCH_1):PAGE84
   175    GND @S9S_MB_2U_LIB.S9S_MB_2U(SCH_1):GND   I178 @S9S_MB_2U_LIB.S9S_MB_2U(SCH_1):PAGE84
   177    GND @S9S_MB_2U_LIB.S9S_MB_2U(SCH_1):GND   I178 @S9S_MB_2U_LIB.S9S_MB_2U(SCH_1):PAGE84
   180    GND @S9S_MB_2U_LIB.S9S_MB_2U(SCH_1):GND   I178 @S9S_MB_2U_LIB.S9S_MB_2U(SCH_1):PAGE84
   182    GND @S9S_MB_2U_LIB.S9S_MB_2U(SCH_1):GND   I178 @S9S_MB_2U_LIB.S9S_MB_2U(SCH_1):PAGE84
   184    GND @S9S_MB_2U_LIB.S9S_MB_2U(SCH_1):GND   I178 @S9S_MB_2U_LIB.S9S_MB_2U(SCH_1):PAGE84
   186    GND @S9S_MB_2U_LIB.S9S_MB_2U(SCH_1):GND   I178 @S9S_MB_2U_LIB.S9S_MB_2U(SCH_1):PAGE84
   188    GND @S9S_MB_2U_LIB.S9S_MB_2U(SCH_1):GND   I178 @S9S_MB_2U_LIB.S9S_MB_2U(SCH_1):PAGE84
   191    GND @S9S_MB_2U_LIB.S9S_MB_2U(SCH_1):GND   I178 @S9S_MB_2U_LIB.S9S_MB_2U(SCH_1):PAGE84
   193    GND @S9S_MB_2U_LIB.S9S_MB_2U(SCH_1):GND   I178 @S9S_MB_2U_LIB.S9S_MB_2U(SCH_1):PAGE84
   195    GND @S9S_MB_2U_LIB.S9S_MB_2U(SCH_1):GND   I178 @S9S_MB_2U_LIB.S9S_MB_2U(SCH_1):PAGE84
   197    GND @S9S_MB_2U_LIB.S9S_MB_2U(SCH_1):GND   I178 @S9S_MB_2U_LIB.S9S_MB_2U(SCH_1):PAGE84
   199    GND @S9S_MB_2U_LIB.S9S_MB_2U(SCH_1):GND   I178 @S9S_MB_2U_LIB.S9S_MB_2U(SCH_1):PAGE84
   202    GND @S9S_MB_2U_LIB.S9S_MB_2U(SCH_1):GND   I178 @S9S_MB_2U_LIB.S9S_MB_2U(SCH_1):PAGE84
   204    GND @S9S_MB_2U_LIB.S9S_MB_2U(SCH_1):GND   I178 @S9S_MB_2U_LIB.S9S_MB_2U(SCH_1):PAGE84
   206    GND @S9S_MB_2U_LIB.S9S_MB_2U(SCH_1):GND   I178 @S9S_MB_2U_LIB.S9S_MB_2U(SCH_1):PAGE84
   208    GND @S9S_MB_2U_LIB.S9S_MB_2U(SCH_1):GND   I178 @S9S_MB_2U_LIB.S9S_MB_2U(SCH_1):PAGE84
   210    GND @S9S_MB_2U_LIB.S9S_MB_2U(SCH_1):GND   I178 @S9S_MB_2U_LIB.S9S_MB_2U(SCH_1):PAGE84
   212    GND @S9S_MB_2U_LIB.S9S_MB_2U(SCH_1):GND   I178 @S9S_MB_2U_LIB.S9S_MB_2U(SCH_1):PAGE84
   214    GND @S9S_MB_2U_LIB.S9S_MB_2U(SCH_1):GND   I178 @S9S_MB_2U_LIB.S9S_MB_2U(SCH_1):PAGE84
   216    GND @S9S_MB_2U_LIB.S9S_MB_2U(SCH_1):GND   I178 @S9S_MB_2U_LIB.S9S_MB_2U(SCH_1):PAGE84
   219    GND @S9S_MB_2U_LIB.S9S_MB_2U(SCH_1):GND   I178 @S9S_MB_2U_LIB.S9S_MB_2U(SCH_1):PAGE84
   222    GND @S9S_MB_2U_LIB.S9S_MB_2U(SCH_1):GND   I178 @S9S_MB_2U_LIB.S9S_MB_2U(SCH_1):PAGE84
   224    GND @S9S_MB_2U_LIB.S9S_MB_2U(SCH_1):GND   I178 @S9S_MB_2U_LIB.S9S_MB_2U(SCH_1):PAGE84
   226    GND @S9S_MB_2U_LIB.S9S_MB_2U(SCH_1):GND   I178 @S9S_MB_2U_LIB.S9S_MB_2U(SCH_1):PAGE84
   228    GND @S9S_MB_2U_LIB.S9S_MB_2U(SCH_1):GND   I178 @S9S_MB_2U_LIB.S9S_MB_2U(SCH_1):PAGE84
   233    GND @S9S_MB_2U_LIB.S9S_MB_2U(SCH_1):GND   I178 @S9S_MB_2U_LIB.S9S_MB_2U(SCH_1):PAGE84
   237    GND @S9S_MB_2U_LIB.S9S_MB_2U(SCH_1):GND   I178 @S9S_MB_2U_LIB.S9S_MB_2U(SCH_1):PAGE84
   242    GND @S9S_MB_2U_LIB.S9S_MB_2U(SCH_1):GND   I178 @S9S_MB_2U_LIB.S9S_MB_2U(SCH_1):PAGE84
   244    GND @S9S_MB_2U_LIB.S9S_MB_2U(SCH_1):GND   I178 @S9S_MB_2U_LIB.S9S_MB_2U(SCH_1):PAGE84
   246    GND @S9S_MB_2U_LIB.S9S_MB_2U(SCH_1):GND   I178 @S9S_MB_2U_LIB.S9S_MB_2U(SCH_1):PAGE84
   248    GND @S9S_MB_2U_LIB.S9S_MB_2U(SCH_1):GND   I178 @S9S_MB_2U_LIB.S9S_MB_2U(SCH_1):PAGE84
   251    GND @S9S_MB_2U_LIB.S9S_MB_2U(SCH_1):GND   I178 @S9S_MB_2U_LIB.S9S_MB_2U(SCH_1):PAGE84
   253    GND @S9S_MB_2U_LIB.S9S_MB_2U(SCH_1):GND   I178 @S9S_MB_2U_LIB.S9S_MB_2U(SCH_1):PAGE84
   255    GND @S9S_MB_2U_LIB.S9S_MB_2U(SCH_1):GND   I178 @S9S_MB_2U_LIB.S9S_MB_2U(SCH_1):PAGE84
   257    GND @S9S_MB_2U_LIB.S9S_MB_2U(SCH_1):GND   I178 @S9S_MB_2U_LIB.S9S_MB_2U(SCH_1):PAGE84
   259    GND @S9S_MB_2U_LIB.S9S_MB_2U(SCH_1):GND   I178 @S9S_MB_2U_LIB.S9S_MB_2U(SCH_1):PAGE84
   262    GND @S9S_MB_2U_LIB.S9S_MB_2U(SCH_1):GND   I178 @S9S_MB_2U_LIB.S9S_MB_2U(SCH_1):PAGE84
   264    GND @S9S_MB_2U_LIB.S9S_MB_2U(SCH_1):GND   I178 @S9S_MB_2U_LIB.S9S_MB_2U(SCH_1):PAGE84
   266    GND @S9S_MB_2U_LIB.S9S_MB_2U(SCH_1):GND   I178 @S9S_MB_2U_LIB.S9S_MB_2U(SCH_1):PAGE84
   268    GND @S9S_MB_2U_LIB.S9S_MB_2U(SCH_1):GND   I178 @S9S_MB_2U_LIB.S9S_MB_2U(SCH_1):PAGE84
   270    GND @S9S_MB_2U_LIB.S9S_MB_2U(SCH_1):GND   I178 @S9S_MB_2U_LIB.S9S_MB_2U(SCH_1):PAGE84
   273    GND @S9S_MB_2U_LIB.S9S_MB_2U(SCH_1):GND   I178 @S9S_MB_2U_LIB.S9S_MB_2U(SCH_1):PAGE84
   275    GND @S9S_MB_2U_LIB.S9S_MB_2U(SCH_1):GND   I178 @S9S_MB_2U_LIB.S9S_MB_2U(SCH_1):PAGE84
   277    GND @S9S_MB_2U_LIB.S9S_MB_2U(SCH_1):GND   I178 @S9S_MB_2U_LIB.S9S_MB_2U(SCH_1):PAGE84
   279    GND @S9S_MB_2U_LIB.S9S_MB_2U(SCH_1):GND   I178 @S9S_MB_2U_LIB.S9S_MB_2U(SCH_1):PAGE84
   281    GND @S9S_MB_2U_LIB.S9S_MB_2U(SCH_1):GND   I178 @S9S_MB_2U_LIB.S9S_MB_2U(SCH_1):PAGE84
   284    GND @S9S_MB_2U_LIB.S9S_MB_2U(SCH_1):GND   I178 @S9S_MB_2U_LIB.S9S_MB_2U(SCH_1):PAGE84
   286    GND @S9S_MB_2U_LIB.S9S_MB_2U(SCH_1):GND   I178 @S9S_MB_2U_LIB.S9S_MB_2U(SCH_1):PAGE84
   288    GND @S9S_MB_2U_LIB.S9S_MB_2U(SCH_1):GND   I178 @S9S_MB_2U_LIB.S9S_MB_2U(SCH_1):PAGE84
     1 P12V_S3_AUX_CPU0_NVDIMM @S9S_MB_2U_LIB.S9S_MB_2U(SCH_1):P12V_S3_AUX_CPU0_NVDIMM   I178 @S9S_MB_2U_LIB.S9S_MB_2U(SCH_1):PAGE84
   145 P12V_S3_AUX_CPU0_NVDIMM @S9S_MB_2U_LIB.S9S_MB_2U(SCH_1):P12V_S3_AUX_CPU0_NVDIMM   I178 @S9S_MB_2U_LIB.S9S_MB_2U(SCH_1):PAGE84
   146 P12V_S3_AUX_CPU0_NVDIMM @S9S_MB_2U_LIB.S9S_MB_2U(SCH_1):P12V_S3_AUX_CPU0_NVDIMM   I178 @S9S_MB_2U_LIB.S9S_MB_2U(SCH_1):PAGE84
   230    GND @S9S_MB_2U_LIB.S9S_MB_2U(SCH_1):GND   I178 @S9S_MB_2U_LIB.S9S_MB_2U(SCH_1):PAGE84
   235    GND @S9S_MB_2U_LIB.S9S_MB_2U(SCH_1):GND   I178 @S9S_MB_2U_LIB.S9S_MB_2U(SCH_1):PAGE84
   240    GND @S9S_MB_2U_LIB.S9S_MB_2U(SCH_1):GND   I178 @S9S_MB_2U_LIB.S9S_MB_2U(SCH_1):PAGE84
   132    GND @S9S_MB_2U_LIB.S9S_MB_2U(SCH_1):GND   I178 @S9S_MB_2U_LIB.S9S_MB_2U(SCH_1):PAGE84
   136    GND @S9S_MB_2U_LIB.S9S_MB_2U(SCH_1):GND   I178 @S9S_MB_2U_LIB.S9S_MB_2U(SCH_1):PAGE84
   139    GND @S9S_MB_2U_LIB.S9S_MB_2U(SCH_1):GND   I178 @S9S_MB_2U_LIB.S9S_MB_2U(SCH_1):PAGE84
   141    GND @S9S_MB_2U_LIB.S9S_MB_2U(SCH_1):GND   I178 @S9S_MB_2U_LIB.S9S_MB_2U(SCH_1):PAGE84
    G1    GND @S9S_MB_2U_LIB.S9S_MB_2U(SCH_1):GND   I178 @S9S_MB_2U_LIB.S9S_MB_2U(SCH_1):PAGE84
    G2    GND @S9S_MB_2U_LIB.S9S_MB_2U(SCH_1):GND   I178 @S9S_MB_2U_LIB.S9S_MB_2U(SCH_1):PAGE84
    G3    GND @S9S_MB_2U_LIB.S9S_MB_2U(SCH_1):GND   I178 @S9S_MB_2U_LIB.S9S_MB_2U(SCH_1):PAGE84

  J4 SCONN288_ADR50017P087CC-SCONN2A
     3 P3V3_AUX @S9S_MB_2U_LIB.S9S_MB_2U(SCH_1):P3V3_AUX    I23 @S9S_MB_2U_LIB.S9S_MB_2U(SCH_1):PAGE85
     2 TP_CHB_CPU0_DIMM2_FRU_0 @S9S_MB_2U_LIB.S9S_MB_2U(SCH_1):TP_CHB_CPU0_DIMM2_FRU_0    I23 @S9S_MB_2U_LIB.S9S_MB_2U(SCH_1):PAGE85
   144 TP_CHB_CPU0_DIMM2_FRU_1 @S9S_MB_2U_LIB.S9S_MB_2U(SCH_1):TP_CHB_CPU0_DIMM2_FRU_1    I23 @S9S_MB_2U_LIB.S9S_MB_2U(SCH_1):PAGE85
   149 TP_CHB_CPU0_DIMM2_FRU_2 @S9S_MB_2U_LIB.S9S_MB_2U(SCH_1):TP_CHB_CPU0_DIMM2_FRU_2    I23 @S9S_MB_2U_LIB.S9S_MB_2U(SCH_1):PAGE85
   150 TP_CHB_CPU0_DIMM2_FRU_3 @S9S_MB_2U_LIB.S9S_MB_2U(SCH_1):TP_CHB_CPU0_DIMM2_FRU_3    I23 @S9S_MB_2U_LIB.S9S_MB_2U(SCH_1):PAGE85
   220 TP_CHB_CPU0_DIMM2_FRU_4 @S9S_MB_2U_LIB.S9S_MB_2U(SCH_1):TP_CHB_CPU0_DIMM2_FRU_4    I23 @S9S_MB_2U_LIB.S9S_MB_2U(SCH_1):PAGE85
   231 TP_CHB_CPU0_DIMM2_FRU_5 @S9S_MB_2U_LIB.S9S_MB_2U(SCH_1):TP_CHB_CPU0_DIMM2_FRU_5    I23 @S9S_MB_2U_LIB.S9S_MB_2U(SCH_1):PAGE85
   232 TP_CHB_CPU0_DIMM2_FRU_6 @S9S_MB_2U_LIB.S9S_MB_2U(SCH_1):TP_CHB_CPU0_DIMM2_FRU_6    I23 @S9S_MB_2U_LIB.S9S_MB_2U(SCH_1):PAGE85
   207 RST_M_AB_CPU0_FPGA_N @S9S_MB_2U_LIB.S9S_MB_2U(SCH_1):RST_M_AB_CPU0_FPGA_N    I23 @S9S_MB_2U_LIB.S9S_MB_2U(SCH_1):PAGE85
   147 PWRGD_CHB_CPU0_DIMM2 @S9S_MB_2U_LIB.S9S_MB_2U(SCH_1):PWRGD_CHB_CPU0_DIMM2    I23 @S9S_MB_2U_LIB.S9S_MB_2U(SCH_1):PAGE85
   227 M_B_CPU0_SB_PAR @S9S_MB_2U_LIB.S9S_MB_2U(SCH_1):M_B_CPU0_SB_PAR    I23 @S9S_MB_2U_LIB.S9S_MB_2U(SCH_1):PAGE85
    74 M_B_CPU0_SA_PAR @S9S_MB_2U_LIB.S9S_MB_2U(SCH_1):M_B_CPU0_SA_PAR    I23 @S9S_MB_2U_LIB.S9S_MB_2U(SCH_1):PAGE85
    87 M_B_CPU0_SB_RSP<1> @S9S_MB_2U_LIB.S9S_MB_2U(SCH_1):M_B_CPU0_SB_RSP(1)    I23 @S9S_MB_2U_LIB.S9S_MB_2U(SCH_1):PAGE85
    86 M_B_CPU0_SA_RSP<1> @S9S_MB_2U_LIB.S9S_MB_2U(SCH_1):M_B_CPU0_SA_RSP(1)    I23 @S9S_MB_2U_LIB.S9S_MB_2U(SCH_1):PAGE85
     5 I3C_SPD_DDRABCD_CPU0_LVC1_SDA @S9S_MB_2U_LIB.S9S_MB_2U(SCH_1):I3C_SPD_DDRABCD_CPU0_LVC1_SDA    I23 @S9S_MB_2U_LIB.S9S_MB_2U(SCH_1):PAGE85
     4 I3C_SPD_DDRABCD_CPU0_LVC1_SCL_3 @S9S_MB_2U_LIB.S9S_MB_2U(SCH_1):I3C_SPD_DDRABCD_CPU0_LVC1_SCL_R4    I23 @S9S_MB_2U_LIB.S9S_MB_2U(SCH_1):PAGE85
   148 PD_CHB_CPU0_DIMM2_SAA @S9S_MB_2U_LIB.S9S_MB_2U(SCH_1):PD_CHB_CPU0_DIMM2_SAA    I23 @S9S_MB_2U_LIB.S9S_MB_2U(SCH_1):PAGE85
   100 M_B_CPU0_SB_DQ<0> @S9S_MB_2U_LIB.S9S_MB_2U(SCH_1):M_B_CPU0_SB_DQ(0)    I23 @S9S_MB_2U_LIB.S9S_MB_2U(SCH_1):PAGE85
   102 M_B_CPU0_SB_DQ<1> @S9S_MB_2U_LIB.S9S_MB_2U(SCH_1):M_B_CPU0_SB_DQ(1)    I23 @S9S_MB_2U_LIB.S9S_MB_2U(SCH_1):PAGE85
   245 M_B_CPU0_SB_DQ<2> @S9S_MB_2U_LIB.S9S_MB_2U(SCH_1):M_B_CPU0_SB_DQ(2)    I23 @S9S_MB_2U_LIB.S9S_MB_2U(SCH_1):PAGE85
   247 M_B_CPU0_SB_DQ<3> @S9S_MB_2U_LIB.S9S_MB_2U(SCH_1):M_B_CPU0_SB_DQ(3)    I23 @S9S_MB_2U_LIB.S9S_MB_2U(SCH_1):PAGE85
   107 M_B_CPU0_SB_DQ<4> @S9S_MB_2U_LIB.S9S_MB_2U(SCH_1):M_B_CPU0_SB_DQ(4)    I23 @S9S_MB_2U_LIB.S9S_MB_2U(SCH_1):PAGE85
   109 M_B_CPU0_SB_DQ<5> @S9S_MB_2U_LIB.S9S_MB_2U(SCH_1):M_B_CPU0_SB_DQ(5)    I23 @S9S_MB_2U_LIB.S9S_MB_2U(SCH_1):PAGE85
   252 M_B_CPU0_SB_DQ<6> @S9S_MB_2U_LIB.S9S_MB_2U(SCH_1):M_B_CPU0_SB_DQ(6)    I23 @S9S_MB_2U_LIB.S9S_MB_2U(SCH_1):PAGE85
   254 M_B_CPU0_SB_DQ<7> @S9S_MB_2U_LIB.S9S_MB_2U(SCH_1):M_B_CPU0_SB_DQ(7)    I23 @S9S_MB_2U_LIB.S9S_MB_2U(SCH_1):PAGE85
   111 M_B_CPU0_SB_DQ<8> @S9S_MB_2U_LIB.S9S_MB_2U(SCH_1):M_B_CPU0_SB_DQ(8)    I23 @S9S_MB_2U_LIB.S9S_MB_2U(SCH_1):PAGE85
   113 M_B_CPU0_SB_DQ<9> @S9S_MB_2U_LIB.S9S_MB_2U(SCH_1):M_B_CPU0_SB_DQ(9)    I23 @S9S_MB_2U_LIB.S9S_MB_2U(SCH_1):PAGE85
   256 M_B_CPU0_SB_DQ<10> @S9S_MB_2U_LIB.S9S_MB_2U(SCH_1):M_B_CPU0_SB_DQ(10)    I23 @S9S_MB_2U_LIB.S9S_MB_2U(SCH_1):PAGE85
   258 M_B_CPU0_SB_DQ<11> @S9S_MB_2U_LIB.S9S_MB_2U(SCH_1):M_B_CPU0_SB_DQ(11)    I23 @S9S_MB_2U_LIB.S9S_MB_2U(SCH_1):PAGE85
   118 M_B_CPU0_SB_DQ<12> @S9S_MB_2U_LIB.S9S_MB_2U(SCH_1):M_B_CPU0_SB_DQ(12)    I23 @S9S_MB_2U_LIB.S9S_MB_2U(SCH_1):PAGE85
   120 M_B_CPU0_SB_DQ<13> @S9S_MB_2U_LIB.S9S_MB_2U(SCH_1):M_B_CPU0_SB_DQ(13)    I23 @S9S_MB_2U_LIB.S9S_MB_2U(SCH_1):PAGE85
   263 M_B_CPU0_SB_DQ<14> @S9S_MB_2U_LIB.S9S_MB_2U(SCH_1):M_B_CPU0_SB_DQ(14)    I23 @S9S_MB_2U_LIB.S9S_MB_2U(SCH_1):PAGE85
   265 M_B_CPU0_SB_DQ<15> @S9S_MB_2U_LIB.S9S_MB_2U(SCH_1):M_B_CPU0_SB_DQ(15)    I23 @S9S_MB_2U_LIB.S9S_MB_2U(SCH_1):PAGE85
   122 M_B_CPU0_SB_DQ<16> @S9S_MB_2U_LIB.S9S_MB_2U(SCH_1):M_B_CPU0_SB_DQ(16)    I23 @S9S_MB_2U_LIB.S9S_MB_2U(SCH_1):PAGE85
   124 M_B_CPU0_SB_DQ<17> @S9S_MB_2U_LIB.S9S_MB_2U(SCH_1):M_B_CPU0_SB_DQ(17)    I23 @S9S_MB_2U_LIB.S9S_MB_2U(SCH_1):PAGE85
   267 M_B_CPU0_SB_DQ<18> @S9S_MB_2U_LIB.S9S_MB_2U(SCH_1):M_B_CPU0_SB_DQ(18)    I23 @S9S_MB_2U_LIB.S9S_MB_2U(SCH_1):PAGE85
   269 M_B_CPU0_SB_DQ<19> @S9S_MB_2U_LIB.S9S_MB_2U(SCH_1):M_B_CPU0_SB_DQ(19)    I23 @S9S_MB_2U_LIB.S9S_MB_2U(SCH_1):PAGE85
   129 M_B_CPU0_SB_DQ<20> @S9S_MB_2U_LIB.S9S_MB_2U(SCH_1):M_B_CPU0_SB_DQ(20)    I23 @S9S_MB_2U_LIB.S9S_MB_2U(SCH_1):PAGE85
   131 M_B_CPU0_SB_DQ<21> @S9S_MB_2U_LIB.S9S_MB_2U(SCH_1):M_B_CPU0_SB_DQ(21)    I23 @S9S_MB_2U_LIB.S9S_MB_2U(SCH_1):PAGE85
   274 M_B_CPU0_SB_DQ<22> @S9S_MB_2U_LIB.S9S_MB_2U(SCH_1):M_B_CPU0_SB_DQ(22)    I23 @S9S_MB_2U_LIB.S9S_MB_2U(SCH_1):PAGE85
   276 M_B_CPU0_SB_DQ<23> @S9S_MB_2U_LIB.S9S_MB_2U(SCH_1):M_B_CPU0_SB_DQ(23)    I23 @S9S_MB_2U_LIB.S9S_MB_2U(SCH_1):PAGE85
   133 M_B_CPU0_SB_DQ<24> @S9S_MB_2U_LIB.S9S_MB_2U(SCH_1):M_B_CPU0_SB_DQ(24)    I23 @S9S_MB_2U_LIB.S9S_MB_2U(SCH_1):PAGE85
   135 M_B_CPU0_SB_DQ<25> @S9S_MB_2U_LIB.S9S_MB_2U(SCH_1):M_B_CPU0_SB_DQ(25)    I23 @S9S_MB_2U_LIB.S9S_MB_2U(SCH_1):PAGE85
   278 M_B_CPU0_SB_DQ<26> @S9S_MB_2U_LIB.S9S_MB_2U(SCH_1):M_B_CPU0_SB_DQ(26)    I23 @S9S_MB_2U_LIB.S9S_MB_2U(SCH_1):PAGE85
   280 M_B_CPU0_SB_DQ<27> @S9S_MB_2U_LIB.S9S_MB_2U(SCH_1):M_B_CPU0_SB_DQ(27)    I23 @S9S_MB_2U_LIB.S9S_MB_2U(SCH_1):PAGE85
   140 M_B_CPU0_SB_DQ<28> @S9S_MB_2U_LIB.S9S_MB_2U(SCH_1):M_B_CPU0_SB_DQ(28)    I23 @S9S_MB_2U_LIB.S9S_MB_2U(SCH_1):PAGE85
   142 M_B_CPU0_SB_DQ<29> @S9S_MB_2U_LIB.S9S_MB_2U(SCH_1):M_B_CPU0_SB_DQ(29)    I23 @S9S_MB_2U_LIB.S9S_MB_2U(SCH_1):PAGE85
   285 M_B_CPU0_SB_DQ<30> @S9S_MB_2U_LIB.S9S_MB_2U(SCH_1):M_B_CPU0_SB_DQ(30)    I23 @S9S_MB_2U_LIB.S9S_MB_2U(SCH_1):PAGE85
   287 M_B_CPU0_SB_DQ<31> @S9S_MB_2U_LIB.S9S_MB_2U(SCH_1):M_B_CPU0_SB_DQ(31)    I23 @S9S_MB_2U_LIB.S9S_MB_2U(SCH_1):PAGE85
     7 M_B_CPU0_SA_DQ<0> @S9S_MB_2U_LIB.S9S_MB_2U(SCH_1):M_B_CPU0_SA_DQ(0)    I23 @S9S_MB_2U_LIB.S9S_MB_2U(SCH_1):PAGE85
     9 M_B_CPU0_SA_DQ<1> @S9S_MB_2U_LIB.S9S_MB_2U(SCH_1):M_B_CPU0_SA_DQ(1)    I23 @S9S_MB_2U_LIB.S9S_MB_2U(SCH_1):PAGE85
   152 M_B_CPU0_SA_DQ<2> @S9S_MB_2U_LIB.S9S_MB_2U(SCH_1):M_B_CPU0_SA_DQ(2)    I23 @S9S_MB_2U_LIB.S9S_MB_2U(SCH_1):PAGE85
   154 M_B_CPU0_SA_DQ<3> @S9S_MB_2U_LIB.S9S_MB_2U(SCH_1):M_B_CPU0_SA_DQ(3)    I23 @S9S_MB_2U_LIB.S9S_MB_2U(SCH_1):PAGE85
    14 M_B_CPU0_SA_DQ<4> @S9S_MB_2U_LIB.S9S_MB_2U(SCH_1):M_B_CPU0_SA_DQ(4)    I23 @S9S_MB_2U_LIB.S9S_MB_2U(SCH_1):PAGE85
    16 M_B_CPU0_SA_DQ<5> @S9S_MB_2U_LIB.S9S_MB_2U(SCH_1):M_B_CPU0_SA_DQ(5)    I23 @S9S_MB_2U_LIB.S9S_MB_2U(SCH_1):PAGE85
   159 M_B_CPU0_SA_DQ<6> @S9S_MB_2U_LIB.S9S_MB_2U(SCH_1):M_B_CPU0_SA_DQ(6)    I23 @S9S_MB_2U_LIB.S9S_MB_2U(SCH_1):PAGE85
   161 M_B_CPU0_SA_DQ<7> @S9S_MB_2U_LIB.S9S_MB_2U(SCH_1):M_B_CPU0_SA_DQ(7)    I23 @S9S_MB_2U_LIB.S9S_MB_2U(SCH_1):PAGE85
    18 M_B_CPU0_SA_DQ<8> @S9S_MB_2U_LIB.S9S_MB_2U(SCH_1):M_B_CPU0_SA_DQ(8)    I23 @S9S_MB_2U_LIB.S9S_MB_2U(SCH_1):PAGE85
    20 M_B_CPU0_SA_DQ<9> @S9S_MB_2U_LIB.S9S_MB_2U(SCH_1):M_B_CPU0_SA_DQ(9)    I23 @S9S_MB_2U_LIB.S9S_MB_2U(SCH_1):PAGE85
   163 M_B_CPU0_SA_DQ<10> @S9S_MB_2U_LIB.S9S_MB_2U(SCH_1):M_B_CPU0_SA_DQ(10)    I23 @S9S_MB_2U_LIB.S9S_MB_2U(SCH_1):PAGE85
   165 M_B_CPU0_SA_DQ<11> @S9S_MB_2U_LIB.S9S_MB_2U(SCH_1):M_B_CPU0_SA_DQ(11)    I23 @S9S_MB_2U_LIB.S9S_MB_2U(SCH_1):PAGE85
    25 M_B_CPU0_SA_DQ<12> @S9S_MB_2U_LIB.S9S_MB_2U(SCH_1):M_B_CPU0_SA_DQ(12)    I23 @S9S_MB_2U_LIB.S9S_MB_2U(SCH_1):PAGE85
    27 M_B_CPU0_SA_DQ<13> @S9S_MB_2U_LIB.S9S_MB_2U(SCH_1):M_B_CPU0_SA_DQ(13)    I23 @S9S_MB_2U_LIB.S9S_MB_2U(SCH_1):PAGE85
   170 M_B_CPU0_SA_DQ<14> @S9S_MB_2U_LIB.S9S_MB_2U(SCH_1):M_B_CPU0_SA_DQ(14)    I23 @S9S_MB_2U_LIB.S9S_MB_2U(SCH_1):PAGE85
   172 M_B_CPU0_SA_DQ<15> @S9S_MB_2U_LIB.S9S_MB_2U(SCH_1):M_B_CPU0_SA_DQ(15)    I23 @S9S_MB_2U_LIB.S9S_MB_2U(SCH_1):PAGE85
    29 M_B_CPU0_SA_DQ<16> @S9S_MB_2U_LIB.S9S_MB_2U(SCH_1):M_B_CPU0_SA_DQ(16)    I23 @S9S_MB_2U_LIB.S9S_MB_2U(SCH_1):PAGE85
    31 M_B_CPU0_SA_DQ<17> @S9S_MB_2U_LIB.S9S_MB_2U(SCH_1):M_B_CPU0_SA_DQ(17)    I23 @S9S_MB_2U_LIB.S9S_MB_2U(SCH_1):PAGE85
   174 M_B_CPU0_SA_DQ<18> @S9S_MB_2U_LIB.S9S_MB_2U(SCH_1):M_B_CPU0_SA_DQ(18)    I23 @S9S_MB_2U_LIB.S9S_MB_2U(SCH_1):PAGE85
   176 M_B_CPU0_SA_DQ<19> @S9S_MB_2U_LIB.S9S_MB_2U(SCH_1):M_B_CPU0_SA_DQ(19)    I23 @S9S_MB_2U_LIB.S9S_MB_2U(SCH_1):PAGE85
    36 M_B_CPU0_SA_DQ<20> @S9S_MB_2U_LIB.S9S_MB_2U(SCH_1):M_B_CPU0_SA_DQ(20)    I23 @S9S_MB_2U_LIB.S9S_MB_2U(SCH_1):PAGE85
    38 M_B_CPU0_SA_DQ<21> @S9S_MB_2U_LIB.S9S_MB_2U(SCH_1):M_B_CPU0_SA_DQ(21)    I23 @S9S_MB_2U_LIB.S9S_MB_2U(SCH_1):PAGE85
   181 M_B_CPU0_SA_DQ<22> @S9S_MB_2U_LIB.S9S_MB_2U(SCH_1):M_B_CPU0_SA_DQ(22)    I23 @S9S_MB_2U_LIB.S9S_MB_2U(SCH_1):PAGE85
   183 M_B_CPU0_SA_DQ<23> @S9S_MB_2U_LIB.S9S_MB_2U(SCH_1):M_B_CPU0_SA_DQ(23)    I23 @S9S_MB_2U_LIB.S9S_MB_2U(SCH_1):PAGE85
    40 M_B_CPU0_SA_DQ<24> @S9S_MB_2U_LIB.S9S_MB_2U(SCH_1):M_B_CPU0_SA_DQ(24)    I23 @S9S_MB_2U_LIB.S9S_MB_2U(SCH_1):PAGE85
    42 M_B_CPU0_SA_DQ<25> @S9S_MB_2U_LIB.S9S_MB_2U(SCH_1):M_B_CPU0_SA_DQ(25)    I23 @S9S_MB_2U_LIB.S9S_MB_2U(SCH_1):PAGE85
   185 M_B_CPU0_SA_DQ<26> @S9S_MB_2U_LIB.S9S_MB_2U(SCH_1):M_B_CPU0_SA_DQ(26)    I23 @S9S_MB_2U_LIB.S9S_MB_2U(SCH_1):PAGE85
   187 M_B_CPU0_SA_DQ<27> @S9S_MB_2U_LIB.S9S_MB_2U(SCH_1):M_B_CPU0_SA_DQ(27)    I23 @S9S_MB_2U_LIB.S9S_MB_2U(SCH_1):PAGE85
    47 M_B_CPU0_SA_DQ<28> @S9S_MB_2U_LIB.S9S_MB_2U(SCH_1):M_B_CPU0_SA_DQ(28)    I23 @S9S_MB_2U_LIB.S9S_MB_2U(SCH_1):PAGE85
    49 M_B_CPU0_SA_DQ<29> @S9S_MB_2U_LIB.S9S_MB_2U(SCH_1):M_B_CPU0_SA_DQ(29)    I23 @S9S_MB_2U_LIB.S9S_MB_2U(SCH_1):PAGE85
   192 M_B_CPU0_SA_DQ<30> @S9S_MB_2U_LIB.S9S_MB_2U(SCH_1):M_B_CPU0_SA_DQ(30)    I23 @S9S_MB_2U_LIB.S9S_MB_2U(SCH_1):PAGE85
   229 M_B_CPU0_SB_CS_N<3> @S9S_MB_2U_LIB.S9S_MB_2U(SCH_1):M_B_CPU0_SB_CS_N(3)    I23 @S9S_MB_2U_LIB.S9S_MB_2U(SCH_1):PAGE85
   209 M_B_CPU0_SA_CS_N<3> @S9S_MB_2U_LIB.S9S_MB_2U(SCH_1):M_B_CPU0_SA_CS_N(3)    I23 @S9S_MB_2U_LIB.S9S_MB_2U(SCH_1):PAGE85
    84 M_B_CPU0_SB_CS_N<2> @S9S_MB_2U_LIB.S9S_MB_2U(SCH_1):M_B_CPU0_SB_CS_N(2)    I23 @S9S_MB_2U_LIB.S9S_MB_2U(SCH_1):PAGE85
    64 M_B_CPU0_SA_CS_N<2> @S9S_MB_2U_LIB.S9S_MB_2U(SCH_1):M_B_CPU0_SA_CS_N(2)    I23 @S9S_MB_2U_LIB.S9S_MB_2U(SCH_1):PAGE85
   217 M_B_CPU0_CLK_DP<1> @S9S_MB_2U_LIB.S9S_MB_2U(SCH_1):M_B_CPU0_CLK_DP(1)    I23 @S9S_MB_2U_LIB.S9S_MB_2U(SCH_1):PAGE85
   218 M_B_CPU0_CLK_DN<1> @S9S_MB_2U_LIB.S9S_MB_2U(SCH_1):M_B_CPU0_CLK_DN(1)    I23 @S9S_MB_2U_LIB.S9S_MB_2U(SCH_1):PAGE85
    96 M_B_CPU0_SB_CB<0> @S9S_MB_2U_LIB.S9S_MB_2U(SCH_1):M_B_CPU0_SB_CB(0)    I23 @S9S_MB_2U_LIB.S9S_MB_2U(SCH_1):PAGE85
    98 M_B_CPU0_SB_CB<1> @S9S_MB_2U_LIB.S9S_MB_2U(SCH_1):M_B_CPU0_SB_CB(1)    I23 @S9S_MB_2U_LIB.S9S_MB_2U(SCH_1):PAGE85
   241 M_B_CPU0_SB_CB<2> @S9S_MB_2U_LIB.S9S_MB_2U(SCH_1):M_B_CPU0_SB_CB(2)    I23 @S9S_MB_2U_LIB.S9S_MB_2U(SCH_1):PAGE85
   243 M_B_CPU0_SB_CB<3> @S9S_MB_2U_LIB.S9S_MB_2U(SCH_1):M_B_CPU0_SB_CB(3)    I23 @S9S_MB_2U_LIB.S9S_MB_2U(SCH_1):PAGE85
    89 M_B_CPU0_SB_CB<4> @S9S_MB_2U_LIB.S9S_MB_2U(SCH_1):M_B_CPU0_SB_CB(4)    I23 @S9S_MB_2U_LIB.S9S_MB_2U(SCH_1):PAGE85
    91 M_B_CPU0_SB_CB<5> @S9S_MB_2U_LIB.S9S_MB_2U(SCH_1):M_B_CPU0_SB_CB(5)    I23 @S9S_MB_2U_LIB.S9S_MB_2U(SCH_1):PAGE85
   234 M_B_CPU0_SB_CB<6> @S9S_MB_2U_LIB.S9S_MB_2U(SCH_1):M_B_CPU0_SB_CB(6)    I23 @S9S_MB_2U_LIB.S9S_MB_2U(SCH_1):PAGE85
    51 M_B_CPU0_SA_CB<0> @S9S_MB_2U_LIB.S9S_MB_2U(SCH_1):M_B_CPU0_SA_CB(0)    I23 @S9S_MB_2U_LIB.S9S_MB_2U(SCH_1):PAGE85
   196 M_B_CPU0_SA_CB<2> @S9S_MB_2U_LIB.S9S_MB_2U(SCH_1):M_B_CPU0_SA_CB(2)    I23 @S9S_MB_2U_LIB.S9S_MB_2U(SCH_1):PAGE85
   198 M_B_CPU0_SA_CB<3> @S9S_MB_2U_LIB.S9S_MB_2U(SCH_1):M_B_CPU0_SA_CB(3)    I23 @S9S_MB_2U_LIB.S9S_MB_2U(SCH_1):PAGE85
    60 M_B_CPU0_SA_CB<5> @S9S_MB_2U_LIB.S9S_MB_2U(SCH_1):M_B_CPU0_SA_CB(5)    I23 @S9S_MB_2U_LIB.S9S_MB_2U(SCH_1):PAGE85
   203 M_B_CPU0_SA_CB<6> @S9S_MB_2U_LIB.S9S_MB_2U(SCH_1):M_B_CPU0_SA_CB(6)    I23 @S9S_MB_2U_LIB.S9S_MB_2U(SCH_1):PAGE85
    82 M_B_CPU0_SB_CA<6> @S9S_MB_2U_LIB.S9S_MB_2U(SCH_1):M_B_CPU0_SB_CA(6)    I23 @S9S_MB_2U_LIB.S9S_MB_2U(SCH_1):PAGE85
    72 M_B_CPU0_SA_CA<6> @S9S_MB_2U_LIB.S9S_MB_2U(SCH_1):M_B_CPU0_SA_CA(6)    I23 @S9S_MB_2U_LIB.S9S_MB_2U(SCH_1):PAGE85
   225 M_B_CPU0_SB_CA<5> @S9S_MB_2U_LIB.S9S_MB_2U(SCH_1):M_B_CPU0_SB_CA(5)    I23 @S9S_MB_2U_LIB.S9S_MB_2U(SCH_1):PAGE85
   215 M_B_CPU0_SA_CA<5> @S9S_MB_2U_LIB.S9S_MB_2U(SCH_1):M_B_CPU0_SA_CA(5)    I23 @S9S_MB_2U_LIB.S9S_MB_2U(SCH_1):PAGE85
    80 M_B_CPU0_SB_CA<4> @S9S_MB_2U_LIB.S9S_MB_2U(SCH_1):M_B_CPU0_SB_CA(4)    I23 @S9S_MB_2U_LIB.S9S_MB_2U(SCH_1):PAGE85
    70 M_B_CPU0_SA_CA<4> @S9S_MB_2U_LIB.S9S_MB_2U(SCH_1):M_B_CPU0_SA_CA(4)    I23 @S9S_MB_2U_LIB.S9S_MB_2U(SCH_1):PAGE85
   223 M_B_CPU0_SB_CA<3> @S9S_MB_2U_LIB.S9S_MB_2U(SCH_1):M_B_CPU0_SB_CA(3)    I23 @S9S_MB_2U_LIB.S9S_MB_2U(SCH_1):PAGE85
   213 M_B_CPU0_SA_CA<3> @S9S_MB_2U_LIB.S9S_MB_2U(SCH_1):M_B_CPU0_SA_CA(3)    I23 @S9S_MB_2U_LIB.S9S_MB_2U(SCH_1):PAGE85
    78 M_B_CPU0_SB_CA<2> @S9S_MB_2U_LIB.S9S_MB_2U(SCH_1):M_B_CPU0_SB_CA(2)    I23 @S9S_MB_2U_LIB.S9S_MB_2U(SCH_1):PAGE85
    68 M_B_CPU0_SA_CA<2> @S9S_MB_2U_LIB.S9S_MB_2U(SCH_1):M_B_CPU0_SA_CA(2)    I23 @S9S_MB_2U_LIB.S9S_MB_2U(SCH_1):PAGE85
   221 M_B_CPU0_SB_CA<1> @S9S_MB_2U_LIB.S9S_MB_2U(SCH_1):M_B_CPU0_SB_CA(1)    I23 @S9S_MB_2U_LIB.S9S_MB_2U(SCH_1):PAGE85
   211 M_B_CPU0_SA_CA<1> @S9S_MB_2U_LIB.S9S_MB_2U(SCH_1):M_B_CPU0_SA_CA(1)    I23 @S9S_MB_2U_LIB.S9S_MB_2U(SCH_1):PAGE85
    76 M_B_CPU0_SB_CA<0> @S9S_MB_2U_LIB.S9S_MB_2U(SCH_1):M_B_CPU0_SB_CA(0)    I23 @S9S_MB_2U_LIB.S9S_MB_2U(SCH_1):PAGE85
    66 M_B_CPU0_SA_CA<0> @S9S_MB_2U_LIB.S9S_MB_2U(SCH_1):M_B_CPU0_SA_CA(0)    I23 @S9S_MB_2U_LIB.S9S_MB_2U(SCH_1):PAGE85
    62 M_B_CPU0_ALERT_N @S9S_MB_2U_LIB.S9S_MB_2U(SCH_1):M_B_CPU0_ALERT_N    I23 @S9S_MB_2U_LIB.S9S_MB_2U(SCH_1):PAGE85
   236 M_B_CPU0_SB_CB<7> @S9S_MB_2U_LIB.S9S_MB_2U(SCH_1):M_B_CPU0_SB_CB(7)    I23 @S9S_MB_2U_LIB.S9S_MB_2U(SCH_1):PAGE85
    53 M_B_CPU0_SA_CB<1> @S9S_MB_2U_LIB.S9S_MB_2U(SCH_1):M_B_CPU0_SA_CB(1)    I23 @S9S_MB_2U_LIB.S9S_MB_2U(SCH_1):PAGE85
    58 M_B_CPU0_SA_CB<4> @S9S_MB_2U_LIB.S9S_MB_2U(SCH_1):M_B_CPU0_SA_CB(4)    I23 @S9S_MB_2U_LIB.S9S_MB_2U(SCH_1):PAGE85
   205 M_B_CPU0_SA_CB<7> @S9S_MB_2U_LIB.S9S_MB_2U(SCH_1):M_B_CPU0_SA_CB(7)    I23 @S9S_MB_2U_LIB.S9S_MB_2U(SCH_1):PAGE85
   194 M_B_CPU0_SA_DQ<31> @S9S_MB_2U_LIB.S9S_MB_2U(SCH_1):M_B_CPU0_SA_DQ(31)    I23 @S9S_MB_2U_LIB.S9S_MB_2U(SCH_1):PAGE85
    93 M_B_CPU0_SB_DQS_DP<9> @S9S_MB_2U_LIB.S9S_MB_2U(SCH_1):M_B_CPU0_SB_DQS_DP(9)   I178 @S9S_MB_2U_LIB.S9S_MB_2U(SCH_1):PAGE85
    94 M_B_CPU0_SB_DQS_DN<9> @S9S_MB_2U_LIB.S9S_MB_2U(SCH_1):M_B_CPU0_SB_DQS_DN(9)   I178 @S9S_MB_2U_LIB.S9S_MB_2U(SCH_1):PAGE85
   201 M_B_CPU0_SA_DQS_DP<9> @S9S_MB_2U_LIB.S9S_MB_2U(SCH_1):M_B_CPU0_SA_DQS_DP(9)   I178 @S9S_MB_2U_LIB.S9S_MB_2U(SCH_1):PAGE85
   200 M_B_CPU0_SA_DQS_DN<9> @S9S_MB_2U_LIB.S9S_MB_2U(SCH_1):M_B_CPU0_SA_DQS_DN(9)   I178 @S9S_MB_2U_LIB.S9S_MB_2U(SCH_1):PAGE85
   190 M_B_CPU0_SA_DQS_DP<8> @S9S_MB_2U_LIB.S9S_MB_2U(SCH_1):M_B_CPU0_SA_DQS_DP(8)   I178 @S9S_MB_2U_LIB.S9S_MB_2U(SCH_1):PAGE85
   189 M_B_CPU0_SA_DQS_DN<8> @S9S_MB_2U_LIB.S9S_MB_2U(SCH_1):M_B_CPU0_SA_DQS_DN(8)   I178 @S9S_MB_2U_LIB.S9S_MB_2U(SCH_1):PAGE85
   271 M_B_CPU0_SB_DQS_DN<7> @S9S_MB_2U_LIB.S9S_MB_2U(SCH_1):M_B_CPU0_SB_DQS_DN(7)   I178 @S9S_MB_2U_LIB.S9S_MB_2U(SCH_1):PAGE85
   179 M_B_CPU0_SA_DQS_DP<7> @S9S_MB_2U_LIB.S9S_MB_2U(SCH_1):M_B_CPU0_SA_DQS_DP(7)   I178 @S9S_MB_2U_LIB.S9S_MB_2U(SCH_1):PAGE85
   261 M_B_CPU0_SB_DQS_DP<6> @S9S_MB_2U_LIB.S9S_MB_2U(SCH_1):M_B_CPU0_SB_DQS_DP(6)   I178 @S9S_MB_2U_LIB.S9S_MB_2U(SCH_1):PAGE85
   260 M_B_CPU0_SB_DQS_DN<6> @S9S_MB_2U_LIB.S9S_MB_2U(SCH_1):M_B_CPU0_SB_DQS_DN(6)   I178 @S9S_MB_2U_LIB.S9S_MB_2U(SCH_1):PAGE85
   167 M_B_CPU0_SA_DQS_DN<6> @S9S_MB_2U_LIB.S9S_MB_2U(SCH_1):M_B_CPU0_SA_DQS_DN(6)   I178 @S9S_MB_2U_LIB.S9S_MB_2U(SCH_1):PAGE85
   250 M_B_CPU0_SB_DQS_DP<5> @S9S_MB_2U_LIB.S9S_MB_2U(SCH_1):M_B_CPU0_SB_DQS_DP(5)   I178 @S9S_MB_2U_LIB.S9S_MB_2U(SCH_1):PAGE85
   249 M_B_CPU0_SB_DQS_DN<5> @S9S_MB_2U_LIB.S9S_MB_2U(SCH_1):M_B_CPU0_SB_DQS_DN(5)   I178 @S9S_MB_2U_LIB.S9S_MB_2U(SCH_1):PAGE85
   157 M_B_CPU0_SA_DQS_DP<5> @S9S_MB_2U_LIB.S9S_MB_2U(SCH_1):M_B_CPU0_SA_DQS_DP(5)   I178 @S9S_MB_2U_LIB.S9S_MB_2U(SCH_1):PAGE85
   156 M_B_CPU0_SA_DQS_DN<5> @S9S_MB_2U_LIB.S9S_MB_2U(SCH_1):M_B_CPU0_SA_DQS_DN(5)   I178 @S9S_MB_2U_LIB.S9S_MB_2U(SCH_1):PAGE85
   239 M_B_CPU0_SB_DQS_DP<4> @S9S_MB_2U_LIB.S9S_MB_2U(SCH_1):M_B_CPU0_SB_DQS_DP(4)   I178 @S9S_MB_2U_LIB.S9S_MB_2U(SCH_1):PAGE85
   238 M_B_CPU0_SB_DQS_DN<4> @S9S_MB_2U_LIB.S9S_MB_2U(SCH_1):M_B_CPU0_SB_DQS_DN(4)   I178 @S9S_MB_2U_LIB.S9S_MB_2U(SCH_1):PAGE85
    55 M_B_CPU0_SA_DQS_DP<4> @S9S_MB_2U_LIB.S9S_MB_2U(SCH_1):M_B_CPU0_SA_DQS_DP(4)   I178 @S9S_MB_2U_LIB.S9S_MB_2U(SCH_1):PAGE85
    56 M_B_CPU0_SA_DQS_DN<4> @S9S_MB_2U_LIB.S9S_MB_2U(SCH_1):M_B_CPU0_SA_DQS_DN(4)   I178 @S9S_MB_2U_LIB.S9S_MB_2U(SCH_1):PAGE85
   137 M_B_CPU0_SB_DQS_DP<3> @S9S_MB_2U_LIB.S9S_MB_2U(SCH_1):M_B_CPU0_SB_DQS_DP(3)   I178 @S9S_MB_2U_LIB.S9S_MB_2U(SCH_1):PAGE85
   138 M_B_CPU0_SB_DQS_DN<3> @S9S_MB_2U_LIB.S9S_MB_2U(SCH_1):M_B_CPU0_SB_DQS_DN(3)   I178 @S9S_MB_2U_LIB.S9S_MB_2U(SCH_1):PAGE85
    44 M_B_CPU0_SA_DQS_DP<3> @S9S_MB_2U_LIB.S9S_MB_2U(SCH_1):M_B_CPU0_SA_DQS_DP(3)   I178 @S9S_MB_2U_LIB.S9S_MB_2U(SCH_1):PAGE85
    45 M_B_CPU0_SA_DQS_DN<3> @S9S_MB_2U_LIB.S9S_MB_2U(SCH_1):M_B_CPU0_SA_DQS_DN(3)   I178 @S9S_MB_2U_LIB.S9S_MB_2U(SCH_1):PAGE85
   126 M_B_CPU0_SB_DQS_DP<2> @S9S_MB_2U_LIB.S9S_MB_2U(SCH_1):M_B_CPU0_SB_DQS_DP(2)   I178 @S9S_MB_2U_LIB.S9S_MB_2U(SCH_1):PAGE85
   127 M_B_CPU0_SB_DQS_DN<2> @S9S_MB_2U_LIB.S9S_MB_2U(SCH_1):M_B_CPU0_SB_DQS_DN(2)   I178 @S9S_MB_2U_LIB.S9S_MB_2U(SCH_1):PAGE85
    33 M_B_CPU0_SA_DQS_DP<2> @S9S_MB_2U_LIB.S9S_MB_2U(SCH_1):M_B_CPU0_SA_DQS_DP(2)   I178 @S9S_MB_2U_LIB.S9S_MB_2U(SCH_1):PAGE85
    34 M_B_CPU0_SA_DQS_DN<2> @S9S_MB_2U_LIB.S9S_MB_2U(SCH_1):M_B_CPU0_SA_DQS_DN(2)   I178 @S9S_MB_2U_LIB.S9S_MB_2U(SCH_1):PAGE85
   115 M_B_CPU0_SB_DQS_DP<1> @S9S_MB_2U_LIB.S9S_MB_2U(SCH_1):M_B_CPU0_SB_DQS_DP(1)   I178 @S9S_MB_2U_LIB.S9S_MB_2U(SCH_1):PAGE85
   116 M_B_CPU0_SB_DQS_DN<1> @S9S_MB_2U_LIB.S9S_MB_2U(SCH_1):M_B_CPU0_SB_DQS_DN(1)   I178 @S9S_MB_2U_LIB.S9S_MB_2U(SCH_1):PAGE85
    22 M_B_CPU0_SA_DQS_DP<1> @S9S_MB_2U_LIB.S9S_MB_2U(SCH_1):M_B_CPU0_SA_DQS_DP(1)   I178 @S9S_MB_2U_LIB.S9S_MB_2U(SCH_1):PAGE85
    23 M_B_CPU0_SA_DQS_DN<1> @S9S_MB_2U_LIB.S9S_MB_2U(SCH_1):M_B_CPU0_SA_DQS_DN(1)   I178 @S9S_MB_2U_LIB.S9S_MB_2U(SCH_1):PAGE85
   104 M_B_CPU0_SB_DQS_DP<0> @S9S_MB_2U_LIB.S9S_MB_2U(SCH_1):M_B_CPU0_SB_DQS_DP(0)   I178 @S9S_MB_2U_LIB.S9S_MB_2U(SCH_1):PAGE85
   105 M_B_CPU0_SB_DQS_DN<0> @S9S_MB_2U_LIB.S9S_MB_2U(SCH_1):M_B_CPU0_SB_DQS_DN(0)   I178 @S9S_MB_2U_LIB.S9S_MB_2U(SCH_1):PAGE85
    11 M_B_CPU0_SA_DQS_DP<0> @S9S_MB_2U_LIB.S9S_MB_2U(SCH_1):M_B_CPU0_SA_DQS_DP(0)   I178 @S9S_MB_2U_LIB.S9S_MB_2U(SCH_1):PAGE85
    12 M_B_CPU0_SA_DQS_DN<0> @S9S_MB_2U_LIB.S9S_MB_2U(SCH_1):M_B_CPU0_SA_DQS_DN(0)   I178 @S9S_MB_2U_LIB.S9S_MB_2U(SCH_1):PAGE85
   272 M_B_CPU0_SB_DQS_DP<7> @S9S_MB_2U_LIB.S9S_MB_2U(SCH_1):M_B_CPU0_SB_DQS_DP(7)   I178 @S9S_MB_2U_LIB.S9S_MB_2U(SCH_1):PAGE85
   282 M_B_CPU0_SB_DQS_DN<8> @S9S_MB_2U_LIB.S9S_MB_2U(SCH_1):M_B_CPU0_SB_DQS_DN(8)   I178 @S9S_MB_2U_LIB.S9S_MB_2U(SCH_1):PAGE85
   283 M_B_CPU0_SB_DQS_DP<8> @S9S_MB_2U_LIB.S9S_MB_2U(SCH_1):M_B_CPU0_SB_DQS_DP(8)   I178 @S9S_MB_2U_LIB.S9S_MB_2U(SCH_1):PAGE85
   168 M_B_CPU0_SA_DQS_DP<6> @S9S_MB_2U_LIB.S9S_MB_2U(SCH_1):M_B_CPU0_SA_DQS_DP(6)   I178 @S9S_MB_2U_LIB.S9S_MB_2U(SCH_1):PAGE85
   178 M_B_CPU0_SA_DQS_DN<7> @S9S_MB_2U_LIB.S9S_MB_2U(SCH_1):M_B_CPU0_SA_DQS_DN(7)   I178 @S9S_MB_2U_LIB.S9S_MB_2U(SCH_1):PAGE85
     6    GND @S9S_MB_2U_LIB.S9S_MB_2U(SCH_1):GND   I174 @S9S_MB_2U_LIB.S9S_MB_2U(SCH_1):PAGE85
     8    GND @S9S_MB_2U_LIB.S9S_MB_2U(SCH_1):GND   I174 @S9S_MB_2U_LIB.S9S_MB_2U(SCH_1):PAGE85
    10    GND @S9S_MB_2U_LIB.S9S_MB_2U(SCH_1):GND   I174 @S9S_MB_2U_LIB.S9S_MB_2U(SCH_1):PAGE85
    13    GND @S9S_MB_2U_LIB.S9S_MB_2U(SCH_1):GND   I174 @S9S_MB_2U_LIB.S9S_MB_2U(SCH_1):PAGE85
    15    GND @S9S_MB_2U_LIB.S9S_MB_2U(SCH_1):GND   I174 @S9S_MB_2U_LIB.S9S_MB_2U(SCH_1):PAGE85
    17    GND @S9S_MB_2U_LIB.S9S_MB_2U(SCH_1):GND   I174 @S9S_MB_2U_LIB.S9S_MB_2U(SCH_1):PAGE85
    19    GND @S9S_MB_2U_LIB.S9S_MB_2U(SCH_1):GND   I174 @S9S_MB_2U_LIB.S9S_MB_2U(SCH_1):PAGE85
    21    GND @S9S_MB_2U_LIB.S9S_MB_2U(SCH_1):GND   I174 @S9S_MB_2U_LIB.S9S_MB_2U(SCH_1):PAGE85
    24    GND @S9S_MB_2U_LIB.S9S_MB_2U(SCH_1):GND   I174 @S9S_MB_2U_LIB.S9S_MB_2U(SCH_1):PAGE85
    26    GND @S9S_MB_2U_LIB.S9S_MB_2U(SCH_1):GND   I174 @S9S_MB_2U_LIB.S9S_MB_2U(SCH_1):PAGE85
    28    GND @S9S_MB_2U_LIB.S9S_MB_2U(SCH_1):GND   I174 @S9S_MB_2U_LIB.S9S_MB_2U(SCH_1):PAGE85
    30    GND @S9S_MB_2U_LIB.S9S_MB_2U(SCH_1):GND   I174 @S9S_MB_2U_LIB.S9S_MB_2U(SCH_1):PAGE85
    32    GND @S9S_MB_2U_LIB.S9S_MB_2U(SCH_1):GND   I174 @S9S_MB_2U_LIB.S9S_MB_2U(SCH_1):PAGE85
    35    GND @S9S_MB_2U_LIB.S9S_MB_2U(SCH_1):GND   I174 @S9S_MB_2U_LIB.S9S_MB_2U(SCH_1):PAGE85
    37    GND @S9S_MB_2U_LIB.S9S_MB_2U(SCH_1):GND   I174 @S9S_MB_2U_LIB.S9S_MB_2U(SCH_1):PAGE85
    39    GND @S9S_MB_2U_LIB.S9S_MB_2U(SCH_1):GND   I174 @S9S_MB_2U_LIB.S9S_MB_2U(SCH_1):PAGE85
    41    GND @S9S_MB_2U_LIB.S9S_MB_2U(SCH_1):GND   I174 @S9S_MB_2U_LIB.S9S_MB_2U(SCH_1):PAGE85
    43    GND @S9S_MB_2U_LIB.S9S_MB_2U(SCH_1):GND   I174 @S9S_MB_2U_LIB.S9S_MB_2U(SCH_1):PAGE85
    46    GND @S9S_MB_2U_LIB.S9S_MB_2U(SCH_1):GND   I174 @S9S_MB_2U_LIB.S9S_MB_2U(SCH_1):PAGE85
    48    GND @S9S_MB_2U_LIB.S9S_MB_2U(SCH_1):GND   I174 @S9S_MB_2U_LIB.S9S_MB_2U(SCH_1):PAGE85
    50    GND @S9S_MB_2U_LIB.S9S_MB_2U(SCH_1):GND   I174 @S9S_MB_2U_LIB.S9S_MB_2U(SCH_1):PAGE85
    52    GND @S9S_MB_2U_LIB.S9S_MB_2U(SCH_1):GND   I174 @S9S_MB_2U_LIB.S9S_MB_2U(SCH_1):PAGE85
    54    GND @S9S_MB_2U_LIB.S9S_MB_2U(SCH_1):GND   I174 @S9S_MB_2U_LIB.S9S_MB_2U(SCH_1):PAGE85
    57    GND @S9S_MB_2U_LIB.S9S_MB_2U(SCH_1):GND   I174 @S9S_MB_2U_LIB.S9S_MB_2U(SCH_1):PAGE85
    59    GND @S9S_MB_2U_LIB.S9S_MB_2U(SCH_1):GND   I174 @S9S_MB_2U_LIB.S9S_MB_2U(SCH_1):PAGE85
    61    GND @S9S_MB_2U_LIB.S9S_MB_2U(SCH_1):GND   I174 @S9S_MB_2U_LIB.S9S_MB_2U(SCH_1):PAGE85
    63    GND @S9S_MB_2U_LIB.S9S_MB_2U(SCH_1):GND   I174 @S9S_MB_2U_LIB.S9S_MB_2U(SCH_1):PAGE85
    65    GND @S9S_MB_2U_LIB.S9S_MB_2U(SCH_1):GND   I174 @S9S_MB_2U_LIB.S9S_MB_2U(SCH_1):PAGE85
    67    GND @S9S_MB_2U_LIB.S9S_MB_2U(SCH_1):GND   I174 @S9S_MB_2U_LIB.S9S_MB_2U(SCH_1):PAGE85
    69    GND @S9S_MB_2U_LIB.S9S_MB_2U(SCH_1):GND   I174 @S9S_MB_2U_LIB.S9S_MB_2U(SCH_1):PAGE85
    71    GND @S9S_MB_2U_LIB.S9S_MB_2U(SCH_1):GND   I174 @S9S_MB_2U_LIB.S9S_MB_2U(SCH_1):PAGE85
    73    GND @S9S_MB_2U_LIB.S9S_MB_2U(SCH_1):GND   I174 @S9S_MB_2U_LIB.S9S_MB_2U(SCH_1):PAGE85
    75    GND @S9S_MB_2U_LIB.S9S_MB_2U(SCH_1):GND   I174 @S9S_MB_2U_LIB.S9S_MB_2U(SCH_1):PAGE85
    77    GND @S9S_MB_2U_LIB.S9S_MB_2U(SCH_1):GND   I174 @S9S_MB_2U_LIB.S9S_MB_2U(SCH_1):PAGE85
    79    GND @S9S_MB_2U_LIB.S9S_MB_2U(SCH_1):GND   I174 @S9S_MB_2U_LIB.S9S_MB_2U(SCH_1):PAGE85
    81    GND @S9S_MB_2U_LIB.S9S_MB_2U(SCH_1):GND   I174 @S9S_MB_2U_LIB.S9S_MB_2U(SCH_1):PAGE85
    83    GND @S9S_MB_2U_LIB.S9S_MB_2U(SCH_1):GND   I174 @S9S_MB_2U_LIB.S9S_MB_2U(SCH_1):PAGE85
    85    GND @S9S_MB_2U_LIB.S9S_MB_2U(SCH_1):GND   I174 @S9S_MB_2U_LIB.S9S_MB_2U(SCH_1):PAGE85
    88    GND @S9S_MB_2U_LIB.S9S_MB_2U(SCH_1):GND   I174 @S9S_MB_2U_LIB.S9S_MB_2U(SCH_1):PAGE85
    90    GND @S9S_MB_2U_LIB.S9S_MB_2U(SCH_1):GND   I174 @S9S_MB_2U_LIB.S9S_MB_2U(SCH_1):PAGE85
    92    GND @S9S_MB_2U_LIB.S9S_MB_2U(SCH_1):GND   I174 @S9S_MB_2U_LIB.S9S_MB_2U(SCH_1):PAGE85
    95    GND @S9S_MB_2U_LIB.S9S_MB_2U(SCH_1):GND   I174 @S9S_MB_2U_LIB.S9S_MB_2U(SCH_1):PAGE85
    97    GND @S9S_MB_2U_LIB.S9S_MB_2U(SCH_1):GND   I174 @S9S_MB_2U_LIB.S9S_MB_2U(SCH_1):PAGE85
    99    GND @S9S_MB_2U_LIB.S9S_MB_2U(SCH_1):GND   I174 @S9S_MB_2U_LIB.S9S_MB_2U(SCH_1):PAGE85
   101    GND @S9S_MB_2U_LIB.S9S_MB_2U(SCH_1):GND   I174 @S9S_MB_2U_LIB.S9S_MB_2U(SCH_1):PAGE85
   103    GND @S9S_MB_2U_LIB.S9S_MB_2U(SCH_1):GND   I174 @S9S_MB_2U_LIB.S9S_MB_2U(SCH_1):PAGE85
   106    GND @S9S_MB_2U_LIB.S9S_MB_2U(SCH_1):GND   I174 @S9S_MB_2U_LIB.S9S_MB_2U(SCH_1):PAGE85
   108    GND @S9S_MB_2U_LIB.S9S_MB_2U(SCH_1):GND   I174 @S9S_MB_2U_LIB.S9S_MB_2U(SCH_1):PAGE85
   110    GND @S9S_MB_2U_LIB.S9S_MB_2U(SCH_1):GND   I174 @S9S_MB_2U_LIB.S9S_MB_2U(SCH_1):PAGE85
   112    GND @S9S_MB_2U_LIB.S9S_MB_2U(SCH_1):GND   I174 @S9S_MB_2U_LIB.S9S_MB_2U(SCH_1):PAGE85
   114    GND @S9S_MB_2U_LIB.S9S_MB_2U(SCH_1):GND   I174 @S9S_MB_2U_LIB.S9S_MB_2U(SCH_1):PAGE85
   117    GND @S9S_MB_2U_LIB.S9S_MB_2U(SCH_1):GND   I174 @S9S_MB_2U_LIB.S9S_MB_2U(SCH_1):PAGE85
   119    GND @S9S_MB_2U_LIB.S9S_MB_2U(SCH_1):GND   I174 @S9S_MB_2U_LIB.S9S_MB_2U(SCH_1):PAGE85
   121    GND @S9S_MB_2U_LIB.S9S_MB_2U(SCH_1):GND   I174 @S9S_MB_2U_LIB.S9S_MB_2U(SCH_1):PAGE85
   123    GND @S9S_MB_2U_LIB.S9S_MB_2U(SCH_1):GND   I174 @S9S_MB_2U_LIB.S9S_MB_2U(SCH_1):PAGE85
   125    GND @S9S_MB_2U_LIB.S9S_MB_2U(SCH_1):GND   I174 @S9S_MB_2U_LIB.S9S_MB_2U(SCH_1):PAGE85
   128    GND @S9S_MB_2U_LIB.S9S_MB_2U(SCH_1):GND   I174 @S9S_MB_2U_LIB.S9S_MB_2U(SCH_1):PAGE85
   130    GND @S9S_MB_2U_LIB.S9S_MB_2U(SCH_1):GND   I174 @S9S_MB_2U_LIB.S9S_MB_2U(SCH_1):PAGE85
   134    GND @S9S_MB_2U_LIB.S9S_MB_2U(SCH_1):GND   I174 @S9S_MB_2U_LIB.S9S_MB_2U(SCH_1):PAGE85
   143    GND @S9S_MB_2U_LIB.S9S_MB_2U(SCH_1):GND   I174 @S9S_MB_2U_LIB.S9S_MB_2U(SCH_1):PAGE85
   151    GND @S9S_MB_2U_LIB.S9S_MB_2U(SCH_1):GND   I174 @S9S_MB_2U_LIB.S9S_MB_2U(SCH_1):PAGE85
   153    GND @S9S_MB_2U_LIB.S9S_MB_2U(SCH_1):GND   I174 @S9S_MB_2U_LIB.S9S_MB_2U(SCH_1):PAGE85
   155    GND @S9S_MB_2U_LIB.S9S_MB_2U(SCH_1):GND   I174 @S9S_MB_2U_LIB.S9S_MB_2U(SCH_1):PAGE85
   158    GND @S9S_MB_2U_LIB.S9S_MB_2U(SCH_1):GND   I174 @S9S_MB_2U_LIB.S9S_MB_2U(SCH_1):PAGE85
   160    GND @S9S_MB_2U_LIB.S9S_MB_2U(SCH_1):GND   I174 @S9S_MB_2U_LIB.S9S_MB_2U(SCH_1):PAGE85
   162    GND @S9S_MB_2U_LIB.S9S_MB_2U(SCH_1):GND   I174 @S9S_MB_2U_LIB.S9S_MB_2U(SCH_1):PAGE85
   164    GND @S9S_MB_2U_LIB.S9S_MB_2U(SCH_1):GND   I174 @S9S_MB_2U_LIB.S9S_MB_2U(SCH_1):PAGE85
   166    GND @S9S_MB_2U_LIB.S9S_MB_2U(SCH_1):GND   I174 @S9S_MB_2U_LIB.S9S_MB_2U(SCH_1):PAGE85
   169    GND @S9S_MB_2U_LIB.S9S_MB_2U(SCH_1):GND   I174 @S9S_MB_2U_LIB.S9S_MB_2U(SCH_1):PAGE85
   171    GND @S9S_MB_2U_LIB.S9S_MB_2U(SCH_1):GND   I174 @S9S_MB_2U_LIB.S9S_MB_2U(SCH_1):PAGE85
   173    GND @S9S_MB_2U_LIB.S9S_MB_2U(SCH_1):GND   I174 @S9S_MB_2U_LIB.S9S_MB_2U(SCH_1):PAGE85
   175    GND @S9S_MB_2U_LIB.S9S_MB_2U(SCH_1):GND   I174 @S9S_MB_2U_LIB.S9S_MB_2U(SCH_1):PAGE85
   177    GND @S9S_MB_2U_LIB.S9S_MB_2U(SCH_1):GND   I174 @S9S_MB_2U_LIB.S9S_MB_2U(SCH_1):PAGE85
   180    GND @S9S_MB_2U_LIB.S9S_MB_2U(SCH_1):GND   I174 @S9S_MB_2U_LIB.S9S_MB_2U(SCH_1):PAGE85
   182    GND @S9S_MB_2U_LIB.S9S_MB_2U(SCH_1):GND   I174 @S9S_MB_2U_LIB.S9S_MB_2U(SCH_1):PAGE85
   184    GND @S9S_MB_2U_LIB.S9S_MB_2U(SCH_1):GND   I174 @S9S_MB_2U_LIB.S9S_MB_2U(SCH_1):PAGE85
   186    GND @S9S_MB_2U_LIB.S9S_MB_2U(SCH_1):GND   I174 @S9S_MB_2U_LIB.S9S_MB_2U(SCH_1):PAGE85
   188    GND @S9S_MB_2U_LIB.S9S_MB_2U(SCH_1):GND   I174 @S9S_MB_2U_LIB.S9S_MB_2U(SCH_1):PAGE85
   191    GND @S9S_MB_2U_LIB.S9S_MB_2U(SCH_1):GND   I174 @S9S_MB_2U_LIB.S9S_MB_2U(SCH_1):PAGE85
   193    GND @S9S_MB_2U_LIB.S9S_MB_2U(SCH_1):GND   I174 @S9S_MB_2U_LIB.S9S_MB_2U(SCH_1):PAGE85
   195    GND @S9S_MB_2U_LIB.S9S_MB_2U(SCH_1):GND   I174 @S9S_MB_2U_LIB.S9S_MB_2U(SCH_1):PAGE85
   197    GND @S9S_MB_2U_LIB.S9S_MB_2U(SCH_1):GND   I174 @S9S_MB_2U_LIB.S9S_MB_2U(SCH_1):PAGE85
   199    GND @S9S_MB_2U_LIB.S9S_MB_2U(SCH_1):GND   I174 @S9S_MB_2U_LIB.S9S_MB_2U(SCH_1):PAGE85
   202    GND @S9S_MB_2U_LIB.S9S_MB_2U(SCH_1):GND   I174 @S9S_MB_2U_LIB.S9S_MB_2U(SCH_1):PAGE85
   204    GND @S9S_MB_2U_LIB.S9S_MB_2U(SCH_1):GND   I174 @S9S_MB_2U_LIB.S9S_MB_2U(SCH_1):PAGE85
   206    GND @S9S_MB_2U_LIB.S9S_MB_2U(SCH_1):GND   I174 @S9S_MB_2U_LIB.S9S_MB_2U(SCH_1):PAGE85
   208    GND @S9S_MB_2U_LIB.S9S_MB_2U(SCH_1):GND   I174 @S9S_MB_2U_LIB.S9S_MB_2U(SCH_1):PAGE85
   210    GND @S9S_MB_2U_LIB.S9S_MB_2U(SCH_1):GND   I174 @S9S_MB_2U_LIB.S9S_MB_2U(SCH_1):PAGE85
   212    GND @S9S_MB_2U_LIB.S9S_MB_2U(SCH_1):GND   I174 @S9S_MB_2U_LIB.S9S_MB_2U(SCH_1):PAGE85
   214    GND @S9S_MB_2U_LIB.S9S_MB_2U(SCH_1):GND   I174 @S9S_MB_2U_LIB.S9S_MB_2U(SCH_1):PAGE85
   216    GND @S9S_MB_2U_LIB.S9S_MB_2U(SCH_1):GND   I174 @S9S_MB_2U_LIB.S9S_MB_2U(SCH_1):PAGE85
   219    GND @S9S_MB_2U_LIB.S9S_MB_2U(SCH_1):GND   I174 @S9S_MB_2U_LIB.S9S_MB_2U(SCH_1):PAGE85
   222    GND @S9S_MB_2U_LIB.S9S_MB_2U(SCH_1):GND   I174 @S9S_MB_2U_LIB.S9S_MB_2U(SCH_1):PAGE85
   224    GND @S9S_MB_2U_LIB.S9S_MB_2U(SCH_1):GND   I174 @S9S_MB_2U_LIB.S9S_MB_2U(SCH_1):PAGE85
   226    GND @S9S_MB_2U_LIB.S9S_MB_2U(SCH_1):GND   I174 @S9S_MB_2U_LIB.S9S_MB_2U(SCH_1):PAGE85
   228    GND @S9S_MB_2U_LIB.S9S_MB_2U(SCH_1):GND   I174 @S9S_MB_2U_LIB.S9S_MB_2U(SCH_1):PAGE85
   233    GND @S9S_MB_2U_LIB.S9S_MB_2U(SCH_1):GND   I174 @S9S_MB_2U_LIB.S9S_MB_2U(SCH_1):PAGE85
   237    GND @S9S_MB_2U_LIB.S9S_MB_2U(SCH_1):GND   I174 @S9S_MB_2U_LIB.S9S_MB_2U(SCH_1):PAGE85
   242    GND @S9S_MB_2U_LIB.S9S_MB_2U(SCH_1):GND   I174 @S9S_MB_2U_LIB.S9S_MB_2U(SCH_1):PAGE85
   244    GND @S9S_MB_2U_LIB.S9S_MB_2U(SCH_1):GND   I174 @S9S_MB_2U_LIB.S9S_MB_2U(SCH_1):PAGE85
   246    GND @S9S_MB_2U_LIB.S9S_MB_2U(SCH_1):GND   I174 @S9S_MB_2U_LIB.S9S_MB_2U(SCH_1):PAGE85
   248    GND @S9S_MB_2U_LIB.S9S_MB_2U(SCH_1):GND   I174 @S9S_MB_2U_LIB.S9S_MB_2U(SCH_1):PAGE85
   251    GND @S9S_MB_2U_LIB.S9S_MB_2U(SCH_1):GND   I174 @S9S_MB_2U_LIB.S9S_MB_2U(SCH_1):PAGE85
   253    GND @S9S_MB_2U_LIB.S9S_MB_2U(SCH_1):GND   I174 @S9S_MB_2U_LIB.S9S_MB_2U(SCH_1):PAGE85
   255    GND @S9S_MB_2U_LIB.S9S_MB_2U(SCH_1):GND   I174 @S9S_MB_2U_LIB.S9S_MB_2U(SCH_1):PAGE85
   257    GND @S9S_MB_2U_LIB.S9S_MB_2U(SCH_1):GND   I174 @S9S_MB_2U_LIB.S9S_MB_2U(SCH_1):PAGE85
   259    GND @S9S_MB_2U_LIB.S9S_MB_2U(SCH_1):GND   I174 @S9S_MB_2U_LIB.S9S_MB_2U(SCH_1):PAGE85
   262    GND @S9S_MB_2U_LIB.S9S_MB_2U(SCH_1):GND   I174 @S9S_MB_2U_LIB.S9S_MB_2U(SCH_1):PAGE85
   264    GND @S9S_MB_2U_LIB.S9S_MB_2U(SCH_1):GND   I174 @S9S_MB_2U_LIB.S9S_MB_2U(SCH_1):PAGE85
   266    GND @S9S_MB_2U_LIB.S9S_MB_2U(SCH_1):GND   I174 @S9S_MB_2U_LIB.S9S_MB_2U(SCH_1):PAGE85
   268    GND @S9S_MB_2U_LIB.S9S_MB_2U(SCH_1):GND   I174 @S9S_MB_2U_LIB.S9S_MB_2U(SCH_1):PAGE85
   270    GND @S9S_MB_2U_LIB.S9S_MB_2U(SCH_1):GND   I174 @S9S_MB_2U_LIB.S9S_MB_2U(SCH_1):PAGE85
   273    GND @S9S_MB_2U_LIB.S9S_MB_2U(SCH_1):GND   I174 @S9S_MB_2U_LIB.S9S_MB_2U(SCH_1):PAGE85
   275    GND @S9S_MB_2U_LIB.S9S_MB_2U(SCH_1):GND   I174 @S9S_MB_2U_LIB.S9S_MB_2U(SCH_1):PAGE85
   277    GND @S9S_MB_2U_LIB.S9S_MB_2U(SCH_1):GND   I174 @S9S_MB_2U_LIB.S9S_MB_2U(SCH_1):PAGE85
   279    GND @S9S_MB_2U_LIB.S9S_MB_2U(SCH_1):GND   I174 @S9S_MB_2U_LIB.S9S_MB_2U(SCH_1):PAGE85
   281    GND @S9S_MB_2U_LIB.S9S_MB_2U(SCH_1):GND   I174 @S9S_MB_2U_LIB.S9S_MB_2U(SCH_1):PAGE85
   284    GND @S9S_MB_2U_LIB.S9S_MB_2U(SCH_1):GND   I174 @S9S_MB_2U_LIB.S9S_MB_2U(SCH_1):PAGE85
   286    GND @S9S_MB_2U_LIB.S9S_MB_2U(SCH_1):GND   I174 @S9S_MB_2U_LIB.S9S_MB_2U(SCH_1):PAGE85
   288    GND @S9S_MB_2U_LIB.S9S_MB_2U(SCH_1):GND   I174 @S9S_MB_2U_LIB.S9S_MB_2U(SCH_1):PAGE85
     1 P12V_S3_AUX_CPU0_NVDIMM @S9S_MB_2U_LIB.S9S_MB_2U(SCH_1):P12V_S3_AUX_CPU0_NVDIMM   I174 @S9S_MB_2U_LIB.S9S_MB_2U(SCH_1):PAGE85
   145 P12V_S3_AUX_CPU0_NVDIMM @S9S_MB_2U_LIB.S9S_MB_2U(SCH_1):P12V_S3_AUX_CPU0_NVDIMM   I174 @S9S_MB_2U_LIB.S9S_MB_2U(SCH_1):PAGE85
   146 P12V_S3_AUX_CPU0_NVDIMM @S9S_MB_2U_LIB.S9S_MB_2U(SCH_1):P12V_S3_AUX_CPU0_NVDIMM   I174 @S9S_MB_2U_LIB.S9S_MB_2U(SCH_1):PAGE85
   230    GND @S9S_MB_2U_LIB.S9S_MB_2U(SCH_1):GND   I174 @S9S_MB_2U_LIB.S9S_MB_2U(SCH_1):PAGE85
   235    GND @S9S_MB_2U_LIB.S9S_MB_2U(SCH_1):GND   I174 @S9S_MB_2U_LIB.S9S_MB_2U(SCH_1):PAGE85
   240    GND @S9S_MB_2U_LIB.S9S_MB_2U(SCH_1):GND   I174 @S9S_MB_2U_LIB.S9S_MB_2U(SCH_1):PAGE85
   132    GND @S9S_MB_2U_LIB.S9S_MB_2U(SCH_1):GND   I174 @S9S_MB_2U_LIB.S9S_MB_2U(SCH_1):PAGE85
   136    GND @S9S_MB_2U_LIB.S9S_MB_2U(SCH_1):GND   I174 @S9S_MB_2U_LIB.S9S_MB_2U(SCH_1):PAGE85
   139    GND @S9S_MB_2U_LIB.S9S_MB_2U(SCH_1):GND   I174 @S9S_MB_2U_LIB.S9S_MB_2U(SCH_1):PAGE85
   141    GND @S9S_MB_2U_LIB.S9S_MB_2U(SCH_1):GND   I174 @S9S_MB_2U_LIB.S9S_MB_2U(SCH_1):PAGE85
    G1    GND @S9S_MB_2U_LIB.S9S_MB_2U(SCH_1):GND   I174 @S9S_MB_2U_LIB.S9S_MB_2U(SCH_1):PAGE85
    G2    GND @S9S_MB_2U_LIB.S9S_MB_2U(SCH_1):GND   I174 @S9S_MB_2U_LIB.S9S_MB_2U(SCH_1):PAGE85
    G3    GND @S9S_MB_2U_LIB.S9S_MB_2U(SCH_1):GND   I174 @S9S_MB_2U_LIB.S9S_MB_2U(SCH_1):PAGE85

  J5 SCONN288_ADR50017P130CC-SCONN2A
     3 P3V3_AUX @S9S_MB_2U_LIB.S9S_MB_2U(SCH_1):P3V3_AUX    I24 @S9S_MB_2U_LIB.S9S_MB_2U(SCH_1):PAGE86
     2 TP_CHC_CPU0_DIMM1_FRU_0 @S9S_MB_2U_LIB.S9S_MB_2U(SCH_1):TP_CHC_CPU0_DIMM1_FRU_0    I24 @S9S_MB_2U_LIB.S9S_MB_2U(SCH_1):PAGE86
   144 TP_CHC_CPU0_DIMM1_FRU_1 @S9S_MB_2U_LIB.S9S_MB_2U(SCH_1):TP_CHC_CPU0_DIMM1_FRU_1    I24 @S9S_MB_2U_LIB.S9S_MB_2U(SCH_1):PAGE86
   149 TP_CHC_CPU0_DIMM1_FRU_2 @S9S_MB_2U_LIB.S9S_MB_2U(SCH_1):TP_CHC_CPU0_DIMM1_FRU_2    I24 @S9S_MB_2U_LIB.S9S_MB_2U(SCH_1):PAGE86
   150 TP_CHC_CPU0_DIMM1_FRU_3 @S9S_MB_2U_LIB.S9S_MB_2U(SCH_1):TP_CHC_CPU0_DIMM1_FRU_3    I24 @S9S_MB_2U_LIB.S9S_MB_2U(SCH_1):PAGE86
   220 TP_CHC_CPU0_DIMM1_FRU_4 @S9S_MB_2U_LIB.S9S_MB_2U(SCH_1):TP_CHC_CPU0_DIMM1_FRU_4    I24 @S9S_MB_2U_LIB.S9S_MB_2U(SCH_1):PAGE86
   231 TP_CHC_CPU0_DIMM1_FRU_5 @S9S_MB_2U_LIB.S9S_MB_2U(SCH_1):TP_CHC_CPU0_DIMM1_FRU_5    I24 @S9S_MB_2U_LIB.S9S_MB_2U(SCH_1):PAGE86
   232 TP_CHC_CPU0_DIMM1_FRU_6 @S9S_MB_2U_LIB.S9S_MB_2U(SCH_1):TP_CHC_CPU0_DIMM1_FRU_6    I24 @S9S_MB_2U_LIB.S9S_MB_2U(SCH_1):PAGE86
   207 RST_M_CD_CPU0_FPGA_N @S9S_MB_2U_LIB.S9S_MB_2U(SCH_1):RST_M_CD_CPU0_FPGA_N    I24 @S9S_MB_2U_LIB.S9S_MB_2U(SCH_1):PAGE86
   147 PWRGD_CHC_CPU0_DIMM1 @S9S_MB_2U_LIB.S9S_MB_2U(SCH_1):PWRGD_CHC_CPU0_DIMM1    I24 @S9S_MB_2U_LIB.S9S_MB_2U(SCH_1):PAGE86
   227 M_C_CPU0_SB_PAR @S9S_MB_2U_LIB.S9S_MB_2U(SCH_1):M_C_CPU0_SB_PAR    I24 @S9S_MB_2U_LIB.S9S_MB_2U(SCH_1):PAGE86
    74 M_C_CPU0_SA_PAR @S9S_MB_2U_LIB.S9S_MB_2U(SCH_1):M_C_CPU0_SA_PAR    I24 @S9S_MB_2U_LIB.S9S_MB_2U(SCH_1):PAGE86
    87 M_C_CPU0_SB_RSP<0> @S9S_MB_2U_LIB.S9S_MB_2U(SCH_1):M_C_CPU0_SB_RSP(0)    I24 @S9S_MB_2U_LIB.S9S_MB_2U(SCH_1):PAGE86
    86 M_C_CPU0_SA_RSP<0> @S9S_MB_2U_LIB.S9S_MB_2U(SCH_1):M_C_CPU0_SA_RSP(0)    I24 @S9S_MB_2U_LIB.S9S_MB_2U(SCH_1):PAGE86
     5 I3C_SPD_DDRABCD_CPU0_LVC1_SDA @S9S_MB_2U_LIB.S9S_MB_2U(SCH_1):I3C_SPD_DDRABCD_CPU0_LVC1_SDA    I24 @S9S_MB_2U_LIB.S9S_MB_2U(SCH_1):PAGE86
     4 I3C_SPD_DDRABCD_CPU0_LVC1_SCL_4 @S9S_MB_2U_LIB.S9S_MB_2U(SCH_1):I3C_SPD_DDRABCD_CPU0_LVC1_SCL_R5    I24 @S9S_MB_2U_LIB.S9S_MB_2U(SCH_1):PAGE86
   148 PD_CHC_CPU0_DIMM1_SAA @S9S_MB_2U_LIB.S9S_MB_2U(SCH_1):PD_CHC_CPU0_DIMM1_SAA    I24 @S9S_MB_2U_LIB.S9S_MB_2U(SCH_1):PAGE86
   100 M_C_CPU0_SB_DQ<0> @S9S_MB_2U_LIB.S9S_MB_2U(SCH_1):M_C_CPU0_SB_DQ(0)    I24 @S9S_MB_2U_LIB.S9S_MB_2U(SCH_1):PAGE86
   102 M_C_CPU0_SB_DQ<1> @S9S_MB_2U_LIB.S9S_MB_2U(SCH_1):M_C_CPU0_SB_DQ(1)    I24 @S9S_MB_2U_LIB.S9S_MB_2U(SCH_1):PAGE86
   245 M_C_CPU0_SB_DQ<2> @S9S_MB_2U_LIB.S9S_MB_2U(SCH_1):M_C_CPU0_SB_DQ(2)    I24 @S9S_MB_2U_LIB.S9S_MB_2U(SCH_1):PAGE86
   247 M_C_CPU0_SB_DQ<3> @S9S_MB_2U_LIB.S9S_MB_2U(SCH_1):M_C_CPU0_SB_DQ(3)    I24 @S9S_MB_2U_LIB.S9S_MB_2U(SCH_1):PAGE86
   107 M_C_CPU0_SB_DQ<4> @S9S_MB_2U_LIB.S9S_MB_2U(SCH_1):M_C_CPU0_SB_DQ(4)    I24 @S9S_MB_2U_LIB.S9S_MB_2U(SCH_1):PAGE86
   109 M_C_CPU0_SB_DQ<5> @S9S_MB_2U_LIB.S9S_MB_2U(SCH_1):M_C_CPU0_SB_DQ(5)    I24 @S9S_MB_2U_LIB.S9S_MB_2U(SCH_1):PAGE86
   252 M_C_CPU0_SB_DQ<6> @S9S_MB_2U_LIB.S9S_MB_2U(SCH_1):M_C_CPU0_SB_DQ(6)    I24 @S9S_MB_2U_LIB.S9S_MB_2U(SCH_1):PAGE86
   254 M_C_CPU0_SB_DQ<7> @S9S_MB_2U_LIB.S9S_MB_2U(SCH_1):M_C_CPU0_SB_DQ(7)    I24 @S9S_MB_2U_LIB.S9S_MB_2U(SCH_1):PAGE86
   111 M_C_CPU0_SB_DQ<8> @S9S_MB_2U_LIB.S9S_MB_2U(SCH_1):M_C_CPU0_SB_DQ(8)    I24 @S9S_MB_2U_LIB.S9S_MB_2U(SCH_1):PAGE86
   113 M_C_CPU0_SB_DQ<9> @S9S_MB_2U_LIB.S9S_MB_2U(SCH_1):M_C_CPU0_SB_DQ(9)    I24 @S9S_MB_2U_LIB.S9S_MB_2U(SCH_1):PAGE86
   256 M_C_CPU0_SB_DQ<10> @S9S_MB_2U_LIB.S9S_MB_2U(SCH_1):M_C_CPU0_SB_DQ(10)    I24 @S9S_MB_2U_LIB.S9S_MB_2U(SCH_1):PAGE86
   258 M_C_CPU0_SB_DQ<11> @S9S_MB_2U_LIB.S9S_MB_2U(SCH_1):M_C_CPU0_SB_DQ(11)    I24 @S9S_MB_2U_LIB.S9S_MB_2U(SCH_1):PAGE86
   118 M_C_CPU0_SB_DQ<12> @S9S_MB_2U_LIB.S9S_MB_2U(SCH_1):M_C_CPU0_SB_DQ(12)    I24 @S9S_MB_2U_LIB.S9S_MB_2U(SCH_1):PAGE86
   120 M_C_CPU0_SB_DQ<13> @S9S_MB_2U_LIB.S9S_MB_2U(SCH_1):M_C_CPU0_SB_DQ(13)    I24 @S9S_MB_2U_LIB.S9S_MB_2U(SCH_1):PAGE86
   263 M_C_CPU0_SB_DQ<14> @S9S_MB_2U_LIB.S9S_MB_2U(SCH_1):M_C_CPU0_SB_DQ(14)    I24 @S9S_MB_2U_LIB.S9S_MB_2U(SCH_1):PAGE86
   265 M_C_CPU0_SB_DQ<15> @S9S_MB_2U_LIB.S9S_MB_2U(SCH_1):M_C_CPU0_SB_DQ(15)    I24 @S9S_MB_2U_LIB.S9S_MB_2U(SCH_1):PAGE86
   122 M_C_CPU0_SB_DQ<16> @S9S_MB_2U_LIB.S9S_MB_2U(SCH_1):M_C_CPU0_SB_DQ(16)    I24 @S9S_MB_2U_LIB.S9S_MB_2U(SCH_1):PAGE86
   124 M_C_CPU0_SB_DQ<17> @S9S_MB_2U_LIB.S9S_MB_2U(SCH_1):M_C_CPU0_SB_DQ(17)    I24 @S9S_MB_2U_LIB.S9S_MB_2U(SCH_1):PAGE86
   267 M_C_CPU0_SB_DQ<18> @S9S_MB_2U_LIB.S9S_MB_2U(SCH_1):M_C_CPU0_SB_DQ(18)    I24 @S9S_MB_2U_LIB.S9S_MB_2U(SCH_1):PAGE86
   269 M_C_CPU0_SB_DQ<19> @S9S_MB_2U_LIB.S9S_MB_2U(SCH_1):M_C_CPU0_SB_DQ(19)    I24 @S9S_MB_2U_LIB.S9S_MB_2U(SCH_1):PAGE86
   129 M_C_CPU0_SB_DQ<20> @S9S_MB_2U_LIB.S9S_MB_2U(SCH_1):M_C_CPU0_SB_DQ(20)    I24 @S9S_MB_2U_LIB.S9S_MB_2U(SCH_1):PAGE86
   131 M_C_CPU0_SB_DQ<21> @S9S_MB_2U_LIB.S9S_MB_2U(SCH_1):M_C_CPU0_SB_DQ(21)    I24 @S9S_MB_2U_LIB.S9S_MB_2U(SCH_1):PAGE86
   274 M_C_CPU0_SB_DQ<22> @S9S_MB_2U_LIB.S9S_MB_2U(SCH_1):M_C_CPU0_SB_DQ(22)    I24 @S9S_MB_2U_LIB.S9S_MB_2U(SCH_1):PAGE86
   276 M_C_CPU0_SB_DQ<23> @S9S_MB_2U_LIB.S9S_MB_2U(SCH_1):M_C_CPU0_SB_DQ(23)    I24 @S9S_MB_2U_LIB.S9S_MB_2U(SCH_1):PAGE86
   133 M_C_CPU0_SB_DQ<24> @S9S_MB_2U_LIB.S9S_MB_2U(SCH_1):M_C_CPU0_SB_DQ(24)    I24 @S9S_MB_2U_LIB.S9S_MB_2U(SCH_1):PAGE86
   135 M_C_CPU0_SB_DQ<25> @S9S_MB_2U_LIB.S9S_MB_2U(SCH_1):M_C_CPU0_SB_DQ(25)    I24 @S9S_MB_2U_LIB.S9S_MB_2U(SCH_1):PAGE86
   278 M_C_CPU0_SB_DQ<26> @S9S_MB_2U_LIB.S9S_MB_2U(SCH_1):M_C_CPU0_SB_DQ(26)    I24 @S9S_MB_2U_LIB.S9S_MB_2U(SCH_1):PAGE86
   280 M_C_CPU0_SB_DQ<27> @S9S_MB_2U_LIB.S9S_MB_2U(SCH_1):M_C_CPU0_SB_DQ(27)    I24 @S9S_MB_2U_LIB.S9S_MB_2U(SCH_1):PAGE86
   140 M_C_CPU0_SB_DQ<28> @S9S_MB_2U_LIB.S9S_MB_2U(SCH_1):M_C_CPU0_SB_DQ(28)    I24 @S9S_MB_2U_LIB.S9S_MB_2U(SCH_1):PAGE86
   142 M_C_CPU0_SB_DQ<29> @S9S_MB_2U_LIB.S9S_MB_2U(SCH_1):M_C_CPU0_SB_DQ(29)    I24 @S9S_MB_2U_LIB.S9S_MB_2U(SCH_1):PAGE86
   285 M_C_CPU0_SB_DQ<30> @S9S_MB_2U_LIB.S9S_MB_2U(SCH_1):M_C_CPU0_SB_DQ(30)    I24 @S9S_MB_2U_LIB.S9S_MB_2U(SCH_1):PAGE86
   287 M_C_CPU0_SB_DQ<31> @S9S_MB_2U_LIB.S9S_MB_2U(SCH_1):M_C_CPU0_SB_DQ(31)    I24 @S9S_MB_2U_LIB.S9S_MB_2U(SCH_1):PAGE86
     7 M_C_CPU0_SA_DQ<0> @S9S_MB_2U_LIB.S9S_MB_2U(SCH_1):M_C_CPU0_SA_DQ(0)    I24 @S9S_MB_2U_LIB.S9S_MB_2U(SCH_1):PAGE86
     9 M_C_CPU0_SA_DQ<1> @S9S_MB_2U_LIB.S9S_MB_2U(SCH_1):M_C_CPU0_SA_DQ(1)    I24 @S9S_MB_2U_LIB.S9S_MB_2U(SCH_1):PAGE86
   152 M_C_CPU0_SA_DQ<2> @S9S_MB_2U_LIB.S9S_MB_2U(SCH_1):M_C_CPU0_SA_DQ(2)    I24 @S9S_MB_2U_LIB.S9S_MB_2U(SCH_1):PAGE86
   154 M_C_CPU0_SA_DQ<3> @S9S_MB_2U_LIB.S9S_MB_2U(SCH_1):M_C_CPU0_SA_DQ(3)    I24 @S9S_MB_2U_LIB.S9S_MB_2U(SCH_1):PAGE86
    14 M_C_CPU0_SA_DQ<4> @S9S_MB_2U_LIB.S9S_MB_2U(SCH_1):M_C_CPU0_SA_DQ(4)    I24 @S9S_MB_2U_LIB.S9S_MB_2U(SCH_1):PAGE86
    16 M_C_CPU0_SA_DQ<5> @S9S_MB_2U_LIB.S9S_MB_2U(SCH_1):M_C_CPU0_SA_DQ(5)    I24 @S9S_MB_2U_LIB.S9S_MB_2U(SCH_1):PAGE86
   159 M_C_CPU0_SA_DQ<6> @S9S_MB_2U_LIB.S9S_MB_2U(SCH_1):M_C_CPU0_SA_DQ(6)    I24 @S9S_MB_2U_LIB.S9S_MB_2U(SCH_1):PAGE86
   161 M_C_CPU0_SA_DQ<7> @S9S_MB_2U_LIB.S9S_MB_2U(SCH_1):M_C_CPU0_SA_DQ(7)    I24 @S9S_MB_2U_LIB.S9S_MB_2U(SCH_1):PAGE86
    18 M_C_CPU0_SA_DQ<8> @S9S_MB_2U_LIB.S9S_MB_2U(SCH_1):M_C_CPU0_SA_DQ(8)    I24 @S9S_MB_2U_LIB.S9S_MB_2U(SCH_1):PAGE86
    20 M_C_CPU0_SA_DQ<9> @S9S_MB_2U_LIB.S9S_MB_2U(SCH_1):M_C_CPU0_SA_DQ(9)    I24 @S9S_MB_2U_LIB.S9S_MB_2U(SCH_1):PAGE86
   163 M_C_CPU0_SA_DQ<10> @S9S_MB_2U_LIB.S9S_MB_2U(SCH_1):M_C_CPU0_SA_DQ(10)    I24 @S9S_MB_2U_LIB.S9S_MB_2U(SCH_1):PAGE86
   165 M_C_CPU0_SA_DQ<11> @S9S_MB_2U_LIB.S9S_MB_2U(SCH_1):M_C_CPU0_SA_DQ(11)    I24 @S9S_MB_2U_LIB.S9S_MB_2U(SCH_1):PAGE86
    25 M_C_CPU0_SA_DQ<12> @S9S_MB_2U_LIB.S9S_MB_2U(SCH_1):M_C_CPU0_SA_DQ(12)    I24 @S9S_MB_2U_LIB.S9S_MB_2U(SCH_1):PAGE86
    27 M_C_CPU0_SA_DQ<13> @S9S_MB_2U_LIB.S9S_MB_2U(SCH_1):M_C_CPU0_SA_DQ(13)    I24 @S9S_MB_2U_LIB.S9S_MB_2U(SCH_1):PAGE86
   170 M_C_CPU0_SA_DQ<14> @S9S_MB_2U_LIB.S9S_MB_2U(SCH_1):M_C_CPU0_SA_DQ(14)    I24 @S9S_MB_2U_LIB.S9S_MB_2U(SCH_1):PAGE86
   172 M_C_CPU0_SA_DQ<15> @S9S_MB_2U_LIB.S9S_MB_2U(SCH_1):M_C_CPU0_SA_DQ(15)    I24 @S9S_MB_2U_LIB.S9S_MB_2U(SCH_1):PAGE86
    29 M_C_CPU0_SA_DQ<16> @S9S_MB_2U_LIB.S9S_MB_2U(SCH_1):M_C_CPU0_SA_DQ(16)    I24 @S9S_MB_2U_LIB.S9S_MB_2U(SCH_1):PAGE86
    31 M_C_CPU0_SA_DQ<17> @S9S_MB_2U_LIB.S9S_MB_2U(SCH_1):M_C_CPU0_SA_DQ(17)    I24 @S9S_MB_2U_LIB.S9S_MB_2U(SCH_1):PAGE86
   174 M_C_CPU0_SA_DQ<18> @S9S_MB_2U_LIB.S9S_MB_2U(SCH_1):M_C_CPU0_SA_DQ(18)    I24 @S9S_MB_2U_LIB.S9S_MB_2U(SCH_1):PAGE86
   176 M_C_CPU0_SA_DQ<19> @S9S_MB_2U_LIB.S9S_MB_2U(SCH_1):M_C_CPU0_SA_DQ(19)    I24 @S9S_MB_2U_LIB.S9S_MB_2U(SCH_1):PAGE86
    36 M_C_CPU0_SA_DQ<20> @S9S_MB_2U_LIB.S9S_MB_2U(SCH_1):M_C_CPU0_SA_DQ(20)    I24 @S9S_MB_2U_LIB.S9S_MB_2U(SCH_1):PAGE86
    38 M_C_CPU0_SA_DQ<21> @S9S_MB_2U_LIB.S9S_MB_2U(SCH_1):M_C_CPU0_SA_DQ(21)    I24 @S9S_MB_2U_LIB.S9S_MB_2U(SCH_1):PAGE86
   181 M_C_CPU0_SA_DQ<22> @S9S_MB_2U_LIB.S9S_MB_2U(SCH_1):M_C_CPU0_SA_DQ(22)    I24 @S9S_MB_2U_LIB.S9S_MB_2U(SCH_1):PAGE86
   183 M_C_CPU0_SA_DQ<23> @S9S_MB_2U_LIB.S9S_MB_2U(SCH_1):M_C_CPU0_SA_DQ(23)    I24 @S9S_MB_2U_LIB.S9S_MB_2U(SCH_1):PAGE86
    40 M_C_CPU0_SA_DQ<24> @S9S_MB_2U_LIB.S9S_MB_2U(SCH_1):M_C_CPU0_SA_DQ(24)    I24 @S9S_MB_2U_LIB.S9S_MB_2U(SCH_1):PAGE86
    42 M_C_CPU0_SA_DQ<25> @S9S_MB_2U_LIB.S9S_MB_2U(SCH_1):M_C_CPU0_SA_DQ(25)    I24 @S9S_MB_2U_LIB.S9S_MB_2U(SCH_1):PAGE86
   185 M_C_CPU0_SA_DQ<26> @S9S_MB_2U_LIB.S9S_MB_2U(SCH_1):M_C_CPU0_SA_DQ(26)    I24 @S9S_MB_2U_LIB.S9S_MB_2U(SCH_1):PAGE86
   187 M_C_CPU0_SA_DQ<27> @S9S_MB_2U_LIB.S9S_MB_2U(SCH_1):M_C_CPU0_SA_DQ(27)    I24 @S9S_MB_2U_LIB.S9S_MB_2U(SCH_1):PAGE86
    47 M_C_CPU0_SA_DQ<28> @S9S_MB_2U_LIB.S9S_MB_2U(SCH_1):M_C_CPU0_SA_DQ(28)    I24 @S9S_MB_2U_LIB.S9S_MB_2U(SCH_1):PAGE86
    49 M_C_CPU0_SA_DQ<29> @S9S_MB_2U_LIB.S9S_MB_2U(SCH_1):M_C_CPU0_SA_DQ(29)    I24 @S9S_MB_2U_LIB.S9S_MB_2U(SCH_1):PAGE86
   192 M_C_CPU0_SA_DQ<30> @S9S_MB_2U_LIB.S9S_MB_2U(SCH_1):M_C_CPU0_SA_DQ(30)    I24 @S9S_MB_2U_LIB.S9S_MB_2U(SCH_1):PAGE86
   229 M_C_CPU0_SB_CS_N<1> @S9S_MB_2U_LIB.S9S_MB_2U(SCH_1):M_C_CPU0_SB_CS_N(1)    I24 @S9S_MB_2U_LIB.S9S_MB_2U(SCH_1):PAGE86
   209 M_C_CPU0_SA_CS_N<1> @S9S_MB_2U_LIB.S9S_MB_2U(SCH_1):M_C_CPU0_SA_CS_N(1)    I24 @S9S_MB_2U_LIB.S9S_MB_2U(SCH_1):PAGE86
    84 M_C_CPU0_SB_CS_N<0> @S9S_MB_2U_LIB.S9S_MB_2U(SCH_1):M_C_CPU0_SB_CS_N(0)    I24 @S9S_MB_2U_LIB.S9S_MB_2U(SCH_1):PAGE86
    64 M_C_CPU0_SA_CS_N<0> @S9S_MB_2U_LIB.S9S_MB_2U(SCH_1):M_C_CPU0_SA_CS_N(0)    I24 @S9S_MB_2U_LIB.S9S_MB_2U(SCH_1):PAGE86
   217 M_C_CPU0_CLK_DP<0> @S9S_MB_2U_LIB.S9S_MB_2U(SCH_1):M_C_CPU0_CLK_DP(0)    I24 @S9S_MB_2U_LIB.S9S_MB_2U(SCH_1):PAGE86
   218 M_C_CPU0_CLK_DN<0> @S9S_MB_2U_LIB.S9S_MB_2U(SCH_1):M_C_CPU0_CLK_DN(0)    I24 @S9S_MB_2U_LIB.S9S_MB_2U(SCH_1):PAGE86
    96 M_C_CPU0_SB_CB<0> @S9S_MB_2U_LIB.S9S_MB_2U(SCH_1):M_C_CPU0_SB_CB(0)    I24 @S9S_MB_2U_LIB.S9S_MB_2U(SCH_1):PAGE86
    98 M_C_CPU0_SB_CB<1> @S9S_MB_2U_LIB.S9S_MB_2U(SCH_1):M_C_CPU0_SB_CB(1)    I24 @S9S_MB_2U_LIB.S9S_MB_2U(SCH_1):PAGE86
   241 M_C_CPU0_SB_CB<2> @S9S_MB_2U_LIB.S9S_MB_2U(SCH_1):M_C_CPU0_SB_CB(2)    I24 @S9S_MB_2U_LIB.S9S_MB_2U(SCH_1):PAGE86
   243 M_C_CPU0_SB_CB<3> @S9S_MB_2U_LIB.S9S_MB_2U(SCH_1):M_C_CPU0_SB_CB(3)    I24 @S9S_MB_2U_LIB.S9S_MB_2U(SCH_1):PAGE86
    89 M_C_CPU0_SB_CB<4> @S9S_MB_2U_LIB.S9S_MB_2U(SCH_1):M_C_CPU0_SB_CB(4)    I24 @S9S_MB_2U_LIB.S9S_MB_2U(SCH_1):PAGE86
    91 M_C_CPU0_SB_CB<5> @S9S_MB_2U_LIB.S9S_MB_2U(SCH_1):M_C_CPU0_SB_CB(5)    I24 @S9S_MB_2U_LIB.S9S_MB_2U(SCH_1):PAGE86
   234 M_C_CPU0_SB_CB<6> @S9S_MB_2U_LIB.S9S_MB_2U(SCH_1):M_C_CPU0_SB_CB(6)    I24 @S9S_MB_2U_LIB.S9S_MB_2U(SCH_1):PAGE86
    51 M_C_CPU0_SA_CB<0> @S9S_MB_2U_LIB.S9S_MB_2U(SCH_1):M_C_CPU0_SA_CB(0)    I24 @S9S_MB_2U_LIB.S9S_MB_2U(SCH_1):PAGE86
   196 M_C_CPU0_SA_CB<2> @S9S_MB_2U_LIB.S9S_MB_2U(SCH_1):M_C_CPU0_SA_CB(2)    I24 @S9S_MB_2U_LIB.S9S_MB_2U(SCH_1):PAGE86
   198 M_C_CPU0_SA_CB<3> @S9S_MB_2U_LIB.S9S_MB_2U(SCH_1):M_C_CPU0_SA_CB(3)    I24 @S9S_MB_2U_LIB.S9S_MB_2U(SCH_1):PAGE86
    60 M_C_CPU0_SA_CB<5> @S9S_MB_2U_LIB.S9S_MB_2U(SCH_1):M_C_CPU0_SA_CB(5)    I24 @S9S_MB_2U_LIB.S9S_MB_2U(SCH_1):PAGE86
   203 M_C_CPU0_SA_CB<6> @S9S_MB_2U_LIB.S9S_MB_2U(SCH_1):M_C_CPU0_SA_CB(6)    I24 @S9S_MB_2U_LIB.S9S_MB_2U(SCH_1):PAGE86
    82 M_C_CPU0_SB_CA<6> @S9S_MB_2U_LIB.S9S_MB_2U(SCH_1):M_C_CPU0_SB_CA(6)    I24 @S9S_MB_2U_LIB.S9S_MB_2U(SCH_1):PAGE86
    72 M_C_CPU0_SA_CA<6> @S9S_MB_2U_LIB.S9S_MB_2U(SCH_1):M_C_CPU0_SA_CA(6)    I24 @S9S_MB_2U_LIB.S9S_MB_2U(SCH_1):PAGE86
   225 M_C_CPU0_SB_CA<5> @S9S_MB_2U_LIB.S9S_MB_2U(SCH_1):M_C_CPU0_SB_CA(5)    I24 @S9S_MB_2U_LIB.S9S_MB_2U(SCH_1):PAGE86
   215 M_C_CPU0_SA_CA<5> @S9S_MB_2U_LIB.S9S_MB_2U(SCH_1):M_C_CPU0_SA_CA(5)    I24 @S9S_MB_2U_LIB.S9S_MB_2U(SCH_1):PAGE86
    80 M_C_CPU0_SB_CA<4> @S9S_MB_2U_LIB.S9S_MB_2U(SCH_1):M_C_CPU0_SB_CA(4)    I24 @S9S_MB_2U_LIB.S9S_MB_2U(SCH_1):PAGE86
    70 M_C_CPU0_SA_CA<4> @S9S_MB_2U_LIB.S9S_MB_2U(SCH_1):M_C_CPU0_SA_CA(4)    I24 @S9S_MB_2U_LIB.S9S_MB_2U(SCH_1):PAGE86
   223 M_C_CPU0_SB_CA<3> @S9S_MB_2U_LIB.S9S_MB_2U(SCH_1):M_C_CPU0_SB_CA(3)    I24 @S9S_MB_2U_LIB.S9S_MB_2U(SCH_1):PAGE86
   213 M_C_CPU0_SA_CA<3> @S9S_MB_2U_LIB.S9S_MB_2U(SCH_1):M_C_CPU0_SA_CA(3)    I24 @S9S_MB_2U_LIB.S9S_MB_2U(SCH_1):PAGE86
    78 M_C_CPU0_SB_CA<2> @S9S_MB_2U_LIB.S9S_MB_2U(SCH_1):M_C_CPU0_SB_CA(2)    I24 @S9S_MB_2U_LIB.S9S_MB_2U(SCH_1):PAGE86
    68 M_C_CPU0_SA_CA<2> @S9S_MB_2U_LIB.S9S_MB_2U(SCH_1):M_C_CPU0_SA_CA(2)    I24 @S9S_MB_2U_LIB.S9S_MB_2U(SCH_1):PAGE86
   221 M_C_CPU0_SB_CA<1> @S9S_MB_2U_LIB.S9S_MB_2U(SCH_1):M_C_CPU0_SB_CA(1)    I24 @S9S_MB_2U_LIB.S9S_MB_2U(SCH_1):PAGE86
   211 M_C_CPU0_SA_CA<1> @S9S_MB_2U_LIB.S9S_MB_2U(SCH_1):M_C_CPU0_SA_CA(1)    I24 @S9S_MB_2U_LIB.S9S_MB_2U(SCH_1):PAGE86
    76 M_C_CPU0_SB_CA<0> @S9S_MB_2U_LIB.S9S_MB_2U(SCH_1):M_C_CPU0_SB_CA(0)    I24 @S9S_MB_2U_LIB.S9S_MB_2U(SCH_1):PAGE86
    66 M_C_CPU0_SA_CA<0> @S9S_MB_2U_LIB.S9S_MB_2U(SCH_1):M_C_CPU0_SA_CA(0)    I24 @S9S_MB_2U_LIB.S9S_MB_2U(SCH_1):PAGE86
    62 M_C_CPU0_ALERT_N @S9S_MB_2U_LIB.S9S_MB_2U(SCH_1):M_C_CPU0_ALERT_N    I24 @S9S_MB_2U_LIB.S9S_MB_2U(SCH_1):PAGE86
   236 M_C_CPU0_SB_CB<7> @S9S_MB_2U_LIB.S9S_MB_2U(SCH_1):M_C_CPU0_SB_CB(7)    I24 @S9S_MB_2U_LIB.S9S_MB_2U(SCH_1):PAGE86
    53 M_C_CPU0_SA_CB<1> @S9S_MB_2U_LIB.S9S_MB_2U(SCH_1):M_C_CPU0_SA_CB(1)    I24 @S9S_MB_2U_LIB.S9S_MB_2U(SCH_1):PAGE86
    58 M_C_CPU0_SA_CB<4> @S9S_MB_2U_LIB.S9S_MB_2U(SCH_1):M_C_CPU0_SA_CB(4)    I24 @S9S_MB_2U_LIB.S9S_MB_2U(SCH_1):PAGE86
   205 M_C_CPU0_SA_CB<7> @S9S_MB_2U_LIB.S9S_MB_2U(SCH_1):M_C_CPU0_SA_CB(7)    I24 @S9S_MB_2U_LIB.S9S_MB_2U(SCH_1):PAGE86
   194 M_C_CPU0_SA_DQ<31> @S9S_MB_2U_LIB.S9S_MB_2U(SCH_1):M_C_CPU0_SA_DQ(31)    I24 @S9S_MB_2U_LIB.S9S_MB_2U(SCH_1):PAGE86
    93 M_C_CPU0_SB_DQS_DP<9> @S9S_MB_2U_LIB.S9S_MB_2U(SCH_1):M_C_CPU0_SB_DQS_DP(9)   I178 @S9S_MB_2U_LIB.S9S_MB_2U(SCH_1):PAGE86
    94 M_C_CPU0_SB_DQS_DN<9> @S9S_MB_2U_LIB.S9S_MB_2U(SCH_1):M_C_CPU0_SB_DQS_DN(9)   I178 @S9S_MB_2U_LIB.S9S_MB_2U(SCH_1):PAGE86
   201 M_C_CPU0_SA_DQS_DP<9> @S9S_MB_2U_LIB.S9S_MB_2U(SCH_1):M_C_CPU0_SA_DQS_DP(9)   I178 @S9S_MB_2U_LIB.S9S_MB_2U(SCH_1):PAGE86
   200 M_C_CPU0_SA_DQS_DN<9> @S9S_MB_2U_LIB.S9S_MB_2U(SCH_1):M_C_CPU0_SA_DQS_DN(9)   I178 @S9S_MB_2U_LIB.S9S_MB_2U(SCH_1):PAGE86
   190 M_C_CPU0_SA_DQS_DP<8> @S9S_MB_2U_LIB.S9S_MB_2U(SCH_1):M_C_CPU0_SA_DQS_DP(8)   I178 @S9S_MB_2U_LIB.S9S_MB_2U(SCH_1):PAGE86
   189 M_C_CPU0_SA_DQS_DN<8> @S9S_MB_2U_LIB.S9S_MB_2U(SCH_1):M_C_CPU0_SA_DQS_DN(8)   I178 @S9S_MB_2U_LIB.S9S_MB_2U(SCH_1):PAGE86
   271 M_C_CPU0_SB_DQS_DN<7> @S9S_MB_2U_LIB.S9S_MB_2U(SCH_1):M_C_CPU0_SB_DQS_DN(7)   I178 @S9S_MB_2U_LIB.S9S_MB_2U(SCH_1):PAGE86
   179 M_C_CPU0_SA_DQS_DP<7> @S9S_MB_2U_LIB.S9S_MB_2U(SCH_1):M_C_CPU0_SA_DQS_DP(7)   I178 @S9S_MB_2U_LIB.S9S_MB_2U(SCH_1):PAGE86
   261 M_C_CPU0_SB_DQS_DP<6> @S9S_MB_2U_LIB.S9S_MB_2U(SCH_1):M_C_CPU0_SB_DQS_DP(6)   I178 @S9S_MB_2U_LIB.S9S_MB_2U(SCH_1):PAGE86
   260 M_C_CPU0_SB_DQS_DN<6> @S9S_MB_2U_LIB.S9S_MB_2U(SCH_1):M_C_CPU0_SB_DQS_DN(6)   I178 @S9S_MB_2U_LIB.S9S_MB_2U(SCH_1):PAGE86
   167 M_C_CPU0_SA_DQS_DN<6> @S9S_MB_2U_LIB.S9S_MB_2U(SCH_1):M_C_CPU0_SA_DQS_DN(6)   I178 @S9S_MB_2U_LIB.S9S_MB_2U(SCH_1):PAGE86
   250 M_C_CPU0_SB_DQS_DP<5> @S9S_MB_2U_LIB.S9S_MB_2U(SCH_1):M_C_CPU0_SB_DQS_DP(5)   I178 @S9S_MB_2U_LIB.S9S_MB_2U(SCH_1):PAGE86
   249 M_C_CPU0_SB_DQS_DN<5> @S9S_MB_2U_LIB.S9S_MB_2U(SCH_1):M_C_CPU0_SB_DQS_DN(5)   I178 @S9S_MB_2U_LIB.S9S_MB_2U(SCH_1):PAGE86
   157 M_C_CPU0_SA_DQS_DP<5> @S9S_MB_2U_LIB.S9S_MB_2U(SCH_1):M_C_CPU0_SA_DQS_DP(5)   I178 @S9S_MB_2U_LIB.S9S_MB_2U(SCH_1):PAGE86
   156 M_C_CPU0_SA_DQS_DN<5> @S9S_MB_2U_LIB.S9S_MB_2U(SCH_1):M_C_CPU0_SA_DQS_DN(5)   I178 @S9S_MB_2U_LIB.S9S_MB_2U(SCH_1):PAGE86
   239 M_C_CPU0_SB_DQS_DP<4> @S9S_MB_2U_LIB.S9S_MB_2U(SCH_1):M_C_CPU0_SB_DQS_DP(4)   I178 @S9S_MB_2U_LIB.S9S_MB_2U(SCH_1):PAGE86
   238 M_C_CPU0_SB_DQS_DN<4> @S9S_MB_2U_LIB.S9S_MB_2U(SCH_1):M_C_CPU0_SB_DQS_DN(4)   I178 @S9S_MB_2U_LIB.S9S_MB_2U(SCH_1):PAGE86
    55 M_C_CPU0_SA_DQS_DP<4> @S9S_MB_2U_LIB.S9S_MB_2U(SCH_1):M_C_CPU0_SA_DQS_DP(4)   I178 @S9S_MB_2U_LIB.S9S_MB_2U(SCH_1):PAGE86
    56 M_C_CPU0_SA_DQS_DN<4> @S9S_MB_2U_LIB.S9S_MB_2U(SCH_1):M_C_CPU0_SA_DQS_DN(4)   I178 @S9S_MB_2U_LIB.S9S_MB_2U(SCH_1):PAGE86
   137 M_C_CPU0_SB_DQS_DP<3> @S9S_MB_2U_LIB.S9S_MB_2U(SCH_1):M_C_CPU0_SB_DQS_DP(3)   I178 @S9S_MB_2U_LIB.S9S_MB_2U(SCH_1):PAGE86
   138 M_C_CPU0_SB_DQS_DN<3> @S9S_MB_2U_LIB.S9S_MB_2U(SCH_1):M_C_CPU0_SB_DQS_DN(3)   I178 @S9S_MB_2U_LIB.S9S_MB_2U(SCH_1):PAGE86
    44 M_C_CPU0_SA_DQS_DP<3> @S9S_MB_2U_LIB.S9S_MB_2U(SCH_1):M_C_CPU0_SA_DQS_DP(3)   I178 @S9S_MB_2U_LIB.S9S_MB_2U(SCH_1):PAGE86
    45 M_C_CPU0_SA_DQS_DN<3> @S9S_MB_2U_LIB.S9S_MB_2U(SCH_1):M_C_CPU0_SA_DQS_DN(3)   I178 @S9S_MB_2U_LIB.S9S_MB_2U(SCH_1):PAGE86
   126 M_C_CPU0_SB_DQS_DP<2> @S9S_MB_2U_LIB.S9S_MB_2U(SCH_1):M_C_CPU0_SB_DQS_DP(2)   I178 @S9S_MB_2U_LIB.S9S_MB_2U(SCH_1):PAGE86
   127 M_C_CPU0_SB_DQS_DN<2> @S9S_MB_2U_LIB.S9S_MB_2U(SCH_1):M_C_CPU0_SB_DQS_DN(2)   I178 @S9S_MB_2U_LIB.S9S_MB_2U(SCH_1):PAGE86
    33 M_C_CPU0_SA_DQS_DP<2> @S9S_MB_2U_LIB.S9S_MB_2U(SCH_1):M_C_CPU0_SA_DQS_DP(2)   I178 @S9S_MB_2U_LIB.S9S_MB_2U(SCH_1):PAGE86
    34 M_C_CPU0_SA_DQS_DN<2> @S9S_MB_2U_LIB.S9S_MB_2U(SCH_1):M_C_CPU0_SA_DQS_DN(2)   I178 @S9S_MB_2U_LIB.S9S_MB_2U(SCH_1):PAGE86
   115 M_C_CPU0_SB_DQS_DP<1> @S9S_MB_2U_LIB.S9S_MB_2U(SCH_1):M_C_CPU0_SB_DQS_DP(1)   I178 @S9S_MB_2U_LIB.S9S_MB_2U(SCH_1):PAGE86
   116 M_C_CPU0_SB_DQS_DN<1> @S9S_MB_2U_LIB.S9S_MB_2U(SCH_1):M_C_CPU0_SB_DQS_DN(1)   I178 @S9S_MB_2U_LIB.S9S_MB_2U(SCH_1):PAGE86
    22 M_C_CPU0_SA_DQS_DP<1> @S9S_MB_2U_LIB.S9S_MB_2U(SCH_1):M_C_CPU0_SA_DQS_DP(1)   I178 @S9S_MB_2U_LIB.S9S_MB_2U(SCH_1):PAGE86
    23 M_C_CPU0_SA_DQS_DN<1> @S9S_MB_2U_LIB.S9S_MB_2U(SCH_1):M_C_CPU0_SA_DQS_DN(1)   I178 @S9S_MB_2U_LIB.S9S_MB_2U(SCH_1):PAGE86
   104 M_C_CPU0_SB_DQS_DP<0> @S9S_MB_2U_LIB.S9S_MB_2U(SCH_1):M_C_CPU0_SB_DQS_DP(0)   I178 @S9S_MB_2U_LIB.S9S_MB_2U(SCH_1):PAGE86
   105 M_C_CPU0_SB_DQS_DN<0> @S9S_MB_2U_LIB.S9S_MB_2U(SCH_1):M_C_CPU0_SB_DQS_DN(0)   I178 @S9S_MB_2U_LIB.S9S_MB_2U(SCH_1):PAGE86
    11 M_C_CPU0_SA_DQS_DP<0> @S9S_MB_2U_LIB.S9S_MB_2U(SCH_1):M_C_CPU0_SA_DQS_DP(0)   I178 @S9S_MB_2U_LIB.S9S_MB_2U(SCH_1):PAGE86
    12 M_C_CPU0_SA_DQS_DN<0> @S9S_MB_2U_LIB.S9S_MB_2U(SCH_1):M_C_CPU0_SA_DQS_DN(0)   I178 @S9S_MB_2U_LIB.S9S_MB_2U(SCH_1):PAGE86
   272 M_C_CPU0_SB_DQS_DP<7> @S9S_MB_2U_LIB.S9S_MB_2U(SCH_1):M_C_CPU0_SB_DQS_DP(7)   I178 @S9S_MB_2U_LIB.S9S_MB_2U(SCH_1):PAGE86
   282 M_C_CPU0_SB_DQS_DN<8> @S9S_MB_2U_LIB.S9S_MB_2U(SCH_1):M_C_CPU0_SB_DQS_DN(8)   I178 @S9S_MB_2U_LIB.S9S_MB_2U(SCH_1):PAGE86
   283 M_C_CPU0_SB_DQS_DP<8> @S9S_MB_2U_LIB.S9S_MB_2U(SCH_1):M_C_CPU0_SB_DQS_DP(8)   I178 @S9S_MB_2U_LIB.S9S_MB_2U(SCH_1):PAGE86
   168 M_C_CPU0_SA_DQS_DP<6> @S9S_MB_2U_LIB.S9S_MB_2U(SCH_1):M_C_CPU0_SA_DQS_DP(6)   I178 @S9S_MB_2U_LIB.S9S_MB_2U(SCH_1):PAGE86
   178 M_C_CPU0_SA_DQS_DN<7> @S9S_MB_2U_LIB.S9S_MB_2U(SCH_1):M_C_CPU0_SA_DQS_DN(7)   I178 @S9S_MB_2U_LIB.S9S_MB_2U(SCH_1):PAGE86
     6    GND @S9S_MB_2U_LIB.S9S_MB_2U(SCH_1):GND   I174 @S9S_MB_2U_LIB.S9S_MB_2U(SCH_1):PAGE86
     8    GND @S9S_MB_2U_LIB.S9S_MB_2U(SCH_1):GND   I174 @S9S_MB_2U_LIB.S9S_MB_2U(SCH_1):PAGE86
    10    GND @S9S_MB_2U_LIB.S9S_MB_2U(SCH_1):GND   I174 @S9S_MB_2U_LIB.S9S_MB_2U(SCH_1):PAGE86
    13    GND @S9S_MB_2U_LIB.S9S_MB_2U(SCH_1):GND   I174 @S9S_MB_2U_LIB.S9S_MB_2U(SCH_1):PAGE86
    15    GND @S9S_MB_2U_LIB.S9S_MB_2U(SCH_1):GND   I174 @S9S_MB_2U_LIB.S9S_MB_2U(SCH_1):PAGE86
    17    GND @S9S_MB_2U_LIB.S9S_MB_2U(SCH_1):GND   I174 @S9S_MB_2U_LIB.S9S_MB_2U(SCH_1):PAGE86
    19    GND @S9S_MB_2U_LIB.S9S_MB_2U(SCH_1):GND   I174 @S9S_MB_2U_LIB.S9S_MB_2U(SCH_1):PAGE86
    21    GND @S9S_MB_2U_LIB.S9S_MB_2U(SCH_1):GND   I174 @S9S_MB_2U_LIB.S9S_MB_2U(SCH_1):PAGE86
    24    GND @S9S_MB_2U_LIB.S9S_MB_2U(SCH_1):GND   I174 @S9S_MB_2U_LIB.S9S_MB_2U(SCH_1):PAGE86
    26    GND @S9S_MB_2U_LIB.S9S_MB_2U(SCH_1):GND   I174 @S9S_MB_2U_LIB.S9S_MB_2U(SCH_1):PAGE86
    28    GND @S9S_MB_2U_LIB.S9S_MB_2U(SCH_1):GND   I174 @S9S_MB_2U_LIB.S9S_MB_2U(SCH_1):PAGE86
    30    GND @S9S_MB_2U_LIB.S9S_MB_2U(SCH_1):GND   I174 @S9S_MB_2U_LIB.S9S_MB_2U(SCH_1):PAGE86
    32    GND @S9S_MB_2U_LIB.S9S_MB_2U(SCH_1):GND   I174 @S9S_MB_2U_LIB.S9S_MB_2U(SCH_1):PAGE86
    35    GND @S9S_MB_2U_LIB.S9S_MB_2U(SCH_1):GND   I174 @S9S_MB_2U_LIB.S9S_MB_2U(SCH_1):PAGE86
    37    GND @S9S_MB_2U_LIB.S9S_MB_2U(SCH_1):GND   I174 @S9S_MB_2U_LIB.S9S_MB_2U(SCH_1):PAGE86
    39    GND @S9S_MB_2U_LIB.S9S_MB_2U(SCH_1):GND   I174 @S9S_MB_2U_LIB.S9S_MB_2U(SCH_1):PAGE86
    41    GND @S9S_MB_2U_LIB.S9S_MB_2U(SCH_1):GND   I174 @S9S_MB_2U_LIB.S9S_MB_2U(SCH_1):PAGE86
    43    GND @S9S_MB_2U_LIB.S9S_MB_2U(SCH_1):GND   I174 @S9S_MB_2U_LIB.S9S_MB_2U(SCH_1):PAGE86
    46    GND @S9S_MB_2U_LIB.S9S_MB_2U(SCH_1):GND   I174 @S9S_MB_2U_LIB.S9S_MB_2U(SCH_1):PAGE86
    48    GND @S9S_MB_2U_LIB.S9S_MB_2U(SCH_1):GND   I174 @S9S_MB_2U_LIB.S9S_MB_2U(SCH_1):PAGE86
    50    GND @S9S_MB_2U_LIB.S9S_MB_2U(SCH_1):GND   I174 @S9S_MB_2U_LIB.S9S_MB_2U(SCH_1):PAGE86
    52    GND @S9S_MB_2U_LIB.S9S_MB_2U(SCH_1):GND   I174 @S9S_MB_2U_LIB.S9S_MB_2U(SCH_1):PAGE86
    54    GND @S9S_MB_2U_LIB.S9S_MB_2U(SCH_1):GND   I174 @S9S_MB_2U_LIB.S9S_MB_2U(SCH_1):PAGE86
    57    GND @S9S_MB_2U_LIB.S9S_MB_2U(SCH_1):GND   I174 @S9S_MB_2U_LIB.S9S_MB_2U(SCH_1):PAGE86
    59    GND @S9S_MB_2U_LIB.S9S_MB_2U(SCH_1):GND   I174 @S9S_MB_2U_LIB.S9S_MB_2U(SCH_1):PAGE86
    61    GND @S9S_MB_2U_LIB.S9S_MB_2U(SCH_1):GND   I174 @S9S_MB_2U_LIB.S9S_MB_2U(SCH_1):PAGE86
    63    GND @S9S_MB_2U_LIB.S9S_MB_2U(SCH_1):GND   I174 @S9S_MB_2U_LIB.S9S_MB_2U(SCH_1):PAGE86
    65    GND @S9S_MB_2U_LIB.S9S_MB_2U(SCH_1):GND   I174 @S9S_MB_2U_LIB.S9S_MB_2U(SCH_1):PAGE86
    67    GND @S9S_MB_2U_LIB.S9S_MB_2U(SCH_1):GND   I174 @S9S_MB_2U_LIB.S9S_MB_2U(SCH_1):PAGE86
    69    GND @S9S_MB_2U_LIB.S9S_MB_2U(SCH_1):GND   I174 @S9S_MB_2U_LIB.S9S_MB_2U(SCH_1):PAGE86
    71    GND @S9S_MB_2U_LIB.S9S_MB_2U(SCH_1):GND   I174 @S9S_MB_2U_LIB.S9S_MB_2U(SCH_1):PAGE86
    73    GND @S9S_MB_2U_LIB.S9S_MB_2U(SCH_1):GND   I174 @S9S_MB_2U_LIB.S9S_MB_2U(SCH_1):PAGE86
    75    GND @S9S_MB_2U_LIB.S9S_MB_2U(SCH_1):GND   I174 @S9S_MB_2U_LIB.S9S_MB_2U(SCH_1):PAGE86
    77    GND @S9S_MB_2U_LIB.S9S_MB_2U(SCH_1):GND   I174 @S9S_MB_2U_LIB.S9S_MB_2U(SCH_1):PAGE86
    79    GND @S9S_MB_2U_LIB.S9S_MB_2U(SCH_1):GND   I174 @S9S_MB_2U_LIB.S9S_MB_2U(SCH_1):PAGE86
    81    GND @S9S_MB_2U_LIB.S9S_MB_2U(SCH_1):GND   I174 @S9S_MB_2U_LIB.S9S_MB_2U(SCH_1):PAGE86
    83    GND @S9S_MB_2U_LIB.S9S_MB_2U(SCH_1):GND   I174 @S9S_MB_2U_LIB.S9S_MB_2U(SCH_1):PAGE86
    85    GND @S9S_MB_2U_LIB.S9S_MB_2U(SCH_1):GND   I174 @S9S_MB_2U_LIB.S9S_MB_2U(SCH_1):PAGE86
    88    GND @S9S_MB_2U_LIB.S9S_MB_2U(SCH_1):GND   I174 @S9S_MB_2U_LIB.S9S_MB_2U(SCH_1):PAGE86
    90    GND @S9S_MB_2U_LIB.S9S_MB_2U(SCH_1):GND   I174 @S9S_MB_2U_LIB.S9S_MB_2U(SCH_1):PAGE86
    92    GND @S9S_MB_2U_LIB.S9S_MB_2U(SCH_1):GND   I174 @S9S_MB_2U_LIB.S9S_MB_2U(SCH_1):PAGE86
    95    GND @S9S_MB_2U_LIB.S9S_MB_2U(SCH_1):GND   I174 @S9S_MB_2U_LIB.S9S_MB_2U(SCH_1):PAGE86
    97    GND @S9S_MB_2U_LIB.S9S_MB_2U(SCH_1):GND   I174 @S9S_MB_2U_LIB.S9S_MB_2U(SCH_1):PAGE86
    99    GND @S9S_MB_2U_LIB.S9S_MB_2U(SCH_1):GND   I174 @S9S_MB_2U_LIB.S9S_MB_2U(SCH_1):PAGE86
   101    GND @S9S_MB_2U_LIB.S9S_MB_2U(SCH_1):GND   I174 @S9S_MB_2U_LIB.S9S_MB_2U(SCH_1):PAGE86
   103    GND @S9S_MB_2U_LIB.S9S_MB_2U(SCH_1):GND   I174 @S9S_MB_2U_LIB.S9S_MB_2U(SCH_1):PAGE86
   106    GND @S9S_MB_2U_LIB.S9S_MB_2U(SCH_1):GND   I174 @S9S_MB_2U_LIB.S9S_MB_2U(SCH_1):PAGE86
   108    GND @S9S_MB_2U_LIB.S9S_MB_2U(SCH_1):GND   I174 @S9S_MB_2U_LIB.S9S_MB_2U(SCH_1):PAGE86
   110    GND @S9S_MB_2U_LIB.S9S_MB_2U(SCH_1):GND   I174 @S9S_MB_2U_LIB.S9S_MB_2U(SCH_1):PAGE86
   112    GND @S9S_MB_2U_LIB.S9S_MB_2U(SCH_1):GND   I174 @S9S_MB_2U_LIB.S9S_MB_2U(SCH_1):PAGE86
   114    GND @S9S_MB_2U_LIB.S9S_MB_2U(SCH_1):GND   I174 @S9S_MB_2U_LIB.S9S_MB_2U(SCH_1):PAGE86
   117    GND @S9S_MB_2U_LIB.S9S_MB_2U(SCH_1):GND   I174 @S9S_MB_2U_LIB.S9S_MB_2U(SCH_1):PAGE86
   119    GND @S9S_MB_2U_LIB.S9S_MB_2U(SCH_1):GND   I174 @S9S_MB_2U_LIB.S9S_MB_2U(SCH_1):PAGE86
   121    GND @S9S_MB_2U_LIB.S9S_MB_2U(SCH_1):GND   I174 @S9S_MB_2U_LIB.S9S_MB_2U(SCH_1):PAGE86
   123    GND @S9S_MB_2U_LIB.S9S_MB_2U(SCH_1):GND   I174 @S9S_MB_2U_LIB.S9S_MB_2U(SCH_1):PAGE86
   125    GND @S9S_MB_2U_LIB.S9S_MB_2U(SCH_1):GND   I174 @S9S_MB_2U_LIB.S9S_MB_2U(SCH_1):PAGE86
   128    GND @S9S_MB_2U_LIB.S9S_MB_2U(SCH_1):GND   I174 @S9S_MB_2U_LIB.S9S_MB_2U(SCH_1):PAGE86
   130    GND @S9S_MB_2U_LIB.S9S_MB_2U(SCH_1):GND   I174 @S9S_MB_2U_LIB.S9S_MB_2U(SCH_1):PAGE86
   134    GND @S9S_MB_2U_LIB.S9S_MB_2U(SCH_1):GND   I174 @S9S_MB_2U_LIB.S9S_MB_2U(SCH_1):PAGE86
   143    GND @S9S_MB_2U_LIB.S9S_MB_2U(SCH_1):GND   I174 @S9S_MB_2U_LIB.S9S_MB_2U(SCH_1):PAGE86
   151    GND @S9S_MB_2U_LIB.S9S_MB_2U(SCH_1):GND   I174 @S9S_MB_2U_LIB.S9S_MB_2U(SCH_1):PAGE86
   153    GND @S9S_MB_2U_LIB.S9S_MB_2U(SCH_1):GND   I174 @S9S_MB_2U_LIB.S9S_MB_2U(SCH_1):PAGE86
   155    GND @S9S_MB_2U_LIB.S9S_MB_2U(SCH_1):GND   I174 @S9S_MB_2U_LIB.S9S_MB_2U(SCH_1):PAGE86
   158    GND @S9S_MB_2U_LIB.S9S_MB_2U(SCH_1):GND   I174 @S9S_MB_2U_LIB.S9S_MB_2U(SCH_1):PAGE86
   160    GND @S9S_MB_2U_LIB.S9S_MB_2U(SCH_1):GND   I174 @S9S_MB_2U_LIB.S9S_MB_2U(SCH_1):PAGE86
   162    GND @S9S_MB_2U_LIB.S9S_MB_2U(SCH_1):GND   I174 @S9S_MB_2U_LIB.S9S_MB_2U(SCH_1):PAGE86
   164    GND @S9S_MB_2U_LIB.S9S_MB_2U(SCH_1):GND   I174 @S9S_MB_2U_LIB.S9S_MB_2U(SCH_1):PAGE86
   166    GND @S9S_MB_2U_LIB.S9S_MB_2U(SCH_1):GND   I174 @S9S_MB_2U_LIB.S9S_MB_2U(SCH_1):PAGE86
   169    GND @S9S_MB_2U_LIB.S9S_MB_2U(SCH_1):GND   I174 @S9S_MB_2U_LIB.S9S_MB_2U(SCH_1):PAGE86
   171    GND @S9S_MB_2U_LIB.S9S_MB_2U(SCH_1):GND   I174 @S9S_MB_2U_LIB.S9S_MB_2U(SCH_1):PAGE86
   173    GND @S9S_MB_2U_LIB.S9S_MB_2U(SCH_1):GND   I174 @S9S_MB_2U_LIB.S9S_MB_2U(SCH_1):PAGE86
   175    GND @S9S_MB_2U_LIB.S9S_MB_2U(SCH_1):GND   I174 @S9S_MB_2U_LIB.S9S_MB_2U(SCH_1):PAGE86
   177    GND @S9S_MB_2U_LIB.S9S_MB_2U(SCH_1):GND   I174 @S9S_MB_2U_LIB.S9S_MB_2U(SCH_1):PAGE86
   180    GND @S9S_MB_2U_LIB.S9S_MB_2U(SCH_1):GND   I174 @S9S_MB_2U_LIB.S9S_MB_2U(SCH_1):PAGE86
   182    GND @S9S_MB_2U_LIB.S9S_MB_2U(SCH_1):GND   I174 @S9S_MB_2U_LIB.S9S_MB_2U(SCH_1):PAGE86
   184    GND @S9S_MB_2U_LIB.S9S_MB_2U(SCH_1):GND   I174 @S9S_MB_2U_LIB.S9S_MB_2U(SCH_1):PAGE86
   186    GND @S9S_MB_2U_LIB.S9S_MB_2U(SCH_1):GND   I174 @S9S_MB_2U_LIB.S9S_MB_2U(SCH_1):PAGE86
   188    GND @S9S_MB_2U_LIB.S9S_MB_2U(SCH_1):GND   I174 @S9S_MB_2U_LIB.S9S_MB_2U(SCH_1):PAGE86
   191    GND @S9S_MB_2U_LIB.S9S_MB_2U(SCH_1):GND   I174 @S9S_MB_2U_LIB.S9S_MB_2U(SCH_1):PAGE86
   193    GND @S9S_MB_2U_LIB.S9S_MB_2U(SCH_1):GND   I174 @S9S_MB_2U_LIB.S9S_MB_2U(SCH_1):PAGE86
   195    GND @S9S_MB_2U_LIB.S9S_MB_2U(SCH_1):GND   I174 @S9S_MB_2U_LIB.S9S_MB_2U(SCH_1):PAGE86
   197    GND @S9S_MB_2U_LIB.S9S_MB_2U(SCH_1):GND   I174 @S9S_MB_2U_LIB.S9S_MB_2U(SCH_1):PAGE86
   199    GND @S9S_MB_2U_LIB.S9S_MB_2U(SCH_1):GND   I174 @S9S_MB_2U_LIB.S9S_MB_2U(SCH_1):PAGE86
   202    GND @S9S_MB_2U_LIB.S9S_MB_2U(SCH_1):GND   I174 @S9S_MB_2U_LIB.S9S_MB_2U(SCH_1):PAGE86
   204    GND @S9S_MB_2U_LIB.S9S_MB_2U(SCH_1):GND   I174 @S9S_MB_2U_LIB.S9S_MB_2U(SCH_1):PAGE86
   206    GND @S9S_MB_2U_LIB.S9S_MB_2U(SCH_1):GND   I174 @S9S_MB_2U_LIB.S9S_MB_2U(SCH_1):PAGE86
   208    GND @S9S_MB_2U_LIB.S9S_MB_2U(SCH_1):GND   I174 @S9S_MB_2U_LIB.S9S_MB_2U(SCH_1):PAGE86
   210    GND @S9S_MB_2U_LIB.S9S_MB_2U(SCH_1):GND   I174 @S9S_MB_2U_LIB.S9S_MB_2U(SCH_1):PAGE86
   212    GND @S9S_MB_2U_LIB.S9S_MB_2U(SCH_1):GND   I174 @S9S_MB_2U_LIB.S9S_MB_2U(SCH_1):PAGE86
   214    GND @S9S_MB_2U_LIB.S9S_MB_2U(SCH_1):GND   I174 @S9S_MB_2U_LIB.S9S_MB_2U(SCH_1):PAGE86
   216    GND @S9S_MB_2U_LIB.S9S_MB_2U(SCH_1):GND   I174 @S9S_MB_2U_LIB.S9S_MB_2U(SCH_1):PAGE86
   219    GND @S9S_MB_2U_LIB.S9S_MB_2U(SCH_1):GND   I174 @S9S_MB_2U_LIB.S9S_MB_2U(SCH_1):PAGE86
   222    GND @S9S_MB_2U_LIB.S9S_MB_2U(SCH_1):GND   I174 @S9S_MB_2U_LIB.S9S_MB_2U(SCH_1):PAGE86
   224    GND @S9S_MB_2U_LIB.S9S_MB_2U(SCH_1):GND   I174 @S9S_MB_2U_LIB.S9S_MB_2U(SCH_1):PAGE86
   226    GND @S9S_MB_2U_LIB.S9S_MB_2U(SCH_1):GND   I174 @S9S_MB_2U_LIB.S9S_MB_2U(SCH_1):PAGE86
   228    GND @S9S_MB_2U_LIB.S9S_MB_2U(SCH_1):GND   I174 @S9S_MB_2U_LIB.S9S_MB_2U(SCH_1):PAGE86
   233    GND @S9S_MB_2U_LIB.S9S_MB_2U(SCH_1):GND   I174 @S9S_MB_2U_LIB.S9S_MB_2U(SCH_1):PAGE86
   237    GND @S9S_MB_2U_LIB.S9S_MB_2U(SCH_1):GND   I174 @S9S_MB_2U_LIB.S9S_MB_2U(SCH_1):PAGE86
   242    GND @S9S_MB_2U_LIB.S9S_MB_2U(SCH_1):GND   I174 @S9S_MB_2U_LIB.S9S_MB_2U(SCH_1):PAGE86
   244    GND @S9S_MB_2U_LIB.S9S_MB_2U(SCH_1):GND   I174 @S9S_MB_2U_LIB.S9S_MB_2U(SCH_1):PAGE86
   246    GND @S9S_MB_2U_LIB.S9S_MB_2U(SCH_1):GND   I174 @S9S_MB_2U_LIB.S9S_MB_2U(SCH_1):PAGE86
   248    GND @S9S_MB_2U_LIB.S9S_MB_2U(SCH_1):GND   I174 @S9S_MB_2U_LIB.S9S_MB_2U(SCH_1):PAGE86
   251    GND @S9S_MB_2U_LIB.S9S_MB_2U(SCH_1):GND   I174 @S9S_MB_2U_LIB.S9S_MB_2U(SCH_1):PAGE86
   253    GND @S9S_MB_2U_LIB.S9S_MB_2U(SCH_1):GND   I174 @S9S_MB_2U_LIB.S9S_MB_2U(SCH_1):PAGE86
   255    GND @S9S_MB_2U_LIB.S9S_MB_2U(SCH_1):GND   I174 @S9S_MB_2U_LIB.S9S_MB_2U(SCH_1):PAGE86
   257    GND @S9S_MB_2U_LIB.S9S_MB_2U(SCH_1):GND   I174 @S9S_MB_2U_LIB.S9S_MB_2U(SCH_1):PAGE86
   259    GND @S9S_MB_2U_LIB.S9S_MB_2U(SCH_1):GND   I174 @S9S_MB_2U_LIB.S9S_MB_2U(SCH_1):PAGE86
   262    GND @S9S_MB_2U_LIB.S9S_MB_2U(SCH_1):GND   I174 @S9S_MB_2U_LIB.S9S_MB_2U(SCH_1):PAGE86
   264    GND @S9S_MB_2U_LIB.S9S_MB_2U(SCH_1):GND   I174 @S9S_MB_2U_LIB.S9S_MB_2U(SCH_1):PAGE86
   266    GND @S9S_MB_2U_LIB.S9S_MB_2U(SCH_1):GND   I174 @S9S_MB_2U_LIB.S9S_MB_2U(SCH_1):PAGE86
   268    GND @S9S_MB_2U_LIB.S9S_MB_2U(SCH_1):GND   I174 @S9S_MB_2U_LIB.S9S_MB_2U(SCH_1):PAGE86
   270    GND @S9S_MB_2U_LIB.S9S_MB_2U(SCH_1):GND   I174 @S9S_MB_2U_LIB.S9S_MB_2U(SCH_1):PAGE86
   273    GND @S9S_MB_2U_LIB.S9S_MB_2U(SCH_1):GND   I174 @S9S_MB_2U_LIB.S9S_MB_2U(SCH_1):PAGE86
   275    GND @S9S_MB_2U_LIB.S9S_MB_2U(SCH_1):GND   I174 @S9S_MB_2U_LIB.S9S_MB_2U(SCH_1):PAGE86
   277    GND @S9S_MB_2U_LIB.S9S_MB_2U(SCH_1):GND   I174 @S9S_MB_2U_LIB.S9S_MB_2U(SCH_1):PAGE86
   279    GND @S9S_MB_2U_LIB.S9S_MB_2U(SCH_1):GND   I174 @S9S_MB_2U_LIB.S9S_MB_2U(SCH_1):PAGE86
   281    GND @S9S_MB_2U_LIB.S9S_MB_2U(SCH_1):GND   I174 @S9S_MB_2U_LIB.S9S_MB_2U(SCH_1):PAGE86
   284    GND @S9S_MB_2U_LIB.S9S_MB_2U(SCH_1):GND   I174 @S9S_MB_2U_LIB.S9S_MB_2U(SCH_1):PAGE86
   286    GND @S9S_MB_2U_LIB.S9S_MB_2U(SCH_1):GND   I174 @S9S_MB_2U_LIB.S9S_MB_2U(SCH_1):PAGE86
   288    GND @S9S_MB_2U_LIB.S9S_MB_2U(SCH_1):GND   I174 @S9S_MB_2U_LIB.S9S_MB_2U(SCH_1):PAGE86
     1 P12V_S3_AUX_CPU0_NVDIMM @S9S_MB_2U_LIB.S9S_MB_2U(SCH_1):P12V_S3_AUX_CPU0_NVDIMM   I174 @S9S_MB_2U_LIB.S9S_MB_2U(SCH_1):PAGE86
   145 P12V_S3_AUX_CPU0_NVDIMM @S9S_MB_2U_LIB.S9S_MB_2U(SCH_1):P12V_S3_AUX_CPU0_NVDIMM   I174 @S9S_MB_2U_LIB.S9S_MB_2U(SCH_1):PAGE86
   146 P12V_S3_AUX_CPU0_NVDIMM @S9S_MB_2U_LIB.S9S_MB_2U(SCH_1):P12V_S3_AUX_CPU0_NVDIMM   I174 @S9S_MB_2U_LIB.S9S_MB_2U(SCH_1):PAGE86
   230    GND @S9S_MB_2U_LIB.S9S_MB_2U(SCH_1):GND   I174 @S9S_MB_2U_LIB.S9S_MB_2U(SCH_1):PAGE86
   235    GND @S9S_MB_2U_LIB.S9S_MB_2U(SCH_1):GND   I174 @S9S_MB_2U_LIB.S9S_MB_2U(SCH_1):PAGE86
   240    GND @S9S_MB_2U_LIB.S9S_MB_2U(SCH_1):GND   I174 @S9S_MB_2U_LIB.S9S_MB_2U(SCH_1):PAGE86
   132    GND @S9S_MB_2U_LIB.S9S_MB_2U(SCH_1):GND   I174 @S9S_MB_2U_LIB.S9S_MB_2U(SCH_1):PAGE86
   136    GND @S9S_MB_2U_LIB.S9S_MB_2U(SCH_1):GND   I174 @S9S_MB_2U_LIB.S9S_MB_2U(SCH_1):PAGE86
   139    GND @S9S_MB_2U_LIB.S9S_MB_2U(SCH_1):GND   I174 @S9S_MB_2U_LIB.S9S_MB_2U(SCH_1):PAGE86
   141    GND @S9S_MB_2U_LIB.S9S_MB_2U(SCH_1):GND   I174 @S9S_MB_2U_LIB.S9S_MB_2U(SCH_1):PAGE86
    G1    GND @S9S_MB_2U_LIB.S9S_MB_2U(SCH_1):GND   I174 @S9S_MB_2U_LIB.S9S_MB_2U(SCH_1):PAGE86
    G2    GND @S9S_MB_2U_LIB.S9S_MB_2U(SCH_1):GND   I174 @S9S_MB_2U_LIB.S9S_MB_2U(SCH_1):PAGE86
    G3    GND @S9S_MB_2U_LIB.S9S_MB_2U(SCH_1):GND   I174 @S9S_MB_2U_LIB.S9S_MB_2U(SCH_1):PAGE86

  J6 SCONN288_ADR50017P087CC-SCONN2A
     3 P3V3_AUX @S9S_MB_2U_LIB.S9S_MB_2U(SCH_1):P3V3_AUX    I46 @S9S_MB_2U_LIB.S9S_MB_2U(SCH_1):PAGE87
     2 TP_CHC_CPU0_DIMM2_FRU_0 @S9S_MB_2U_LIB.S9S_MB_2U(SCH_1):TP_CHC_CPU0_DIMM2_FRU_0    I46 @S9S_MB_2U_LIB.S9S_MB_2U(SCH_1):PAGE87
   144 TP_CHC_CPU0_DIMM2_FRU_1 @S9S_MB_2U_LIB.S9S_MB_2U(SCH_1):TP_CHC_CPU0_DIMM2_FRU_1    I46 @S9S_MB_2U_LIB.S9S_MB_2U(SCH_1):PAGE87
   149 TP_CHC_CPU0_DIMM2_FRU_2 @S9S_MB_2U_LIB.S9S_MB_2U(SCH_1):TP_CHC_CPU0_DIMM2_FRU_2    I46 @S9S_MB_2U_LIB.S9S_MB_2U(SCH_1):PAGE87
   150 TP_CHC_CPU0_DIMM2_FRU_3 @S9S_MB_2U_LIB.S9S_MB_2U(SCH_1):TP_CHC_CPU0_DIMM2_FRU_3    I46 @S9S_MB_2U_LIB.S9S_MB_2U(SCH_1):PAGE87
   220 TP_CHC_CPU0_DIMM2_FRU_4 @S9S_MB_2U_LIB.S9S_MB_2U(SCH_1):TP_CHC_CPU0_DIMM2_FRU_4    I46 @S9S_MB_2U_LIB.S9S_MB_2U(SCH_1):PAGE87
   231 TP_CHC_CPU0_DIMM2_FRU_5 @S9S_MB_2U_LIB.S9S_MB_2U(SCH_1):TP_CHC_CPU0_DIMM2_FRU_5    I46 @S9S_MB_2U_LIB.S9S_MB_2U(SCH_1):PAGE87
   232 TP_CHC_CPU0_DIMM2_FRU_6 @S9S_MB_2U_LIB.S9S_MB_2U(SCH_1):TP_CHC_CPU0_DIMM2_FRU_6    I46 @S9S_MB_2U_LIB.S9S_MB_2U(SCH_1):PAGE87
   207 RST_M_CD_CPU0_FPGA_N @S9S_MB_2U_LIB.S9S_MB_2U(SCH_1):RST_M_CD_CPU0_FPGA_N    I46 @S9S_MB_2U_LIB.S9S_MB_2U(SCH_1):PAGE87
   147 PWRGD_CHC_CPU0_DIMM2 @S9S_MB_2U_LIB.S9S_MB_2U(SCH_1):PWRGD_CHC_CPU0_DIMM2    I46 @S9S_MB_2U_LIB.S9S_MB_2U(SCH_1):PAGE87
   227 M_C_CPU0_SB_PAR @S9S_MB_2U_LIB.S9S_MB_2U(SCH_1):M_C_CPU0_SB_PAR    I46 @S9S_MB_2U_LIB.S9S_MB_2U(SCH_1):PAGE87
    74 M_C_CPU0_SA_PAR @S9S_MB_2U_LIB.S9S_MB_2U(SCH_1):M_C_CPU0_SA_PAR    I46 @S9S_MB_2U_LIB.S9S_MB_2U(SCH_1):PAGE87
    87 M_C_CPU0_SB_RSP<1> @S9S_MB_2U_LIB.S9S_MB_2U(SCH_1):M_C_CPU0_SB_RSP(1)    I46 @S9S_MB_2U_LIB.S9S_MB_2U(SCH_1):PAGE87
    86 M_C_CPU0_SA_RSP<1> @S9S_MB_2U_LIB.S9S_MB_2U(SCH_1):M_C_CPU0_SA_RSP(1)    I46 @S9S_MB_2U_LIB.S9S_MB_2U(SCH_1):PAGE87
     5 I3C_SPD_DDRABCD_CPU0_LVC1_SDA @S9S_MB_2U_LIB.S9S_MB_2U(SCH_1):I3C_SPD_DDRABCD_CPU0_LVC1_SDA    I46 @S9S_MB_2U_LIB.S9S_MB_2U(SCH_1):PAGE87
     4 I3C_SPD_DDRABCD_CPU0_LVC1_SCL_5 @S9S_MB_2U_LIB.S9S_MB_2U(SCH_1):I3C_SPD_DDRABCD_CPU0_LVC1_SCL_R6    I46 @S9S_MB_2U_LIB.S9S_MB_2U(SCH_1):PAGE87
   148 PD_CHC_CPU0_DIMM2_SAA @S9S_MB_2U_LIB.S9S_MB_2U(SCH_1):PD_CHC_CPU0_DIMM2_SAA    I46 @S9S_MB_2U_LIB.S9S_MB_2U(SCH_1):PAGE87
   100 M_C_CPU0_SB_DQ<0> @S9S_MB_2U_LIB.S9S_MB_2U(SCH_1):M_C_CPU0_SB_DQ(0)    I46 @S9S_MB_2U_LIB.S9S_MB_2U(SCH_1):PAGE87
   102 M_C_CPU0_SB_DQ<1> @S9S_MB_2U_LIB.S9S_MB_2U(SCH_1):M_C_CPU0_SB_DQ(1)    I46 @S9S_MB_2U_LIB.S9S_MB_2U(SCH_1):PAGE87
   245 M_C_CPU0_SB_DQ<2> @S9S_MB_2U_LIB.S9S_MB_2U(SCH_1):M_C_CPU0_SB_DQ(2)    I46 @S9S_MB_2U_LIB.S9S_MB_2U(SCH_1):PAGE87
   247 M_C_CPU0_SB_DQ<3> @S9S_MB_2U_LIB.S9S_MB_2U(SCH_1):M_C_CPU0_SB_DQ(3)    I46 @S9S_MB_2U_LIB.S9S_MB_2U(SCH_1):PAGE87
   107 M_C_CPU0_SB_DQ<4> @S9S_MB_2U_LIB.S9S_MB_2U(SCH_1):M_C_CPU0_SB_DQ(4)    I46 @S9S_MB_2U_LIB.S9S_MB_2U(SCH_1):PAGE87
   109 M_C_CPU0_SB_DQ<5> @S9S_MB_2U_LIB.S9S_MB_2U(SCH_1):M_C_CPU0_SB_DQ(5)    I46 @S9S_MB_2U_LIB.S9S_MB_2U(SCH_1):PAGE87
   252 M_C_CPU0_SB_DQ<6> @S9S_MB_2U_LIB.S9S_MB_2U(SCH_1):M_C_CPU0_SB_DQ(6)    I46 @S9S_MB_2U_LIB.S9S_MB_2U(SCH_1):PAGE87
   254 M_C_CPU0_SB_DQ<7> @S9S_MB_2U_LIB.S9S_MB_2U(SCH_1):M_C_CPU0_SB_DQ(7)    I46 @S9S_MB_2U_LIB.S9S_MB_2U(SCH_1):PAGE87
   111 M_C_CPU0_SB_DQ<8> @S9S_MB_2U_LIB.S9S_MB_2U(SCH_1):M_C_CPU0_SB_DQ(8)    I46 @S9S_MB_2U_LIB.S9S_MB_2U(SCH_1):PAGE87
   113 M_C_CPU0_SB_DQ<9> @S9S_MB_2U_LIB.S9S_MB_2U(SCH_1):M_C_CPU0_SB_DQ(9)    I46 @S9S_MB_2U_LIB.S9S_MB_2U(SCH_1):PAGE87
   256 M_C_CPU0_SB_DQ<10> @S9S_MB_2U_LIB.S9S_MB_2U(SCH_1):M_C_CPU0_SB_DQ(10)    I46 @S9S_MB_2U_LIB.S9S_MB_2U(SCH_1):PAGE87
   258 M_C_CPU0_SB_DQ<11> @S9S_MB_2U_LIB.S9S_MB_2U(SCH_1):M_C_CPU0_SB_DQ(11)    I46 @S9S_MB_2U_LIB.S9S_MB_2U(SCH_1):PAGE87
   118 M_C_CPU0_SB_DQ<12> @S9S_MB_2U_LIB.S9S_MB_2U(SCH_1):M_C_CPU0_SB_DQ(12)    I46 @S9S_MB_2U_LIB.S9S_MB_2U(SCH_1):PAGE87
   120 M_C_CPU0_SB_DQ<13> @S9S_MB_2U_LIB.S9S_MB_2U(SCH_1):M_C_CPU0_SB_DQ(13)    I46 @S9S_MB_2U_LIB.S9S_MB_2U(SCH_1):PAGE87
   263 M_C_CPU0_SB_DQ<14> @S9S_MB_2U_LIB.S9S_MB_2U(SCH_1):M_C_CPU0_SB_DQ(14)    I46 @S9S_MB_2U_LIB.S9S_MB_2U(SCH_1):PAGE87
   265 M_C_CPU0_SB_DQ<15> @S9S_MB_2U_LIB.S9S_MB_2U(SCH_1):M_C_CPU0_SB_DQ(15)    I46 @S9S_MB_2U_LIB.S9S_MB_2U(SCH_1):PAGE87
   122 M_C_CPU0_SB_DQ<16> @S9S_MB_2U_LIB.S9S_MB_2U(SCH_1):M_C_CPU0_SB_DQ(16)    I46 @S9S_MB_2U_LIB.S9S_MB_2U(SCH_1):PAGE87
   124 M_C_CPU0_SB_DQ<17> @S9S_MB_2U_LIB.S9S_MB_2U(SCH_1):M_C_CPU0_SB_DQ(17)    I46 @S9S_MB_2U_LIB.S9S_MB_2U(SCH_1):PAGE87
   267 M_C_CPU0_SB_DQ<18> @S9S_MB_2U_LIB.S9S_MB_2U(SCH_1):M_C_CPU0_SB_DQ(18)    I46 @S9S_MB_2U_LIB.S9S_MB_2U(SCH_1):PAGE87
   269 M_C_CPU0_SB_DQ<19> @S9S_MB_2U_LIB.S9S_MB_2U(SCH_1):M_C_CPU0_SB_DQ(19)    I46 @S9S_MB_2U_LIB.S9S_MB_2U(SCH_1):PAGE87
   129 M_C_CPU0_SB_DQ<20> @S9S_MB_2U_LIB.S9S_MB_2U(SCH_1):M_C_CPU0_SB_DQ(20)    I46 @S9S_MB_2U_LIB.S9S_MB_2U(SCH_1):PAGE87
   131 M_C_CPU0_SB_DQ<21> @S9S_MB_2U_LIB.S9S_MB_2U(SCH_1):M_C_CPU0_SB_DQ(21)    I46 @S9S_MB_2U_LIB.S9S_MB_2U(SCH_1):PAGE87
   274 M_C_CPU0_SB_DQ<22> @S9S_MB_2U_LIB.S9S_MB_2U(SCH_1):M_C_CPU0_SB_DQ(22)    I46 @S9S_MB_2U_LIB.S9S_MB_2U(SCH_1):PAGE87
   276 M_C_CPU0_SB_DQ<23> @S9S_MB_2U_LIB.S9S_MB_2U(SCH_1):M_C_CPU0_SB_DQ(23)    I46 @S9S_MB_2U_LIB.S9S_MB_2U(SCH_1):PAGE87
   133 M_C_CPU0_SB_DQ<24> @S9S_MB_2U_LIB.S9S_MB_2U(SCH_1):M_C_CPU0_SB_DQ(24)    I46 @S9S_MB_2U_LIB.S9S_MB_2U(SCH_1):PAGE87
   135 M_C_CPU0_SB_DQ<25> @S9S_MB_2U_LIB.S9S_MB_2U(SCH_1):M_C_CPU0_SB_DQ(25)    I46 @S9S_MB_2U_LIB.S9S_MB_2U(SCH_1):PAGE87
   278 M_C_CPU0_SB_DQ<26> @S9S_MB_2U_LIB.S9S_MB_2U(SCH_1):M_C_CPU0_SB_DQ(26)    I46 @S9S_MB_2U_LIB.S9S_MB_2U(SCH_1):PAGE87
   280 M_C_CPU0_SB_DQ<27> @S9S_MB_2U_LIB.S9S_MB_2U(SCH_1):M_C_CPU0_SB_DQ(27)    I46 @S9S_MB_2U_LIB.S9S_MB_2U(SCH_1):PAGE87
   140 M_C_CPU0_SB_DQ<28> @S9S_MB_2U_LIB.S9S_MB_2U(SCH_1):M_C_CPU0_SB_DQ(28)    I46 @S9S_MB_2U_LIB.S9S_MB_2U(SCH_1):PAGE87
   142 M_C_CPU0_SB_DQ<29> @S9S_MB_2U_LIB.S9S_MB_2U(SCH_1):M_C_CPU0_SB_DQ(29)    I46 @S9S_MB_2U_LIB.S9S_MB_2U(SCH_1):PAGE87
   285 M_C_CPU0_SB_DQ<30> @S9S_MB_2U_LIB.S9S_MB_2U(SCH_1):M_C_CPU0_SB_DQ(30)    I46 @S9S_MB_2U_LIB.S9S_MB_2U(SCH_1):PAGE87
   287 M_C_CPU0_SB_DQ<31> @S9S_MB_2U_LIB.S9S_MB_2U(SCH_1):M_C_CPU0_SB_DQ(31)    I46 @S9S_MB_2U_LIB.S9S_MB_2U(SCH_1):PAGE87
     7 M_C_CPU0_SA_DQ<0> @S9S_MB_2U_LIB.S9S_MB_2U(SCH_1):M_C_CPU0_SA_DQ(0)    I46 @S9S_MB_2U_LIB.S9S_MB_2U(SCH_1):PAGE87
     9 M_C_CPU0_SA_DQ<1> @S9S_MB_2U_LIB.S9S_MB_2U(SCH_1):M_C_CPU0_SA_DQ(1)    I46 @S9S_MB_2U_LIB.S9S_MB_2U(SCH_1):PAGE87
   152 M_C_CPU0_SA_DQ<2> @S9S_MB_2U_LIB.S9S_MB_2U(SCH_1):M_C_CPU0_SA_DQ(2)    I46 @S9S_MB_2U_LIB.S9S_MB_2U(SCH_1):PAGE87
   154 M_C_CPU0_SA_DQ<3> @S9S_MB_2U_LIB.S9S_MB_2U(SCH_1):M_C_CPU0_SA_DQ(3)    I46 @S9S_MB_2U_LIB.S9S_MB_2U(SCH_1):PAGE87
    14 M_C_CPU0_SA_DQ<4> @S9S_MB_2U_LIB.S9S_MB_2U(SCH_1):M_C_CPU0_SA_DQ(4)    I46 @S9S_MB_2U_LIB.S9S_MB_2U(SCH_1):PAGE87
    16 M_C_CPU0_SA_DQ<5> @S9S_MB_2U_LIB.S9S_MB_2U(SCH_1):M_C_CPU0_SA_DQ(5)    I46 @S9S_MB_2U_LIB.S9S_MB_2U(SCH_1):PAGE87
   159 M_C_CPU0_SA_DQ<6> @S9S_MB_2U_LIB.S9S_MB_2U(SCH_1):M_C_CPU0_SA_DQ(6)    I46 @S9S_MB_2U_LIB.S9S_MB_2U(SCH_1):PAGE87
   161 M_C_CPU0_SA_DQ<7> @S9S_MB_2U_LIB.S9S_MB_2U(SCH_1):M_C_CPU0_SA_DQ(7)    I46 @S9S_MB_2U_LIB.S9S_MB_2U(SCH_1):PAGE87
    18 M_C_CPU0_SA_DQ<8> @S9S_MB_2U_LIB.S9S_MB_2U(SCH_1):M_C_CPU0_SA_DQ(8)    I46 @S9S_MB_2U_LIB.S9S_MB_2U(SCH_1):PAGE87
    20 M_C_CPU0_SA_DQ<9> @S9S_MB_2U_LIB.S9S_MB_2U(SCH_1):M_C_CPU0_SA_DQ(9)    I46 @S9S_MB_2U_LIB.S9S_MB_2U(SCH_1):PAGE87
   163 M_C_CPU0_SA_DQ<10> @S9S_MB_2U_LIB.S9S_MB_2U(SCH_1):M_C_CPU0_SA_DQ(10)    I46 @S9S_MB_2U_LIB.S9S_MB_2U(SCH_1):PAGE87
   165 M_C_CPU0_SA_DQ<11> @S9S_MB_2U_LIB.S9S_MB_2U(SCH_1):M_C_CPU0_SA_DQ(11)    I46 @S9S_MB_2U_LIB.S9S_MB_2U(SCH_1):PAGE87
    25 M_C_CPU0_SA_DQ<12> @S9S_MB_2U_LIB.S9S_MB_2U(SCH_1):M_C_CPU0_SA_DQ(12)    I46 @S9S_MB_2U_LIB.S9S_MB_2U(SCH_1):PAGE87
    27 M_C_CPU0_SA_DQ<13> @S9S_MB_2U_LIB.S9S_MB_2U(SCH_1):M_C_CPU0_SA_DQ(13)    I46 @S9S_MB_2U_LIB.S9S_MB_2U(SCH_1):PAGE87
   170 M_C_CPU0_SA_DQ<14> @S9S_MB_2U_LIB.S9S_MB_2U(SCH_1):M_C_CPU0_SA_DQ(14)    I46 @S9S_MB_2U_LIB.S9S_MB_2U(SCH_1):PAGE87
   172 M_C_CPU0_SA_DQ<15> @S9S_MB_2U_LIB.S9S_MB_2U(SCH_1):M_C_CPU0_SA_DQ(15)    I46 @S9S_MB_2U_LIB.S9S_MB_2U(SCH_1):PAGE87
    29 M_C_CPU0_SA_DQ<16> @S9S_MB_2U_LIB.S9S_MB_2U(SCH_1):M_C_CPU0_SA_DQ(16)    I46 @S9S_MB_2U_LIB.S9S_MB_2U(SCH_1):PAGE87
    31 M_C_CPU0_SA_DQ<17> @S9S_MB_2U_LIB.S9S_MB_2U(SCH_1):M_C_CPU0_SA_DQ(17)    I46 @S9S_MB_2U_LIB.S9S_MB_2U(SCH_1):PAGE87
   174 M_C_CPU0_SA_DQ<18> @S9S_MB_2U_LIB.S9S_MB_2U(SCH_1):M_C_CPU0_SA_DQ(18)    I46 @S9S_MB_2U_LIB.S9S_MB_2U(SCH_1):PAGE87
   176 M_C_CPU0_SA_DQ<19> @S9S_MB_2U_LIB.S9S_MB_2U(SCH_1):M_C_CPU0_SA_DQ(19)    I46 @S9S_MB_2U_LIB.S9S_MB_2U(SCH_1):PAGE87
    36 M_C_CPU0_SA_DQ<20> @S9S_MB_2U_LIB.S9S_MB_2U(SCH_1):M_C_CPU0_SA_DQ(20)    I46 @S9S_MB_2U_LIB.S9S_MB_2U(SCH_1):PAGE87
    38 M_C_CPU0_SA_DQ<21> @S9S_MB_2U_LIB.S9S_MB_2U(SCH_1):M_C_CPU0_SA_DQ(21)    I46 @S9S_MB_2U_LIB.S9S_MB_2U(SCH_1):PAGE87
   181 M_C_CPU0_SA_DQ<22> @S9S_MB_2U_LIB.S9S_MB_2U(SCH_1):M_C_CPU0_SA_DQ(22)    I46 @S9S_MB_2U_LIB.S9S_MB_2U(SCH_1):PAGE87
   183 M_C_CPU0_SA_DQ<23> @S9S_MB_2U_LIB.S9S_MB_2U(SCH_1):M_C_CPU0_SA_DQ(23)    I46 @S9S_MB_2U_LIB.S9S_MB_2U(SCH_1):PAGE87
    40 M_C_CPU0_SA_DQ<24> @S9S_MB_2U_LIB.S9S_MB_2U(SCH_1):M_C_CPU0_SA_DQ(24)    I46 @S9S_MB_2U_LIB.S9S_MB_2U(SCH_1):PAGE87
    42 M_C_CPU0_SA_DQ<25> @S9S_MB_2U_LIB.S9S_MB_2U(SCH_1):M_C_CPU0_SA_DQ(25)    I46 @S9S_MB_2U_LIB.S9S_MB_2U(SCH_1):PAGE87
   185 M_C_CPU0_SA_DQ<26> @S9S_MB_2U_LIB.S9S_MB_2U(SCH_1):M_C_CPU0_SA_DQ(26)    I46 @S9S_MB_2U_LIB.S9S_MB_2U(SCH_1):PAGE87
   187 M_C_CPU0_SA_DQ<27> @S9S_MB_2U_LIB.S9S_MB_2U(SCH_1):M_C_CPU0_SA_DQ(27)    I46 @S9S_MB_2U_LIB.S9S_MB_2U(SCH_1):PAGE87
    47 M_C_CPU0_SA_DQ<28> @S9S_MB_2U_LIB.S9S_MB_2U(SCH_1):M_C_CPU0_SA_DQ(28)    I46 @S9S_MB_2U_LIB.S9S_MB_2U(SCH_1):PAGE87
    49 M_C_CPU0_SA_DQ<29> @S9S_MB_2U_LIB.S9S_MB_2U(SCH_1):M_C_CPU0_SA_DQ(29)    I46 @S9S_MB_2U_LIB.S9S_MB_2U(SCH_1):PAGE87
   192 M_C_CPU0_SA_DQ<30> @S9S_MB_2U_LIB.S9S_MB_2U(SCH_1):M_C_CPU0_SA_DQ(30)    I46 @S9S_MB_2U_LIB.S9S_MB_2U(SCH_1):PAGE87
   229 M_C_CPU0_SB_CS_N<3> @S9S_MB_2U_LIB.S9S_MB_2U(SCH_1):M_C_CPU0_SB_CS_N(3)    I46 @S9S_MB_2U_LIB.S9S_MB_2U(SCH_1):PAGE87
   209 M_C_CPU0_SA_CS_N<3> @S9S_MB_2U_LIB.S9S_MB_2U(SCH_1):M_C_CPU0_SA_CS_N(3)    I46 @S9S_MB_2U_LIB.S9S_MB_2U(SCH_1):PAGE87
    84 M_C_CPU0_SB_CS_N<2> @S9S_MB_2U_LIB.S9S_MB_2U(SCH_1):M_C_CPU0_SB_CS_N(2)    I46 @S9S_MB_2U_LIB.S9S_MB_2U(SCH_1):PAGE87
    64 M_C_CPU0_SA_CS_N<2> @S9S_MB_2U_LIB.S9S_MB_2U(SCH_1):M_C_CPU0_SA_CS_N(2)    I46 @S9S_MB_2U_LIB.S9S_MB_2U(SCH_1):PAGE87
   217 M_C_CPU0_CLK_DP<1> @S9S_MB_2U_LIB.S9S_MB_2U(SCH_1):M_C_CPU0_CLK_DP(1)    I46 @S9S_MB_2U_LIB.S9S_MB_2U(SCH_1):PAGE87
   218 M_C_CPU0_CLK_DN<1> @S9S_MB_2U_LIB.S9S_MB_2U(SCH_1):M_C_CPU0_CLK_DN(1)    I46 @S9S_MB_2U_LIB.S9S_MB_2U(SCH_1):PAGE87
    96 M_C_CPU0_SB_CB<0> @S9S_MB_2U_LIB.S9S_MB_2U(SCH_1):M_C_CPU0_SB_CB(0)    I46 @S9S_MB_2U_LIB.S9S_MB_2U(SCH_1):PAGE87
    98 M_C_CPU0_SB_CB<1> @S9S_MB_2U_LIB.S9S_MB_2U(SCH_1):M_C_CPU0_SB_CB(1)    I46 @S9S_MB_2U_LIB.S9S_MB_2U(SCH_1):PAGE87
   241 M_C_CPU0_SB_CB<2> @S9S_MB_2U_LIB.S9S_MB_2U(SCH_1):M_C_CPU0_SB_CB(2)    I46 @S9S_MB_2U_LIB.S9S_MB_2U(SCH_1):PAGE87
   243 M_C_CPU0_SB_CB<3> @S9S_MB_2U_LIB.S9S_MB_2U(SCH_1):M_C_CPU0_SB_CB(3)    I46 @S9S_MB_2U_LIB.S9S_MB_2U(SCH_1):PAGE87
    89 M_C_CPU0_SB_CB<4> @S9S_MB_2U_LIB.S9S_MB_2U(SCH_1):M_C_CPU0_SB_CB(4)    I46 @S9S_MB_2U_LIB.S9S_MB_2U(SCH_1):PAGE87
    91 M_C_CPU0_SB_CB<5> @S9S_MB_2U_LIB.S9S_MB_2U(SCH_1):M_C_CPU0_SB_CB(5)    I46 @S9S_MB_2U_LIB.S9S_MB_2U(SCH_1):PAGE87
   234 M_C_CPU0_SB_CB<6> @S9S_MB_2U_LIB.S9S_MB_2U(SCH_1):M_C_CPU0_SB_CB(6)    I46 @S9S_MB_2U_LIB.S9S_MB_2U(SCH_1):PAGE87
    51 M_C_CPU0_SA_CB<0> @S9S_MB_2U_LIB.S9S_MB_2U(SCH_1):M_C_CPU0_SA_CB(0)    I46 @S9S_MB_2U_LIB.S9S_MB_2U(SCH_1):PAGE87
   196 M_C_CPU0_SA_CB<2> @S9S_MB_2U_LIB.S9S_MB_2U(SCH_1):M_C_CPU0_SA_CB(2)    I46 @S9S_MB_2U_LIB.S9S_MB_2U(SCH_1):PAGE87
   198 M_C_CPU0_SA_CB<3> @S9S_MB_2U_LIB.S9S_MB_2U(SCH_1):M_C_CPU0_SA_CB(3)    I46 @S9S_MB_2U_LIB.S9S_MB_2U(SCH_1):PAGE87
    60 M_C_CPU0_SA_CB<5> @S9S_MB_2U_LIB.S9S_MB_2U(SCH_1):M_C_CPU0_SA_CB(5)    I46 @S9S_MB_2U_LIB.S9S_MB_2U(SCH_1):PAGE87
   203 M_C_CPU0_SA_CB<6> @S9S_MB_2U_LIB.S9S_MB_2U(SCH_1):M_C_CPU0_SA_CB(6)    I46 @S9S_MB_2U_LIB.S9S_MB_2U(SCH_1):PAGE87
    82 M_C_CPU0_SB_CA<6> @S9S_MB_2U_LIB.S9S_MB_2U(SCH_1):M_C_CPU0_SB_CA(6)    I46 @S9S_MB_2U_LIB.S9S_MB_2U(SCH_1):PAGE87
    72 M_C_CPU0_SA_CA<6> @S9S_MB_2U_LIB.S9S_MB_2U(SCH_1):M_C_CPU0_SA_CA(6)    I46 @S9S_MB_2U_LIB.S9S_MB_2U(SCH_1):PAGE87
   225 M_C_CPU0_SB_CA<5> @S9S_MB_2U_LIB.S9S_MB_2U(SCH_1):M_C_CPU0_SB_CA(5)    I46 @S9S_MB_2U_LIB.S9S_MB_2U(SCH_1):PAGE87
   215 M_C_CPU0_SA_CA<5> @S9S_MB_2U_LIB.S9S_MB_2U(SCH_1):M_C_CPU0_SA_CA(5)    I46 @S9S_MB_2U_LIB.S9S_MB_2U(SCH_1):PAGE87
    80 M_C_CPU0_SB_CA<4> @S9S_MB_2U_LIB.S9S_MB_2U(SCH_1):M_C_CPU0_SB_CA(4)    I46 @S9S_MB_2U_LIB.S9S_MB_2U(SCH_1):PAGE87
    70 M_C_CPU0_SA_CA<4> @S9S_MB_2U_LIB.S9S_MB_2U(SCH_1):M_C_CPU0_SA_CA(4)    I46 @S9S_MB_2U_LIB.S9S_MB_2U(SCH_1):PAGE87
   223 M_C_CPU0_SB_CA<3> @S9S_MB_2U_LIB.S9S_MB_2U(SCH_1):M_C_CPU0_SB_CA(3)    I46 @S9S_MB_2U_LIB.S9S_MB_2U(SCH_1):PAGE87
   213 M_C_CPU0_SA_CA<3> @S9S_MB_2U_LIB.S9S_MB_2U(SCH_1):M_C_CPU0_SA_CA(3)    I46 @S9S_MB_2U_LIB.S9S_MB_2U(SCH_1):PAGE87
    78 M_C_CPU0_SB_CA<2> @S9S_MB_2U_LIB.S9S_MB_2U(SCH_1):M_C_CPU0_SB_CA(2)    I46 @S9S_MB_2U_LIB.S9S_MB_2U(SCH_1):PAGE87
    68 M_C_CPU0_SA_CA<2> @S9S_MB_2U_LIB.S9S_MB_2U(SCH_1):M_C_CPU0_SA_CA(2)    I46 @S9S_MB_2U_LIB.S9S_MB_2U(SCH_1):PAGE87
   221 M_C_CPU0_SB_CA<1> @S9S_MB_2U_LIB.S9S_MB_2U(SCH_1):M_C_CPU0_SB_CA(1)    I46 @S9S_MB_2U_LIB.S9S_MB_2U(SCH_1):PAGE87
   211 M_C_CPU0_SA_CA<1> @S9S_MB_2U_LIB.S9S_MB_2U(SCH_1):M_C_CPU0_SA_CA(1)    I46 @S9S_MB_2U_LIB.S9S_MB_2U(SCH_1):PAGE87
    76 M_C_CPU0_SB_CA<0> @S9S_MB_2U_LIB.S9S_MB_2U(SCH_1):M_C_CPU0_SB_CA(0)    I46 @S9S_MB_2U_LIB.S9S_MB_2U(SCH_1):PAGE87
    66 M_C_CPU0_SA_CA<0> @S9S_MB_2U_LIB.S9S_MB_2U(SCH_1):M_C_CPU0_SA_CA(0)    I46 @S9S_MB_2U_LIB.S9S_MB_2U(SCH_1):PAGE87
    62 M_C_CPU0_ALERT_N @S9S_MB_2U_LIB.S9S_MB_2U(SCH_1):M_C_CPU0_ALERT_N    I46 @S9S_MB_2U_LIB.S9S_MB_2U(SCH_1):PAGE87
   236 M_C_CPU0_SB_CB<7> @S9S_MB_2U_LIB.S9S_MB_2U(SCH_1):M_C_CPU0_SB_CB(7)    I46 @S9S_MB_2U_LIB.S9S_MB_2U(SCH_1):PAGE87
    53 M_C_CPU0_SA_CB<1> @S9S_MB_2U_LIB.S9S_MB_2U(SCH_1):M_C_CPU0_SA_CB(1)    I46 @S9S_MB_2U_LIB.S9S_MB_2U(SCH_1):PAGE87
    58 M_C_CPU0_SA_CB<4> @S9S_MB_2U_LIB.S9S_MB_2U(SCH_1):M_C_CPU0_SA_CB(4)    I46 @S9S_MB_2U_LIB.S9S_MB_2U(SCH_1):PAGE87
   205 M_C_CPU0_SA_CB<7> @S9S_MB_2U_LIB.S9S_MB_2U(SCH_1):M_C_CPU0_SA_CB(7)    I46 @S9S_MB_2U_LIB.S9S_MB_2U(SCH_1):PAGE87
   194 M_C_CPU0_SA_DQ<31> @S9S_MB_2U_LIB.S9S_MB_2U(SCH_1):M_C_CPU0_SA_DQ(31)    I46 @S9S_MB_2U_LIB.S9S_MB_2U(SCH_1):PAGE87
    93 M_C_CPU0_SB_DQS_DP<9> @S9S_MB_2U_LIB.S9S_MB_2U(SCH_1):M_C_CPU0_SB_DQS_DP(9)   I178 @S9S_MB_2U_LIB.S9S_MB_2U(SCH_1):PAGE87
    94 M_C_CPU0_SB_DQS_DN<9> @S9S_MB_2U_LIB.S9S_MB_2U(SCH_1):M_C_CPU0_SB_DQS_DN(9)   I178 @S9S_MB_2U_LIB.S9S_MB_2U(SCH_1):PAGE87
   201 M_C_CPU0_SA_DQS_DP<9> @S9S_MB_2U_LIB.S9S_MB_2U(SCH_1):M_C_CPU0_SA_DQS_DP(9)   I178 @S9S_MB_2U_LIB.S9S_MB_2U(SCH_1):PAGE87
   200 M_C_CPU0_SA_DQS_DN<9> @S9S_MB_2U_LIB.S9S_MB_2U(SCH_1):M_C_CPU0_SA_DQS_DN(9)   I178 @S9S_MB_2U_LIB.S9S_MB_2U(SCH_1):PAGE87
   190 M_C_CPU0_SA_DQS_DP<8> @S9S_MB_2U_LIB.S9S_MB_2U(SCH_1):M_C_CPU0_SA_DQS_DP(8)   I178 @S9S_MB_2U_LIB.S9S_MB_2U(SCH_1):PAGE87
   189 M_C_CPU0_SA_DQS_DN<8> @S9S_MB_2U_LIB.S9S_MB_2U(SCH_1):M_C_CPU0_SA_DQS_DN(8)   I178 @S9S_MB_2U_LIB.S9S_MB_2U(SCH_1):PAGE87
   271 M_C_CPU0_SB_DQS_DN<7> @S9S_MB_2U_LIB.S9S_MB_2U(SCH_1):M_C_CPU0_SB_DQS_DN(7)   I178 @S9S_MB_2U_LIB.S9S_MB_2U(SCH_1):PAGE87
   179 M_C_CPU0_SA_DQS_DP<7> @S9S_MB_2U_LIB.S9S_MB_2U(SCH_1):M_C_CPU0_SA_DQS_DP(7)   I178 @S9S_MB_2U_LIB.S9S_MB_2U(SCH_1):PAGE87
   261 M_C_CPU0_SB_DQS_DP<6> @S9S_MB_2U_LIB.S9S_MB_2U(SCH_1):M_C_CPU0_SB_DQS_DP(6)   I178 @S9S_MB_2U_LIB.S9S_MB_2U(SCH_1):PAGE87
   260 M_C_CPU0_SB_DQS_DN<6> @S9S_MB_2U_LIB.S9S_MB_2U(SCH_1):M_C_CPU0_SB_DQS_DN(6)   I178 @S9S_MB_2U_LIB.S9S_MB_2U(SCH_1):PAGE87
   167 M_C_CPU0_SA_DQS_DN<6> @S9S_MB_2U_LIB.S9S_MB_2U(SCH_1):M_C_CPU0_SA_DQS_DN(6)   I178 @S9S_MB_2U_LIB.S9S_MB_2U(SCH_1):PAGE87
   250 M_C_CPU0_SB_DQS_DP<5> @S9S_MB_2U_LIB.S9S_MB_2U(SCH_1):M_C_CPU0_SB_DQS_DP(5)   I178 @S9S_MB_2U_LIB.S9S_MB_2U(SCH_1):PAGE87
   249 M_C_CPU0_SB_DQS_DN<5> @S9S_MB_2U_LIB.S9S_MB_2U(SCH_1):M_C_CPU0_SB_DQS_DN(5)   I178 @S9S_MB_2U_LIB.S9S_MB_2U(SCH_1):PAGE87
   157 M_C_CPU0_SA_DQS_DP<5> @S9S_MB_2U_LIB.S9S_MB_2U(SCH_1):M_C_CPU0_SA_DQS_DP(5)   I178 @S9S_MB_2U_LIB.S9S_MB_2U(SCH_1):PAGE87
   156 M_C_CPU0_SA_DQS_DN<5> @S9S_MB_2U_LIB.S9S_MB_2U(SCH_1):M_C_CPU0_SA_DQS_DN(5)   I178 @S9S_MB_2U_LIB.S9S_MB_2U(SCH_1):PAGE87
   239 M_C_CPU0_SB_DQS_DP<4> @S9S_MB_2U_LIB.S9S_MB_2U(SCH_1):M_C_CPU0_SB_DQS_DP(4)   I178 @S9S_MB_2U_LIB.S9S_MB_2U(SCH_1):PAGE87
   238 M_C_CPU0_SB_DQS_DN<4> @S9S_MB_2U_LIB.S9S_MB_2U(SCH_1):M_C_CPU0_SB_DQS_DN(4)   I178 @S9S_MB_2U_LIB.S9S_MB_2U(SCH_1):PAGE87
    55 M_C_CPU0_SA_DQS_DP<4> @S9S_MB_2U_LIB.S9S_MB_2U(SCH_1):M_C_CPU0_SA_DQS_DP(4)   I178 @S9S_MB_2U_LIB.S9S_MB_2U(SCH_1):PAGE87
    56 M_C_CPU0_SA_DQS_DN<4> @S9S_MB_2U_LIB.S9S_MB_2U(SCH_1):M_C_CPU0_SA_DQS_DN(4)   I178 @S9S_MB_2U_LIB.S9S_MB_2U(SCH_1):PAGE87
   137 M_C_CPU0_SB_DQS_DP<3> @S9S_MB_2U_LIB.S9S_MB_2U(SCH_1):M_C_CPU0_SB_DQS_DP(3)   I178 @S9S_MB_2U_LIB.S9S_MB_2U(SCH_1):PAGE87
   138 M_C_CPU0_SB_DQS_DN<3> @S9S_MB_2U_LIB.S9S_MB_2U(SCH_1):M_C_CPU0_SB_DQS_DN(3)   I178 @S9S_MB_2U_LIB.S9S_MB_2U(SCH_1):PAGE87
    44 M_C_CPU0_SA_DQS_DP<3> @S9S_MB_2U_LIB.S9S_MB_2U(SCH_1):M_C_CPU0_SA_DQS_DP(3)   I178 @S9S_MB_2U_LIB.S9S_MB_2U(SCH_1):PAGE87
    45 M_C_CPU0_SA_DQS_DN<3> @S9S_MB_2U_LIB.S9S_MB_2U(SCH_1):M_C_CPU0_SA_DQS_DN(3)   I178 @S9S_MB_2U_LIB.S9S_MB_2U(SCH_1):PAGE87
   126 M_C_CPU0_SB_DQS_DP<2> @S9S_MB_2U_LIB.S9S_MB_2U(SCH_1):M_C_CPU0_SB_DQS_DP(2)   I178 @S9S_MB_2U_LIB.S9S_MB_2U(SCH_1):PAGE87
   127 M_C_CPU0_SB_DQS_DN<2> @S9S_MB_2U_LIB.S9S_MB_2U(SCH_1):M_C_CPU0_SB_DQS_DN(2)   I178 @S9S_MB_2U_LIB.S9S_MB_2U(SCH_1):PAGE87
    33 M_C_CPU0_SA_DQS_DP<2> @S9S_MB_2U_LIB.S9S_MB_2U(SCH_1):M_C_CPU0_SA_DQS_DP(2)   I178 @S9S_MB_2U_LIB.S9S_MB_2U(SCH_1):PAGE87
    34 M_C_CPU0_SA_DQS_DN<2> @S9S_MB_2U_LIB.S9S_MB_2U(SCH_1):M_C_CPU0_SA_DQS_DN(2)   I178 @S9S_MB_2U_LIB.S9S_MB_2U(SCH_1):PAGE87
   115 M_C_CPU0_SB_DQS_DP<1> @S9S_MB_2U_LIB.S9S_MB_2U(SCH_1):M_C_CPU0_SB_DQS_DP(1)   I178 @S9S_MB_2U_LIB.S9S_MB_2U(SCH_1):PAGE87
   116 M_C_CPU0_SB_DQS_DN<1> @S9S_MB_2U_LIB.S9S_MB_2U(SCH_1):M_C_CPU0_SB_DQS_DN(1)   I178 @S9S_MB_2U_LIB.S9S_MB_2U(SCH_1):PAGE87
    22 M_C_CPU0_SA_DQS_DP<1> @S9S_MB_2U_LIB.S9S_MB_2U(SCH_1):M_C_CPU0_SA_DQS_DP(1)   I178 @S9S_MB_2U_LIB.S9S_MB_2U(SCH_1):PAGE87
    23 M_C_CPU0_SA_DQS_DN<1> @S9S_MB_2U_LIB.S9S_MB_2U(SCH_1):M_C_CPU0_SA_DQS_DN(1)   I178 @S9S_MB_2U_LIB.S9S_MB_2U(SCH_1):PAGE87
   104 M_C_CPU0_SB_DQS_DP<0> @S9S_MB_2U_LIB.S9S_MB_2U(SCH_1):M_C_CPU0_SB_DQS_DP(0)   I178 @S9S_MB_2U_LIB.S9S_MB_2U(SCH_1):PAGE87
   105 M_C_CPU0_SB_DQS_DN<0> @S9S_MB_2U_LIB.S9S_MB_2U(SCH_1):M_C_CPU0_SB_DQS_DN(0)   I178 @S9S_MB_2U_LIB.S9S_MB_2U(SCH_1):PAGE87
    11 M_C_CPU0_SA_DQS_DP<0> @S9S_MB_2U_LIB.S9S_MB_2U(SCH_1):M_C_CPU0_SA_DQS_DP(0)   I178 @S9S_MB_2U_LIB.S9S_MB_2U(SCH_1):PAGE87
    12 M_C_CPU0_SA_DQS_DN<0> @S9S_MB_2U_LIB.S9S_MB_2U(SCH_1):M_C_CPU0_SA_DQS_DN(0)   I178 @S9S_MB_2U_LIB.S9S_MB_2U(SCH_1):PAGE87
   272 M_C_CPU0_SB_DQS_DP<7> @S9S_MB_2U_LIB.S9S_MB_2U(SCH_1):M_C_CPU0_SB_DQS_DP(7)   I178 @S9S_MB_2U_LIB.S9S_MB_2U(SCH_1):PAGE87
   282 M_C_CPU0_SB_DQS_DN<8> @S9S_MB_2U_LIB.S9S_MB_2U(SCH_1):M_C_CPU0_SB_DQS_DN(8)   I178 @S9S_MB_2U_LIB.S9S_MB_2U(SCH_1):PAGE87
   283 M_C_CPU0_SB_DQS_DP<8> @S9S_MB_2U_LIB.S9S_MB_2U(SCH_1):M_C_CPU0_SB_DQS_DP(8)   I178 @S9S_MB_2U_LIB.S9S_MB_2U(SCH_1):PAGE87
   168 M_C_CPU0_SA_DQS_DP<6> @S9S_MB_2U_LIB.S9S_MB_2U(SCH_1):M_C_CPU0_SA_DQS_DP(6)   I178 @S9S_MB_2U_LIB.S9S_MB_2U(SCH_1):PAGE87
   178 M_C_CPU0_SA_DQS_DN<7> @S9S_MB_2U_LIB.S9S_MB_2U(SCH_1):M_C_CPU0_SA_DQS_DN(7)   I178 @S9S_MB_2U_LIB.S9S_MB_2U(SCH_1):PAGE87
     6    GND @S9S_MB_2U_LIB.S9S_MB_2U(SCH_1):GND   I175 @S9S_MB_2U_LIB.S9S_MB_2U(SCH_1):PAGE87
     8    GND @S9S_MB_2U_LIB.S9S_MB_2U(SCH_1):GND   I175 @S9S_MB_2U_LIB.S9S_MB_2U(SCH_1):PAGE87
    10    GND @S9S_MB_2U_LIB.S9S_MB_2U(SCH_1):GND   I175 @S9S_MB_2U_LIB.S9S_MB_2U(SCH_1):PAGE87
    13    GND @S9S_MB_2U_LIB.S9S_MB_2U(SCH_1):GND   I175 @S9S_MB_2U_LIB.S9S_MB_2U(SCH_1):PAGE87
    15    GND @S9S_MB_2U_LIB.S9S_MB_2U(SCH_1):GND   I175 @S9S_MB_2U_LIB.S9S_MB_2U(SCH_1):PAGE87
    17    GND @S9S_MB_2U_LIB.S9S_MB_2U(SCH_1):GND   I175 @S9S_MB_2U_LIB.S9S_MB_2U(SCH_1):PAGE87
    19    GND @S9S_MB_2U_LIB.S9S_MB_2U(SCH_1):GND   I175 @S9S_MB_2U_LIB.S9S_MB_2U(SCH_1):PAGE87
    21    GND @S9S_MB_2U_LIB.S9S_MB_2U(SCH_1):GND   I175 @S9S_MB_2U_LIB.S9S_MB_2U(SCH_1):PAGE87
    24    GND @S9S_MB_2U_LIB.S9S_MB_2U(SCH_1):GND   I175 @S9S_MB_2U_LIB.S9S_MB_2U(SCH_1):PAGE87
    26    GND @S9S_MB_2U_LIB.S9S_MB_2U(SCH_1):GND   I175 @S9S_MB_2U_LIB.S9S_MB_2U(SCH_1):PAGE87
    28    GND @S9S_MB_2U_LIB.S9S_MB_2U(SCH_1):GND   I175 @S9S_MB_2U_LIB.S9S_MB_2U(SCH_1):PAGE87
    30    GND @S9S_MB_2U_LIB.S9S_MB_2U(SCH_1):GND   I175 @S9S_MB_2U_LIB.S9S_MB_2U(SCH_1):PAGE87
    32    GND @S9S_MB_2U_LIB.S9S_MB_2U(SCH_1):GND   I175 @S9S_MB_2U_LIB.S9S_MB_2U(SCH_1):PAGE87
    35    GND @S9S_MB_2U_LIB.S9S_MB_2U(SCH_1):GND   I175 @S9S_MB_2U_LIB.S9S_MB_2U(SCH_1):PAGE87
    37    GND @S9S_MB_2U_LIB.S9S_MB_2U(SCH_1):GND   I175 @S9S_MB_2U_LIB.S9S_MB_2U(SCH_1):PAGE87
    39    GND @S9S_MB_2U_LIB.S9S_MB_2U(SCH_1):GND   I175 @S9S_MB_2U_LIB.S9S_MB_2U(SCH_1):PAGE87
    41    GND @S9S_MB_2U_LIB.S9S_MB_2U(SCH_1):GND   I175 @S9S_MB_2U_LIB.S9S_MB_2U(SCH_1):PAGE87
    43    GND @S9S_MB_2U_LIB.S9S_MB_2U(SCH_1):GND   I175 @S9S_MB_2U_LIB.S9S_MB_2U(SCH_1):PAGE87
    46    GND @S9S_MB_2U_LIB.S9S_MB_2U(SCH_1):GND   I175 @S9S_MB_2U_LIB.S9S_MB_2U(SCH_1):PAGE87
    48    GND @S9S_MB_2U_LIB.S9S_MB_2U(SCH_1):GND   I175 @S9S_MB_2U_LIB.S9S_MB_2U(SCH_1):PAGE87
    50    GND @S9S_MB_2U_LIB.S9S_MB_2U(SCH_1):GND   I175 @S9S_MB_2U_LIB.S9S_MB_2U(SCH_1):PAGE87
    52    GND @S9S_MB_2U_LIB.S9S_MB_2U(SCH_1):GND   I175 @S9S_MB_2U_LIB.S9S_MB_2U(SCH_1):PAGE87
    54    GND @S9S_MB_2U_LIB.S9S_MB_2U(SCH_1):GND   I175 @S9S_MB_2U_LIB.S9S_MB_2U(SCH_1):PAGE87
    57    GND @S9S_MB_2U_LIB.S9S_MB_2U(SCH_1):GND   I175 @S9S_MB_2U_LIB.S9S_MB_2U(SCH_1):PAGE87
    59    GND @S9S_MB_2U_LIB.S9S_MB_2U(SCH_1):GND   I175 @S9S_MB_2U_LIB.S9S_MB_2U(SCH_1):PAGE87
    61    GND @S9S_MB_2U_LIB.S9S_MB_2U(SCH_1):GND   I175 @S9S_MB_2U_LIB.S9S_MB_2U(SCH_1):PAGE87
    63    GND @S9S_MB_2U_LIB.S9S_MB_2U(SCH_1):GND   I175 @S9S_MB_2U_LIB.S9S_MB_2U(SCH_1):PAGE87
    65    GND @S9S_MB_2U_LIB.S9S_MB_2U(SCH_1):GND   I175 @S9S_MB_2U_LIB.S9S_MB_2U(SCH_1):PAGE87
    67    GND @S9S_MB_2U_LIB.S9S_MB_2U(SCH_1):GND   I175 @S9S_MB_2U_LIB.S9S_MB_2U(SCH_1):PAGE87
    69    GND @S9S_MB_2U_LIB.S9S_MB_2U(SCH_1):GND   I175 @S9S_MB_2U_LIB.S9S_MB_2U(SCH_1):PAGE87
    71    GND @S9S_MB_2U_LIB.S9S_MB_2U(SCH_1):GND   I175 @S9S_MB_2U_LIB.S9S_MB_2U(SCH_1):PAGE87
    73    GND @S9S_MB_2U_LIB.S9S_MB_2U(SCH_1):GND   I175 @S9S_MB_2U_LIB.S9S_MB_2U(SCH_1):PAGE87
    75    GND @S9S_MB_2U_LIB.S9S_MB_2U(SCH_1):GND   I175 @S9S_MB_2U_LIB.S9S_MB_2U(SCH_1):PAGE87
    77    GND @S9S_MB_2U_LIB.S9S_MB_2U(SCH_1):GND   I175 @S9S_MB_2U_LIB.S9S_MB_2U(SCH_1):PAGE87
    79    GND @S9S_MB_2U_LIB.S9S_MB_2U(SCH_1):GND   I175 @S9S_MB_2U_LIB.S9S_MB_2U(SCH_1):PAGE87
    81    GND @S9S_MB_2U_LIB.S9S_MB_2U(SCH_1):GND   I175 @S9S_MB_2U_LIB.S9S_MB_2U(SCH_1):PAGE87
    83    GND @S9S_MB_2U_LIB.S9S_MB_2U(SCH_1):GND   I175 @S9S_MB_2U_LIB.S9S_MB_2U(SCH_1):PAGE87
    85    GND @S9S_MB_2U_LIB.S9S_MB_2U(SCH_1):GND   I175 @S9S_MB_2U_LIB.S9S_MB_2U(SCH_1):PAGE87
    88    GND @S9S_MB_2U_LIB.S9S_MB_2U(SCH_1):GND   I175 @S9S_MB_2U_LIB.S9S_MB_2U(SCH_1):PAGE87
    90    GND @S9S_MB_2U_LIB.S9S_MB_2U(SCH_1):GND   I175 @S9S_MB_2U_LIB.S9S_MB_2U(SCH_1):PAGE87
    92    GND @S9S_MB_2U_LIB.S9S_MB_2U(SCH_1):GND   I175 @S9S_MB_2U_LIB.S9S_MB_2U(SCH_1):PAGE87
    95    GND @S9S_MB_2U_LIB.S9S_MB_2U(SCH_1):GND   I175 @S9S_MB_2U_LIB.S9S_MB_2U(SCH_1):PAGE87
    97    GND @S9S_MB_2U_LIB.S9S_MB_2U(SCH_1):GND   I175 @S9S_MB_2U_LIB.S9S_MB_2U(SCH_1):PAGE87
    99    GND @S9S_MB_2U_LIB.S9S_MB_2U(SCH_1):GND   I175 @S9S_MB_2U_LIB.S9S_MB_2U(SCH_1):PAGE87
   101    GND @S9S_MB_2U_LIB.S9S_MB_2U(SCH_1):GND   I175 @S9S_MB_2U_LIB.S9S_MB_2U(SCH_1):PAGE87
   103    GND @S9S_MB_2U_LIB.S9S_MB_2U(SCH_1):GND   I175 @S9S_MB_2U_LIB.S9S_MB_2U(SCH_1):PAGE87
   106    GND @S9S_MB_2U_LIB.S9S_MB_2U(SCH_1):GND   I175 @S9S_MB_2U_LIB.S9S_MB_2U(SCH_1):PAGE87
   108    GND @S9S_MB_2U_LIB.S9S_MB_2U(SCH_1):GND   I175 @S9S_MB_2U_LIB.S9S_MB_2U(SCH_1):PAGE87
   110    GND @S9S_MB_2U_LIB.S9S_MB_2U(SCH_1):GND   I175 @S9S_MB_2U_LIB.S9S_MB_2U(SCH_1):PAGE87
   112    GND @S9S_MB_2U_LIB.S9S_MB_2U(SCH_1):GND   I175 @S9S_MB_2U_LIB.S9S_MB_2U(SCH_1):PAGE87
   114    GND @S9S_MB_2U_LIB.S9S_MB_2U(SCH_1):GND   I175 @S9S_MB_2U_LIB.S9S_MB_2U(SCH_1):PAGE87
   117    GND @S9S_MB_2U_LIB.S9S_MB_2U(SCH_1):GND   I175 @S9S_MB_2U_LIB.S9S_MB_2U(SCH_1):PAGE87
   119    GND @S9S_MB_2U_LIB.S9S_MB_2U(SCH_1):GND   I175 @S9S_MB_2U_LIB.S9S_MB_2U(SCH_1):PAGE87
   121    GND @S9S_MB_2U_LIB.S9S_MB_2U(SCH_1):GND   I175 @S9S_MB_2U_LIB.S9S_MB_2U(SCH_1):PAGE87
   123    GND @S9S_MB_2U_LIB.S9S_MB_2U(SCH_1):GND   I175 @S9S_MB_2U_LIB.S9S_MB_2U(SCH_1):PAGE87
   125    GND @S9S_MB_2U_LIB.S9S_MB_2U(SCH_1):GND   I175 @S9S_MB_2U_LIB.S9S_MB_2U(SCH_1):PAGE87
   128    GND @S9S_MB_2U_LIB.S9S_MB_2U(SCH_1):GND   I175 @S9S_MB_2U_LIB.S9S_MB_2U(SCH_1):PAGE87
   130    GND @S9S_MB_2U_LIB.S9S_MB_2U(SCH_1):GND   I175 @S9S_MB_2U_LIB.S9S_MB_2U(SCH_1):PAGE87
   134    GND @S9S_MB_2U_LIB.S9S_MB_2U(SCH_1):GND   I175 @S9S_MB_2U_LIB.S9S_MB_2U(SCH_1):PAGE87
   143    GND @S9S_MB_2U_LIB.S9S_MB_2U(SCH_1):GND   I175 @S9S_MB_2U_LIB.S9S_MB_2U(SCH_1):PAGE87
   151    GND @S9S_MB_2U_LIB.S9S_MB_2U(SCH_1):GND   I175 @S9S_MB_2U_LIB.S9S_MB_2U(SCH_1):PAGE87
   153    GND @S9S_MB_2U_LIB.S9S_MB_2U(SCH_1):GND   I175 @S9S_MB_2U_LIB.S9S_MB_2U(SCH_1):PAGE87
   155    GND @S9S_MB_2U_LIB.S9S_MB_2U(SCH_1):GND   I175 @S9S_MB_2U_LIB.S9S_MB_2U(SCH_1):PAGE87
   158    GND @S9S_MB_2U_LIB.S9S_MB_2U(SCH_1):GND   I175 @S9S_MB_2U_LIB.S9S_MB_2U(SCH_1):PAGE87
   160    GND @S9S_MB_2U_LIB.S9S_MB_2U(SCH_1):GND   I175 @S9S_MB_2U_LIB.S9S_MB_2U(SCH_1):PAGE87
   162    GND @S9S_MB_2U_LIB.S9S_MB_2U(SCH_1):GND   I175 @S9S_MB_2U_LIB.S9S_MB_2U(SCH_1):PAGE87
   164    GND @S9S_MB_2U_LIB.S9S_MB_2U(SCH_1):GND   I175 @S9S_MB_2U_LIB.S9S_MB_2U(SCH_1):PAGE87
   166    GND @S9S_MB_2U_LIB.S9S_MB_2U(SCH_1):GND   I175 @S9S_MB_2U_LIB.S9S_MB_2U(SCH_1):PAGE87
   169    GND @S9S_MB_2U_LIB.S9S_MB_2U(SCH_1):GND   I175 @S9S_MB_2U_LIB.S9S_MB_2U(SCH_1):PAGE87
   171    GND @S9S_MB_2U_LIB.S9S_MB_2U(SCH_1):GND   I175 @S9S_MB_2U_LIB.S9S_MB_2U(SCH_1):PAGE87
   173    GND @S9S_MB_2U_LIB.S9S_MB_2U(SCH_1):GND   I175 @S9S_MB_2U_LIB.S9S_MB_2U(SCH_1):PAGE87
   175    GND @S9S_MB_2U_LIB.S9S_MB_2U(SCH_1):GND   I175 @S9S_MB_2U_LIB.S9S_MB_2U(SCH_1):PAGE87
   177    GND @S9S_MB_2U_LIB.S9S_MB_2U(SCH_1):GND   I175 @S9S_MB_2U_LIB.S9S_MB_2U(SCH_1):PAGE87
   180    GND @S9S_MB_2U_LIB.S9S_MB_2U(SCH_1):GND   I175 @S9S_MB_2U_LIB.S9S_MB_2U(SCH_1):PAGE87
   182    GND @S9S_MB_2U_LIB.S9S_MB_2U(SCH_1):GND   I175 @S9S_MB_2U_LIB.S9S_MB_2U(SCH_1):PAGE87
   184    GND @S9S_MB_2U_LIB.S9S_MB_2U(SCH_1):GND   I175 @S9S_MB_2U_LIB.S9S_MB_2U(SCH_1):PAGE87
   186    GND @S9S_MB_2U_LIB.S9S_MB_2U(SCH_1):GND   I175 @S9S_MB_2U_LIB.S9S_MB_2U(SCH_1):PAGE87
   188    GND @S9S_MB_2U_LIB.S9S_MB_2U(SCH_1):GND   I175 @S9S_MB_2U_LIB.S9S_MB_2U(SCH_1):PAGE87
   191    GND @S9S_MB_2U_LIB.S9S_MB_2U(SCH_1):GND   I175 @S9S_MB_2U_LIB.S9S_MB_2U(SCH_1):PAGE87
   193    GND @S9S_MB_2U_LIB.S9S_MB_2U(SCH_1):GND   I175 @S9S_MB_2U_LIB.S9S_MB_2U(SCH_1):PAGE87
   195    GND @S9S_MB_2U_LIB.S9S_MB_2U(SCH_1):GND   I175 @S9S_MB_2U_LIB.S9S_MB_2U(SCH_1):PAGE87
   197    GND @S9S_MB_2U_LIB.S9S_MB_2U(SCH_1):GND   I175 @S9S_MB_2U_LIB.S9S_MB_2U(SCH_1):PAGE87
   199    GND @S9S_MB_2U_LIB.S9S_MB_2U(SCH_1):GND   I175 @S9S_MB_2U_LIB.S9S_MB_2U(SCH_1):PAGE87
   202    GND @S9S_MB_2U_LIB.S9S_MB_2U(SCH_1):GND   I175 @S9S_MB_2U_LIB.S9S_MB_2U(SCH_1):PAGE87
   204    GND @S9S_MB_2U_LIB.S9S_MB_2U(SCH_1):GND   I175 @S9S_MB_2U_LIB.S9S_MB_2U(SCH_1):PAGE87
   206    GND @S9S_MB_2U_LIB.S9S_MB_2U(SCH_1):GND   I175 @S9S_MB_2U_LIB.S9S_MB_2U(SCH_1):PAGE87
   208    GND @S9S_MB_2U_LIB.S9S_MB_2U(SCH_1):GND   I175 @S9S_MB_2U_LIB.S9S_MB_2U(SCH_1):PAGE87
   210    GND @S9S_MB_2U_LIB.S9S_MB_2U(SCH_1):GND   I175 @S9S_MB_2U_LIB.S9S_MB_2U(SCH_1):PAGE87
   212    GND @S9S_MB_2U_LIB.S9S_MB_2U(SCH_1):GND   I175 @S9S_MB_2U_LIB.S9S_MB_2U(SCH_1):PAGE87
   214    GND @S9S_MB_2U_LIB.S9S_MB_2U(SCH_1):GND   I175 @S9S_MB_2U_LIB.S9S_MB_2U(SCH_1):PAGE87
   216    GND @S9S_MB_2U_LIB.S9S_MB_2U(SCH_1):GND   I175 @S9S_MB_2U_LIB.S9S_MB_2U(SCH_1):PAGE87
   219    GND @S9S_MB_2U_LIB.S9S_MB_2U(SCH_1):GND   I175 @S9S_MB_2U_LIB.S9S_MB_2U(SCH_1):PAGE87
   222    GND @S9S_MB_2U_LIB.S9S_MB_2U(SCH_1):GND   I175 @S9S_MB_2U_LIB.S9S_MB_2U(SCH_1):PAGE87
   224    GND @S9S_MB_2U_LIB.S9S_MB_2U(SCH_1):GND   I175 @S9S_MB_2U_LIB.S9S_MB_2U(SCH_1):PAGE87
   226    GND @S9S_MB_2U_LIB.S9S_MB_2U(SCH_1):GND   I175 @S9S_MB_2U_LIB.S9S_MB_2U(SCH_1):PAGE87
   228    GND @S9S_MB_2U_LIB.S9S_MB_2U(SCH_1):GND   I175 @S9S_MB_2U_LIB.S9S_MB_2U(SCH_1):PAGE87
   233    GND @S9S_MB_2U_LIB.S9S_MB_2U(SCH_1):GND   I175 @S9S_MB_2U_LIB.S9S_MB_2U(SCH_1):PAGE87
   237    GND @S9S_MB_2U_LIB.S9S_MB_2U(SCH_1):GND   I175 @S9S_MB_2U_LIB.S9S_MB_2U(SCH_1):PAGE87
   242    GND @S9S_MB_2U_LIB.S9S_MB_2U(SCH_1):GND   I175 @S9S_MB_2U_LIB.S9S_MB_2U(SCH_1):PAGE87
   244    GND @S9S_MB_2U_LIB.S9S_MB_2U(SCH_1):GND   I175 @S9S_MB_2U_LIB.S9S_MB_2U(SCH_1):PAGE87
   246    GND @S9S_MB_2U_LIB.S9S_MB_2U(SCH_1):GND   I175 @S9S_MB_2U_LIB.S9S_MB_2U(SCH_1):PAGE87
   248    GND @S9S_MB_2U_LIB.S9S_MB_2U(SCH_1):GND   I175 @S9S_MB_2U_LIB.S9S_MB_2U(SCH_1):PAGE87
   251    GND @S9S_MB_2U_LIB.S9S_MB_2U(SCH_1):GND   I175 @S9S_MB_2U_LIB.S9S_MB_2U(SCH_1):PAGE87
   253    GND @S9S_MB_2U_LIB.S9S_MB_2U(SCH_1):GND   I175 @S9S_MB_2U_LIB.S9S_MB_2U(SCH_1):PAGE87
   255    GND @S9S_MB_2U_LIB.S9S_MB_2U(SCH_1):GND   I175 @S9S_MB_2U_LIB.S9S_MB_2U(SCH_1):PAGE87
   257    GND @S9S_MB_2U_LIB.S9S_MB_2U(SCH_1):GND   I175 @S9S_MB_2U_LIB.S9S_MB_2U(SCH_1):PAGE87
   259    GND @S9S_MB_2U_LIB.S9S_MB_2U(SCH_1):GND   I175 @S9S_MB_2U_LIB.S9S_MB_2U(SCH_1):PAGE87
   262    GND @S9S_MB_2U_LIB.S9S_MB_2U(SCH_1):GND   I175 @S9S_MB_2U_LIB.S9S_MB_2U(SCH_1):PAGE87
   264    GND @S9S_MB_2U_LIB.S9S_MB_2U(SCH_1):GND   I175 @S9S_MB_2U_LIB.S9S_MB_2U(SCH_1):PAGE87
   266    GND @S9S_MB_2U_LIB.S9S_MB_2U(SCH_1):GND   I175 @S9S_MB_2U_LIB.S9S_MB_2U(SCH_1):PAGE87
   268    GND @S9S_MB_2U_LIB.S9S_MB_2U(SCH_1):GND   I175 @S9S_MB_2U_LIB.S9S_MB_2U(SCH_1):PAGE87
   270    GND @S9S_MB_2U_LIB.S9S_MB_2U(SCH_1):GND   I175 @S9S_MB_2U_LIB.S9S_MB_2U(SCH_1):PAGE87
   273    GND @S9S_MB_2U_LIB.S9S_MB_2U(SCH_1):GND   I175 @S9S_MB_2U_LIB.S9S_MB_2U(SCH_1):PAGE87
   275    GND @S9S_MB_2U_LIB.S9S_MB_2U(SCH_1):GND   I175 @S9S_MB_2U_LIB.S9S_MB_2U(SCH_1):PAGE87
   277    GND @S9S_MB_2U_LIB.S9S_MB_2U(SCH_1):GND   I175 @S9S_MB_2U_LIB.S9S_MB_2U(SCH_1):PAGE87
   279    GND @S9S_MB_2U_LIB.S9S_MB_2U(SCH_1):GND   I175 @S9S_MB_2U_LIB.S9S_MB_2U(SCH_1):PAGE87
   281    GND @S9S_MB_2U_LIB.S9S_MB_2U(SCH_1):GND   I175 @S9S_MB_2U_LIB.S9S_MB_2U(SCH_1):PAGE87
   284    GND @S9S_MB_2U_LIB.S9S_MB_2U(SCH_1):GND   I175 @S9S_MB_2U_LIB.S9S_MB_2U(SCH_1):PAGE87
   286    GND @S9S_MB_2U_LIB.S9S_MB_2U(SCH_1):GND   I175 @S9S_MB_2U_LIB.S9S_MB_2U(SCH_1):PAGE87
   288    GND @S9S_MB_2U_LIB.S9S_MB_2U(SCH_1):GND   I175 @S9S_MB_2U_LIB.S9S_MB_2U(SCH_1):PAGE87
     1 P12V_S3_AUX_CPU0_NVDIMM @S9S_MB_2U_LIB.S9S_MB_2U(SCH_1):P12V_S3_AUX_CPU0_NVDIMM   I175 @S9S_MB_2U_LIB.S9S_MB_2U(SCH_1):PAGE87
   145 P12V_S3_AUX_CPU0_NVDIMM @S9S_MB_2U_LIB.S9S_MB_2U(SCH_1):P12V_S3_AUX_CPU0_NVDIMM   I175 @S9S_MB_2U_LIB.S9S_MB_2U(SCH_1):PAGE87
   146 P12V_S3_AUX_CPU0_NVDIMM @S9S_MB_2U_LIB.S9S_MB_2U(SCH_1):P12V_S3_AUX_CPU0_NVDIMM   I175 @S9S_MB_2U_LIB.S9S_MB_2U(SCH_1):PAGE87
   230    GND @S9S_MB_2U_LIB.S9S_MB_2U(SCH_1):GND   I175 @S9S_MB_2U_LIB.S9S_MB_2U(SCH_1):PAGE87
   235    GND @S9S_MB_2U_LIB.S9S_MB_2U(SCH_1):GND   I175 @S9S_MB_2U_LIB.S9S_MB_2U(SCH_1):PAGE87
   240    GND @S9S_MB_2U_LIB.S9S_MB_2U(SCH_1):GND   I175 @S9S_MB_2U_LIB.S9S_MB_2U(SCH_1):PAGE87
   132    GND @S9S_MB_2U_LIB.S9S_MB_2U(SCH_1):GND   I175 @S9S_MB_2U_LIB.S9S_MB_2U(SCH_1):PAGE87
   136    GND @S9S_MB_2U_LIB.S9S_MB_2U(SCH_1):GND   I175 @S9S_MB_2U_LIB.S9S_MB_2U(SCH_1):PAGE87
   139    GND @S9S_MB_2U_LIB.S9S_MB_2U(SCH_1):GND   I175 @S9S_MB_2U_LIB.S9S_MB_2U(SCH_1):PAGE87
   141    GND @S9S_MB_2U_LIB.S9S_MB_2U(SCH_1):GND   I175 @S9S_MB_2U_LIB.S9S_MB_2U(SCH_1):PAGE87
    G1    GND @S9S_MB_2U_LIB.S9S_MB_2U(SCH_1):GND   I175 @S9S_MB_2U_LIB.S9S_MB_2U(SCH_1):PAGE87
    G2    GND @S9S_MB_2U_LIB.S9S_MB_2U(SCH_1):GND   I175 @S9S_MB_2U_LIB.S9S_MB_2U(SCH_1):PAGE87
    G3    GND @S9S_MB_2U_LIB.S9S_MB_2U(SCH_1):GND   I175 @S9S_MB_2U_LIB.S9S_MB_2U(SCH_1):PAGE87

  J7 SCONN288_ADR50017P130CC-SCONN2A
     3 P3V3_AUX @S9S_MB_2U_LIB.S9S_MB_2U(SCH_1):P3V3_AUX    I12 @S9S_MB_2U_LIB.S9S_MB_2U(SCH_1):PAGE88
     2 TP_CHD_CPU0_DIMM1_FRU_0 @S9S_MB_2U_LIB.S9S_MB_2U(SCH_1):TP_CHD_CPU0_DIMM1_FRU_0    I12 @S9S_MB_2U_LIB.S9S_MB_2U(SCH_1):PAGE88
   144 TP_CHD_CPU0_DIMM1_FRU_1 @S9S_MB_2U_LIB.S9S_MB_2U(SCH_1):TP_CHD_CPU0_DIMM1_FRU_1    I12 @S9S_MB_2U_LIB.S9S_MB_2U(SCH_1):PAGE88
   149 TP_CHD_CPU0_DIMM1_FRU_2 @S9S_MB_2U_LIB.S9S_MB_2U(SCH_1):TP_CHD_CPU0_DIMM1_FRU_2    I12 @S9S_MB_2U_LIB.S9S_MB_2U(SCH_1):PAGE88
   150 TP_CHD_CPU0_DIMM1_FRU_3 @S9S_MB_2U_LIB.S9S_MB_2U(SCH_1):TP_CHD_CPU0_DIMM1_FRU_3    I12 @S9S_MB_2U_LIB.S9S_MB_2U(SCH_1):PAGE88
   220 TP_CHD_CPU0_DIMM1_FRU_4 @S9S_MB_2U_LIB.S9S_MB_2U(SCH_1):TP_CHD_CPU0_DIMM1_FRU_4    I12 @S9S_MB_2U_LIB.S9S_MB_2U(SCH_1):PAGE88
   231 TP_CHD_CPU0_DIMM1_FRU_5 @S9S_MB_2U_LIB.S9S_MB_2U(SCH_1):TP_CHD_CPU0_DIMM1_FRU_5    I12 @S9S_MB_2U_LIB.S9S_MB_2U(SCH_1):PAGE88
   232 TP_CHD_CPU0_DIMM1_FRU_6 @S9S_MB_2U_LIB.S9S_MB_2U(SCH_1):TP_CHD_CPU0_DIMM1_FRU_6    I12 @S9S_MB_2U_LIB.S9S_MB_2U(SCH_1):PAGE88
   207 RST_M_CD_CPU0_FPGA_N @S9S_MB_2U_LIB.S9S_MB_2U(SCH_1):RST_M_CD_CPU0_FPGA_N    I12 @S9S_MB_2U_LIB.S9S_MB_2U(SCH_1):PAGE88
   147 PWRGD_CHD_CPU0_DIMM1 @S9S_MB_2U_LIB.S9S_MB_2U(SCH_1):PWRGD_CHD_CPU0_DIMM1    I12 @S9S_MB_2U_LIB.S9S_MB_2U(SCH_1):PAGE88
   227 M_D_CPU0_SB_PAR @S9S_MB_2U_LIB.S9S_MB_2U(SCH_1):M_D_CPU0_SB_PAR    I12 @S9S_MB_2U_LIB.S9S_MB_2U(SCH_1):PAGE88
    74 M_D_CPU0_SA_PAR @S9S_MB_2U_LIB.S9S_MB_2U(SCH_1):M_D_CPU0_SA_PAR    I12 @S9S_MB_2U_LIB.S9S_MB_2U(SCH_1):PAGE88
    87 M_D_CPU0_SB_RSP<0> @S9S_MB_2U_LIB.S9S_MB_2U(SCH_1):M_D_CPU0_SB_RSP(0)    I12 @S9S_MB_2U_LIB.S9S_MB_2U(SCH_1):PAGE88
    86 M_D_CPU0_SA_RSP<0> @S9S_MB_2U_LIB.S9S_MB_2U(SCH_1):M_D_CPU0_SA_RSP(0)    I12 @S9S_MB_2U_LIB.S9S_MB_2U(SCH_1):PAGE88
     5 I3C_SPD_DDRABCD_CPU0_LVC1_SDA @S9S_MB_2U_LIB.S9S_MB_2U(SCH_1):I3C_SPD_DDRABCD_CPU0_LVC1_SDA    I12 @S9S_MB_2U_LIB.S9S_MB_2U(SCH_1):PAGE88
     4 I3C_SPD_DDRABCD_CPU0_LVC1_SCL_6 @S9S_MB_2U_LIB.S9S_MB_2U(SCH_1):I3C_SPD_DDRABCD_CPU0_LVC1_SCL_R7    I12 @S9S_MB_2U_LIB.S9S_MB_2U(SCH_1):PAGE88
   148 PD_CHD_CPU0_DIMM1_SAA @S9S_MB_2U_LIB.S9S_MB_2U(SCH_1):PD_CHD_CPU0_DIMM1_SAA    I12 @S9S_MB_2U_LIB.S9S_MB_2U(SCH_1):PAGE88
   100 M_D_CPU0_SB_DQ<0> @S9S_MB_2U_LIB.S9S_MB_2U(SCH_1):M_D_CPU0_SB_DQ(0)    I12 @S9S_MB_2U_LIB.S9S_MB_2U(SCH_1):PAGE88
   102 M_D_CPU0_SB_DQ<1> @S9S_MB_2U_LIB.S9S_MB_2U(SCH_1):M_D_CPU0_SB_DQ(1)    I12 @S9S_MB_2U_LIB.S9S_MB_2U(SCH_1):PAGE88
   245 M_D_CPU0_SB_DQ<2> @S9S_MB_2U_LIB.S9S_MB_2U(SCH_1):M_D_CPU0_SB_DQ(2)    I12 @S9S_MB_2U_LIB.S9S_MB_2U(SCH_1):PAGE88
   247 M_D_CPU0_SB_DQ<3> @S9S_MB_2U_LIB.S9S_MB_2U(SCH_1):M_D_CPU0_SB_DQ(3)    I12 @S9S_MB_2U_LIB.S9S_MB_2U(SCH_1):PAGE88
   107 M_D_CPU0_SB_DQ<4> @S9S_MB_2U_LIB.S9S_MB_2U(SCH_1):M_D_CPU0_SB_DQ(4)    I12 @S9S_MB_2U_LIB.S9S_MB_2U(SCH_1):PAGE88
   109 M_D_CPU0_SB_DQ<5> @S9S_MB_2U_LIB.S9S_MB_2U(SCH_1):M_D_CPU0_SB_DQ(5)    I12 @S9S_MB_2U_LIB.S9S_MB_2U(SCH_1):PAGE88
   252 M_D_CPU0_SB_DQ<6> @S9S_MB_2U_LIB.S9S_MB_2U(SCH_1):M_D_CPU0_SB_DQ(6)    I12 @S9S_MB_2U_LIB.S9S_MB_2U(SCH_1):PAGE88
   254 M_D_CPU0_SB_DQ<7> @S9S_MB_2U_LIB.S9S_MB_2U(SCH_1):M_D_CPU0_SB_DQ(7)    I12 @S9S_MB_2U_LIB.S9S_MB_2U(SCH_1):PAGE88
   111 M_D_CPU0_SB_DQ<8> @S9S_MB_2U_LIB.S9S_MB_2U(SCH_1):M_D_CPU0_SB_DQ(8)    I12 @S9S_MB_2U_LIB.S9S_MB_2U(SCH_1):PAGE88
   113 M_D_CPU0_SB_DQ<9> @S9S_MB_2U_LIB.S9S_MB_2U(SCH_1):M_D_CPU0_SB_DQ(9)    I12 @S9S_MB_2U_LIB.S9S_MB_2U(SCH_1):PAGE88
   256 M_D_CPU0_SB_DQ<10> @S9S_MB_2U_LIB.S9S_MB_2U(SCH_1):M_D_CPU0_SB_DQ(10)    I12 @S9S_MB_2U_LIB.S9S_MB_2U(SCH_1):PAGE88
   258 M_D_CPU0_SB_DQ<11> @S9S_MB_2U_LIB.S9S_MB_2U(SCH_1):M_D_CPU0_SB_DQ(11)    I12 @S9S_MB_2U_LIB.S9S_MB_2U(SCH_1):PAGE88
   118 M_D_CPU0_SB_DQ<12> @S9S_MB_2U_LIB.S9S_MB_2U(SCH_1):M_D_CPU0_SB_DQ(12)    I12 @S9S_MB_2U_LIB.S9S_MB_2U(SCH_1):PAGE88
   120 M_D_CPU0_SB_DQ<13> @S9S_MB_2U_LIB.S9S_MB_2U(SCH_1):M_D_CPU0_SB_DQ(13)    I12 @S9S_MB_2U_LIB.S9S_MB_2U(SCH_1):PAGE88
   263 M_D_CPU0_SB_DQ<14> @S9S_MB_2U_LIB.S9S_MB_2U(SCH_1):M_D_CPU0_SB_DQ(14)    I12 @S9S_MB_2U_LIB.S9S_MB_2U(SCH_1):PAGE88
   265 M_D_CPU0_SB_DQ<15> @S9S_MB_2U_LIB.S9S_MB_2U(SCH_1):M_D_CPU0_SB_DQ(15)    I12 @S9S_MB_2U_LIB.S9S_MB_2U(SCH_1):PAGE88
   122 M_D_CPU0_SB_DQ<16> @S9S_MB_2U_LIB.S9S_MB_2U(SCH_1):M_D_CPU0_SB_DQ(16)    I12 @S9S_MB_2U_LIB.S9S_MB_2U(SCH_1):PAGE88
   124 M_D_CPU0_SB_DQ<17> @S9S_MB_2U_LIB.S9S_MB_2U(SCH_1):M_D_CPU0_SB_DQ(17)    I12 @S9S_MB_2U_LIB.S9S_MB_2U(SCH_1):PAGE88
   267 M_D_CPU0_SB_DQ<18> @S9S_MB_2U_LIB.S9S_MB_2U(SCH_1):M_D_CPU0_SB_DQ(18)    I12 @S9S_MB_2U_LIB.S9S_MB_2U(SCH_1):PAGE88
   269 M_D_CPU0_SB_DQ<19> @S9S_MB_2U_LIB.S9S_MB_2U(SCH_1):M_D_CPU0_SB_DQ(19)    I12 @S9S_MB_2U_LIB.S9S_MB_2U(SCH_1):PAGE88
   129 M_D_CPU0_SB_DQ<20> @S9S_MB_2U_LIB.S9S_MB_2U(SCH_1):M_D_CPU0_SB_DQ(20)    I12 @S9S_MB_2U_LIB.S9S_MB_2U(SCH_1):PAGE88
   131 M_D_CPU0_SB_DQ<21> @S9S_MB_2U_LIB.S9S_MB_2U(SCH_1):M_D_CPU0_SB_DQ(21)    I12 @S9S_MB_2U_LIB.S9S_MB_2U(SCH_1):PAGE88
   274 M_D_CPU0_SB_DQ<22> @S9S_MB_2U_LIB.S9S_MB_2U(SCH_1):M_D_CPU0_SB_DQ(22)    I12 @S9S_MB_2U_LIB.S9S_MB_2U(SCH_1):PAGE88
   276 M_D_CPU0_SB_DQ<23> @S9S_MB_2U_LIB.S9S_MB_2U(SCH_1):M_D_CPU0_SB_DQ(23)    I12 @S9S_MB_2U_LIB.S9S_MB_2U(SCH_1):PAGE88
   133 M_D_CPU0_SB_DQ<24> @S9S_MB_2U_LIB.S9S_MB_2U(SCH_1):M_D_CPU0_SB_DQ(24)    I12 @S9S_MB_2U_LIB.S9S_MB_2U(SCH_1):PAGE88
   135 M_D_CPU0_SB_DQ<25> @S9S_MB_2U_LIB.S9S_MB_2U(SCH_1):M_D_CPU0_SB_DQ(25)    I12 @S9S_MB_2U_LIB.S9S_MB_2U(SCH_1):PAGE88
   278 M_D_CPU0_SB_DQ<26> @S9S_MB_2U_LIB.S9S_MB_2U(SCH_1):M_D_CPU0_SB_DQ(26)    I12 @S9S_MB_2U_LIB.S9S_MB_2U(SCH_1):PAGE88
   280 M_D_CPU0_SB_DQ<27> @S9S_MB_2U_LIB.S9S_MB_2U(SCH_1):M_D_CPU0_SB_DQ(27)    I12 @S9S_MB_2U_LIB.S9S_MB_2U(SCH_1):PAGE88
   140 M_D_CPU0_SB_DQ<28> @S9S_MB_2U_LIB.S9S_MB_2U(SCH_1):M_D_CPU0_SB_DQ(28)    I12 @S9S_MB_2U_LIB.S9S_MB_2U(SCH_1):PAGE88
   142 M_D_CPU0_SB_DQ<29> @S9S_MB_2U_LIB.S9S_MB_2U(SCH_1):M_D_CPU0_SB_DQ(29)    I12 @S9S_MB_2U_LIB.S9S_MB_2U(SCH_1):PAGE88
   285 M_D_CPU0_SB_DQ<30> @S9S_MB_2U_LIB.S9S_MB_2U(SCH_1):M_D_CPU0_SB_DQ(30)    I12 @S9S_MB_2U_LIB.S9S_MB_2U(SCH_1):PAGE88
   287 M_D_CPU0_SB_DQ<31> @S9S_MB_2U_LIB.S9S_MB_2U(SCH_1):M_D_CPU0_SB_DQ(31)    I12 @S9S_MB_2U_LIB.S9S_MB_2U(SCH_1):PAGE88
     7 M_D_CPU0_SA_DQ<0> @S9S_MB_2U_LIB.S9S_MB_2U(SCH_1):M_D_CPU0_SA_DQ(0)    I12 @S9S_MB_2U_LIB.S9S_MB_2U(SCH_1):PAGE88
     9 M_D_CPU0_SA_DQ<1> @S9S_MB_2U_LIB.S9S_MB_2U(SCH_1):M_D_CPU0_SA_DQ(1)    I12 @S9S_MB_2U_LIB.S9S_MB_2U(SCH_1):PAGE88
   152 M_D_CPU0_SA_DQ<2> @S9S_MB_2U_LIB.S9S_MB_2U(SCH_1):M_D_CPU0_SA_DQ(2)    I12 @S9S_MB_2U_LIB.S9S_MB_2U(SCH_1):PAGE88
   154 M_D_CPU0_SA_DQ<3> @S9S_MB_2U_LIB.S9S_MB_2U(SCH_1):M_D_CPU0_SA_DQ(3)    I12 @S9S_MB_2U_LIB.S9S_MB_2U(SCH_1):PAGE88
    14 M_D_CPU0_SA_DQ<4> @S9S_MB_2U_LIB.S9S_MB_2U(SCH_1):M_D_CPU0_SA_DQ(4)    I12 @S9S_MB_2U_LIB.S9S_MB_2U(SCH_1):PAGE88
    16 M_D_CPU0_SA_DQ<5> @S9S_MB_2U_LIB.S9S_MB_2U(SCH_1):M_D_CPU0_SA_DQ(5)    I12 @S9S_MB_2U_LIB.S9S_MB_2U(SCH_1):PAGE88
   159 M_D_CPU0_SA_DQ<6> @S9S_MB_2U_LIB.S9S_MB_2U(SCH_1):M_D_CPU0_SA_DQ(6)    I12 @S9S_MB_2U_LIB.S9S_MB_2U(SCH_1):PAGE88
   161 M_D_CPU0_SA_DQ<7> @S9S_MB_2U_LIB.S9S_MB_2U(SCH_1):M_D_CPU0_SA_DQ(7)    I12 @S9S_MB_2U_LIB.S9S_MB_2U(SCH_1):PAGE88
    18 M_D_CPU0_SA_DQ<8> @S9S_MB_2U_LIB.S9S_MB_2U(SCH_1):M_D_CPU0_SA_DQ(8)    I12 @S9S_MB_2U_LIB.S9S_MB_2U(SCH_1):PAGE88
    20 M_D_CPU0_SA_DQ<9> @S9S_MB_2U_LIB.S9S_MB_2U(SCH_1):M_D_CPU0_SA_DQ(9)    I12 @S9S_MB_2U_LIB.S9S_MB_2U(SCH_1):PAGE88
   163 M_D_CPU0_SA_DQ<10> @S9S_MB_2U_LIB.S9S_MB_2U(SCH_1):M_D_CPU0_SA_DQ(10)    I12 @S9S_MB_2U_LIB.S9S_MB_2U(SCH_1):PAGE88
   165 M_D_CPU0_SA_DQ<11> @S9S_MB_2U_LIB.S9S_MB_2U(SCH_1):M_D_CPU0_SA_DQ(11)    I12 @S9S_MB_2U_LIB.S9S_MB_2U(SCH_1):PAGE88
    25 M_D_CPU0_SA_DQ<12> @S9S_MB_2U_LIB.S9S_MB_2U(SCH_1):M_D_CPU0_SA_DQ(12)    I12 @S9S_MB_2U_LIB.S9S_MB_2U(SCH_1):PAGE88
    27 M_D_CPU0_SA_DQ<13> @S9S_MB_2U_LIB.S9S_MB_2U(SCH_1):M_D_CPU0_SA_DQ(13)    I12 @S9S_MB_2U_LIB.S9S_MB_2U(SCH_1):PAGE88
   170 M_D_CPU0_SA_DQ<14> @S9S_MB_2U_LIB.S9S_MB_2U(SCH_1):M_D_CPU0_SA_DQ(14)    I12 @S9S_MB_2U_LIB.S9S_MB_2U(SCH_1):PAGE88
   172 M_D_CPU0_SA_DQ<15> @S9S_MB_2U_LIB.S9S_MB_2U(SCH_1):M_D_CPU0_SA_DQ(15)    I12 @S9S_MB_2U_LIB.S9S_MB_2U(SCH_1):PAGE88
    29 M_D_CPU0_SA_DQ<16> @S9S_MB_2U_LIB.S9S_MB_2U(SCH_1):M_D_CPU0_SA_DQ(16)    I12 @S9S_MB_2U_LIB.S9S_MB_2U(SCH_1):PAGE88
    31 M_D_CPU0_SA_DQ<17> @S9S_MB_2U_LIB.S9S_MB_2U(SCH_1):M_D_CPU0_SA_DQ(17)    I12 @S9S_MB_2U_LIB.S9S_MB_2U(SCH_1):PAGE88
   174 M_D_CPU0_SA_DQ<18> @S9S_MB_2U_LIB.S9S_MB_2U(SCH_1):M_D_CPU0_SA_DQ(18)    I12 @S9S_MB_2U_LIB.S9S_MB_2U(SCH_1):PAGE88
   176 M_D_CPU0_SA_DQ<19> @S9S_MB_2U_LIB.S9S_MB_2U(SCH_1):M_D_CPU0_SA_DQ(19)    I12 @S9S_MB_2U_LIB.S9S_MB_2U(SCH_1):PAGE88
    36 M_D_CPU0_SA_DQ<20> @S9S_MB_2U_LIB.S9S_MB_2U(SCH_1):M_D_CPU0_SA_DQ(20)    I12 @S9S_MB_2U_LIB.S9S_MB_2U(SCH_1):PAGE88
    38 M_D_CPU0_SA_DQ<21> @S9S_MB_2U_LIB.S9S_MB_2U(SCH_1):M_D_CPU0_SA_DQ(21)    I12 @S9S_MB_2U_LIB.S9S_MB_2U(SCH_1):PAGE88
   181 M_D_CPU0_SA_DQ<22> @S9S_MB_2U_LIB.S9S_MB_2U(SCH_1):M_D_CPU0_SA_DQ(22)    I12 @S9S_MB_2U_LIB.S9S_MB_2U(SCH_1):PAGE88
   183 M_D_CPU0_SA_DQ<23> @S9S_MB_2U_LIB.S9S_MB_2U(SCH_1):M_D_CPU0_SA_DQ(23)    I12 @S9S_MB_2U_LIB.S9S_MB_2U(SCH_1):PAGE88
    40 M_D_CPU0_SA_DQ<24> @S9S_MB_2U_LIB.S9S_MB_2U(SCH_1):M_D_CPU0_SA_DQ(24)    I12 @S9S_MB_2U_LIB.S9S_MB_2U(SCH_1):PAGE88
    42 M_D_CPU0_SA_DQ<25> @S9S_MB_2U_LIB.S9S_MB_2U(SCH_1):M_D_CPU0_SA_DQ(25)    I12 @S9S_MB_2U_LIB.S9S_MB_2U(SCH_1):PAGE88
   185 M_D_CPU0_SA_DQ<26> @S9S_MB_2U_LIB.S9S_MB_2U(SCH_1):M_D_CPU0_SA_DQ(26)    I12 @S9S_MB_2U_LIB.S9S_MB_2U(SCH_1):PAGE88
   187 M_D_CPU0_SA_DQ<27> @S9S_MB_2U_LIB.S9S_MB_2U(SCH_1):M_D_CPU0_SA_DQ(27)    I12 @S9S_MB_2U_LIB.S9S_MB_2U(SCH_1):PAGE88
    47 M_D_CPU0_SA_DQ<28> @S9S_MB_2U_LIB.S9S_MB_2U(SCH_1):M_D_CPU0_SA_DQ(28)    I12 @S9S_MB_2U_LIB.S9S_MB_2U(SCH_1):PAGE88
    49 M_D_CPU0_SA_DQ<29> @S9S_MB_2U_LIB.S9S_MB_2U(SCH_1):M_D_CPU0_SA_DQ(29)    I12 @S9S_MB_2U_LIB.S9S_MB_2U(SCH_1):PAGE88
   192 M_D_CPU0_SA_DQ<30> @S9S_MB_2U_LIB.S9S_MB_2U(SCH_1):M_D_CPU0_SA_DQ(30)    I12 @S9S_MB_2U_LIB.S9S_MB_2U(SCH_1):PAGE88
   229 M_D_CPU0_SB_CS_N<1> @S9S_MB_2U_LIB.S9S_MB_2U(SCH_1):M_D_CPU0_SB_CS_N(1)    I12 @S9S_MB_2U_LIB.S9S_MB_2U(SCH_1):PAGE88
   209 M_D_CPU0_SA_CS_N<1> @S9S_MB_2U_LIB.S9S_MB_2U(SCH_1):M_D_CPU0_SA_CS_N(1)    I12 @S9S_MB_2U_LIB.S9S_MB_2U(SCH_1):PAGE88
    84 M_D_CPU0_SB_CS_N<0> @S9S_MB_2U_LIB.S9S_MB_2U(SCH_1):M_D_CPU0_SB_CS_N(0)    I12 @S9S_MB_2U_LIB.S9S_MB_2U(SCH_1):PAGE88
    64 M_D_CPU0_SA_CS_N<0> @S9S_MB_2U_LIB.S9S_MB_2U(SCH_1):M_D_CPU0_SA_CS_N(0)    I12 @S9S_MB_2U_LIB.S9S_MB_2U(SCH_1):PAGE88
   217 M_D_CPU0_CLK_DP<0> @S9S_MB_2U_LIB.S9S_MB_2U(SCH_1):M_D_CPU0_CLK_DP(0)    I12 @S9S_MB_2U_LIB.S9S_MB_2U(SCH_1):PAGE88
   218 M_D_CPU0_CLK_DN<0> @S9S_MB_2U_LIB.S9S_MB_2U(SCH_1):M_D_CPU0_CLK_DN(0)    I12 @S9S_MB_2U_LIB.S9S_MB_2U(SCH_1):PAGE88
    96 M_D_CPU0_SB_CB<0> @S9S_MB_2U_LIB.S9S_MB_2U(SCH_1):M_D_CPU0_SB_CB(0)    I12 @S9S_MB_2U_LIB.S9S_MB_2U(SCH_1):PAGE88
    98 M_D_CPU0_SB_CB<1> @S9S_MB_2U_LIB.S9S_MB_2U(SCH_1):M_D_CPU0_SB_CB(1)    I12 @S9S_MB_2U_LIB.S9S_MB_2U(SCH_1):PAGE88
   241 M_D_CPU0_SB_CB<2> @S9S_MB_2U_LIB.S9S_MB_2U(SCH_1):M_D_CPU0_SB_CB(2)    I12 @S9S_MB_2U_LIB.S9S_MB_2U(SCH_1):PAGE88
   243 M_D_CPU0_SB_CB<3> @S9S_MB_2U_LIB.S9S_MB_2U(SCH_1):M_D_CPU0_SB_CB(3)    I12 @S9S_MB_2U_LIB.S9S_MB_2U(SCH_1):PAGE88
    89 M_D_CPU0_SB_CB<4> @S9S_MB_2U_LIB.S9S_MB_2U(SCH_1):M_D_CPU0_SB_CB(4)    I12 @S9S_MB_2U_LIB.S9S_MB_2U(SCH_1):PAGE88
    91 M_D_CPU0_SB_CB<5> @S9S_MB_2U_LIB.S9S_MB_2U(SCH_1):M_D_CPU0_SB_CB(5)    I12 @S9S_MB_2U_LIB.S9S_MB_2U(SCH_1):PAGE88
   234 M_D_CPU0_SB_CB<6> @S9S_MB_2U_LIB.S9S_MB_2U(SCH_1):M_D_CPU0_SB_CB(6)    I12 @S9S_MB_2U_LIB.S9S_MB_2U(SCH_1):PAGE88
    51 M_D_CPU0_SA_CB<0> @S9S_MB_2U_LIB.S9S_MB_2U(SCH_1):M_D_CPU0_SA_CB(0)    I12 @S9S_MB_2U_LIB.S9S_MB_2U(SCH_1):PAGE88
   196 M_D_CPU0_SA_CB<2> @S9S_MB_2U_LIB.S9S_MB_2U(SCH_1):M_D_CPU0_SA_CB(2)    I12 @S9S_MB_2U_LIB.S9S_MB_2U(SCH_1):PAGE88
   198 M_D_CPU0_SA_CB<3> @S9S_MB_2U_LIB.S9S_MB_2U(SCH_1):M_D_CPU0_SA_CB(3)    I12 @S9S_MB_2U_LIB.S9S_MB_2U(SCH_1):PAGE88
    60 M_D_CPU0_SA_CB<5> @S9S_MB_2U_LIB.S9S_MB_2U(SCH_1):M_D_CPU0_SA_CB(5)    I12 @S9S_MB_2U_LIB.S9S_MB_2U(SCH_1):PAGE88
   203 M_D_CPU0_SA_CB<6> @S9S_MB_2U_LIB.S9S_MB_2U(SCH_1):M_D_CPU0_SA_CB(6)    I12 @S9S_MB_2U_LIB.S9S_MB_2U(SCH_1):PAGE88
    82 M_D_CPU0_SB_CA<6> @S9S_MB_2U_LIB.S9S_MB_2U(SCH_1):M_D_CPU0_SB_CA(6)    I12 @S9S_MB_2U_LIB.S9S_MB_2U(SCH_1):PAGE88
    72 M_D_CPU0_SA_CA<6> @S9S_MB_2U_LIB.S9S_MB_2U(SCH_1):M_D_CPU0_SA_CA(6)    I12 @S9S_MB_2U_LIB.S9S_MB_2U(SCH_1):PAGE88
   225 M_D_CPU0_SB_CA<5> @S9S_MB_2U_LIB.S9S_MB_2U(SCH_1):M_D_CPU0_SB_CA(5)    I12 @S9S_MB_2U_LIB.S9S_MB_2U(SCH_1):PAGE88
   215 M_D_CPU0_SA_CA<5> @S9S_MB_2U_LIB.S9S_MB_2U(SCH_1):M_D_CPU0_SA_CA(5)    I12 @S9S_MB_2U_LIB.S9S_MB_2U(SCH_1):PAGE88
    80 M_D_CPU0_SB_CA<4> @S9S_MB_2U_LIB.S9S_MB_2U(SCH_1):M_D_CPU0_SB_CA(4)    I12 @S9S_MB_2U_LIB.S9S_MB_2U(SCH_1):PAGE88
    70 M_D_CPU0_SA_CA<4> @S9S_MB_2U_LIB.S9S_MB_2U(SCH_1):M_D_CPU0_SA_CA(4)    I12 @S9S_MB_2U_LIB.S9S_MB_2U(SCH_1):PAGE88
   223 M_D_CPU0_SB_CA<3> @S9S_MB_2U_LIB.S9S_MB_2U(SCH_1):M_D_CPU0_SB_CA(3)    I12 @S9S_MB_2U_LIB.S9S_MB_2U(SCH_1):PAGE88
   213 M_D_CPU0_SA_CA<3> @S9S_MB_2U_LIB.S9S_MB_2U(SCH_1):M_D_CPU0_SA_CA(3)    I12 @S9S_MB_2U_LIB.S9S_MB_2U(SCH_1):PAGE88
    78 M_D_CPU0_SB_CA<2> @S9S_MB_2U_LIB.S9S_MB_2U(SCH_1):M_D_CPU0_SB_CA(2)    I12 @S9S_MB_2U_LIB.S9S_MB_2U(SCH_1):PAGE88
    68 M_D_CPU0_SA_CA<2> @S9S_MB_2U_LIB.S9S_MB_2U(SCH_1):M_D_CPU0_SA_CA(2)    I12 @S9S_MB_2U_LIB.S9S_MB_2U(SCH_1):PAGE88
   221 M_D_CPU0_SB_CA<1> @S9S_MB_2U_LIB.S9S_MB_2U(SCH_1):M_D_CPU0_SB_CA(1)    I12 @S9S_MB_2U_LIB.S9S_MB_2U(SCH_1):PAGE88
   211 M_D_CPU0_SA_CA<1> @S9S_MB_2U_LIB.S9S_MB_2U(SCH_1):M_D_CPU0_SA_CA(1)    I12 @S9S_MB_2U_LIB.S9S_MB_2U(SCH_1):PAGE88
    76 M_D_CPU0_SB_CA<0> @S9S_MB_2U_LIB.S9S_MB_2U(SCH_1):M_D_CPU0_SB_CA(0)    I12 @S9S_MB_2U_LIB.S9S_MB_2U(SCH_1):PAGE88
    66 M_D_CPU0_SA_CA<0> @S9S_MB_2U_LIB.S9S_MB_2U(SCH_1):M_D_CPU0_SA_CA(0)    I12 @S9S_MB_2U_LIB.S9S_MB_2U(SCH_1):PAGE88
    62 M_D_CPU0_ALERT_N @S9S_MB_2U_LIB.S9S_MB_2U(SCH_1):M_D_CPU0_ALERT_N    I12 @S9S_MB_2U_LIB.S9S_MB_2U(SCH_1):PAGE88
   236 M_D_CPU0_SB_CB<7> @S9S_MB_2U_LIB.S9S_MB_2U(SCH_1):M_D_CPU0_SB_CB(7)    I12 @S9S_MB_2U_LIB.S9S_MB_2U(SCH_1):PAGE88
    53 M_D_CPU0_SA_CB<1> @S9S_MB_2U_LIB.S9S_MB_2U(SCH_1):M_D_CPU0_SA_CB(1)    I12 @S9S_MB_2U_LIB.S9S_MB_2U(SCH_1):PAGE88
    58 M_D_CPU0_SA_CB<4> @S9S_MB_2U_LIB.S9S_MB_2U(SCH_1):M_D_CPU0_SA_CB(4)    I12 @S9S_MB_2U_LIB.S9S_MB_2U(SCH_1):PAGE88
   205 M_D_CPU0_SA_CB<7> @S9S_MB_2U_LIB.S9S_MB_2U(SCH_1):M_D_CPU0_SA_CB(7)    I12 @S9S_MB_2U_LIB.S9S_MB_2U(SCH_1):PAGE88
   194 M_D_CPU0_SA_DQ<31> @S9S_MB_2U_LIB.S9S_MB_2U(SCH_1):M_D_CPU0_SA_DQ(31)    I12 @S9S_MB_2U_LIB.S9S_MB_2U(SCH_1):PAGE88
    93 M_D_CPU0_SB_DQS_DP<9> @S9S_MB_2U_LIB.S9S_MB_2U(SCH_1):M_D_CPU0_SB_DQS_DP(9)   I178 @S9S_MB_2U_LIB.S9S_MB_2U(SCH_1):PAGE88
    94 M_D_CPU0_SB_DQS_DN<9> @S9S_MB_2U_LIB.S9S_MB_2U(SCH_1):M_D_CPU0_SB_DQS_DN(9)   I178 @S9S_MB_2U_LIB.S9S_MB_2U(SCH_1):PAGE88
   201 M_D_CPU0_SA_DQS_DP<9> @S9S_MB_2U_LIB.S9S_MB_2U(SCH_1):M_D_CPU0_SA_DQS_DP(9)   I178 @S9S_MB_2U_LIB.S9S_MB_2U(SCH_1):PAGE88
   200 M_D_CPU0_SA_DQS_DN<9> @S9S_MB_2U_LIB.S9S_MB_2U(SCH_1):M_D_CPU0_SA_DQS_DN(9)   I178 @S9S_MB_2U_LIB.S9S_MB_2U(SCH_1):PAGE88
   190 M_D_CPU0_SA_DQS_DP<8> @S9S_MB_2U_LIB.S9S_MB_2U(SCH_1):M_D_CPU0_SA_DQS_DP(8)   I178 @S9S_MB_2U_LIB.S9S_MB_2U(SCH_1):PAGE88
   189 M_D_CPU0_SA_DQS_DN<8> @S9S_MB_2U_LIB.S9S_MB_2U(SCH_1):M_D_CPU0_SA_DQS_DN(8)   I178 @S9S_MB_2U_LIB.S9S_MB_2U(SCH_1):PAGE88
   271 M_D_CPU0_SB_DQS_DN<7> @S9S_MB_2U_LIB.S9S_MB_2U(SCH_1):M_D_CPU0_SB_DQS_DN(7)   I178 @S9S_MB_2U_LIB.S9S_MB_2U(SCH_1):PAGE88
   179 M_D_CPU0_SA_DQS_DP<7> @S9S_MB_2U_LIB.S9S_MB_2U(SCH_1):M_D_CPU0_SA_DQS_DP(7)   I178 @S9S_MB_2U_LIB.S9S_MB_2U(SCH_1):PAGE88
   261 M_D_CPU0_SB_DQS_DP<6> @S9S_MB_2U_LIB.S9S_MB_2U(SCH_1):M_D_CPU0_SB_DQS_DP(6)   I178 @S9S_MB_2U_LIB.S9S_MB_2U(SCH_1):PAGE88
   260 M_D_CPU0_SB_DQS_DN<6> @S9S_MB_2U_LIB.S9S_MB_2U(SCH_1):M_D_CPU0_SB_DQS_DN(6)   I178 @S9S_MB_2U_LIB.S9S_MB_2U(SCH_1):PAGE88
   167 M_D_CPU0_SA_DQS_DN<6> @S9S_MB_2U_LIB.S9S_MB_2U(SCH_1):M_D_CPU0_SA_DQS_DN(6)   I178 @S9S_MB_2U_LIB.S9S_MB_2U(SCH_1):PAGE88
   250 M_D_CPU0_SB_DQS_DP<5> @S9S_MB_2U_LIB.S9S_MB_2U(SCH_1):M_D_CPU0_SB_DQS_DP(5)   I178 @S9S_MB_2U_LIB.S9S_MB_2U(SCH_1):PAGE88
   249 M_D_CPU0_SB_DQS_DN<5> @S9S_MB_2U_LIB.S9S_MB_2U(SCH_1):M_D_CPU0_SB_DQS_DN(5)   I178 @S9S_MB_2U_LIB.S9S_MB_2U(SCH_1):PAGE88
   157 M_D_CPU0_SA_DQS_DP<5> @S9S_MB_2U_LIB.S9S_MB_2U(SCH_1):M_D_CPU0_SA_DQS_DP(5)   I178 @S9S_MB_2U_LIB.S9S_MB_2U(SCH_1):PAGE88
   156 M_D_CPU0_SA_DQS_DN<5> @S9S_MB_2U_LIB.S9S_MB_2U(SCH_1):M_D_CPU0_SA_DQS_DN(5)   I178 @S9S_MB_2U_LIB.S9S_MB_2U(SCH_1):PAGE88
   239 M_D_CPU0_SB_DQS_DP<4> @S9S_MB_2U_LIB.S9S_MB_2U(SCH_1):M_D_CPU0_SB_DQS_DP(4)   I178 @S9S_MB_2U_LIB.S9S_MB_2U(SCH_1):PAGE88
   238 M_D_CPU0_SB_DQS_DN<4> @S9S_MB_2U_LIB.S9S_MB_2U(SCH_1):M_D_CPU0_SB_DQS_DN(4)   I178 @S9S_MB_2U_LIB.S9S_MB_2U(SCH_1):PAGE88
    55 M_D_CPU0_SA_DQS_DP<4> @S9S_MB_2U_LIB.S9S_MB_2U(SCH_1):M_D_CPU0_SA_DQS_DP(4)   I178 @S9S_MB_2U_LIB.S9S_MB_2U(SCH_1):PAGE88
    56 M_D_CPU0_SA_DQS_DN<4> @S9S_MB_2U_LIB.S9S_MB_2U(SCH_1):M_D_CPU0_SA_DQS_DN(4)   I178 @S9S_MB_2U_LIB.S9S_MB_2U(SCH_1):PAGE88
   137 M_D_CPU0_SB_DQS_DP<3> @S9S_MB_2U_LIB.S9S_MB_2U(SCH_1):M_D_CPU0_SB_DQS_DP(3)   I178 @S9S_MB_2U_LIB.S9S_MB_2U(SCH_1):PAGE88
   138 M_D_CPU0_SB_DQS_DN<3> @S9S_MB_2U_LIB.S9S_MB_2U(SCH_1):M_D_CPU0_SB_DQS_DN(3)   I178 @S9S_MB_2U_LIB.S9S_MB_2U(SCH_1):PAGE88
    44 M_D_CPU0_SA_DQS_DP<3> @S9S_MB_2U_LIB.S9S_MB_2U(SCH_1):M_D_CPU0_SA_DQS_DP(3)   I178 @S9S_MB_2U_LIB.S9S_MB_2U(SCH_1):PAGE88
    45 M_D_CPU0_SA_DQS_DN<3> @S9S_MB_2U_LIB.S9S_MB_2U(SCH_1):M_D_CPU0_SA_DQS_DN(3)   I178 @S9S_MB_2U_LIB.S9S_MB_2U(SCH_1):PAGE88
   126 M_D_CPU0_SB_DQS_DP<2> @S9S_MB_2U_LIB.S9S_MB_2U(SCH_1):M_D_CPU0_SB_DQS_DP(2)   I178 @S9S_MB_2U_LIB.S9S_MB_2U(SCH_1):PAGE88
   127 M_D_CPU0_SB_DQS_DN<2> @S9S_MB_2U_LIB.S9S_MB_2U(SCH_1):M_D_CPU0_SB_DQS_DN(2)   I178 @S9S_MB_2U_LIB.S9S_MB_2U(SCH_1):PAGE88
    33 M_D_CPU0_SA_DQS_DP<2> @S9S_MB_2U_LIB.S9S_MB_2U(SCH_1):M_D_CPU0_SA_DQS_DP(2)   I178 @S9S_MB_2U_LIB.S9S_MB_2U(SCH_1):PAGE88
    34 M_D_CPU0_SA_DQS_DN<2> @S9S_MB_2U_LIB.S9S_MB_2U(SCH_1):M_D_CPU0_SA_DQS_DN(2)   I178 @S9S_MB_2U_LIB.S9S_MB_2U(SCH_1):PAGE88
   115 M_D_CPU0_SB_DQS_DP<1> @S9S_MB_2U_LIB.S9S_MB_2U(SCH_1):M_D_CPU0_SB_DQS_DP(1)   I178 @S9S_MB_2U_LIB.S9S_MB_2U(SCH_1):PAGE88
   116 M_D_CPU0_SB_DQS_DN<1> @S9S_MB_2U_LIB.S9S_MB_2U(SCH_1):M_D_CPU0_SB_DQS_DN(1)   I178 @S9S_MB_2U_LIB.S9S_MB_2U(SCH_1):PAGE88
    22 M_D_CPU0_SA_DQS_DP<1> @S9S_MB_2U_LIB.S9S_MB_2U(SCH_1):M_D_CPU0_SA_DQS_DP(1)   I178 @S9S_MB_2U_LIB.S9S_MB_2U(SCH_1):PAGE88
    23 M_D_CPU0_SA_DQS_DN<1> @S9S_MB_2U_LIB.S9S_MB_2U(SCH_1):M_D_CPU0_SA_DQS_DN(1)   I178 @S9S_MB_2U_LIB.S9S_MB_2U(SCH_1):PAGE88
   104 M_D_CPU0_SB_DQS_DP<0> @S9S_MB_2U_LIB.S9S_MB_2U(SCH_1):M_D_CPU0_SB_DQS_DP(0)   I178 @S9S_MB_2U_LIB.S9S_MB_2U(SCH_1):PAGE88
   105 M_D_CPU0_SB_DQS_DN<0> @S9S_MB_2U_LIB.S9S_MB_2U(SCH_1):M_D_CPU0_SB_DQS_DN(0)   I178 @S9S_MB_2U_LIB.S9S_MB_2U(SCH_1):PAGE88
    11 M_D_CPU0_SA_DQS_DP<0> @S9S_MB_2U_LIB.S9S_MB_2U(SCH_1):M_D_CPU0_SA_DQS_DP(0)   I178 @S9S_MB_2U_LIB.S9S_MB_2U(SCH_1):PAGE88
    12 M_D_CPU0_SA_DQS_DN<0> @S9S_MB_2U_LIB.S9S_MB_2U(SCH_1):M_D_CPU0_SA_DQS_DN(0)   I178 @S9S_MB_2U_LIB.S9S_MB_2U(SCH_1):PAGE88
   272 M_D_CPU0_SB_DQS_DP<7> @S9S_MB_2U_LIB.S9S_MB_2U(SCH_1):M_D_CPU0_SB_DQS_DP(7)   I178 @S9S_MB_2U_LIB.S9S_MB_2U(SCH_1):PAGE88
   282 M_D_CPU0_SB_DQS_DN<8> @S9S_MB_2U_LIB.S9S_MB_2U(SCH_1):M_D_CPU0_SB_DQS_DN(8)   I178 @S9S_MB_2U_LIB.S9S_MB_2U(SCH_1):PAGE88
   283 M_D_CPU0_SB_DQS_DP<8> @S9S_MB_2U_LIB.S9S_MB_2U(SCH_1):M_D_CPU0_SB_DQS_DP(8)   I178 @S9S_MB_2U_LIB.S9S_MB_2U(SCH_1):PAGE88
   168 M_D_CPU0_SA_DQS_DP<6> @S9S_MB_2U_LIB.S9S_MB_2U(SCH_1):M_D_CPU0_SA_DQS_DP(6)   I178 @S9S_MB_2U_LIB.S9S_MB_2U(SCH_1):PAGE88
   178 M_D_CPU0_SA_DQS_DN<7> @S9S_MB_2U_LIB.S9S_MB_2U(SCH_1):M_D_CPU0_SA_DQS_DN(7)   I178 @S9S_MB_2U_LIB.S9S_MB_2U(SCH_1):PAGE88
     6    GND @S9S_MB_2U_LIB.S9S_MB_2U(SCH_1):GND   I168 @S9S_MB_2U_LIB.S9S_MB_2U(SCH_1):PAGE88
     8    GND @S9S_MB_2U_LIB.S9S_MB_2U(SCH_1):GND   I168 @S9S_MB_2U_LIB.S9S_MB_2U(SCH_1):PAGE88
    10    GND @S9S_MB_2U_LIB.S9S_MB_2U(SCH_1):GND   I168 @S9S_MB_2U_LIB.S9S_MB_2U(SCH_1):PAGE88
    13    GND @S9S_MB_2U_LIB.S9S_MB_2U(SCH_1):GND   I168 @S9S_MB_2U_LIB.S9S_MB_2U(SCH_1):PAGE88
    15    GND @S9S_MB_2U_LIB.S9S_MB_2U(SCH_1):GND   I168 @S9S_MB_2U_LIB.S9S_MB_2U(SCH_1):PAGE88
    17    GND @S9S_MB_2U_LIB.S9S_MB_2U(SCH_1):GND   I168 @S9S_MB_2U_LIB.S9S_MB_2U(SCH_1):PAGE88
    19    GND @S9S_MB_2U_LIB.S9S_MB_2U(SCH_1):GND   I168 @S9S_MB_2U_LIB.S9S_MB_2U(SCH_1):PAGE88
    21    GND @S9S_MB_2U_LIB.S9S_MB_2U(SCH_1):GND   I168 @S9S_MB_2U_LIB.S9S_MB_2U(SCH_1):PAGE88
    24    GND @S9S_MB_2U_LIB.S9S_MB_2U(SCH_1):GND   I168 @S9S_MB_2U_LIB.S9S_MB_2U(SCH_1):PAGE88
    26    GND @S9S_MB_2U_LIB.S9S_MB_2U(SCH_1):GND   I168 @S9S_MB_2U_LIB.S9S_MB_2U(SCH_1):PAGE88
    28    GND @S9S_MB_2U_LIB.S9S_MB_2U(SCH_1):GND   I168 @S9S_MB_2U_LIB.S9S_MB_2U(SCH_1):PAGE88
    30    GND @S9S_MB_2U_LIB.S9S_MB_2U(SCH_1):GND   I168 @S9S_MB_2U_LIB.S9S_MB_2U(SCH_1):PAGE88
    32    GND @S9S_MB_2U_LIB.S9S_MB_2U(SCH_1):GND   I168 @S9S_MB_2U_LIB.S9S_MB_2U(SCH_1):PAGE88
    35    GND @S9S_MB_2U_LIB.S9S_MB_2U(SCH_1):GND   I168 @S9S_MB_2U_LIB.S9S_MB_2U(SCH_1):PAGE88
    37    GND @S9S_MB_2U_LIB.S9S_MB_2U(SCH_1):GND   I168 @S9S_MB_2U_LIB.S9S_MB_2U(SCH_1):PAGE88
    39    GND @S9S_MB_2U_LIB.S9S_MB_2U(SCH_1):GND   I168 @S9S_MB_2U_LIB.S9S_MB_2U(SCH_1):PAGE88
    41    GND @S9S_MB_2U_LIB.S9S_MB_2U(SCH_1):GND   I168 @S9S_MB_2U_LIB.S9S_MB_2U(SCH_1):PAGE88
    43    GND @S9S_MB_2U_LIB.S9S_MB_2U(SCH_1):GND   I168 @S9S_MB_2U_LIB.S9S_MB_2U(SCH_1):PAGE88
    46    GND @S9S_MB_2U_LIB.S9S_MB_2U(SCH_1):GND   I168 @S9S_MB_2U_LIB.S9S_MB_2U(SCH_1):PAGE88
    48    GND @S9S_MB_2U_LIB.S9S_MB_2U(SCH_1):GND   I168 @S9S_MB_2U_LIB.S9S_MB_2U(SCH_1):PAGE88
    50    GND @S9S_MB_2U_LIB.S9S_MB_2U(SCH_1):GND   I168 @S9S_MB_2U_LIB.S9S_MB_2U(SCH_1):PAGE88
    52    GND @S9S_MB_2U_LIB.S9S_MB_2U(SCH_1):GND   I168 @S9S_MB_2U_LIB.S9S_MB_2U(SCH_1):PAGE88
    54    GND @S9S_MB_2U_LIB.S9S_MB_2U(SCH_1):GND   I168 @S9S_MB_2U_LIB.S9S_MB_2U(SCH_1):PAGE88
    57    GND @S9S_MB_2U_LIB.S9S_MB_2U(SCH_1):GND   I168 @S9S_MB_2U_LIB.S9S_MB_2U(SCH_1):PAGE88
    59    GND @S9S_MB_2U_LIB.S9S_MB_2U(SCH_1):GND   I168 @S9S_MB_2U_LIB.S9S_MB_2U(SCH_1):PAGE88
    61    GND @S9S_MB_2U_LIB.S9S_MB_2U(SCH_1):GND   I168 @S9S_MB_2U_LIB.S9S_MB_2U(SCH_1):PAGE88
    63    GND @S9S_MB_2U_LIB.S9S_MB_2U(SCH_1):GND   I168 @S9S_MB_2U_LIB.S9S_MB_2U(SCH_1):PAGE88
    65    GND @S9S_MB_2U_LIB.S9S_MB_2U(SCH_1):GND   I168 @S9S_MB_2U_LIB.S9S_MB_2U(SCH_1):PAGE88
    67    GND @S9S_MB_2U_LIB.S9S_MB_2U(SCH_1):GND   I168 @S9S_MB_2U_LIB.S9S_MB_2U(SCH_1):PAGE88
    69    GND @S9S_MB_2U_LIB.S9S_MB_2U(SCH_1):GND   I168 @S9S_MB_2U_LIB.S9S_MB_2U(SCH_1):PAGE88
    71    GND @S9S_MB_2U_LIB.S9S_MB_2U(SCH_1):GND   I168 @S9S_MB_2U_LIB.S9S_MB_2U(SCH_1):PAGE88
    73    GND @S9S_MB_2U_LIB.S9S_MB_2U(SCH_1):GND   I168 @S9S_MB_2U_LIB.S9S_MB_2U(SCH_1):PAGE88
    75    GND @S9S_MB_2U_LIB.S9S_MB_2U(SCH_1):GND   I168 @S9S_MB_2U_LIB.S9S_MB_2U(SCH_1):PAGE88
    77    GND @S9S_MB_2U_LIB.S9S_MB_2U(SCH_1):GND   I168 @S9S_MB_2U_LIB.S9S_MB_2U(SCH_1):PAGE88
    79    GND @S9S_MB_2U_LIB.S9S_MB_2U(SCH_1):GND   I168 @S9S_MB_2U_LIB.S9S_MB_2U(SCH_1):PAGE88
    81    GND @S9S_MB_2U_LIB.S9S_MB_2U(SCH_1):GND   I168 @S9S_MB_2U_LIB.S9S_MB_2U(SCH_1):PAGE88
    83    GND @S9S_MB_2U_LIB.S9S_MB_2U(SCH_1):GND   I168 @S9S_MB_2U_LIB.S9S_MB_2U(SCH_1):PAGE88
    85    GND @S9S_MB_2U_LIB.S9S_MB_2U(SCH_1):GND   I168 @S9S_MB_2U_LIB.S9S_MB_2U(SCH_1):PAGE88
    88    GND @S9S_MB_2U_LIB.S9S_MB_2U(SCH_1):GND   I168 @S9S_MB_2U_LIB.S9S_MB_2U(SCH_1):PAGE88
    90    GND @S9S_MB_2U_LIB.S9S_MB_2U(SCH_1):GND   I168 @S9S_MB_2U_LIB.S9S_MB_2U(SCH_1):PAGE88
    92    GND @S9S_MB_2U_LIB.S9S_MB_2U(SCH_1):GND   I168 @S9S_MB_2U_LIB.S9S_MB_2U(SCH_1):PAGE88
    95    GND @S9S_MB_2U_LIB.S9S_MB_2U(SCH_1):GND   I168 @S9S_MB_2U_LIB.S9S_MB_2U(SCH_1):PAGE88
    97    GND @S9S_MB_2U_LIB.S9S_MB_2U(SCH_1):GND   I168 @S9S_MB_2U_LIB.S9S_MB_2U(SCH_1):PAGE88
    99    GND @S9S_MB_2U_LIB.S9S_MB_2U(SCH_1):GND   I168 @S9S_MB_2U_LIB.S9S_MB_2U(SCH_1):PAGE88
   101    GND @S9S_MB_2U_LIB.S9S_MB_2U(SCH_1):GND   I168 @S9S_MB_2U_LIB.S9S_MB_2U(SCH_1):PAGE88
   103    GND @S9S_MB_2U_LIB.S9S_MB_2U(SCH_1):GND   I168 @S9S_MB_2U_LIB.S9S_MB_2U(SCH_1):PAGE88
   106    GND @S9S_MB_2U_LIB.S9S_MB_2U(SCH_1):GND   I168 @S9S_MB_2U_LIB.S9S_MB_2U(SCH_1):PAGE88
   108    GND @S9S_MB_2U_LIB.S9S_MB_2U(SCH_1):GND   I168 @S9S_MB_2U_LIB.S9S_MB_2U(SCH_1):PAGE88
   110    GND @S9S_MB_2U_LIB.S9S_MB_2U(SCH_1):GND   I168 @S9S_MB_2U_LIB.S9S_MB_2U(SCH_1):PAGE88
   112    GND @S9S_MB_2U_LIB.S9S_MB_2U(SCH_1):GND   I168 @S9S_MB_2U_LIB.S9S_MB_2U(SCH_1):PAGE88
   114    GND @S9S_MB_2U_LIB.S9S_MB_2U(SCH_1):GND   I168 @S9S_MB_2U_LIB.S9S_MB_2U(SCH_1):PAGE88
   117    GND @S9S_MB_2U_LIB.S9S_MB_2U(SCH_1):GND   I168 @S9S_MB_2U_LIB.S9S_MB_2U(SCH_1):PAGE88
   119    GND @S9S_MB_2U_LIB.S9S_MB_2U(SCH_1):GND   I168 @S9S_MB_2U_LIB.S9S_MB_2U(SCH_1):PAGE88
   121    GND @S9S_MB_2U_LIB.S9S_MB_2U(SCH_1):GND   I168 @S9S_MB_2U_LIB.S9S_MB_2U(SCH_1):PAGE88
   123    GND @S9S_MB_2U_LIB.S9S_MB_2U(SCH_1):GND   I168 @S9S_MB_2U_LIB.S9S_MB_2U(SCH_1):PAGE88
   125    GND @S9S_MB_2U_LIB.S9S_MB_2U(SCH_1):GND   I168 @S9S_MB_2U_LIB.S9S_MB_2U(SCH_1):PAGE88
   128    GND @S9S_MB_2U_LIB.S9S_MB_2U(SCH_1):GND   I168 @S9S_MB_2U_LIB.S9S_MB_2U(SCH_1):PAGE88
   130    GND @S9S_MB_2U_LIB.S9S_MB_2U(SCH_1):GND   I168 @S9S_MB_2U_LIB.S9S_MB_2U(SCH_1):PAGE88
   134    GND @S9S_MB_2U_LIB.S9S_MB_2U(SCH_1):GND   I168 @S9S_MB_2U_LIB.S9S_MB_2U(SCH_1):PAGE88
   143    GND @S9S_MB_2U_LIB.S9S_MB_2U(SCH_1):GND   I168 @S9S_MB_2U_LIB.S9S_MB_2U(SCH_1):PAGE88
   151    GND @S9S_MB_2U_LIB.S9S_MB_2U(SCH_1):GND   I168 @S9S_MB_2U_LIB.S9S_MB_2U(SCH_1):PAGE88
   153    GND @S9S_MB_2U_LIB.S9S_MB_2U(SCH_1):GND   I168 @S9S_MB_2U_LIB.S9S_MB_2U(SCH_1):PAGE88
   155    GND @S9S_MB_2U_LIB.S9S_MB_2U(SCH_1):GND   I168 @S9S_MB_2U_LIB.S9S_MB_2U(SCH_1):PAGE88
   158    GND @S9S_MB_2U_LIB.S9S_MB_2U(SCH_1):GND   I168 @S9S_MB_2U_LIB.S9S_MB_2U(SCH_1):PAGE88
   160    GND @S9S_MB_2U_LIB.S9S_MB_2U(SCH_1):GND   I168 @S9S_MB_2U_LIB.S9S_MB_2U(SCH_1):PAGE88
   162    GND @S9S_MB_2U_LIB.S9S_MB_2U(SCH_1):GND   I168 @S9S_MB_2U_LIB.S9S_MB_2U(SCH_1):PAGE88
   164    GND @S9S_MB_2U_LIB.S9S_MB_2U(SCH_1):GND   I168 @S9S_MB_2U_LIB.S9S_MB_2U(SCH_1):PAGE88
   166    GND @S9S_MB_2U_LIB.S9S_MB_2U(SCH_1):GND   I168 @S9S_MB_2U_LIB.S9S_MB_2U(SCH_1):PAGE88
   169    GND @S9S_MB_2U_LIB.S9S_MB_2U(SCH_1):GND   I168 @S9S_MB_2U_LIB.S9S_MB_2U(SCH_1):PAGE88
   171    GND @S9S_MB_2U_LIB.S9S_MB_2U(SCH_1):GND   I168 @S9S_MB_2U_LIB.S9S_MB_2U(SCH_1):PAGE88
   173    GND @S9S_MB_2U_LIB.S9S_MB_2U(SCH_1):GND   I168 @S9S_MB_2U_LIB.S9S_MB_2U(SCH_1):PAGE88
   175    GND @S9S_MB_2U_LIB.S9S_MB_2U(SCH_1):GND   I168 @S9S_MB_2U_LIB.S9S_MB_2U(SCH_1):PAGE88
   177    GND @S9S_MB_2U_LIB.S9S_MB_2U(SCH_1):GND   I168 @S9S_MB_2U_LIB.S9S_MB_2U(SCH_1):PAGE88
   180    GND @S9S_MB_2U_LIB.S9S_MB_2U(SCH_1):GND   I168 @S9S_MB_2U_LIB.S9S_MB_2U(SCH_1):PAGE88
   182    GND @S9S_MB_2U_LIB.S9S_MB_2U(SCH_1):GND   I168 @S9S_MB_2U_LIB.S9S_MB_2U(SCH_1):PAGE88
   184    GND @S9S_MB_2U_LIB.S9S_MB_2U(SCH_1):GND   I168 @S9S_MB_2U_LIB.S9S_MB_2U(SCH_1):PAGE88
   186    GND @S9S_MB_2U_LIB.S9S_MB_2U(SCH_1):GND   I168 @S9S_MB_2U_LIB.S9S_MB_2U(SCH_1):PAGE88
   188    GND @S9S_MB_2U_LIB.S9S_MB_2U(SCH_1):GND   I168 @S9S_MB_2U_LIB.S9S_MB_2U(SCH_1):PAGE88
   191    GND @S9S_MB_2U_LIB.S9S_MB_2U(SCH_1):GND   I168 @S9S_MB_2U_LIB.S9S_MB_2U(SCH_1):PAGE88
   193    GND @S9S_MB_2U_LIB.S9S_MB_2U(SCH_1):GND   I168 @S9S_MB_2U_LIB.S9S_MB_2U(SCH_1):PAGE88
   195    GND @S9S_MB_2U_LIB.S9S_MB_2U(SCH_1):GND   I168 @S9S_MB_2U_LIB.S9S_MB_2U(SCH_1):PAGE88
   197    GND @S9S_MB_2U_LIB.S9S_MB_2U(SCH_1):GND   I168 @S9S_MB_2U_LIB.S9S_MB_2U(SCH_1):PAGE88
   199    GND @S9S_MB_2U_LIB.S9S_MB_2U(SCH_1):GND   I168 @S9S_MB_2U_LIB.S9S_MB_2U(SCH_1):PAGE88
   202    GND @S9S_MB_2U_LIB.S9S_MB_2U(SCH_1):GND   I168 @S9S_MB_2U_LIB.S9S_MB_2U(SCH_1):PAGE88
   204    GND @S9S_MB_2U_LIB.S9S_MB_2U(SCH_1):GND   I168 @S9S_MB_2U_LIB.S9S_MB_2U(SCH_1):PAGE88
   206    GND @S9S_MB_2U_LIB.S9S_MB_2U(SCH_1):GND   I168 @S9S_MB_2U_LIB.S9S_MB_2U(SCH_1):PAGE88
   208    GND @S9S_MB_2U_LIB.S9S_MB_2U(SCH_1):GND   I168 @S9S_MB_2U_LIB.S9S_MB_2U(SCH_1):PAGE88
   210    GND @S9S_MB_2U_LIB.S9S_MB_2U(SCH_1):GND   I168 @S9S_MB_2U_LIB.S9S_MB_2U(SCH_1):PAGE88
   212    GND @S9S_MB_2U_LIB.S9S_MB_2U(SCH_1):GND   I168 @S9S_MB_2U_LIB.S9S_MB_2U(SCH_1):PAGE88
   214    GND @S9S_MB_2U_LIB.S9S_MB_2U(SCH_1):GND   I168 @S9S_MB_2U_LIB.S9S_MB_2U(SCH_1):PAGE88
   216    GND @S9S_MB_2U_LIB.S9S_MB_2U(SCH_1):GND   I168 @S9S_MB_2U_LIB.S9S_MB_2U(SCH_1):PAGE88
   219    GND @S9S_MB_2U_LIB.S9S_MB_2U(SCH_1):GND   I168 @S9S_MB_2U_LIB.S9S_MB_2U(SCH_1):PAGE88
   222    GND @S9S_MB_2U_LIB.S9S_MB_2U(SCH_1):GND   I168 @S9S_MB_2U_LIB.S9S_MB_2U(SCH_1):PAGE88
   224    GND @S9S_MB_2U_LIB.S9S_MB_2U(SCH_1):GND   I168 @S9S_MB_2U_LIB.S9S_MB_2U(SCH_1):PAGE88
   226    GND @S9S_MB_2U_LIB.S9S_MB_2U(SCH_1):GND   I168 @S9S_MB_2U_LIB.S9S_MB_2U(SCH_1):PAGE88
   228    GND @S9S_MB_2U_LIB.S9S_MB_2U(SCH_1):GND   I168 @S9S_MB_2U_LIB.S9S_MB_2U(SCH_1):PAGE88
   233    GND @S9S_MB_2U_LIB.S9S_MB_2U(SCH_1):GND   I168 @S9S_MB_2U_LIB.S9S_MB_2U(SCH_1):PAGE88
   237    GND @S9S_MB_2U_LIB.S9S_MB_2U(SCH_1):GND   I168 @S9S_MB_2U_LIB.S9S_MB_2U(SCH_1):PAGE88
   242    GND @S9S_MB_2U_LIB.S9S_MB_2U(SCH_1):GND   I168 @S9S_MB_2U_LIB.S9S_MB_2U(SCH_1):PAGE88
   244    GND @S9S_MB_2U_LIB.S9S_MB_2U(SCH_1):GND   I168 @S9S_MB_2U_LIB.S9S_MB_2U(SCH_1):PAGE88
   246    GND @S9S_MB_2U_LIB.S9S_MB_2U(SCH_1):GND   I168 @S9S_MB_2U_LIB.S9S_MB_2U(SCH_1):PAGE88
   248    GND @S9S_MB_2U_LIB.S9S_MB_2U(SCH_1):GND   I168 @S9S_MB_2U_LIB.S9S_MB_2U(SCH_1):PAGE88
   251    GND @S9S_MB_2U_LIB.S9S_MB_2U(SCH_1):GND   I168 @S9S_MB_2U_LIB.S9S_MB_2U(SCH_1):PAGE88
   253    GND @S9S_MB_2U_LIB.S9S_MB_2U(SCH_1):GND   I168 @S9S_MB_2U_LIB.S9S_MB_2U(SCH_1):PAGE88
   255    GND @S9S_MB_2U_LIB.S9S_MB_2U(SCH_1):GND   I168 @S9S_MB_2U_LIB.S9S_MB_2U(SCH_1):PAGE88
   257    GND @S9S_MB_2U_LIB.S9S_MB_2U(SCH_1):GND   I168 @S9S_MB_2U_LIB.S9S_MB_2U(SCH_1):PAGE88
   259    GND @S9S_MB_2U_LIB.S9S_MB_2U(SCH_1):GND   I168 @S9S_MB_2U_LIB.S9S_MB_2U(SCH_1):PAGE88
   262    GND @S9S_MB_2U_LIB.S9S_MB_2U(SCH_1):GND   I168 @S9S_MB_2U_LIB.S9S_MB_2U(SCH_1):PAGE88
   264    GND @S9S_MB_2U_LIB.S9S_MB_2U(SCH_1):GND   I168 @S9S_MB_2U_LIB.S9S_MB_2U(SCH_1):PAGE88
   266    GND @S9S_MB_2U_LIB.S9S_MB_2U(SCH_1):GND   I168 @S9S_MB_2U_LIB.S9S_MB_2U(SCH_1):PAGE88
   268    GND @S9S_MB_2U_LIB.S9S_MB_2U(SCH_1):GND   I168 @S9S_MB_2U_LIB.S9S_MB_2U(SCH_1):PAGE88
   270    GND @S9S_MB_2U_LIB.S9S_MB_2U(SCH_1):GND   I168 @S9S_MB_2U_LIB.S9S_MB_2U(SCH_1):PAGE88
   273    GND @S9S_MB_2U_LIB.S9S_MB_2U(SCH_1):GND   I168 @S9S_MB_2U_LIB.S9S_MB_2U(SCH_1):PAGE88
   275    GND @S9S_MB_2U_LIB.S9S_MB_2U(SCH_1):GND   I168 @S9S_MB_2U_LIB.S9S_MB_2U(SCH_1):PAGE88
   277    GND @S9S_MB_2U_LIB.S9S_MB_2U(SCH_1):GND   I168 @S9S_MB_2U_LIB.S9S_MB_2U(SCH_1):PAGE88
   279    GND @S9S_MB_2U_LIB.S9S_MB_2U(SCH_1):GND   I168 @S9S_MB_2U_LIB.S9S_MB_2U(SCH_1):PAGE88
   281    GND @S9S_MB_2U_LIB.S9S_MB_2U(SCH_1):GND   I168 @S9S_MB_2U_LIB.S9S_MB_2U(SCH_1):PAGE88
   284    GND @S9S_MB_2U_LIB.S9S_MB_2U(SCH_1):GND   I168 @S9S_MB_2U_LIB.S9S_MB_2U(SCH_1):PAGE88
   286    GND @S9S_MB_2U_LIB.S9S_MB_2U(SCH_1):GND   I168 @S9S_MB_2U_LIB.S9S_MB_2U(SCH_1):PAGE88
   288    GND @S9S_MB_2U_LIB.S9S_MB_2U(SCH_1):GND   I168 @S9S_MB_2U_LIB.S9S_MB_2U(SCH_1):PAGE88
     1 P12V_S3_AUX_CPU0_NVDIMM @S9S_MB_2U_LIB.S9S_MB_2U(SCH_1):P12V_S3_AUX_CPU0_NVDIMM   I168 @S9S_MB_2U_LIB.S9S_MB_2U(SCH_1):PAGE88
   145 P12V_S3_AUX_CPU0_NVDIMM @S9S_MB_2U_LIB.S9S_MB_2U(SCH_1):P12V_S3_AUX_CPU0_NVDIMM   I168 @S9S_MB_2U_LIB.S9S_MB_2U(SCH_1):PAGE88
   146 P12V_S3_AUX_CPU0_NVDIMM @S9S_MB_2U_LIB.S9S_MB_2U(SCH_1):P12V_S3_AUX_CPU0_NVDIMM   I168 @S9S_MB_2U_LIB.S9S_MB_2U(SCH_1):PAGE88
   230    GND @S9S_MB_2U_LIB.S9S_MB_2U(SCH_1):GND   I168 @S9S_MB_2U_LIB.S9S_MB_2U(SCH_1):PAGE88
   235    GND @S9S_MB_2U_LIB.S9S_MB_2U(SCH_1):GND   I168 @S9S_MB_2U_LIB.S9S_MB_2U(SCH_1):PAGE88
   240    GND @S9S_MB_2U_LIB.S9S_MB_2U(SCH_1):GND   I168 @S9S_MB_2U_LIB.S9S_MB_2U(SCH_1):PAGE88
   132    GND @S9S_MB_2U_LIB.S9S_MB_2U(SCH_1):GND   I168 @S9S_MB_2U_LIB.S9S_MB_2U(SCH_1):PAGE88
   136    GND @S9S_MB_2U_LIB.S9S_MB_2U(SCH_1):GND   I168 @S9S_MB_2U_LIB.S9S_MB_2U(SCH_1):PAGE88
   139    GND @S9S_MB_2U_LIB.S9S_MB_2U(SCH_1):GND   I168 @S9S_MB_2U_LIB.S9S_MB_2U(SCH_1):PAGE88
   141    GND @S9S_MB_2U_LIB.S9S_MB_2U(SCH_1):GND   I168 @S9S_MB_2U_LIB.S9S_MB_2U(SCH_1):PAGE88
    G1    GND @S9S_MB_2U_LIB.S9S_MB_2U(SCH_1):GND   I168 @S9S_MB_2U_LIB.S9S_MB_2U(SCH_1):PAGE88
    G2    GND @S9S_MB_2U_LIB.S9S_MB_2U(SCH_1):GND   I168 @S9S_MB_2U_LIB.S9S_MB_2U(SCH_1):PAGE88
    G3    GND @S9S_MB_2U_LIB.S9S_MB_2U(SCH_1):GND   I168 @S9S_MB_2U_LIB.S9S_MB_2U(SCH_1):PAGE88

  J8 SCONN288_ADR50017P087CC-SCONN2A
     3 P3V3_AUX @S9S_MB_2U_LIB.S9S_MB_2U(SCH_1):P3V3_AUX    I50 @S9S_MB_2U_LIB.S9S_MB_2U(SCH_1):PAGE89
     2 TP_CHD_CPU0_DIMM2_FRU_0 @S9S_MB_2U_LIB.S9S_MB_2U(SCH_1):TP_CHD_CPU0_DIMM2_FRU_0    I50 @S9S_MB_2U_LIB.S9S_MB_2U(SCH_1):PAGE89
   144 TP_CHD_CPU0_DIMM2_FRU_1 @S9S_MB_2U_LIB.S9S_MB_2U(SCH_1):TP_CHD_CPU0_DIMM2_FRU_1    I50 @S9S_MB_2U_LIB.S9S_MB_2U(SCH_1):PAGE89
   149 TP_CHD_CPU0_DIMM2_FRU_2 @S9S_MB_2U_LIB.S9S_MB_2U(SCH_1):TP_CHD_CPU0_DIMM2_FRU_2    I50 @S9S_MB_2U_LIB.S9S_MB_2U(SCH_1):PAGE89
   150 TP_CHD_CPU0_DIMM2_FRU_3 @S9S_MB_2U_LIB.S9S_MB_2U(SCH_1):TP_CHD_CPU0_DIMM2_FRU_3    I50 @S9S_MB_2U_LIB.S9S_MB_2U(SCH_1):PAGE89
   220 TP_CHD_CPU0_DIMM2_FRU_4 @S9S_MB_2U_LIB.S9S_MB_2U(SCH_1):TP_CHD_CPU0_DIMM2_FRU_4    I50 @S9S_MB_2U_LIB.S9S_MB_2U(SCH_1):PAGE89
   231 TP_CHD_CPU0_DIMM2_FRU_5 @S9S_MB_2U_LIB.S9S_MB_2U(SCH_1):TP_CHD_CPU0_DIMM2_FRU_5    I50 @S9S_MB_2U_LIB.S9S_MB_2U(SCH_1):PAGE89
   232 TP_CHD_CPU0_DIMM2_FRU_6 @S9S_MB_2U_LIB.S9S_MB_2U(SCH_1):TP_CHD_CPU0_DIMM2_FRU_6    I50 @S9S_MB_2U_LIB.S9S_MB_2U(SCH_1):PAGE89
   207 RST_M_CD_CPU0_FPGA_N @S9S_MB_2U_LIB.S9S_MB_2U(SCH_1):RST_M_CD_CPU0_FPGA_N    I50 @S9S_MB_2U_LIB.S9S_MB_2U(SCH_1):PAGE89
   147 PWRGD_CHD_CPU0_DIMM2 @S9S_MB_2U_LIB.S9S_MB_2U(SCH_1):PWRGD_CHD_CPU0_DIMM2    I50 @S9S_MB_2U_LIB.S9S_MB_2U(SCH_1):PAGE89
   227 M_D_CPU0_SB_PAR @S9S_MB_2U_LIB.S9S_MB_2U(SCH_1):M_D_CPU0_SB_PAR    I50 @S9S_MB_2U_LIB.S9S_MB_2U(SCH_1):PAGE89
    74 M_D_CPU0_SA_PAR @S9S_MB_2U_LIB.S9S_MB_2U(SCH_1):M_D_CPU0_SA_PAR    I50 @S9S_MB_2U_LIB.S9S_MB_2U(SCH_1):PAGE89
    87 M_D_CPU0_SB_RSP<1> @S9S_MB_2U_LIB.S9S_MB_2U(SCH_1):M_D_CPU0_SB_RSP(1)    I50 @S9S_MB_2U_LIB.S9S_MB_2U(SCH_1):PAGE89
    86 M_D_CPU0_SA_RSP<1> @S9S_MB_2U_LIB.S9S_MB_2U(SCH_1):M_D_CPU0_SA_RSP(1)    I50 @S9S_MB_2U_LIB.S9S_MB_2U(SCH_1):PAGE89
     5 I3C_SPD_DDRABCD_CPU0_LVC1_SDA @S9S_MB_2U_LIB.S9S_MB_2U(SCH_1):I3C_SPD_DDRABCD_CPU0_LVC1_SDA    I50 @S9S_MB_2U_LIB.S9S_MB_2U(SCH_1):PAGE89
     4 I3C_SPD_DDRABCD_CPU0_LVC1_SCL_7 @S9S_MB_2U_LIB.S9S_MB_2U(SCH_1):I3C_SPD_DDRABCD_CPU0_LVC1_SCL_R8    I50 @S9S_MB_2U_LIB.S9S_MB_2U(SCH_1):PAGE89
   148 PD_CHD_CPU0_DIMM2_SAA @S9S_MB_2U_LIB.S9S_MB_2U(SCH_1):PD_CHD_CPU0_DIMM2_SAA    I50 @S9S_MB_2U_LIB.S9S_MB_2U(SCH_1):PAGE89
   100 M_D_CPU0_SB_DQ<0> @S9S_MB_2U_LIB.S9S_MB_2U(SCH_1):M_D_CPU0_SB_DQ(0)    I50 @S9S_MB_2U_LIB.S9S_MB_2U(SCH_1):PAGE89
   102 M_D_CPU0_SB_DQ<1> @S9S_MB_2U_LIB.S9S_MB_2U(SCH_1):M_D_CPU0_SB_DQ(1)    I50 @S9S_MB_2U_LIB.S9S_MB_2U(SCH_1):PAGE89
   245 M_D_CPU0_SB_DQ<2> @S9S_MB_2U_LIB.S9S_MB_2U(SCH_1):M_D_CPU0_SB_DQ(2)    I50 @S9S_MB_2U_LIB.S9S_MB_2U(SCH_1):PAGE89
   247 M_D_CPU0_SB_DQ<3> @S9S_MB_2U_LIB.S9S_MB_2U(SCH_1):M_D_CPU0_SB_DQ(3)    I50 @S9S_MB_2U_LIB.S9S_MB_2U(SCH_1):PAGE89
   107 M_D_CPU0_SB_DQ<4> @S9S_MB_2U_LIB.S9S_MB_2U(SCH_1):M_D_CPU0_SB_DQ(4)    I50 @S9S_MB_2U_LIB.S9S_MB_2U(SCH_1):PAGE89
   109 M_D_CPU0_SB_DQ<5> @S9S_MB_2U_LIB.S9S_MB_2U(SCH_1):M_D_CPU0_SB_DQ(5)    I50 @S9S_MB_2U_LIB.S9S_MB_2U(SCH_1):PAGE89
   252 M_D_CPU0_SB_DQ<6> @S9S_MB_2U_LIB.S9S_MB_2U(SCH_1):M_D_CPU0_SB_DQ(6)    I50 @S9S_MB_2U_LIB.S9S_MB_2U(SCH_1):PAGE89
   254 M_D_CPU0_SB_DQ<7> @S9S_MB_2U_LIB.S9S_MB_2U(SCH_1):M_D_CPU0_SB_DQ(7)    I50 @S9S_MB_2U_LIB.S9S_MB_2U(SCH_1):PAGE89
   111 M_D_CPU0_SB_DQ<8> @S9S_MB_2U_LIB.S9S_MB_2U(SCH_1):M_D_CPU0_SB_DQ(8)    I50 @S9S_MB_2U_LIB.S9S_MB_2U(SCH_1):PAGE89
   113 M_D_CPU0_SB_DQ<9> @S9S_MB_2U_LIB.S9S_MB_2U(SCH_1):M_D_CPU0_SB_DQ(9)    I50 @S9S_MB_2U_LIB.S9S_MB_2U(SCH_1):PAGE89
   256 M_D_CPU0_SB_DQ<10> @S9S_MB_2U_LIB.S9S_MB_2U(SCH_1):M_D_CPU0_SB_DQ(10)    I50 @S9S_MB_2U_LIB.S9S_MB_2U(SCH_1):PAGE89
   258 M_D_CPU0_SB_DQ<11> @S9S_MB_2U_LIB.S9S_MB_2U(SCH_1):M_D_CPU0_SB_DQ(11)    I50 @S9S_MB_2U_LIB.S9S_MB_2U(SCH_1):PAGE89
   118 M_D_CPU0_SB_DQ<12> @S9S_MB_2U_LIB.S9S_MB_2U(SCH_1):M_D_CPU0_SB_DQ(12)    I50 @S9S_MB_2U_LIB.S9S_MB_2U(SCH_1):PAGE89
   120 M_D_CPU0_SB_DQ<13> @S9S_MB_2U_LIB.S9S_MB_2U(SCH_1):M_D_CPU0_SB_DQ(13)    I50 @S9S_MB_2U_LIB.S9S_MB_2U(SCH_1):PAGE89
   263 M_D_CPU0_SB_DQ<14> @S9S_MB_2U_LIB.S9S_MB_2U(SCH_1):M_D_CPU0_SB_DQ(14)    I50 @S9S_MB_2U_LIB.S9S_MB_2U(SCH_1):PAGE89
   265 M_D_CPU0_SB_DQ<15> @S9S_MB_2U_LIB.S9S_MB_2U(SCH_1):M_D_CPU0_SB_DQ(15)    I50 @S9S_MB_2U_LIB.S9S_MB_2U(SCH_1):PAGE89
   122 M_D_CPU0_SB_DQ<16> @S9S_MB_2U_LIB.S9S_MB_2U(SCH_1):M_D_CPU0_SB_DQ(16)    I50 @S9S_MB_2U_LIB.S9S_MB_2U(SCH_1):PAGE89
   124 M_D_CPU0_SB_DQ<17> @S9S_MB_2U_LIB.S9S_MB_2U(SCH_1):M_D_CPU0_SB_DQ(17)    I50 @S9S_MB_2U_LIB.S9S_MB_2U(SCH_1):PAGE89
   267 M_D_CPU0_SB_DQ<18> @S9S_MB_2U_LIB.S9S_MB_2U(SCH_1):M_D_CPU0_SB_DQ(18)    I50 @S9S_MB_2U_LIB.S9S_MB_2U(SCH_1):PAGE89
   269 M_D_CPU0_SB_DQ<19> @S9S_MB_2U_LIB.S9S_MB_2U(SCH_1):M_D_CPU0_SB_DQ(19)    I50 @S9S_MB_2U_LIB.S9S_MB_2U(SCH_1):PAGE89
   129 M_D_CPU0_SB_DQ<20> @S9S_MB_2U_LIB.S9S_MB_2U(SCH_1):M_D_CPU0_SB_DQ(20)    I50 @S9S_MB_2U_LIB.S9S_MB_2U(SCH_1):PAGE89
   131 M_D_CPU0_SB_DQ<21> @S9S_MB_2U_LIB.S9S_MB_2U(SCH_1):M_D_CPU0_SB_DQ(21)    I50 @S9S_MB_2U_LIB.S9S_MB_2U(SCH_1):PAGE89
   274 M_D_CPU0_SB_DQ<22> @S9S_MB_2U_LIB.S9S_MB_2U(SCH_1):M_D_CPU0_SB_DQ(22)    I50 @S9S_MB_2U_LIB.S9S_MB_2U(SCH_1):PAGE89
   276 M_D_CPU0_SB_DQ<23> @S9S_MB_2U_LIB.S9S_MB_2U(SCH_1):M_D_CPU0_SB_DQ(23)    I50 @S9S_MB_2U_LIB.S9S_MB_2U(SCH_1):PAGE89
   133 M_D_CPU0_SB_DQ<24> @S9S_MB_2U_LIB.S9S_MB_2U(SCH_1):M_D_CPU0_SB_DQ(24)    I50 @S9S_MB_2U_LIB.S9S_MB_2U(SCH_1):PAGE89
   135 M_D_CPU0_SB_DQ<25> @S9S_MB_2U_LIB.S9S_MB_2U(SCH_1):M_D_CPU0_SB_DQ(25)    I50 @S9S_MB_2U_LIB.S9S_MB_2U(SCH_1):PAGE89
   278 M_D_CPU0_SB_DQ<26> @S9S_MB_2U_LIB.S9S_MB_2U(SCH_1):M_D_CPU0_SB_DQ(26)    I50 @S9S_MB_2U_LIB.S9S_MB_2U(SCH_1):PAGE89
   280 M_D_CPU0_SB_DQ<27> @S9S_MB_2U_LIB.S9S_MB_2U(SCH_1):M_D_CPU0_SB_DQ(27)    I50 @S9S_MB_2U_LIB.S9S_MB_2U(SCH_1):PAGE89
   140 M_D_CPU0_SB_DQ<28> @S9S_MB_2U_LIB.S9S_MB_2U(SCH_1):M_D_CPU0_SB_DQ(28)    I50 @S9S_MB_2U_LIB.S9S_MB_2U(SCH_1):PAGE89
   142 M_D_CPU0_SB_DQ<29> @S9S_MB_2U_LIB.S9S_MB_2U(SCH_1):M_D_CPU0_SB_DQ(29)    I50 @S9S_MB_2U_LIB.S9S_MB_2U(SCH_1):PAGE89
   285 M_D_CPU0_SB_DQ<30> @S9S_MB_2U_LIB.S9S_MB_2U(SCH_1):M_D_CPU0_SB_DQ(30)    I50 @S9S_MB_2U_LIB.S9S_MB_2U(SCH_1):PAGE89
   287 M_D_CPU0_SB_DQ<31> @S9S_MB_2U_LIB.S9S_MB_2U(SCH_1):M_D_CPU0_SB_DQ(31)    I50 @S9S_MB_2U_LIB.S9S_MB_2U(SCH_1):PAGE89
     7 M_D_CPU0_SA_DQ<0> @S9S_MB_2U_LIB.S9S_MB_2U(SCH_1):M_D_CPU0_SA_DQ(0)    I50 @S9S_MB_2U_LIB.S9S_MB_2U(SCH_1):PAGE89
     9 M_D_CPU0_SA_DQ<1> @S9S_MB_2U_LIB.S9S_MB_2U(SCH_1):M_D_CPU0_SA_DQ(1)    I50 @S9S_MB_2U_LIB.S9S_MB_2U(SCH_1):PAGE89
   152 M_D_CPU0_SA_DQ<2> @S9S_MB_2U_LIB.S9S_MB_2U(SCH_1):M_D_CPU0_SA_DQ(2)    I50 @S9S_MB_2U_LIB.S9S_MB_2U(SCH_1):PAGE89
   154 M_D_CPU0_SA_DQ<3> @S9S_MB_2U_LIB.S9S_MB_2U(SCH_1):M_D_CPU0_SA_DQ(3)    I50 @S9S_MB_2U_LIB.S9S_MB_2U(SCH_1):PAGE89
    14 M_D_CPU0_SA_DQ<4> @S9S_MB_2U_LIB.S9S_MB_2U(SCH_1):M_D_CPU0_SA_DQ(4)    I50 @S9S_MB_2U_LIB.S9S_MB_2U(SCH_1):PAGE89
    16 M_D_CPU0_SA_DQ<5> @S9S_MB_2U_LIB.S9S_MB_2U(SCH_1):M_D_CPU0_SA_DQ(5)    I50 @S9S_MB_2U_LIB.S9S_MB_2U(SCH_1):PAGE89
   159 M_D_CPU0_SA_DQ<6> @S9S_MB_2U_LIB.S9S_MB_2U(SCH_1):M_D_CPU0_SA_DQ(6)    I50 @S9S_MB_2U_LIB.S9S_MB_2U(SCH_1):PAGE89
   161 M_D_CPU0_SA_DQ<7> @S9S_MB_2U_LIB.S9S_MB_2U(SCH_1):M_D_CPU0_SA_DQ(7)    I50 @S9S_MB_2U_LIB.S9S_MB_2U(SCH_1):PAGE89
    18 M_D_CPU0_SA_DQ<8> @S9S_MB_2U_LIB.S9S_MB_2U(SCH_1):M_D_CPU0_SA_DQ(8)    I50 @S9S_MB_2U_LIB.S9S_MB_2U(SCH_1):PAGE89
    20 M_D_CPU0_SA_DQ<9> @S9S_MB_2U_LIB.S9S_MB_2U(SCH_1):M_D_CPU0_SA_DQ(9)    I50 @S9S_MB_2U_LIB.S9S_MB_2U(SCH_1):PAGE89
   163 M_D_CPU0_SA_DQ<10> @S9S_MB_2U_LIB.S9S_MB_2U(SCH_1):M_D_CPU0_SA_DQ(10)    I50 @S9S_MB_2U_LIB.S9S_MB_2U(SCH_1):PAGE89
   165 M_D_CPU0_SA_DQ<11> @S9S_MB_2U_LIB.S9S_MB_2U(SCH_1):M_D_CPU0_SA_DQ(11)    I50 @S9S_MB_2U_LIB.S9S_MB_2U(SCH_1):PAGE89
    25 M_D_CPU0_SA_DQ<12> @S9S_MB_2U_LIB.S9S_MB_2U(SCH_1):M_D_CPU0_SA_DQ(12)    I50 @S9S_MB_2U_LIB.S9S_MB_2U(SCH_1):PAGE89
    27 M_D_CPU0_SA_DQ<13> @S9S_MB_2U_LIB.S9S_MB_2U(SCH_1):M_D_CPU0_SA_DQ(13)    I50 @S9S_MB_2U_LIB.S9S_MB_2U(SCH_1):PAGE89
   170 M_D_CPU0_SA_DQ<14> @S9S_MB_2U_LIB.S9S_MB_2U(SCH_1):M_D_CPU0_SA_DQ(14)    I50 @S9S_MB_2U_LIB.S9S_MB_2U(SCH_1):PAGE89
   172 M_D_CPU0_SA_DQ<15> @S9S_MB_2U_LIB.S9S_MB_2U(SCH_1):M_D_CPU0_SA_DQ(15)    I50 @S9S_MB_2U_LIB.S9S_MB_2U(SCH_1):PAGE89
    29 M_D_CPU0_SA_DQ<16> @S9S_MB_2U_LIB.S9S_MB_2U(SCH_1):M_D_CPU0_SA_DQ(16)    I50 @S9S_MB_2U_LIB.S9S_MB_2U(SCH_1):PAGE89
    31 M_D_CPU0_SA_DQ<17> @S9S_MB_2U_LIB.S9S_MB_2U(SCH_1):M_D_CPU0_SA_DQ(17)    I50 @S9S_MB_2U_LIB.S9S_MB_2U(SCH_1):PAGE89
   174 M_D_CPU0_SA_DQ<18> @S9S_MB_2U_LIB.S9S_MB_2U(SCH_1):M_D_CPU0_SA_DQ(18)    I50 @S9S_MB_2U_LIB.S9S_MB_2U(SCH_1):PAGE89
   176 M_D_CPU0_SA_DQ<19> @S9S_MB_2U_LIB.S9S_MB_2U(SCH_1):M_D_CPU0_SA_DQ(19)    I50 @S9S_MB_2U_LIB.S9S_MB_2U(SCH_1):PAGE89
    36 M_D_CPU0_SA_DQ<20> @S9S_MB_2U_LIB.S9S_MB_2U(SCH_1):M_D_CPU0_SA_DQ(20)    I50 @S9S_MB_2U_LIB.S9S_MB_2U(SCH_1):PAGE89
    38 M_D_CPU0_SA_DQ<21> @S9S_MB_2U_LIB.S9S_MB_2U(SCH_1):M_D_CPU0_SA_DQ(21)    I50 @S9S_MB_2U_LIB.S9S_MB_2U(SCH_1):PAGE89
   181 M_D_CPU0_SA_DQ<22> @S9S_MB_2U_LIB.S9S_MB_2U(SCH_1):M_D_CPU0_SA_DQ(22)    I50 @S9S_MB_2U_LIB.S9S_MB_2U(SCH_1):PAGE89
   183 M_D_CPU0_SA_DQ<23> @S9S_MB_2U_LIB.S9S_MB_2U(SCH_1):M_D_CPU0_SA_DQ(23)    I50 @S9S_MB_2U_LIB.S9S_MB_2U(SCH_1):PAGE89
    40 M_D_CPU0_SA_DQ<24> @S9S_MB_2U_LIB.S9S_MB_2U(SCH_1):M_D_CPU0_SA_DQ(24)    I50 @S9S_MB_2U_LIB.S9S_MB_2U(SCH_1):PAGE89
    42 M_D_CPU0_SA_DQ<25> @S9S_MB_2U_LIB.S9S_MB_2U(SCH_1):M_D_CPU0_SA_DQ(25)    I50 @S9S_MB_2U_LIB.S9S_MB_2U(SCH_1):PAGE89
   185 M_D_CPU0_SA_DQ<26> @S9S_MB_2U_LIB.S9S_MB_2U(SCH_1):M_D_CPU0_SA_DQ(26)    I50 @S9S_MB_2U_LIB.S9S_MB_2U(SCH_1):PAGE89
   187 M_D_CPU0_SA_DQ<27> @S9S_MB_2U_LIB.S9S_MB_2U(SCH_1):M_D_CPU0_SA_DQ(27)    I50 @S9S_MB_2U_LIB.S9S_MB_2U(SCH_1):PAGE89
    47 M_D_CPU0_SA_DQ<28> @S9S_MB_2U_LIB.S9S_MB_2U(SCH_1):M_D_CPU0_SA_DQ(28)    I50 @S9S_MB_2U_LIB.S9S_MB_2U(SCH_1):PAGE89
    49 M_D_CPU0_SA_DQ<29> @S9S_MB_2U_LIB.S9S_MB_2U(SCH_1):M_D_CPU0_SA_DQ(29)    I50 @S9S_MB_2U_LIB.S9S_MB_2U(SCH_1):PAGE89
   192 M_D_CPU0_SA_DQ<30> @S9S_MB_2U_LIB.S9S_MB_2U(SCH_1):M_D_CPU0_SA_DQ(30)    I50 @S9S_MB_2U_LIB.S9S_MB_2U(SCH_1):PAGE89
   229 M_D_CPU0_SB_CS_N<3> @S9S_MB_2U_LIB.S9S_MB_2U(SCH_1):M_D_CPU0_SB_CS_N(3)    I50 @S9S_MB_2U_LIB.S9S_MB_2U(SCH_1):PAGE89
   209 M_D_CPU0_SA_CS_N<3> @S9S_MB_2U_LIB.S9S_MB_2U(SCH_1):M_D_CPU0_SA_CS_N(3)    I50 @S9S_MB_2U_LIB.S9S_MB_2U(SCH_1):PAGE89
    84 M_D_CPU0_SB_CS_N<2> @S9S_MB_2U_LIB.S9S_MB_2U(SCH_1):M_D_CPU0_SB_CS_N(2)    I50 @S9S_MB_2U_LIB.S9S_MB_2U(SCH_1):PAGE89
    64 M_D_CPU0_SA_CS_N<2> @S9S_MB_2U_LIB.S9S_MB_2U(SCH_1):M_D_CPU0_SA_CS_N(2)    I50 @S9S_MB_2U_LIB.S9S_MB_2U(SCH_1):PAGE89
   217 M_D_CPU0_CLK_DP<1> @S9S_MB_2U_LIB.S9S_MB_2U(SCH_1):M_D_CPU0_CLK_DP(1)    I50 @S9S_MB_2U_LIB.S9S_MB_2U(SCH_1):PAGE89
   218 M_D_CPU0_CLK_DN<1> @S9S_MB_2U_LIB.S9S_MB_2U(SCH_1):M_D_CPU0_CLK_DN(1)    I50 @S9S_MB_2U_LIB.S9S_MB_2U(SCH_1):PAGE89
    96 M_D_CPU0_SB_CB<0> @S9S_MB_2U_LIB.S9S_MB_2U(SCH_1):M_D_CPU0_SB_CB(0)    I50 @S9S_MB_2U_LIB.S9S_MB_2U(SCH_1):PAGE89
    98 M_D_CPU0_SB_CB<1> @S9S_MB_2U_LIB.S9S_MB_2U(SCH_1):M_D_CPU0_SB_CB(1)    I50 @S9S_MB_2U_LIB.S9S_MB_2U(SCH_1):PAGE89
   241 M_D_CPU0_SB_CB<2> @S9S_MB_2U_LIB.S9S_MB_2U(SCH_1):M_D_CPU0_SB_CB(2)    I50 @S9S_MB_2U_LIB.S9S_MB_2U(SCH_1):PAGE89
   243 M_D_CPU0_SB_CB<3> @S9S_MB_2U_LIB.S9S_MB_2U(SCH_1):M_D_CPU0_SB_CB(3)    I50 @S9S_MB_2U_LIB.S9S_MB_2U(SCH_1):PAGE89
    89 M_D_CPU0_SB_CB<4> @S9S_MB_2U_LIB.S9S_MB_2U(SCH_1):M_D_CPU0_SB_CB(4)    I50 @S9S_MB_2U_LIB.S9S_MB_2U(SCH_1):PAGE89
    91 M_D_CPU0_SB_CB<5> @S9S_MB_2U_LIB.S9S_MB_2U(SCH_1):M_D_CPU0_SB_CB(5)    I50 @S9S_MB_2U_LIB.S9S_MB_2U(SCH_1):PAGE89
   234 M_D_CPU0_SB_CB<6> @S9S_MB_2U_LIB.S9S_MB_2U(SCH_1):M_D_CPU0_SB_CB(6)    I50 @S9S_MB_2U_LIB.S9S_MB_2U(SCH_1):PAGE89
    51 M_D_CPU0_SA_CB<0> @S9S_MB_2U_LIB.S9S_MB_2U(SCH_1):M_D_CPU0_SA_CB(0)    I50 @S9S_MB_2U_LIB.S9S_MB_2U(SCH_1):PAGE89
   196 M_D_CPU0_SA_CB<2> @S9S_MB_2U_LIB.S9S_MB_2U(SCH_1):M_D_CPU0_SA_CB(2)    I50 @S9S_MB_2U_LIB.S9S_MB_2U(SCH_1):PAGE89
   198 M_D_CPU0_SA_CB<3> @S9S_MB_2U_LIB.S9S_MB_2U(SCH_1):M_D_CPU0_SA_CB(3)    I50 @S9S_MB_2U_LIB.S9S_MB_2U(SCH_1):PAGE89
    60 M_D_CPU0_SA_CB<5> @S9S_MB_2U_LIB.S9S_MB_2U(SCH_1):M_D_CPU0_SA_CB(5)    I50 @S9S_MB_2U_LIB.S9S_MB_2U(SCH_1):PAGE89
   203 M_D_CPU0_SA_CB<6> @S9S_MB_2U_LIB.S9S_MB_2U(SCH_1):M_D_CPU0_SA_CB(6)    I50 @S9S_MB_2U_LIB.S9S_MB_2U(SCH_1):PAGE89
    82 M_D_CPU0_SB_CA<6> @S9S_MB_2U_LIB.S9S_MB_2U(SCH_1):M_D_CPU0_SB_CA(6)    I50 @S9S_MB_2U_LIB.S9S_MB_2U(SCH_1):PAGE89
    72 M_D_CPU0_SA_CA<6> @S9S_MB_2U_LIB.S9S_MB_2U(SCH_1):M_D_CPU0_SA_CA(6)    I50 @S9S_MB_2U_LIB.S9S_MB_2U(SCH_1):PAGE89
   225 M_D_CPU0_SB_CA<5> @S9S_MB_2U_LIB.S9S_MB_2U(SCH_1):M_D_CPU0_SB_CA(5)    I50 @S9S_MB_2U_LIB.S9S_MB_2U(SCH_1):PAGE89
   215 M_D_CPU0_SA_CA<5> @S9S_MB_2U_LIB.S9S_MB_2U(SCH_1):M_D_CPU0_SA_CA(5)    I50 @S9S_MB_2U_LIB.S9S_MB_2U(SCH_1):PAGE89
    80 M_D_CPU0_SB_CA<4> @S9S_MB_2U_LIB.S9S_MB_2U(SCH_1):M_D_CPU0_SB_CA(4)    I50 @S9S_MB_2U_LIB.S9S_MB_2U(SCH_1):PAGE89
    70 M_D_CPU0_SA_CA<4> @S9S_MB_2U_LIB.S9S_MB_2U(SCH_1):M_D_CPU0_SA_CA(4)    I50 @S9S_MB_2U_LIB.S9S_MB_2U(SCH_1):PAGE89
   223 M_D_CPU0_SB_CA<3> @S9S_MB_2U_LIB.S9S_MB_2U(SCH_1):M_D_CPU0_SB_CA(3)    I50 @S9S_MB_2U_LIB.S9S_MB_2U(SCH_1):PAGE89
   213 M_D_CPU0_SA_CA<3> @S9S_MB_2U_LIB.S9S_MB_2U(SCH_1):M_D_CPU0_SA_CA(3)    I50 @S9S_MB_2U_LIB.S9S_MB_2U(SCH_1):PAGE89
    78 M_D_CPU0_SB_CA<2> @S9S_MB_2U_LIB.S9S_MB_2U(SCH_1):M_D_CPU0_SB_CA(2)    I50 @S9S_MB_2U_LIB.S9S_MB_2U(SCH_1):PAGE89
    68 M_D_CPU0_SA_CA<2> @S9S_MB_2U_LIB.S9S_MB_2U(SCH_1):M_D_CPU0_SA_CA(2)    I50 @S9S_MB_2U_LIB.S9S_MB_2U(SCH_1):PAGE89
   221 M_D_CPU0_SB_CA<1> @S9S_MB_2U_LIB.S9S_MB_2U(SCH_1):M_D_CPU0_SB_CA(1)    I50 @S9S_MB_2U_LIB.S9S_MB_2U(SCH_1):PAGE89
   211 M_D_CPU0_SA_CA<1> @S9S_MB_2U_LIB.S9S_MB_2U(SCH_1):M_D_CPU0_SA_CA(1)    I50 @S9S_MB_2U_LIB.S9S_MB_2U(SCH_1):PAGE89
    76 M_D_CPU0_SB_CA<0> @S9S_MB_2U_LIB.S9S_MB_2U(SCH_1):M_D_CPU0_SB_CA(0)    I50 @S9S_MB_2U_LIB.S9S_MB_2U(SCH_1):PAGE89
    66 M_D_CPU0_SA_CA<0> @S9S_MB_2U_LIB.S9S_MB_2U(SCH_1):M_D_CPU0_SA_CA(0)    I50 @S9S_MB_2U_LIB.S9S_MB_2U(SCH_1):PAGE89
    62 M_D_CPU0_ALERT_N @S9S_MB_2U_LIB.S9S_MB_2U(SCH_1):M_D_CPU0_ALERT_N    I50 @S9S_MB_2U_LIB.S9S_MB_2U(SCH_1):PAGE89
   236 M_D_CPU0_SB_CB<7> @S9S_MB_2U_LIB.S9S_MB_2U(SCH_1):M_D_CPU0_SB_CB(7)    I50 @S9S_MB_2U_LIB.S9S_MB_2U(SCH_1):PAGE89
    53 M_D_CPU0_SA_CB<1> @S9S_MB_2U_LIB.S9S_MB_2U(SCH_1):M_D_CPU0_SA_CB(1)    I50 @S9S_MB_2U_LIB.S9S_MB_2U(SCH_1):PAGE89
    58 M_D_CPU0_SA_CB<4> @S9S_MB_2U_LIB.S9S_MB_2U(SCH_1):M_D_CPU0_SA_CB(4)    I50 @S9S_MB_2U_LIB.S9S_MB_2U(SCH_1):PAGE89
   205 M_D_CPU0_SA_CB<7> @S9S_MB_2U_LIB.S9S_MB_2U(SCH_1):M_D_CPU0_SA_CB(7)    I50 @S9S_MB_2U_LIB.S9S_MB_2U(SCH_1):PAGE89
   194 M_D_CPU0_SA_DQ<31> @S9S_MB_2U_LIB.S9S_MB_2U(SCH_1):M_D_CPU0_SA_DQ(31)    I50 @S9S_MB_2U_LIB.S9S_MB_2U(SCH_1):PAGE89
    93 M_D_CPU0_SB_DQS_DP<9> @S9S_MB_2U_LIB.S9S_MB_2U(SCH_1):M_D_CPU0_SB_DQS_DP(9)   I178 @S9S_MB_2U_LIB.S9S_MB_2U(SCH_1):PAGE89
    94 M_D_CPU0_SB_DQS_DN<9> @S9S_MB_2U_LIB.S9S_MB_2U(SCH_1):M_D_CPU0_SB_DQS_DN(9)   I178 @S9S_MB_2U_LIB.S9S_MB_2U(SCH_1):PAGE89
   201 M_D_CPU0_SA_DQS_DP<9> @S9S_MB_2U_LIB.S9S_MB_2U(SCH_1):M_D_CPU0_SA_DQS_DP(9)   I178 @S9S_MB_2U_LIB.S9S_MB_2U(SCH_1):PAGE89
   200 M_D_CPU0_SA_DQS_DN<9> @S9S_MB_2U_LIB.S9S_MB_2U(SCH_1):M_D_CPU0_SA_DQS_DN(9)   I178 @S9S_MB_2U_LIB.S9S_MB_2U(SCH_1):PAGE89
   190 M_D_CPU0_SA_DQS_DP<8> @S9S_MB_2U_LIB.S9S_MB_2U(SCH_1):M_D_CPU0_SA_DQS_DP(8)   I178 @S9S_MB_2U_LIB.S9S_MB_2U(SCH_1):PAGE89
   189 M_D_CPU0_SA_DQS_DN<8> @S9S_MB_2U_LIB.S9S_MB_2U(SCH_1):M_D_CPU0_SA_DQS_DN(8)   I178 @S9S_MB_2U_LIB.S9S_MB_2U(SCH_1):PAGE89
   271 M_D_CPU0_SB_DQS_DN<7> @S9S_MB_2U_LIB.S9S_MB_2U(SCH_1):M_D_CPU0_SB_DQS_DN(7)   I178 @S9S_MB_2U_LIB.S9S_MB_2U(SCH_1):PAGE89
   179 M_D_CPU0_SA_DQS_DP<7> @S9S_MB_2U_LIB.S9S_MB_2U(SCH_1):M_D_CPU0_SA_DQS_DP(7)   I178 @S9S_MB_2U_LIB.S9S_MB_2U(SCH_1):PAGE89
   261 M_D_CPU0_SB_DQS_DP<6> @S9S_MB_2U_LIB.S9S_MB_2U(SCH_1):M_D_CPU0_SB_DQS_DP(6)   I178 @S9S_MB_2U_LIB.S9S_MB_2U(SCH_1):PAGE89
   260 M_D_CPU0_SB_DQS_DN<6> @S9S_MB_2U_LIB.S9S_MB_2U(SCH_1):M_D_CPU0_SB_DQS_DN(6)   I178 @S9S_MB_2U_LIB.S9S_MB_2U(SCH_1):PAGE89
   167 M_D_CPU0_SA_DQS_DN<6> @S9S_MB_2U_LIB.S9S_MB_2U(SCH_1):M_D_CPU0_SA_DQS_DN(6)   I178 @S9S_MB_2U_LIB.S9S_MB_2U(SCH_1):PAGE89
   250 M_D_CPU0_SB_DQS_DP<5> @S9S_MB_2U_LIB.S9S_MB_2U(SCH_1):M_D_CPU0_SB_DQS_DP(5)   I178 @S9S_MB_2U_LIB.S9S_MB_2U(SCH_1):PAGE89
   249 M_D_CPU0_SB_DQS_DN<5> @S9S_MB_2U_LIB.S9S_MB_2U(SCH_1):M_D_CPU0_SB_DQS_DN(5)   I178 @S9S_MB_2U_LIB.S9S_MB_2U(SCH_1):PAGE89
   157 M_D_CPU0_SA_DQS_DP<5> @S9S_MB_2U_LIB.S9S_MB_2U(SCH_1):M_D_CPU0_SA_DQS_DP(5)   I178 @S9S_MB_2U_LIB.S9S_MB_2U(SCH_1):PAGE89
   156 M_D_CPU0_SA_DQS_DN<5> @S9S_MB_2U_LIB.S9S_MB_2U(SCH_1):M_D_CPU0_SA_DQS_DN(5)   I178 @S9S_MB_2U_LIB.S9S_MB_2U(SCH_1):PAGE89
   239 M_D_CPU0_SB_DQS_DP<4> @S9S_MB_2U_LIB.S9S_MB_2U(SCH_1):M_D_CPU0_SB_DQS_DP(4)   I178 @S9S_MB_2U_LIB.S9S_MB_2U(SCH_1):PAGE89
   238 M_D_CPU0_SB_DQS_DN<4> @S9S_MB_2U_LIB.S9S_MB_2U(SCH_1):M_D_CPU0_SB_DQS_DN(4)   I178 @S9S_MB_2U_LIB.S9S_MB_2U(SCH_1):PAGE89
    55 M_D_CPU0_SA_DQS_DP<4> @S9S_MB_2U_LIB.S9S_MB_2U(SCH_1):M_D_CPU0_SA_DQS_DP(4)   I178 @S9S_MB_2U_LIB.S9S_MB_2U(SCH_1):PAGE89
    56 M_D_CPU0_SA_DQS_DN<4> @S9S_MB_2U_LIB.S9S_MB_2U(SCH_1):M_D_CPU0_SA_DQS_DN(4)   I178 @S9S_MB_2U_LIB.S9S_MB_2U(SCH_1):PAGE89
   137 M_D_CPU0_SB_DQS_DP<3> @S9S_MB_2U_LIB.S9S_MB_2U(SCH_1):M_D_CPU0_SB_DQS_DP(3)   I178 @S9S_MB_2U_LIB.S9S_MB_2U(SCH_1):PAGE89
   138 M_D_CPU0_SB_DQS_DN<3> @S9S_MB_2U_LIB.S9S_MB_2U(SCH_1):M_D_CPU0_SB_DQS_DN(3)   I178 @S9S_MB_2U_LIB.S9S_MB_2U(SCH_1):PAGE89
    44 M_D_CPU0_SA_DQS_DP<3> @S9S_MB_2U_LIB.S9S_MB_2U(SCH_1):M_D_CPU0_SA_DQS_DP(3)   I178 @S9S_MB_2U_LIB.S9S_MB_2U(SCH_1):PAGE89
    45 M_D_CPU0_SA_DQS_DN<3> @S9S_MB_2U_LIB.S9S_MB_2U(SCH_1):M_D_CPU0_SA_DQS_DN(3)   I178 @S9S_MB_2U_LIB.S9S_MB_2U(SCH_1):PAGE89
   126 M_D_CPU0_SB_DQS_DP<2> @S9S_MB_2U_LIB.S9S_MB_2U(SCH_1):M_D_CPU0_SB_DQS_DP(2)   I178 @S9S_MB_2U_LIB.S9S_MB_2U(SCH_1):PAGE89
   127 M_D_CPU0_SB_DQS_DN<2> @S9S_MB_2U_LIB.S9S_MB_2U(SCH_1):M_D_CPU0_SB_DQS_DN(2)   I178 @S9S_MB_2U_LIB.S9S_MB_2U(SCH_1):PAGE89
    33 M_D_CPU0_SA_DQS_DP<2> @S9S_MB_2U_LIB.S9S_MB_2U(SCH_1):M_D_CPU0_SA_DQS_DP(2)   I178 @S9S_MB_2U_LIB.S9S_MB_2U(SCH_1):PAGE89
    34 M_D_CPU0_SA_DQS_DN<2> @S9S_MB_2U_LIB.S9S_MB_2U(SCH_1):M_D_CPU0_SA_DQS_DN(2)   I178 @S9S_MB_2U_LIB.S9S_MB_2U(SCH_1):PAGE89
   115 M_D_CPU0_SB_DQS_DP<1> @S9S_MB_2U_LIB.S9S_MB_2U(SCH_1):M_D_CPU0_SB_DQS_DP(1)   I178 @S9S_MB_2U_LIB.S9S_MB_2U(SCH_1):PAGE89
   116 M_D_CPU0_SB_DQS_DN<1> @S9S_MB_2U_LIB.S9S_MB_2U(SCH_1):M_D_CPU0_SB_DQS_DN(1)   I178 @S9S_MB_2U_LIB.S9S_MB_2U(SCH_1):PAGE89
    22 M_D_CPU0_SA_DQS_DP<1> @S9S_MB_2U_LIB.S9S_MB_2U(SCH_1):M_D_CPU0_SA_DQS_DP(1)   I178 @S9S_MB_2U_LIB.S9S_MB_2U(SCH_1):PAGE89
    23 M_D_CPU0_SA_DQS_DN<1> @S9S_MB_2U_LIB.S9S_MB_2U(SCH_1):M_D_CPU0_SA_DQS_DN(1)   I178 @S9S_MB_2U_LIB.S9S_MB_2U(SCH_1):PAGE89
   104 M_D_CPU0_SB_DQS_DP<0> @S9S_MB_2U_LIB.S9S_MB_2U(SCH_1):M_D_CPU0_SB_DQS_DP(0)   I178 @S9S_MB_2U_LIB.S9S_MB_2U(SCH_1):PAGE89
   105 M_D_CPU0_SB_DQS_DN<0> @S9S_MB_2U_LIB.S9S_MB_2U(SCH_1):M_D_CPU0_SB_DQS_DN(0)   I178 @S9S_MB_2U_LIB.S9S_MB_2U(SCH_1):PAGE89
    11 M_D_CPU0_SA_DQS_DP<0> @S9S_MB_2U_LIB.S9S_MB_2U(SCH_1):M_D_CPU0_SA_DQS_DP(0)   I178 @S9S_MB_2U_LIB.S9S_MB_2U(SCH_1):PAGE89
    12 M_D_CPU0_SA_DQS_DN<0> @S9S_MB_2U_LIB.S9S_MB_2U(SCH_1):M_D_CPU0_SA_DQS_DN(0)   I178 @S9S_MB_2U_LIB.S9S_MB_2U(SCH_1):PAGE89
   272 M_D_CPU0_SB_DQS_DP<7> @S9S_MB_2U_LIB.S9S_MB_2U(SCH_1):M_D_CPU0_SB_DQS_DP(7)   I178 @S9S_MB_2U_LIB.S9S_MB_2U(SCH_1):PAGE89
   282 M_D_CPU0_SB_DQS_DN<8> @S9S_MB_2U_LIB.S9S_MB_2U(SCH_1):M_D_CPU0_SB_DQS_DN(8)   I178 @S9S_MB_2U_LIB.S9S_MB_2U(SCH_1):PAGE89
   283 M_D_CPU0_SB_DQS_DP<8> @S9S_MB_2U_LIB.S9S_MB_2U(SCH_1):M_D_CPU0_SB_DQS_DP(8)   I178 @S9S_MB_2U_LIB.S9S_MB_2U(SCH_1):PAGE89
   168 M_D_CPU0_SA_DQS_DP<6> @S9S_MB_2U_LIB.S9S_MB_2U(SCH_1):M_D_CPU0_SA_DQS_DP(6)   I178 @S9S_MB_2U_LIB.S9S_MB_2U(SCH_1):PAGE89
   178 M_D_CPU0_SA_DQS_DN<7> @S9S_MB_2U_LIB.S9S_MB_2U(SCH_1):M_D_CPU0_SA_DQS_DN(7)   I178 @S9S_MB_2U_LIB.S9S_MB_2U(SCH_1):PAGE89
     6    GND @S9S_MB_2U_LIB.S9S_MB_2U(SCH_1):GND   I175 @S9S_MB_2U_LIB.S9S_MB_2U(SCH_1):PAGE89
     8    GND @S9S_MB_2U_LIB.S9S_MB_2U(SCH_1):GND   I175 @S9S_MB_2U_LIB.S9S_MB_2U(SCH_1):PAGE89
    10    GND @S9S_MB_2U_LIB.S9S_MB_2U(SCH_1):GND   I175 @S9S_MB_2U_LIB.S9S_MB_2U(SCH_1):PAGE89
    13    GND @S9S_MB_2U_LIB.S9S_MB_2U(SCH_1):GND   I175 @S9S_MB_2U_LIB.S9S_MB_2U(SCH_1):PAGE89
    15    GND @S9S_MB_2U_LIB.S9S_MB_2U(SCH_1):GND   I175 @S9S_MB_2U_LIB.S9S_MB_2U(SCH_1):PAGE89
    17    GND @S9S_MB_2U_LIB.S9S_MB_2U(SCH_1):GND   I175 @S9S_MB_2U_LIB.S9S_MB_2U(SCH_1):PAGE89
    19    GND @S9S_MB_2U_LIB.S9S_MB_2U(SCH_1):GND   I175 @S9S_MB_2U_LIB.S9S_MB_2U(SCH_1):PAGE89
    21    GND @S9S_MB_2U_LIB.S9S_MB_2U(SCH_1):GND   I175 @S9S_MB_2U_LIB.S9S_MB_2U(SCH_1):PAGE89
    24    GND @S9S_MB_2U_LIB.S9S_MB_2U(SCH_1):GND   I175 @S9S_MB_2U_LIB.S9S_MB_2U(SCH_1):PAGE89
    26    GND @S9S_MB_2U_LIB.S9S_MB_2U(SCH_1):GND   I175 @S9S_MB_2U_LIB.S9S_MB_2U(SCH_1):PAGE89
    28    GND @S9S_MB_2U_LIB.S9S_MB_2U(SCH_1):GND   I175 @S9S_MB_2U_LIB.S9S_MB_2U(SCH_1):PAGE89
    30    GND @S9S_MB_2U_LIB.S9S_MB_2U(SCH_1):GND   I175 @S9S_MB_2U_LIB.S9S_MB_2U(SCH_1):PAGE89
    32    GND @S9S_MB_2U_LIB.S9S_MB_2U(SCH_1):GND   I175 @S9S_MB_2U_LIB.S9S_MB_2U(SCH_1):PAGE89
    35    GND @S9S_MB_2U_LIB.S9S_MB_2U(SCH_1):GND   I175 @S9S_MB_2U_LIB.S9S_MB_2U(SCH_1):PAGE89
    37    GND @S9S_MB_2U_LIB.S9S_MB_2U(SCH_1):GND   I175 @S9S_MB_2U_LIB.S9S_MB_2U(SCH_1):PAGE89
    39    GND @S9S_MB_2U_LIB.S9S_MB_2U(SCH_1):GND   I175 @S9S_MB_2U_LIB.S9S_MB_2U(SCH_1):PAGE89
    41    GND @S9S_MB_2U_LIB.S9S_MB_2U(SCH_1):GND   I175 @S9S_MB_2U_LIB.S9S_MB_2U(SCH_1):PAGE89
    43    GND @S9S_MB_2U_LIB.S9S_MB_2U(SCH_1):GND   I175 @S9S_MB_2U_LIB.S9S_MB_2U(SCH_1):PAGE89
    46    GND @S9S_MB_2U_LIB.S9S_MB_2U(SCH_1):GND   I175 @S9S_MB_2U_LIB.S9S_MB_2U(SCH_1):PAGE89
    48    GND @S9S_MB_2U_LIB.S9S_MB_2U(SCH_1):GND   I175 @S9S_MB_2U_LIB.S9S_MB_2U(SCH_1):PAGE89
    50    GND @S9S_MB_2U_LIB.S9S_MB_2U(SCH_1):GND   I175 @S9S_MB_2U_LIB.S9S_MB_2U(SCH_1):PAGE89
    52    GND @S9S_MB_2U_LIB.S9S_MB_2U(SCH_1):GND   I175 @S9S_MB_2U_LIB.S9S_MB_2U(SCH_1):PAGE89
    54    GND @S9S_MB_2U_LIB.S9S_MB_2U(SCH_1):GND   I175 @S9S_MB_2U_LIB.S9S_MB_2U(SCH_1):PAGE89
    57    GND @S9S_MB_2U_LIB.S9S_MB_2U(SCH_1):GND   I175 @S9S_MB_2U_LIB.S9S_MB_2U(SCH_1):PAGE89
    59    GND @S9S_MB_2U_LIB.S9S_MB_2U(SCH_1):GND   I175 @S9S_MB_2U_LIB.S9S_MB_2U(SCH_1):PAGE89
    61    GND @S9S_MB_2U_LIB.S9S_MB_2U(SCH_1):GND   I175 @S9S_MB_2U_LIB.S9S_MB_2U(SCH_1):PAGE89
    63    GND @S9S_MB_2U_LIB.S9S_MB_2U(SCH_1):GND   I175 @S9S_MB_2U_LIB.S9S_MB_2U(SCH_1):PAGE89
    65    GND @S9S_MB_2U_LIB.S9S_MB_2U(SCH_1):GND   I175 @S9S_MB_2U_LIB.S9S_MB_2U(SCH_1):PAGE89
    67    GND @S9S_MB_2U_LIB.S9S_MB_2U(SCH_1):GND   I175 @S9S_MB_2U_LIB.S9S_MB_2U(SCH_1):PAGE89
    69    GND @S9S_MB_2U_LIB.S9S_MB_2U(SCH_1):GND   I175 @S9S_MB_2U_LIB.S9S_MB_2U(SCH_1):PAGE89
    71    GND @S9S_MB_2U_LIB.S9S_MB_2U(SCH_1):GND   I175 @S9S_MB_2U_LIB.S9S_MB_2U(SCH_1):PAGE89
    73    GND @S9S_MB_2U_LIB.S9S_MB_2U(SCH_1):GND   I175 @S9S_MB_2U_LIB.S9S_MB_2U(SCH_1):PAGE89
    75    GND @S9S_MB_2U_LIB.S9S_MB_2U(SCH_1):GND   I175 @S9S_MB_2U_LIB.S9S_MB_2U(SCH_1):PAGE89
    77    GND @S9S_MB_2U_LIB.S9S_MB_2U(SCH_1):GND   I175 @S9S_MB_2U_LIB.S9S_MB_2U(SCH_1):PAGE89
    79    GND @S9S_MB_2U_LIB.S9S_MB_2U(SCH_1):GND   I175 @S9S_MB_2U_LIB.S9S_MB_2U(SCH_1):PAGE89
    81    GND @S9S_MB_2U_LIB.S9S_MB_2U(SCH_1):GND   I175 @S9S_MB_2U_LIB.S9S_MB_2U(SCH_1):PAGE89
    83    GND @S9S_MB_2U_LIB.S9S_MB_2U(SCH_1):GND   I175 @S9S_MB_2U_LIB.S9S_MB_2U(SCH_1):PAGE89
    85    GND @S9S_MB_2U_LIB.S9S_MB_2U(SCH_1):GND   I175 @S9S_MB_2U_LIB.S9S_MB_2U(SCH_1):PAGE89
    88    GND @S9S_MB_2U_LIB.S9S_MB_2U(SCH_1):GND   I175 @S9S_MB_2U_LIB.S9S_MB_2U(SCH_1):PAGE89
    90    GND @S9S_MB_2U_LIB.S9S_MB_2U(SCH_1):GND   I175 @S9S_MB_2U_LIB.S9S_MB_2U(SCH_1):PAGE89
    92    GND @S9S_MB_2U_LIB.S9S_MB_2U(SCH_1):GND   I175 @S9S_MB_2U_LIB.S9S_MB_2U(SCH_1):PAGE89
    95    GND @S9S_MB_2U_LIB.S9S_MB_2U(SCH_1):GND   I175 @S9S_MB_2U_LIB.S9S_MB_2U(SCH_1):PAGE89
    97    GND @S9S_MB_2U_LIB.S9S_MB_2U(SCH_1):GND   I175 @S9S_MB_2U_LIB.S9S_MB_2U(SCH_1):PAGE89
    99    GND @S9S_MB_2U_LIB.S9S_MB_2U(SCH_1):GND   I175 @S9S_MB_2U_LIB.S9S_MB_2U(SCH_1):PAGE89
   101    GND @S9S_MB_2U_LIB.S9S_MB_2U(SCH_1):GND   I175 @S9S_MB_2U_LIB.S9S_MB_2U(SCH_1):PAGE89
   103    GND @S9S_MB_2U_LIB.S9S_MB_2U(SCH_1):GND   I175 @S9S_MB_2U_LIB.S9S_MB_2U(SCH_1):PAGE89
   106    GND @S9S_MB_2U_LIB.S9S_MB_2U(SCH_1):GND   I175 @S9S_MB_2U_LIB.S9S_MB_2U(SCH_1):PAGE89
   108    GND @S9S_MB_2U_LIB.S9S_MB_2U(SCH_1):GND   I175 @S9S_MB_2U_LIB.S9S_MB_2U(SCH_1):PAGE89
   110    GND @S9S_MB_2U_LIB.S9S_MB_2U(SCH_1):GND   I175 @S9S_MB_2U_LIB.S9S_MB_2U(SCH_1):PAGE89
   112    GND @S9S_MB_2U_LIB.S9S_MB_2U(SCH_1):GND   I175 @S9S_MB_2U_LIB.S9S_MB_2U(SCH_1):PAGE89
   114    GND @S9S_MB_2U_LIB.S9S_MB_2U(SCH_1):GND   I175 @S9S_MB_2U_LIB.S9S_MB_2U(SCH_1):PAGE89
   117    GND @S9S_MB_2U_LIB.S9S_MB_2U(SCH_1):GND   I175 @S9S_MB_2U_LIB.S9S_MB_2U(SCH_1):PAGE89
   119    GND @S9S_MB_2U_LIB.S9S_MB_2U(SCH_1):GND   I175 @S9S_MB_2U_LIB.S9S_MB_2U(SCH_1):PAGE89
   121    GND @S9S_MB_2U_LIB.S9S_MB_2U(SCH_1):GND   I175 @S9S_MB_2U_LIB.S9S_MB_2U(SCH_1):PAGE89
   123    GND @S9S_MB_2U_LIB.S9S_MB_2U(SCH_1):GND   I175 @S9S_MB_2U_LIB.S9S_MB_2U(SCH_1):PAGE89
   125    GND @S9S_MB_2U_LIB.S9S_MB_2U(SCH_1):GND   I175 @S9S_MB_2U_LIB.S9S_MB_2U(SCH_1):PAGE89
   128    GND @S9S_MB_2U_LIB.S9S_MB_2U(SCH_1):GND   I175 @S9S_MB_2U_LIB.S9S_MB_2U(SCH_1):PAGE89
   130    GND @S9S_MB_2U_LIB.S9S_MB_2U(SCH_1):GND   I175 @S9S_MB_2U_LIB.S9S_MB_2U(SCH_1):PAGE89
   134    GND @S9S_MB_2U_LIB.S9S_MB_2U(SCH_1):GND   I175 @S9S_MB_2U_LIB.S9S_MB_2U(SCH_1):PAGE89
   143    GND @S9S_MB_2U_LIB.S9S_MB_2U(SCH_1):GND   I175 @S9S_MB_2U_LIB.S9S_MB_2U(SCH_1):PAGE89
   151    GND @S9S_MB_2U_LIB.S9S_MB_2U(SCH_1):GND   I175 @S9S_MB_2U_LIB.S9S_MB_2U(SCH_1):PAGE89
   153    GND @S9S_MB_2U_LIB.S9S_MB_2U(SCH_1):GND   I175 @S9S_MB_2U_LIB.S9S_MB_2U(SCH_1):PAGE89
   155    GND @S9S_MB_2U_LIB.S9S_MB_2U(SCH_1):GND   I175 @S9S_MB_2U_LIB.S9S_MB_2U(SCH_1):PAGE89
   158    GND @S9S_MB_2U_LIB.S9S_MB_2U(SCH_1):GND   I175 @S9S_MB_2U_LIB.S9S_MB_2U(SCH_1):PAGE89
   160    GND @S9S_MB_2U_LIB.S9S_MB_2U(SCH_1):GND   I175 @S9S_MB_2U_LIB.S9S_MB_2U(SCH_1):PAGE89
   162    GND @S9S_MB_2U_LIB.S9S_MB_2U(SCH_1):GND   I175 @S9S_MB_2U_LIB.S9S_MB_2U(SCH_1):PAGE89
   164    GND @S9S_MB_2U_LIB.S9S_MB_2U(SCH_1):GND   I175 @S9S_MB_2U_LIB.S9S_MB_2U(SCH_1):PAGE89
   166    GND @S9S_MB_2U_LIB.S9S_MB_2U(SCH_1):GND   I175 @S9S_MB_2U_LIB.S9S_MB_2U(SCH_1):PAGE89
   169    GND @S9S_MB_2U_LIB.S9S_MB_2U(SCH_1):GND   I175 @S9S_MB_2U_LIB.S9S_MB_2U(SCH_1):PAGE89
   171    GND @S9S_MB_2U_LIB.S9S_MB_2U(SCH_1):GND   I175 @S9S_MB_2U_LIB.S9S_MB_2U(SCH_1):PAGE89
   173    GND @S9S_MB_2U_LIB.S9S_MB_2U(SCH_1):GND   I175 @S9S_MB_2U_LIB.S9S_MB_2U(SCH_1):PAGE89
   175    GND @S9S_MB_2U_LIB.S9S_MB_2U(SCH_1):GND   I175 @S9S_MB_2U_LIB.S9S_MB_2U(SCH_1):PAGE89
   177    GND @S9S_MB_2U_LIB.S9S_MB_2U(SCH_1):GND   I175 @S9S_MB_2U_LIB.S9S_MB_2U(SCH_1):PAGE89
   180    GND @S9S_MB_2U_LIB.S9S_MB_2U(SCH_1):GND   I175 @S9S_MB_2U_LIB.S9S_MB_2U(SCH_1):PAGE89
   182    GND @S9S_MB_2U_LIB.S9S_MB_2U(SCH_1):GND   I175 @S9S_MB_2U_LIB.S9S_MB_2U(SCH_1):PAGE89
   184    GND @S9S_MB_2U_LIB.S9S_MB_2U(SCH_1):GND   I175 @S9S_MB_2U_LIB.S9S_MB_2U(SCH_1):PAGE89
   186    GND @S9S_MB_2U_LIB.S9S_MB_2U(SCH_1):GND   I175 @S9S_MB_2U_LIB.S9S_MB_2U(SCH_1):PAGE89
   188    GND @S9S_MB_2U_LIB.S9S_MB_2U(SCH_1):GND   I175 @S9S_MB_2U_LIB.S9S_MB_2U(SCH_1):PAGE89
   191    GND @S9S_MB_2U_LIB.S9S_MB_2U(SCH_1):GND   I175 @S9S_MB_2U_LIB.S9S_MB_2U(SCH_1):PAGE89
   193    GND @S9S_MB_2U_LIB.S9S_MB_2U(SCH_1):GND   I175 @S9S_MB_2U_LIB.S9S_MB_2U(SCH_1):PAGE89
   195    GND @S9S_MB_2U_LIB.S9S_MB_2U(SCH_1):GND   I175 @S9S_MB_2U_LIB.S9S_MB_2U(SCH_1):PAGE89
   197    GND @S9S_MB_2U_LIB.S9S_MB_2U(SCH_1):GND   I175 @S9S_MB_2U_LIB.S9S_MB_2U(SCH_1):PAGE89
   199    GND @S9S_MB_2U_LIB.S9S_MB_2U(SCH_1):GND   I175 @S9S_MB_2U_LIB.S9S_MB_2U(SCH_1):PAGE89
   202    GND @S9S_MB_2U_LIB.S9S_MB_2U(SCH_1):GND   I175 @S9S_MB_2U_LIB.S9S_MB_2U(SCH_1):PAGE89
   204    GND @S9S_MB_2U_LIB.S9S_MB_2U(SCH_1):GND   I175 @S9S_MB_2U_LIB.S9S_MB_2U(SCH_1):PAGE89
   206    GND @S9S_MB_2U_LIB.S9S_MB_2U(SCH_1):GND   I175 @S9S_MB_2U_LIB.S9S_MB_2U(SCH_1):PAGE89
   208    GND @S9S_MB_2U_LIB.S9S_MB_2U(SCH_1):GND   I175 @S9S_MB_2U_LIB.S9S_MB_2U(SCH_1):PAGE89
   210    GND @S9S_MB_2U_LIB.S9S_MB_2U(SCH_1):GND   I175 @S9S_MB_2U_LIB.S9S_MB_2U(SCH_1):PAGE89
   212    GND @S9S_MB_2U_LIB.S9S_MB_2U(SCH_1):GND   I175 @S9S_MB_2U_LIB.S9S_MB_2U(SCH_1):PAGE89
   214    GND @S9S_MB_2U_LIB.S9S_MB_2U(SCH_1):GND   I175 @S9S_MB_2U_LIB.S9S_MB_2U(SCH_1):PAGE89
   216    GND @S9S_MB_2U_LIB.S9S_MB_2U(SCH_1):GND   I175 @S9S_MB_2U_LIB.S9S_MB_2U(SCH_1):PAGE89
   219    GND @S9S_MB_2U_LIB.S9S_MB_2U(SCH_1):GND   I175 @S9S_MB_2U_LIB.S9S_MB_2U(SCH_1):PAGE89
   222    GND @S9S_MB_2U_LIB.S9S_MB_2U(SCH_1):GND   I175 @S9S_MB_2U_LIB.S9S_MB_2U(SCH_1):PAGE89
   224    GND @S9S_MB_2U_LIB.S9S_MB_2U(SCH_1):GND   I175 @S9S_MB_2U_LIB.S9S_MB_2U(SCH_1):PAGE89
   226    GND @S9S_MB_2U_LIB.S9S_MB_2U(SCH_1):GND   I175 @S9S_MB_2U_LIB.S9S_MB_2U(SCH_1):PAGE89
   228    GND @S9S_MB_2U_LIB.S9S_MB_2U(SCH_1):GND   I175 @S9S_MB_2U_LIB.S9S_MB_2U(SCH_1):PAGE89
   233    GND @S9S_MB_2U_LIB.S9S_MB_2U(SCH_1):GND   I175 @S9S_MB_2U_LIB.S9S_MB_2U(SCH_1):PAGE89
   237    GND @S9S_MB_2U_LIB.S9S_MB_2U(SCH_1):GND   I175 @S9S_MB_2U_LIB.S9S_MB_2U(SCH_1):PAGE89
   242    GND @S9S_MB_2U_LIB.S9S_MB_2U(SCH_1):GND   I175 @S9S_MB_2U_LIB.S9S_MB_2U(SCH_1):PAGE89
   244    GND @S9S_MB_2U_LIB.S9S_MB_2U(SCH_1):GND   I175 @S9S_MB_2U_LIB.S9S_MB_2U(SCH_1):PAGE89
   246    GND @S9S_MB_2U_LIB.S9S_MB_2U(SCH_1):GND   I175 @S9S_MB_2U_LIB.S9S_MB_2U(SCH_1):PAGE89
   248    GND @S9S_MB_2U_LIB.S9S_MB_2U(SCH_1):GND   I175 @S9S_MB_2U_LIB.S9S_MB_2U(SCH_1):PAGE89
   251    GND @S9S_MB_2U_LIB.S9S_MB_2U(SCH_1):GND   I175 @S9S_MB_2U_LIB.S9S_MB_2U(SCH_1):PAGE89
   253    GND @S9S_MB_2U_LIB.S9S_MB_2U(SCH_1):GND   I175 @S9S_MB_2U_LIB.S9S_MB_2U(SCH_1):PAGE89
   255    GND @S9S_MB_2U_LIB.S9S_MB_2U(SCH_1):GND   I175 @S9S_MB_2U_LIB.S9S_MB_2U(SCH_1):PAGE89
   257    GND @S9S_MB_2U_LIB.S9S_MB_2U(SCH_1):GND   I175 @S9S_MB_2U_LIB.S9S_MB_2U(SCH_1):PAGE89
   259    GND @S9S_MB_2U_LIB.S9S_MB_2U(SCH_1):GND   I175 @S9S_MB_2U_LIB.S9S_MB_2U(SCH_1):PAGE89
   262    GND @S9S_MB_2U_LIB.S9S_MB_2U(SCH_1):GND   I175 @S9S_MB_2U_LIB.S9S_MB_2U(SCH_1):PAGE89
   264    GND @S9S_MB_2U_LIB.S9S_MB_2U(SCH_1):GND   I175 @S9S_MB_2U_LIB.S9S_MB_2U(SCH_1):PAGE89
   266    GND @S9S_MB_2U_LIB.S9S_MB_2U(SCH_1):GND   I175 @S9S_MB_2U_LIB.S9S_MB_2U(SCH_1):PAGE89
   268    GND @S9S_MB_2U_LIB.S9S_MB_2U(SCH_1):GND   I175 @S9S_MB_2U_LIB.S9S_MB_2U(SCH_1):PAGE89
   270    GND @S9S_MB_2U_LIB.S9S_MB_2U(SCH_1):GND   I175 @S9S_MB_2U_LIB.S9S_MB_2U(SCH_1):PAGE89
   273    GND @S9S_MB_2U_LIB.S9S_MB_2U(SCH_1):GND   I175 @S9S_MB_2U_LIB.S9S_MB_2U(SCH_1):PAGE89
   275    GND @S9S_MB_2U_LIB.S9S_MB_2U(SCH_1):GND   I175 @S9S_MB_2U_LIB.S9S_MB_2U(SCH_1):PAGE89
   277    GND @S9S_MB_2U_LIB.S9S_MB_2U(SCH_1):GND   I175 @S9S_MB_2U_LIB.S9S_MB_2U(SCH_1):PAGE89
   279    GND @S9S_MB_2U_LIB.S9S_MB_2U(SCH_1):GND   I175 @S9S_MB_2U_LIB.S9S_MB_2U(SCH_1):PAGE89
   281    GND @S9S_MB_2U_LIB.S9S_MB_2U(SCH_1):GND   I175 @S9S_MB_2U_LIB.S9S_MB_2U(SCH_1):PAGE89
   284    GND @S9S_MB_2U_LIB.S9S_MB_2U(SCH_1):GND   I175 @S9S_MB_2U_LIB.S9S_MB_2U(SCH_1):PAGE89
   286    GND @S9S_MB_2U_LIB.S9S_MB_2U(SCH_1):GND   I175 @S9S_MB_2U_LIB.S9S_MB_2U(SCH_1):PAGE89
   288    GND @S9S_MB_2U_LIB.S9S_MB_2U(SCH_1):GND   I175 @S9S_MB_2U_LIB.S9S_MB_2U(SCH_1):PAGE89
     1 P12V_S3_AUX_CPU0_NVDIMM @S9S_MB_2U_LIB.S9S_MB_2U(SCH_1):P12V_S3_AUX_CPU0_NVDIMM   I175 @S9S_MB_2U_LIB.S9S_MB_2U(SCH_1):PAGE89
   145 P12V_S3_AUX_CPU0_NVDIMM @S9S_MB_2U_LIB.S9S_MB_2U(SCH_1):P12V_S3_AUX_CPU0_NVDIMM   I175 @S9S_MB_2U_LIB.S9S_MB_2U(SCH_1):PAGE89
   146 P12V_S3_AUX_CPU0_NVDIMM @S9S_MB_2U_LIB.S9S_MB_2U(SCH_1):P12V_S3_AUX_CPU0_NVDIMM   I175 @S9S_MB_2U_LIB.S9S_MB_2U(SCH_1):PAGE89
   230    GND @S9S_MB_2U_LIB.S9S_MB_2U(SCH_1):GND   I175 @S9S_MB_2U_LIB.S9S_MB_2U(SCH_1):PAGE89
   235    GND @S9S_MB_2U_LIB.S9S_MB_2U(SCH_1):GND   I175 @S9S_MB_2U_LIB.S9S_MB_2U(SCH_1):PAGE89
   240    GND @S9S_MB_2U_LIB.S9S_MB_2U(SCH_1):GND   I175 @S9S_MB_2U_LIB.S9S_MB_2U(SCH_1):PAGE89
   132    GND @S9S_MB_2U_LIB.S9S_MB_2U(SCH_1):GND   I175 @S9S_MB_2U_LIB.S9S_MB_2U(SCH_1):PAGE89
   136    GND @S9S_MB_2U_LIB.S9S_MB_2U(SCH_1):GND   I175 @S9S_MB_2U_LIB.S9S_MB_2U(SCH_1):PAGE89
   139    GND @S9S_MB_2U_LIB.S9S_MB_2U(SCH_1):GND   I175 @S9S_MB_2U_LIB.S9S_MB_2U(SCH_1):PAGE89
   141    GND @S9S_MB_2U_LIB.S9S_MB_2U(SCH_1):GND   I175 @S9S_MB_2U_LIB.S9S_MB_2U(SCH_1):PAGE89
    G1    GND @S9S_MB_2U_LIB.S9S_MB_2U(SCH_1):GND   I175 @S9S_MB_2U_LIB.S9S_MB_2U(SCH_1):PAGE89
    G2    GND @S9S_MB_2U_LIB.S9S_MB_2U(SCH_1):GND   I175 @S9S_MB_2U_LIB.S9S_MB_2U(SCH_1):PAGE89
    G3    GND @S9S_MB_2U_LIB.S9S_MB_2U(SCH_1):GND   I175 @S9S_MB_2U_LIB.S9S_MB_2U(SCH_1):PAGE89

  J9 SCONN288_ADR50017P130CC-SCONN2A
     3 P3V3_AUX @S9S_MB_2U_LIB.S9S_MB_2U(SCH_1):P3V3_AUX    I12 @S9S_MB_2U_LIB.S9S_MB_2U(SCH_1):PAGE90
     2 TP_CHE_CPU0_DIMM1_FRU_0 @S9S_MB_2U_LIB.S9S_MB_2U(SCH_1):TP_CHE_CPU0_DIMM1_FRU_0    I12 @S9S_MB_2U_LIB.S9S_MB_2U(SCH_1):PAGE90
   144 TP_CHE_CPU0_DIMM1_FRU_1 @S9S_MB_2U_LIB.S9S_MB_2U(SCH_1):TP_CHE_CPU0_DIMM1_FRU_1    I12 @S9S_MB_2U_LIB.S9S_MB_2U(SCH_1):PAGE90
   149 TP_CHE_CPU0_DIMM1_FRU_2 @S9S_MB_2U_LIB.S9S_MB_2U(SCH_1):TP_CHE_CPU0_DIMM1_FRU_2    I12 @S9S_MB_2U_LIB.S9S_MB_2U(SCH_1):PAGE90
   150 TP_CHE_CPU0_DIMM1_FRU_3 @S9S_MB_2U_LIB.S9S_MB_2U(SCH_1):TP_CHE_CPU0_DIMM1_FRU_3    I12 @S9S_MB_2U_LIB.S9S_MB_2U(SCH_1):PAGE90
   220 TP_CHE_CPU0_DIMM1_FRU_4 @S9S_MB_2U_LIB.S9S_MB_2U(SCH_1):TP_CHE_CPU0_DIMM1_FRU_4    I12 @S9S_MB_2U_LIB.S9S_MB_2U(SCH_1):PAGE90
   231 TP_CHE_CPU0_DIMM1_FRU_5 @S9S_MB_2U_LIB.S9S_MB_2U(SCH_1):TP_CHE_CPU0_DIMM1_FRU_5    I12 @S9S_MB_2U_LIB.S9S_MB_2U(SCH_1):PAGE90
   232 TP_CHE_CPU0_DIMM1_FRU_6 @S9S_MB_2U_LIB.S9S_MB_2U(SCH_1):TP_CHE_CPU0_DIMM1_FRU_6    I12 @S9S_MB_2U_LIB.S9S_MB_2U(SCH_1):PAGE90
   207 RST_M_EF_CPU0_FPGA_N @S9S_MB_2U_LIB.S9S_MB_2U(SCH_1):RST_M_EF_CPU0_FPGA_N    I12 @S9S_MB_2U_LIB.S9S_MB_2U(SCH_1):PAGE90
   147 PWRGD_CHE_CPU0_DIMM1 @S9S_MB_2U_LIB.S9S_MB_2U(SCH_1):PWRGD_CHE_CPU0_DIMM1    I12 @S9S_MB_2U_LIB.S9S_MB_2U(SCH_1):PAGE90
   227 M_E_CPU0_SB_PAR @S9S_MB_2U_LIB.S9S_MB_2U(SCH_1):M_E_CPU0_SB_PAR    I12 @S9S_MB_2U_LIB.S9S_MB_2U(SCH_1):PAGE90
    74 M_E_CPU0_SA_PAR @S9S_MB_2U_LIB.S9S_MB_2U(SCH_1):M_E_CPU0_SA_PAR    I12 @S9S_MB_2U_LIB.S9S_MB_2U(SCH_1):PAGE90
    87 M_E_CPU0_SB_RSP<0> @S9S_MB_2U_LIB.S9S_MB_2U(SCH_1):M_E_CPU0_SB_RSP(0)    I12 @S9S_MB_2U_LIB.S9S_MB_2U(SCH_1):PAGE90
    86 M_E_CPU0_SA_RSP<0> @S9S_MB_2U_LIB.S9S_MB_2U(SCH_1):M_E_CPU0_SA_RSP(0)    I12 @S9S_MB_2U_LIB.S9S_MB_2U(SCH_1):PAGE90
     5 I3C_SPD_DDREFGH_CPU0_LVC1_SDA @S9S_MB_2U_LIB.S9S_MB_2U(SCH_1):I3C_SPD_DDREFGH_CPU0_LVC1_SDA    I12 @S9S_MB_2U_LIB.S9S_MB_2U(SCH_1):PAGE90
     4 I3C_SPD_DDREFGH_CPU0_LVC1_SCL_R @S9S_MB_2U_LIB.S9S_MB_2U(SCH_1):I3C_SPD_DDREFGH_CPU0_LVC1_SCL_R1    I12 @S9S_MB_2U_LIB.S9S_MB_2U(SCH_1):PAGE90
   148 PD_CHE_CPU0_DIMM1_SAA @S9S_MB_2U_LIB.S9S_MB_2U(SCH_1):PD_CHE_CPU0_DIMM1_SAA    I12 @S9S_MB_2U_LIB.S9S_MB_2U(SCH_1):PAGE90
   100 M_E_CPU0_SB_DQ<0> @S9S_MB_2U_LIB.S9S_MB_2U(SCH_1):M_E_CPU0_SB_DQ(0)    I12 @S9S_MB_2U_LIB.S9S_MB_2U(SCH_1):PAGE90
   102 M_E_CPU0_SB_DQ<1> @S9S_MB_2U_LIB.S9S_MB_2U(SCH_1):M_E_CPU0_SB_DQ(1)    I12 @S9S_MB_2U_LIB.S9S_MB_2U(SCH_1):PAGE90
   245 M_E_CPU0_SB_DQ<2> @S9S_MB_2U_LIB.S9S_MB_2U(SCH_1):M_E_CPU0_SB_DQ(2)    I12 @S9S_MB_2U_LIB.S9S_MB_2U(SCH_1):PAGE90
   247 M_E_CPU0_SB_DQ<3> @S9S_MB_2U_LIB.S9S_MB_2U(SCH_1):M_E_CPU0_SB_DQ(3)    I12 @S9S_MB_2U_LIB.S9S_MB_2U(SCH_1):PAGE90
   107 M_E_CPU0_SB_DQ<4> @S9S_MB_2U_LIB.S9S_MB_2U(SCH_1):M_E_CPU0_SB_DQ(4)    I12 @S9S_MB_2U_LIB.S9S_MB_2U(SCH_1):PAGE90
   109 M_E_CPU0_SB_DQ<5> @S9S_MB_2U_LIB.S9S_MB_2U(SCH_1):M_E_CPU0_SB_DQ(5)    I12 @S9S_MB_2U_LIB.S9S_MB_2U(SCH_1):PAGE90
   252 M_E_CPU0_SB_DQ<6> @S9S_MB_2U_LIB.S9S_MB_2U(SCH_1):M_E_CPU0_SB_DQ(6)    I12 @S9S_MB_2U_LIB.S9S_MB_2U(SCH_1):PAGE90
   254 M_E_CPU0_SB_DQ<7> @S9S_MB_2U_LIB.S9S_MB_2U(SCH_1):M_E_CPU0_SB_DQ(7)    I12 @S9S_MB_2U_LIB.S9S_MB_2U(SCH_1):PAGE90
   111 M_E_CPU0_SB_DQ<8> @S9S_MB_2U_LIB.S9S_MB_2U(SCH_1):M_E_CPU0_SB_DQ(8)    I12 @S9S_MB_2U_LIB.S9S_MB_2U(SCH_1):PAGE90
   113 M_E_CPU0_SB_DQ<9> @S9S_MB_2U_LIB.S9S_MB_2U(SCH_1):M_E_CPU0_SB_DQ(9)    I12 @S9S_MB_2U_LIB.S9S_MB_2U(SCH_1):PAGE90
   256 M_E_CPU0_SB_DQ<10> @S9S_MB_2U_LIB.S9S_MB_2U(SCH_1):M_E_CPU0_SB_DQ(10)    I12 @S9S_MB_2U_LIB.S9S_MB_2U(SCH_1):PAGE90
   258 M_E_CPU0_SB_DQ<11> @S9S_MB_2U_LIB.S9S_MB_2U(SCH_1):M_E_CPU0_SB_DQ(11)    I12 @S9S_MB_2U_LIB.S9S_MB_2U(SCH_1):PAGE90
   118 M_E_CPU0_SB_DQ<12> @S9S_MB_2U_LIB.S9S_MB_2U(SCH_1):M_E_CPU0_SB_DQ(12)    I12 @S9S_MB_2U_LIB.S9S_MB_2U(SCH_1):PAGE90
   120 M_E_CPU0_SB_DQ<13> @S9S_MB_2U_LIB.S9S_MB_2U(SCH_1):M_E_CPU0_SB_DQ(13)    I12 @S9S_MB_2U_LIB.S9S_MB_2U(SCH_1):PAGE90
   263 M_E_CPU0_SB_DQ<14> @S9S_MB_2U_LIB.S9S_MB_2U(SCH_1):M_E_CPU0_SB_DQ(14)    I12 @S9S_MB_2U_LIB.S9S_MB_2U(SCH_1):PAGE90
   265 M_E_CPU0_SB_DQ<15> @S9S_MB_2U_LIB.S9S_MB_2U(SCH_1):M_E_CPU0_SB_DQ(15)    I12 @S9S_MB_2U_LIB.S9S_MB_2U(SCH_1):PAGE90
   122 M_E_CPU0_SB_DQ<16> @S9S_MB_2U_LIB.S9S_MB_2U(SCH_1):M_E_CPU0_SB_DQ(16)    I12 @S9S_MB_2U_LIB.S9S_MB_2U(SCH_1):PAGE90
   124 M_E_CPU0_SB_DQ<17> @S9S_MB_2U_LIB.S9S_MB_2U(SCH_1):M_E_CPU0_SB_DQ(17)    I12 @S9S_MB_2U_LIB.S9S_MB_2U(SCH_1):PAGE90
   267 M_E_CPU0_SB_DQ<18> @S9S_MB_2U_LIB.S9S_MB_2U(SCH_1):M_E_CPU0_SB_DQ(18)    I12 @S9S_MB_2U_LIB.S9S_MB_2U(SCH_1):PAGE90
   269 M_E_CPU0_SB_DQ<19> @S9S_MB_2U_LIB.S9S_MB_2U(SCH_1):M_E_CPU0_SB_DQ(19)    I12 @S9S_MB_2U_LIB.S9S_MB_2U(SCH_1):PAGE90
   129 M_E_CPU0_SB_DQ<20> @S9S_MB_2U_LIB.S9S_MB_2U(SCH_1):M_E_CPU0_SB_DQ(20)    I12 @S9S_MB_2U_LIB.S9S_MB_2U(SCH_1):PAGE90
   131 M_E_CPU0_SB_DQ<21> @S9S_MB_2U_LIB.S9S_MB_2U(SCH_1):M_E_CPU0_SB_DQ(21)    I12 @S9S_MB_2U_LIB.S9S_MB_2U(SCH_1):PAGE90
   274 M_E_CPU0_SB_DQ<22> @S9S_MB_2U_LIB.S9S_MB_2U(SCH_1):M_E_CPU0_SB_DQ(22)    I12 @S9S_MB_2U_LIB.S9S_MB_2U(SCH_1):PAGE90
   276 M_E_CPU0_SB_DQ<23> @S9S_MB_2U_LIB.S9S_MB_2U(SCH_1):M_E_CPU0_SB_DQ(23)    I12 @S9S_MB_2U_LIB.S9S_MB_2U(SCH_1):PAGE90
   133 M_E_CPU0_SB_DQ<24> @S9S_MB_2U_LIB.S9S_MB_2U(SCH_1):M_E_CPU0_SB_DQ(24)    I12 @S9S_MB_2U_LIB.S9S_MB_2U(SCH_1):PAGE90
   135 M_E_CPU0_SB_DQ<25> @S9S_MB_2U_LIB.S9S_MB_2U(SCH_1):M_E_CPU0_SB_DQ(25)    I12 @S9S_MB_2U_LIB.S9S_MB_2U(SCH_1):PAGE90
   278 M_E_CPU0_SB_DQ<26> @S9S_MB_2U_LIB.S9S_MB_2U(SCH_1):M_E_CPU0_SB_DQ(26)    I12 @S9S_MB_2U_LIB.S9S_MB_2U(SCH_1):PAGE90
   280 M_E_CPU0_SB_DQ<27> @S9S_MB_2U_LIB.S9S_MB_2U(SCH_1):M_E_CPU0_SB_DQ(27)    I12 @S9S_MB_2U_LIB.S9S_MB_2U(SCH_1):PAGE90
   140 M_E_CPU0_SB_DQ<28> @S9S_MB_2U_LIB.S9S_MB_2U(SCH_1):M_E_CPU0_SB_DQ(28)    I12 @S9S_MB_2U_LIB.S9S_MB_2U(SCH_1):PAGE90
   142 M_E_CPU0_SB_DQ<29> @S9S_MB_2U_LIB.S9S_MB_2U(SCH_1):M_E_CPU0_SB_DQ(29)    I12 @S9S_MB_2U_LIB.S9S_MB_2U(SCH_1):PAGE90
   285 M_E_CPU0_SB_DQ<30> @S9S_MB_2U_LIB.S9S_MB_2U(SCH_1):M_E_CPU0_SB_DQ(30)    I12 @S9S_MB_2U_LIB.S9S_MB_2U(SCH_1):PAGE90
   287 M_E_CPU0_SB_DQ<31> @S9S_MB_2U_LIB.S9S_MB_2U(SCH_1):M_E_CPU0_SB_DQ(31)    I12 @S9S_MB_2U_LIB.S9S_MB_2U(SCH_1):PAGE90
     7 M_E_CPU0_SA_DQ<0> @S9S_MB_2U_LIB.S9S_MB_2U(SCH_1):M_E_CPU0_SA_DQ(0)    I12 @S9S_MB_2U_LIB.S9S_MB_2U(SCH_1):PAGE90
     9 M_E_CPU0_SA_DQ<1> @S9S_MB_2U_LIB.S9S_MB_2U(SCH_1):M_E_CPU0_SA_DQ(1)    I12 @S9S_MB_2U_LIB.S9S_MB_2U(SCH_1):PAGE90
   152 M_E_CPU0_SA_DQ<2> @S9S_MB_2U_LIB.S9S_MB_2U(SCH_1):M_E_CPU0_SA_DQ(2)    I12 @S9S_MB_2U_LIB.S9S_MB_2U(SCH_1):PAGE90
   154 M_E_CPU0_SA_DQ<3> @S9S_MB_2U_LIB.S9S_MB_2U(SCH_1):M_E_CPU0_SA_DQ(3)    I12 @S9S_MB_2U_LIB.S9S_MB_2U(SCH_1):PAGE90
    14 M_E_CPU0_SA_DQ<4> @S9S_MB_2U_LIB.S9S_MB_2U(SCH_1):M_E_CPU0_SA_DQ(4)    I12 @S9S_MB_2U_LIB.S9S_MB_2U(SCH_1):PAGE90
    16 M_E_CPU0_SA_DQ<5> @S9S_MB_2U_LIB.S9S_MB_2U(SCH_1):M_E_CPU0_SA_DQ(5)    I12 @S9S_MB_2U_LIB.S9S_MB_2U(SCH_1):PAGE90
   159 M_E_CPU0_SA_DQ<6> @S9S_MB_2U_LIB.S9S_MB_2U(SCH_1):M_E_CPU0_SA_DQ(6)    I12 @S9S_MB_2U_LIB.S9S_MB_2U(SCH_1):PAGE90
   161 M_E_CPU0_SA_DQ<7> @S9S_MB_2U_LIB.S9S_MB_2U(SCH_1):M_E_CPU0_SA_DQ(7)    I12 @S9S_MB_2U_LIB.S9S_MB_2U(SCH_1):PAGE90
    18 M_E_CPU0_SA_DQ<8> @S9S_MB_2U_LIB.S9S_MB_2U(SCH_1):M_E_CPU0_SA_DQ(8)    I12 @S9S_MB_2U_LIB.S9S_MB_2U(SCH_1):PAGE90
    20 M_E_CPU0_SA_DQ<9> @S9S_MB_2U_LIB.S9S_MB_2U(SCH_1):M_E_CPU0_SA_DQ(9)    I12 @S9S_MB_2U_LIB.S9S_MB_2U(SCH_1):PAGE90
   163 M_E_CPU0_SA_DQ<10> @S9S_MB_2U_LIB.S9S_MB_2U(SCH_1):M_E_CPU0_SA_DQ(10)    I12 @S9S_MB_2U_LIB.S9S_MB_2U(SCH_1):PAGE90
   165 M_E_CPU0_SA_DQ<11> @S9S_MB_2U_LIB.S9S_MB_2U(SCH_1):M_E_CPU0_SA_DQ(11)    I12 @S9S_MB_2U_LIB.S9S_MB_2U(SCH_1):PAGE90
    25 M_E_CPU0_SA_DQ<12> @S9S_MB_2U_LIB.S9S_MB_2U(SCH_1):M_E_CPU0_SA_DQ(12)    I12 @S9S_MB_2U_LIB.S9S_MB_2U(SCH_1):PAGE90
    27 M_E_CPU0_SA_DQ<13> @S9S_MB_2U_LIB.S9S_MB_2U(SCH_1):M_E_CPU0_SA_DQ(13)    I12 @S9S_MB_2U_LIB.S9S_MB_2U(SCH_1):PAGE90
   170 M_E_CPU0_SA_DQ<14> @S9S_MB_2U_LIB.S9S_MB_2U(SCH_1):M_E_CPU0_SA_DQ(14)    I12 @S9S_MB_2U_LIB.S9S_MB_2U(SCH_1):PAGE90
   172 M_E_CPU0_SA_DQ<15> @S9S_MB_2U_LIB.S9S_MB_2U(SCH_1):M_E_CPU0_SA_DQ(15)    I12 @S9S_MB_2U_LIB.S9S_MB_2U(SCH_1):PAGE90
    29 M_E_CPU0_SA_DQ<16> @S9S_MB_2U_LIB.S9S_MB_2U(SCH_1):M_E_CPU0_SA_DQ(16)    I12 @S9S_MB_2U_LIB.S9S_MB_2U(SCH_1):PAGE90
    31 M_E_CPU0_SA_DQ<17> @S9S_MB_2U_LIB.S9S_MB_2U(SCH_1):M_E_CPU0_SA_DQ(17)    I12 @S9S_MB_2U_LIB.S9S_MB_2U(SCH_1):PAGE90
   174 M_E_CPU0_SA_DQ<18> @S9S_MB_2U_LIB.S9S_MB_2U(SCH_1):M_E_CPU0_SA_DQ(18)    I12 @S9S_MB_2U_LIB.S9S_MB_2U(SCH_1):PAGE90
   176 M_E_CPU0_SA_DQ<19> @S9S_MB_2U_LIB.S9S_MB_2U(SCH_1):M_E_CPU0_SA_DQ(19)    I12 @S9S_MB_2U_LIB.S9S_MB_2U(SCH_1):PAGE90
    36 M_E_CPU0_SA_DQ<20> @S9S_MB_2U_LIB.S9S_MB_2U(SCH_1):M_E_CPU0_SA_DQ(20)    I12 @S9S_MB_2U_LIB.S9S_MB_2U(SCH_1):PAGE90
    38 M_E_CPU0_SA_DQ<21> @S9S_MB_2U_LIB.S9S_MB_2U(SCH_1):M_E_CPU0_SA_DQ(21)    I12 @S9S_MB_2U_LIB.S9S_MB_2U(SCH_1):PAGE90
   181 M_E_CPU0_SA_DQ<22> @S9S_MB_2U_LIB.S9S_MB_2U(SCH_1):M_E_CPU0_SA_DQ(22)    I12 @S9S_MB_2U_LIB.S9S_MB_2U(SCH_1):PAGE90
   183 M_E_CPU0_SA_DQ<23> @S9S_MB_2U_LIB.S9S_MB_2U(SCH_1):M_E_CPU0_SA_DQ(23)    I12 @S9S_MB_2U_LIB.S9S_MB_2U(SCH_1):PAGE90
    40 M_E_CPU0_SA_DQ<24> @S9S_MB_2U_LIB.S9S_MB_2U(SCH_1):M_E_CPU0_SA_DQ(24)    I12 @S9S_MB_2U_LIB.S9S_MB_2U(SCH_1):PAGE90
    42 M_E_CPU0_SA_DQ<25> @S9S_MB_2U_LIB.S9S_MB_2U(SCH_1):M_E_CPU0_SA_DQ(25)    I12 @S9S_MB_2U_LIB.S9S_MB_2U(SCH_1):PAGE90
   185 M_E_CPU0_SA_DQ<26> @S9S_MB_2U_LIB.S9S_MB_2U(SCH_1):M_E_CPU0_SA_DQ(26)    I12 @S9S_MB_2U_LIB.S9S_MB_2U(SCH_1):PAGE90
   187 M_E_CPU0_SA_DQ<27> @S9S_MB_2U_LIB.S9S_MB_2U(SCH_1):M_E_CPU0_SA_DQ(27)    I12 @S9S_MB_2U_LIB.S9S_MB_2U(SCH_1):PAGE90
    47 M_E_CPU0_SA_DQ<28> @S9S_MB_2U_LIB.S9S_MB_2U(SCH_1):M_E_CPU0_SA_DQ(28)    I12 @S9S_MB_2U_LIB.S9S_MB_2U(SCH_1):PAGE90
    49 M_E_CPU0_SA_DQ<29> @S9S_MB_2U_LIB.S9S_MB_2U(SCH_1):M_E_CPU0_SA_DQ(29)    I12 @S9S_MB_2U_LIB.S9S_MB_2U(SCH_1):PAGE90
   192 M_E_CPU0_SA_DQ<30> @S9S_MB_2U_LIB.S9S_MB_2U(SCH_1):M_E_CPU0_SA_DQ(30)    I12 @S9S_MB_2U_LIB.S9S_MB_2U(SCH_1):PAGE90
   229 M_E_CPU0_SB_CS_N<1> @S9S_MB_2U_LIB.S9S_MB_2U(SCH_1):M_E_CPU0_SB_CS_N(1)    I12 @S9S_MB_2U_LIB.S9S_MB_2U(SCH_1):PAGE90
   209 M_E_CPU0_SA_CS_N<1> @S9S_MB_2U_LIB.S9S_MB_2U(SCH_1):M_E_CPU0_SA_CS_N(1)    I12 @S9S_MB_2U_LIB.S9S_MB_2U(SCH_1):PAGE90
    84 M_E_CPU0_SB_CS_N<0> @S9S_MB_2U_LIB.S9S_MB_2U(SCH_1):M_E_CPU0_SB_CS_N(0)    I12 @S9S_MB_2U_LIB.S9S_MB_2U(SCH_1):PAGE90
    64 M_E_CPU0_SA_CS_N<0> @S9S_MB_2U_LIB.S9S_MB_2U(SCH_1):M_E_CPU0_SA_CS_N(0)    I12 @S9S_MB_2U_LIB.S9S_MB_2U(SCH_1):PAGE90
   217 M_E_CPU0_CLK_DP<0> @S9S_MB_2U_LIB.S9S_MB_2U(SCH_1):M_E_CPU0_CLK_DP(0)    I12 @S9S_MB_2U_LIB.S9S_MB_2U(SCH_1):PAGE90
   218 M_E_CPU0_CLK_DN<0> @S9S_MB_2U_LIB.S9S_MB_2U(SCH_1):M_E_CPU0_CLK_DN(0)    I12 @S9S_MB_2U_LIB.S9S_MB_2U(SCH_1):PAGE90
    96 M_E_CPU0_SB_CB<0> @S9S_MB_2U_LIB.S9S_MB_2U(SCH_1):M_E_CPU0_SB_CB(0)    I12 @S9S_MB_2U_LIB.S9S_MB_2U(SCH_1):PAGE90
    98 M_E_CPU0_SB_CB<1> @S9S_MB_2U_LIB.S9S_MB_2U(SCH_1):M_E_CPU0_SB_CB(1)    I12 @S9S_MB_2U_LIB.S9S_MB_2U(SCH_1):PAGE90
   241 M_E_CPU0_SB_CB<2> @S9S_MB_2U_LIB.S9S_MB_2U(SCH_1):M_E_CPU0_SB_CB(2)    I12 @S9S_MB_2U_LIB.S9S_MB_2U(SCH_1):PAGE90
   243 M_E_CPU0_SB_CB<3> @S9S_MB_2U_LIB.S9S_MB_2U(SCH_1):M_E_CPU0_SB_CB(3)    I12 @S9S_MB_2U_LIB.S9S_MB_2U(SCH_1):PAGE90
    89 M_E_CPU0_SB_CB<4> @S9S_MB_2U_LIB.S9S_MB_2U(SCH_1):M_E_CPU0_SB_CB(4)    I12 @S9S_MB_2U_LIB.S9S_MB_2U(SCH_1):PAGE90
    91 M_E_CPU0_SB_CB<5> @S9S_MB_2U_LIB.S9S_MB_2U(SCH_1):M_E_CPU0_SB_CB(5)    I12 @S9S_MB_2U_LIB.S9S_MB_2U(SCH_1):PAGE90
   234 M_E_CPU0_SB_CB<6> @S9S_MB_2U_LIB.S9S_MB_2U(SCH_1):M_E_CPU0_SB_CB(6)    I12 @S9S_MB_2U_LIB.S9S_MB_2U(SCH_1):PAGE90
    51 M_E_CPU0_SA_CB<0> @S9S_MB_2U_LIB.S9S_MB_2U(SCH_1):M_E_CPU0_SA_CB(0)    I12 @S9S_MB_2U_LIB.S9S_MB_2U(SCH_1):PAGE90
   196 M_E_CPU0_SA_CB<2> @S9S_MB_2U_LIB.S9S_MB_2U(SCH_1):M_E_CPU0_SA_CB(2)    I12 @S9S_MB_2U_LIB.S9S_MB_2U(SCH_1):PAGE90
   198 M_E_CPU0_SA_CB<3> @S9S_MB_2U_LIB.S9S_MB_2U(SCH_1):M_E_CPU0_SA_CB(3)    I12 @S9S_MB_2U_LIB.S9S_MB_2U(SCH_1):PAGE90
    60 M_E_CPU0_SA_CB<5> @S9S_MB_2U_LIB.S9S_MB_2U(SCH_1):M_E_CPU0_SA_CB(5)    I12 @S9S_MB_2U_LIB.S9S_MB_2U(SCH_1):PAGE90
   203 M_E_CPU0_SA_CB<6> @S9S_MB_2U_LIB.S9S_MB_2U(SCH_1):M_E_CPU0_SA_CB(6)    I12 @S9S_MB_2U_LIB.S9S_MB_2U(SCH_1):PAGE90
    82 M_E_CPU0_SB_CA<6> @S9S_MB_2U_LIB.S9S_MB_2U(SCH_1):M_E_CPU0_SB_CA(6)    I12 @S9S_MB_2U_LIB.S9S_MB_2U(SCH_1):PAGE90
    72 M_E_CPU0_SA_CA<6> @S9S_MB_2U_LIB.S9S_MB_2U(SCH_1):M_E_CPU0_SA_CA(6)    I12 @S9S_MB_2U_LIB.S9S_MB_2U(SCH_1):PAGE90
   225 M_E_CPU0_SB_CA<5> @S9S_MB_2U_LIB.S9S_MB_2U(SCH_1):M_E_CPU0_SB_CA(5)    I12 @S9S_MB_2U_LIB.S9S_MB_2U(SCH_1):PAGE90
   215 M_E_CPU0_SA_CA<5> @S9S_MB_2U_LIB.S9S_MB_2U(SCH_1):M_E_CPU0_SA_CA(5)    I12 @S9S_MB_2U_LIB.S9S_MB_2U(SCH_1):PAGE90
    80 M_E_CPU0_SB_CA<4> @S9S_MB_2U_LIB.S9S_MB_2U(SCH_1):M_E_CPU0_SB_CA(4)    I12 @S9S_MB_2U_LIB.S9S_MB_2U(SCH_1):PAGE90
    70 M_E_CPU0_SA_CA<4> @S9S_MB_2U_LIB.S9S_MB_2U(SCH_1):M_E_CPU0_SA_CA(4)    I12 @S9S_MB_2U_LIB.S9S_MB_2U(SCH_1):PAGE90
   223 M_E_CPU0_SB_CA<3> @S9S_MB_2U_LIB.S9S_MB_2U(SCH_1):M_E_CPU0_SB_CA(3)    I12 @S9S_MB_2U_LIB.S9S_MB_2U(SCH_1):PAGE90
   213 M_E_CPU0_SA_CA<3> @S9S_MB_2U_LIB.S9S_MB_2U(SCH_1):M_E_CPU0_SA_CA(3)    I12 @S9S_MB_2U_LIB.S9S_MB_2U(SCH_1):PAGE90
    78 M_E_CPU0_SB_CA<2> @S9S_MB_2U_LIB.S9S_MB_2U(SCH_1):M_E_CPU0_SB_CA(2)    I12 @S9S_MB_2U_LIB.S9S_MB_2U(SCH_1):PAGE90
    68 M_E_CPU0_SA_CA<2> @S9S_MB_2U_LIB.S9S_MB_2U(SCH_1):M_E_CPU0_SA_CA(2)    I12 @S9S_MB_2U_LIB.S9S_MB_2U(SCH_1):PAGE90
   221 M_E_CPU0_SB_CA<1> @S9S_MB_2U_LIB.S9S_MB_2U(SCH_1):M_E_CPU0_SB_CA(1)    I12 @S9S_MB_2U_LIB.S9S_MB_2U(SCH_1):PAGE90
   211 M_E_CPU0_SA_CA<1> @S9S_MB_2U_LIB.S9S_MB_2U(SCH_1):M_E_CPU0_SA_CA(1)    I12 @S9S_MB_2U_LIB.S9S_MB_2U(SCH_1):PAGE90
    76 M_E_CPU0_SB_CA<0> @S9S_MB_2U_LIB.S9S_MB_2U(SCH_1):M_E_CPU0_SB_CA(0)    I12 @S9S_MB_2U_LIB.S9S_MB_2U(SCH_1):PAGE90
    66 M_E_CPU0_SA_CA<0> @S9S_MB_2U_LIB.S9S_MB_2U(SCH_1):M_E_CPU0_SA_CA(0)    I12 @S9S_MB_2U_LIB.S9S_MB_2U(SCH_1):PAGE90
    62 M_E_CPU0_ALERT_N @S9S_MB_2U_LIB.S9S_MB_2U(SCH_1):M_E_CPU0_ALERT_N    I12 @S9S_MB_2U_LIB.S9S_MB_2U(SCH_1):PAGE90
   236 M_E_CPU0_SB_CB<7> @S9S_MB_2U_LIB.S9S_MB_2U(SCH_1):M_E_CPU0_SB_CB(7)    I12 @S9S_MB_2U_LIB.S9S_MB_2U(SCH_1):PAGE90
    53 M_E_CPU0_SA_CB<1> @S9S_MB_2U_LIB.S9S_MB_2U(SCH_1):M_E_CPU0_SA_CB(1)    I12 @S9S_MB_2U_LIB.S9S_MB_2U(SCH_1):PAGE90
    58 M_E_CPU0_SA_CB<4> @S9S_MB_2U_LIB.S9S_MB_2U(SCH_1):M_E_CPU0_SA_CB(4)    I12 @S9S_MB_2U_LIB.S9S_MB_2U(SCH_1):PAGE90
   205 M_E_CPU0_SA_CB<7> @S9S_MB_2U_LIB.S9S_MB_2U(SCH_1):M_E_CPU0_SA_CB(7)    I12 @S9S_MB_2U_LIB.S9S_MB_2U(SCH_1):PAGE90
   194 M_E_CPU0_SA_DQ<31> @S9S_MB_2U_LIB.S9S_MB_2U(SCH_1):M_E_CPU0_SA_DQ(31)    I12 @S9S_MB_2U_LIB.S9S_MB_2U(SCH_1):PAGE90
    93 M_E_CPU0_SB_DQS_DP<9> @S9S_MB_2U_LIB.S9S_MB_2U(SCH_1):M_E_CPU0_SB_DQS_DP(9)   I178 @S9S_MB_2U_LIB.S9S_MB_2U(SCH_1):PAGE90
    94 M_E_CPU0_SB_DQS_DN<9> @S9S_MB_2U_LIB.S9S_MB_2U(SCH_1):M_E_CPU0_SB_DQS_DN(9)   I178 @S9S_MB_2U_LIB.S9S_MB_2U(SCH_1):PAGE90
   201 M_E_CPU0_SA_DQS_DP<9> @S9S_MB_2U_LIB.S9S_MB_2U(SCH_1):M_E_CPU0_SA_DQS_DP(9)   I178 @S9S_MB_2U_LIB.S9S_MB_2U(SCH_1):PAGE90
   200 M_E_CPU0_SA_DQS_DN<9> @S9S_MB_2U_LIB.S9S_MB_2U(SCH_1):M_E_CPU0_SA_DQS_DN(9)   I178 @S9S_MB_2U_LIB.S9S_MB_2U(SCH_1):PAGE90
   190 M_E_CPU0_SA_DQS_DP<8> @S9S_MB_2U_LIB.S9S_MB_2U(SCH_1):M_E_CPU0_SA_DQS_DP(8)   I178 @S9S_MB_2U_LIB.S9S_MB_2U(SCH_1):PAGE90
   189 M_E_CPU0_SA_DQS_DN<8> @S9S_MB_2U_LIB.S9S_MB_2U(SCH_1):M_E_CPU0_SA_DQS_DN(8)   I178 @S9S_MB_2U_LIB.S9S_MB_2U(SCH_1):PAGE90
   271 M_E_CPU0_SB_DQS_DN<7> @S9S_MB_2U_LIB.S9S_MB_2U(SCH_1):M_E_CPU0_SB_DQS_DN(7)   I178 @S9S_MB_2U_LIB.S9S_MB_2U(SCH_1):PAGE90
   179 M_E_CPU0_SA_DQS_DP<7> @S9S_MB_2U_LIB.S9S_MB_2U(SCH_1):M_E_CPU0_SA_DQS_DP(7)   I178 @S9S_MB_2U_LIB.S9S_MB_2U(SCH_1):PAGE90
   261 M_E_CPU0_SB_DQS_DP<6> @S9S_MB_2U_LIB.S9S_MB_2U(SCH_1):M_E_CPU0_SB_DQS_DP(6)   I178 @S9S_MB_2U_LIB.S9S_MB_2U(SCH_1):PAGE90
   260 M_E_CPU0_SB_DQS_DN<6> @S9S_MB_2U_LIB.S9S_MB_2U(SCH_1):M_E_CPU0_SB_DQS_DN(6)   I178 @S9S_MB_2U_LIB.S9S_MB_2U(SCH_1):PAGE90
   167 M_E_CPU0_SA_DQS_DN<6> @S9S_MB_2U_LIB.S9S_MB_2U(SCH_1):M_E_CPU0_SA_DQS_DN(6)   I178 @S9S_MB_2U_LIB.S9S_MB_2U(SCH_1):PAGE90
   250 M_E_CPU0_SB_DQS_DP<5> @S9S_MB_2U_LIB.S9S_MB_2U(SCH_1):M_E_CPU0_SB_DQS_DP(5)   I178 @S9S_MB_2U_LIB.S9S_MB_2U(SCH_1):PAGE90
   249 M_E_CPU0_SB_DQS_DN<5> @S9S_MB_2U_LIB.S9S_MB_2U(SCH_1):M_E_CPU0_SB_DQS_DN(5)   I178 @S9S_MB_2U_LIB.S9S_MB_2U(SCH_1):PAGE90
   157 M_E_CPU0_SA_DQS_DP<5> @S9S_MB_2U_LIB.S9S_MB_2U(SCH_1):M_E_CPU0_SA_DQS_DP(5)   I178 @S9S_MB_2U_LIB.S9S_MB_2U(SCH_1):PAGE90
   156 M_E_CPU0_SA_DQS_DN<5> @S9S_MB_2U_LIB.S9S_MB_2U(SCH_1):M_E_CPU0_SA_DQS_DN(5)   I178 @S9S_MB_2U_LIB.S9S_MB_2U(SCH_1):PAGE90
   239 M_E_CPU0_SB_DQS_DP<4> @S9S_MB_2U_LIB.S9S_MB_2U(SCH_1):M_E_CPU0_SB_DQS_DP(4)   I178 @S9S_MB_2U_LIB.S9S_MB_2U(SCH_1):PAGE90
   238 M_E_CPU0_SB_DQS_DN<4> @S9S_MB_2U_LIB.S9S_MB_2U(SCH_1):M_E_CPU0_SB_DQS_DN(4)   I178 @S9S_MB_2U_LIB.S9S_MB_2U(SCH_1):PAGE90
    55 M_E_CPU0_SA_DQS_DP<4> @S9S_MB_2U_LIB.S9S_MB_2U(SCH_1):M_E_CPU0_SA_DQS_DP(4)   I178 @S9S_MB_2U_LIB.S9S_MB_2U(SCH_1):PAGE90
    56 M_E_CPU0_SA_DQS_DN<4> @S9S_MB_2U_LIB.S9S_MB_2U(SCH_1):M_E_CPU0_SA_DQS_DN(4)   I178 @S9S_MB_2U_LIB.S9S_MB_2U(SCH_1):PAGE90
   137 M_E_CPU0_SB_DQS_DP<3> @S9S_MB_2U_LIB.S9S_MB_2U(SCH_1):M_E_CPU0_SB_DQS_DP(3)   I178 @S9S_MB_2U_LIB.S9S_MB_2U(SCH_1):PAGE90
   138 M_E_CPU0_SB_DQS_DN<3> @S9S_MB_2U_LIB.S9S_MB_2U(SCH_1):M_E_CPU0_SB_DQS_DN(3)   I178 @S9S_MB_2U_LIB.S9S_MB_2U(SCH_1):PAGE90
    44 M_E_CPU0_SA_DQS_DP<3> @S9S_MB_2U_LIB.S9S_MB_2U(SCH_1):M_E_CPU0_SA_DQS_DP(3)   I178 @S9S_MB_2U_LIB.S9S_MB_2U(SCH_1):PAGE90
    45 M_E_CPU0_SA_DQS_DN<3> @S9S_MB_2U_LIB.S9S_MB_2U(SCH_1):M_E_CPU0_SA_DQS_DN(3)   I178 @S9S_MB_2U_LIB.S9S_MB_2U(SCH_1):PAGE90
   126 M_E_CPU0_SB_DQS_DP<2> @S9S_MB_2U_LIB.S9S_MB_2U(SCH_1):M_E_CPU0_SB_DQS_DP(2)   I178 @S9S_MB_2U_LIB.S9S_MB_2U(SCH_1):PAGE90
   127 M_E_CPU0_SB_DQS_DN<2> @S9S_MB_2U_LIB.S9S_MB_2U(SCH_1):M_E_CPU0_SB_DQS_DN(2)   I178 @S9S_MB_2U_LIB.S9S_MB_2U(SCH_1):PAGE90
    33 M_E_CPU0_SA_DQS_DP<2> @S9S_MB_2U_LIB.S9S_MB_2U(SCH_1):M_E_CPU0_SA_DQS_DP(2)   I178 @S9S_MB_2U_LIB.S9S_MB_2U(SCH_1):PAGE90
    34 M_E_CPU0_SA_DQS_DN<2> @S9S_MB_2U_LIB.S9S_MB_2U(SCH_1):M_E_CPU0_SA_DQS_DN(2)   I178 @S9S_MB_2U_LIB.S9S_MB_2U(SCH_1):PAGE90
   115 M_E_CPU0_SB_DQS_DP<1> @S9S_MB_2U_LIB.S9S_MB_2U(SCH_1):M_E_CPU0_SB_DQS_DP(1)   I178 @S9S_MB_2U_LIB.S9S_MB_2U(SCH_1):PAGE90
   116 M_E_CPU0_SB_DQS_DN<1> @S9S_MB_2U_LIB.S9S_MB_2U(SCH_1):M_E_CPU0_SB_DQS_DN(1)   I178 @S9S_MB_2U_LIB.S9S_MB_2U(SCH_1):PAGE90
    22 M_E_CPU0_SA_DQS_DP<1> @S9S_MB_2U_LIB.S9S_MB_2U(SCH_1):M_E_CPU0_SA_DQS_DP(1)   I178 @S9S_MB_2U_LIB.S9S_MB_2U(SCH_1):PAGE90
    23 M_E_CPU0_SA_DQS_DN<1> @S9S_MB_2U_LIB.S9S_MB_2U(SCH_1):M_E_CPU0_SA_DQS_DN(1)   I178 @S9S_MB_2U_LIB.S9S_MB_2U(SCH_1):PAGE90
   104 M_E_CPU0_SB_DQS_DP<0> @S9S_MB_2U_LIB.S9S_MB_2U(SCH_1):M_E_CPU0_SB_DQS_DP(0)   I178 @S9S_MB_2U_LIB.S9S_MB_2U(SCH_1):PAGE90
   105 M_E_CPU0_SB_DQS_DN<0> @S9S_MB_2U_LIB.S9S_MB_2U(SCH_1):M_E_CPU0_SB_DQS_DN(0)   I178 @S9S_MB_2U_LIB.S9S_MB_2U(SCH_1):PAGE90
    11 M_E_CPU0_SA_DQS_DP<0> @S9S_MB_2U_LIB.S9S_MB_2U(SCH_1):M_E_CPU0_SA_DQS_DP(0)   I178 @S9S_MB_2U_LIB.S9S_MB_2U(SCH_1):PAGE90
    12 M_E_CPU0_SA_DQS_DN<0> @S9S_MB_2U_LIB.S9S_MB_2U(SCH_1):M_E_CPU0_SA_DQS_DN(0)   I178 @S9S_MB_2U_LIB.S9S_MB_2U(SCH_1):PAGE90
   272 M_E_CPU0_SB_DQS_DP<7> @S9S_MB_2U_LIB.S9S_MB_2U(SCH_1):M_E_CPU0_SB_DQS_DP(7)   I178 @S9S_MB_2U_LIB.S9S_MB_2U(SCH_1):PAGE90
   282 M_E_CPU0_SB_DQS_DN<8> @S9S_MB_2U_LIB.S9S_MB_2U(SCH_1):M_E_CPU0_SB_DQS_DN(8)   I178 @S9S_MB_2U_LIB.S9S_MB_2U(SCH_1):PAGE90
   283 M_E_CPU0_SB_DQS_DP<8> @S9S_MB_2U_LIB.S9S_MB_2U(SCH_1):M_E_CPU0_SB_DQS_DP(8)   I178 @S9S_MB_2U_LIB.S9S_MB_2U(SCH_1):PAGE90
   168 M_E_CPU0_SA_DQS_DP<6> @S9S_MB_2U_LIB.S9S_MB_2U(SCH_1):M_E_CPU0_SA_DQS_DP(6)   I178 @S9S_MB_2U_LIB.S9S_MB_2U(SCH_1):PAGE90
   178 M_E_CPU0_SA_DQS_DN<7> @S9S_MB_2U_LIB.S9S_MB_2U(SCH_1):M_E_CPU0_SA_DQS_DN(7)   I178 @S9S_MB_2U_LIB.S9S_MB_2U(SCH_1):PAGE90
     6    GND @S9S_MB_2U_LIB.S9S_MB_2U(SCH_1):GND   I147 @S9S_MB_2U_LIB.S9S_MB_2U(SCH_1):PAGE90
     8    GND @S9S_MB_2U_LIB.S9S_MB_2U(SCH_1):GND   I147 @S9S_MB_2U_LIB.S9S_MB_2U(SCH_1):PAGE90
    10    GND @S9S_MB_2U_LIB.S9S_MB_2U(SCH_1):GND   I147 @S9S_MB_2U_LIB.S9S_MB_2U(SCH_1):PAGE90
    13    GND @S9S_MB_2U_LIB.S9S_MB_2U(SCH_1):GND   I147 @S9S_MB_2U_LIB.S9S_MB_2U(SCH_1):PAGE90
    15    GND @S9S_MB_2U_LIB.S9S_MB_2U(SCH_1):GND   I147 @S9S_MB_2U_LIB.S9S_MB_2U(SCH_1):PAGE90
    17    GND @S9S_MB_2U_LIB.S9S_MB_2U(SCH_1):GND   I147 @S9S_MB_2U_LIB.S9S_MB_2U(SCH_1):PAGE90
    19    GND @S9S_MB_2U_LIB.S9S_MB_2U(SCH_1):GND   I147 @S9S_MB_2U_LIB.S9S_MB_2U(SCH_1):PAGE90
    21    GND @S9S_MB_2U_LIB.S9S_MB_2U(SCH_1):GND   I147 @S9S_MB_2U_LIB.S9S_MB_2U(SCH_1):PAGE90
    24    GND @S9S_MB_2U_LIB.S9S_MB_2U(SCH_1):GND   I147 @S9S_MB_2U_LIB.S9S_MB_2U(SCH_1):PAGE90
    26    GND @S9S_MB_2U_LIB.S9S_MB_2U(SCH_1):GND   I147 @S9S_MB_2U_LIB.S9S_MB_2U(SCH_1):PAGE90
    28    GND @S9S_MB_2U_LIB.S9S_MB_2U(SCH_1):GND   I147 @S9S_MB_2U_LIB.S9S_MB_2U(SCH_1):PAGE90
    30    GND @S9S_MB_2U_LIB.S9S_MB_2U(SCH_1):GND   I147 @S9S_MB_2U_LIB.S9S_MB_2U(SCH_1):PAGE90
    32    GND @S9S_MB_2U_LIB.S9S_MB_2U(SCH_1):GND   I147 @S9S_MB_2U_LIB.S9S_MB_2U(SCH_1):PAGE90
    35    GND @S9S_MB_2U_LIB.S9S_MB_2U(SCH_1):GND   I147 @S9S_MB_2U_LIB.S9S_MB_2U(SCH_1):PAGE90
    37    GND @S9S_MB_2U_LIB.S9S_MB_2U(SCH_1):GND   I147 @S9S_MB_2U_LIB.S9S_MB_2U(SCH_1):PAGE90
    39    GND @S9S_MB_2U_LIB.S9S_MB_2U(SCH_1):GND   I147 @S9S_MB_2U_LIB.S9S_MB_2U(SCH_1):PAGE90
    41    GND @S9S_MB_2U_LIB.S9S_MB_2U(SCH_1):GND   I147 @S9S_MB_2U_LIB.S9S_MB_2U(SCH_1):PAGE90
    43    GND @S9S_MB_2U_LIB.S9S_MB_2U(SCH_1):GND   I147 @S9S_MB_2U_LIB.S9S_MB_2U(SCH_1):PAGE90
    46    GND @S9S_MB_2U_LIB.S9S_MB_2U(SCH_1):GND   I147 @S9S_MB_2U_LIB.S9S_MB_2U(SCH_1):PAGE90
    48    GND @S9S_MB_2U_LIB.S9S_MB_2U(SCH_1):GND   I147 @S9S_MB_2U_LIB.S9S_MB_2U(SCH_1):PAGE90
    50    GND @S9S_MB_2U_LIB.S9S_MB_2U(SCH_1):GND   I147 @S9S_MB_2U_LIB.S9S_MB_2U(SCH_1):PAGE90
    52    GND @S9S_MB_2U_LIB.S9S_MB_2U(SCH_1):GND   I147 @S9S_MB_2U_LIB.S9S_MB_2U(SCH_1):PAGE90
    54    GND @S9S_MB_2U_LIB.S9S_MB_2U(SCH_1):GND   I147 @S9S_MB_2U_LIB.S9S_MB_2U(SCH_1):PAGE90
    57    GND @S9S_MB_2U_LIB.S9S_MB_2U(SCH_1):GND   I147 @S9S_MB_2U_LIB.S9S_MB_2U(SCH_1):PAGE90
    59    GND @S9S_MB_2U_LIB.S9S_MB_2U(SCH_1):GND   I147 @S9S_MB_2U_LIB.S9S_MB_2U(SCH_1):PAGE90
    61    GND @S9S_MB_2U_LIB.S9S_MB_2U(SCH_1):GND   I147 @S9S_MB_2U_LIB.S9S_MB_2U(SCH_1):PAGE90
    63    GND @S9S_MB_2U_LIB.S9S_MB_2U(SCH_1):GND   I147 @S9S_MB_2U_LIB.S9S_MB_2U(SCH_1):PAGE90
    65    GND @S9S_MB_2U_LIB.S9S_MB_2U(SCH_1):GND   I147 @S9S_MB_2U_LIB.S9S_MB_2U(SCH_1):PAGE90
    67    GND @S9S_MB_2U_LIB.S9S_MB_2U(SCH_1):GND   I147 @S9S_MB_2U_LIB.S9S_MB_2U(SCH_1):PAGE90
    69    GND @S9S_MB_2U_LIB.S9S_MB_2U(SCH_1):GND   I147 @S9S_MB_2U_LIB.S9S_MB_2U(SCH_1):PAGE90
    71    GND @S9S_MB_2U_LIB.S9S_MB_2U(SCH_1):GND   I147 @S9S_MB_2U_LIB.S9S_MB_2U(SCH_1):PAGE90
    73    GND @S9S_MB_2U_LIB.S9S_MB_2U(SCH_1):GND   I147 @S9S_MB_2U_LIB.S9S_MB_2U(SCH_1):PAGE90
    75    GND @S9S_MB_2U_LIB.S9S_MB_2U(SCH_1):GND   I147 @S9S_MB_2U_LIB.S9S_MB_2U(SCH_1):PAGE90
    77    GND @S9S_MB_2U_LIB.S9S_MB_2U(SCH_1):GND   I147 @S9S_MB_2U_LIB.S9S_MB_2U(SCH_1):PAGE90
    79    GND @S9S_MB_2U_LIB.S9S_MB_2U(SCH_1):GND   I147 @S9S_MB_2U_LIB.S9S_MB_2U(SCH_1):PAGE90
    81    GND @S9S_MB_2U_LIB.S9S_MB_2U(SCH_1):GND   I147 @S9S_MB_2U_LIB.S9S_MB_2U(SCH_1):PAGE90
    83    GND @S9S_MB_2U_LIB.S9S_MB_2U(SCH_1):GND   I147 @S9S_MB_2U_LIB.S9S_MB_2U(SCH_1):PAGE90
    85    GND @S9S_MB_2U_LIB.S9S_MB_2U(SCH_1):GND   I147 @S9S_MB_2U_LIB.S9S_MB_2U(SCH_1):PAGE90
    88    GND @S9S_MB_2U_LIB.S9S_MB_2U(SCH_1):GND   I147 @S9S_MB_2U_LIB.S9S_MB_2U(SCH_1):PAGE90
    90    GND @S9S_MB_2U_LIB.S9S_MB_2U(SCH_1):GND   I147 @S9S_MB_2U_LIB.S9S_MB_2U(SCH_1):PAGE90
    92    GND @S9S_MB_2U_LIB.S9S_MB_2U(SCH_1):GND   I147 @S9S_MB_2U_LIB.S9S_MB_2U(SCH_1):PAGE90
    95    GND @S9S_MB_2U_LIB.S9S_MB_2U(SCH_1):GND   I147 @S9S_MB_2U_LIB.S9S_MB_2U(SCH_1):PAGE90
    97    GND @S9S_MB_2U_LIB.S9S_MB_2U(SCH_1):GND   I147 @S9S_MB_2U_LIB.S9S_MB_2U(SCH_1):PAGE90
    99    GND @S9S_MB_2U_LIB.S9S_MB_2U(SCH_1):GND   I147 @S9S_MB_2U_LIB.S9S_MB_2U(SCH_1):PAGE90
   101    GND @S9S_MB_2U_LIB.S9S_MB_2U(SCH_1):GND   I147 @S9S_MB_2U_LIB.S9S_MB_2U(SCH_1):PAGE90
   103    GND @S9S_MB_2U_LIB.S9S_MB_2U(SCH_1):GND   I147 @S9S_MB_2U_LIB.S9S_MB_2U(SCH_1):PAGE90
   106    GND @S9S_MB_2U_LIB.S9S_MB_2U(SCH_1):GND   I147 @S9S_MB_2U_LIB.S9S_MB_2U(SCH_1):PAGE90
   108    GND @S9S_MB_2U_LIB.S9S_MB_2U(SCH_1):GND   I147 @S9S_MB_2U_LIB.S9S_MB_2U(SCH_1):PAGE90
   110    GND @S9S_MB_2U_LIB.S9S_MB_2U(SCH_1):GND   I147 @S9S_MB_2U_LIB.S9S_MB_2U(SCH_1):PAGE90
   112    GND @S9S_MB_2U_LIB.S9S_MB_2U(SCH_1):GND   I147 @S9S_MB_2U_LIB.S9S_MB_2U(SCH_1):PAGE90
   114    GND @S9S_MB_2U_LIB.S9S_MB_2U(SCH_1):GND   I147 @S9S_MB_2U_LIB.S9S_MB_2U(SCH_1):PAGE90
   117    GND @S9S_MB_2U_LIB.S9S_MB_2U(SCH_1):GND   I147 @S9S_MB_2U_LIB.S9S_MB_2U(SCH_1):PAGE90
   119    GND @S9S_MB_2U_LIB.S9S_MB_2U(SCH_1):GND   I147 @S9S_MB_2U_LIB.S9S_MB_2U(SCH_1):PAGE90
   121    GND @S9S_MB_2U_LIB.S9S_MB_2U(SCH_1):GND   I147 @S9S_MB_2U_LIB.S9S_MB_2U(SCH_1):PAGE90
   123    GND @S9S_MB_2U_LIB.S9S_MB_2U(SCH_1):GND   I147 @S9S_MB_2U_LIB.S9S_MB_2U(SCH_1):PAGE90
   125    GND @S9S_MB_2U_LIB.S9S_MB_2U(SCH_1):GND   I147 @S9S_MB_2U_LIB.S9S_MB_2U(SCH_1):PAGE90
   128    GND @S9S_MB_2U_LIB.S9S_MB_2U(SCH_1):GND   I147 @S9S_MB_2U_LIB.S9S_MB_2U(SCH_1):PAGE90
   130    GND @S9S_MB_2U_LIB.S9S_MB_2U(SCH_1):GND   I147 @S9S_MB_2U_LIB.S9S_MB_2U(SCH_1):PAGE90
   134    GND @S9S_MB_2U_LIB.S9S_MB_2U(SCH_1):GND   I147 @S9S_MB_2U_LIB.S9S_MB_2U(SCH_1):PAGE90
   143    GND @S9S_MB_2U_LIB.S9S_MB_2U(SCH_1):GND   I147 @S9S_MB_2U_LIB.S9S_MB_2U(SCH_1):PAGE90
   151    GND @S9S_MB_2U_LIB.S9S_MB_2U(SCH_1):GND   I147 @S9S_MB_2U_LIB.S9S_MB_2U(SCH_1):PAGE90
   153    GND @S9S_MB_2U_LIB.S9S_MB_2U(SCH_1):GND   I147 @S9S_MB_2U_LIB.S9S_MB_2U(SCH_1):PAGE90
   155    GND @S9S_MB_2U_LIB.S9S_MB_2U(SCH_1):GND   I147 @S9S_MB_2U_LIB.S9S_MB_2U(SCH_1):PAGE90
   158    GND @S9S_MB_2U_LIB.S9S_MB_2U(SCH_1):GND   I147 @S9S_MB_2U_LIB.S9S_MB_2U(SCH_1):PAGE90
   160    GND @S9S_MB_2U_LIB.S9S_MB_2U(SCH_1):GND   I147 @S9S_MB_2U_LIB.S9S_MB_2U(SCH_1):PAGE90
   162    GND @S9S_MB_2U_LIB.S9S_MB_2U(SCH_1):GND   I147 @S9S_MB_2U_LIB.S9S_MB_2U(SCH_1):PAGE90
   164    GND @S9S_MB_2U_LIB.S9S_MB_2U(SCH_1):GND   I147 @S9S_MB_2U_LIB.S9S_MB_2U(SCH_1):PAGE90
   166    GND @S9S_MB_2U_LIB.S9S_MB_2U(SCH_1):GND   I147 @S9S_MB_2U_LIB.S9S_MB_2U(SCH_1):PAGE90
   169    GND @S9S_MB_2U_LIB.S9S_MB_2U(SCH_1):GND   I147 @S9S_MB_2U_LIB.S9S_MB_2U(SCH_1):PAGE90
   171    GND @S9S_MB_2U_LIB.S9S_MB_2U(SCH_1):GND   I147 @S9S_MB_2U_LIB.S9S_MB_2U(SCH_1):PAGE90
   173    GND @S9S_MB_2U_LIB.S9S_MB_2U(SCH_1):GND   I147 @S9S_MB_2U_LIB.S9S_MB_2U(SCH_1):PAGE90
   175    GND @S9S_MB_2U_LIB.S9S_MB_2U(SCH_1):GND   I147 @S9S_MB_2U_LIB.S9S_MB_2U(SCH_1):PAGE90
   177    GND @S9S_MB_2U_LIB.S9S_MB_2U(SCH_1):GND   I147 @S9S_MB_2U_LIB.S9S_MB_2U(SCH_1):PAGE90
   180    GND @S9S_MB_2U_LIB.S9S_MB_2U(SCH_1):GND   I147 @S9S_MB_2U_LIB.S9S_MB_2U(SCH_1):PAGE90
   182    GND @S9S_MB_2U_LIB.S9S_MB_2U(SCH_1):GND   I147 @S9S_MB_2U_LIB.S9S_MB_2U(SCH_1):PAGE90
   184    GND @S9S_MB_2U_LIB.S9S_MB_2U(SCH_1):GND   I147 @S9S_MB_2U_LIB.S9S_MB_2U(SCH_1):PAGE90
   186    GND @S9S_MB_2U_LIB.S9S_MB_2U(SCH_1):GND   I147 @S9S_MB_2U_LIB.S9S_MB_2U(SCH_1):PAGE90
   188    GND @S9S_MB_2U_LIB.S9S_MB_2U(SCH_1):GND   I147 @S9S_MB_2U_LIB.S9S_MB_2U(SCH_1):PAGE90
   191    GND @S9S_MB_2U_LIB.S9S_MB_2U(SCH_1):GND   I147 @S9S_MB_2U_LIB.S9S_MB_2U(SCH_1):PAGE90
   193    GND @S9S_MB_2U_LIB.S9S_MB_2U(SCH_1):GND   I147 @S9S_MB_2U_LIB.S9S_MB_2U(SCH_1):PAGE90
   195    GND @S9S_MB_2U_LIB.S9S_MB_2U(SCH_1):GND   I147 @S9S_MB_2U_LIB.S9S_MB_2U(SCH_1):PAGE90
   197    GND @S9S_MB_2U_LIB.S9S_MB_2U(SCH_1):GND   I147 @S9S_MB_2U_LIB.S9S_MB_2U(SCH_1):PAGE90
   199    GND @S9S_MB_2U_LIB.S9S_MB_2U(SCH_1):GND   I147 @S9S_MB_2U_LIB.S9S_MB_2U(SCH_1):PAGE90
   202    GND @S9S_MB_2U_LIB.S9S_MB_2U(SCH_1):GND   I147 @S9S_MB_2U_LIB.S9S_MB_2U(SCH_1):PAGE90
   204    GND @S9S_MB_2U_LIB.S9S_MB_2U(SCH_1):GND   I147 @S9S_MB_2U_LIB.S9S_MB_2U(SCH_1):PAGE90
   206    GND @S9S_MB_2U_LIB.S9S_MB_2U(SCH_1):GND   I147 @S9S_MB_2U_LIB.S9S_MB_2U(SCH_1):PAGE90
   208    GND @S9S_MB_2U_LIB.S9S_MB_2U(SCH_1):GND   I147 @S9S_MB_2U_LIB.S9S_MB_2U(SCH_1):PAGE90
   210    GND @S9S_MB_2U_LIB.S9S_MB_2U(SCH_1):GND   I147 @S9S_MB_2U_LIB.S9S_MB_2U(SCH_1):PAGE90
   212    GND @S9S_MB_2U_LIB.S9S_MB_2U(SCH_1):GND   I147 @S9S_MB_2U_LIB.S9S_MB_2U(SCH_1):PAGE90
   214    GND @S9S_MB_2U_LIB.S9S_MB_2U(SCH_1):GND   I147 @S9S_MB_2U_LIB.S9S_MB_2U(SCH_1):PAGE90
   216    GND @S9S_MB_2U_LIB.S9S_MB_2U(SCH_1):GND   I147 @S9S_MB_2U_LIB.S9S_MB_2U(SCH_1):PAGE90
   219    GND @S9S_MB_2U_LIB.S9S_MB_2U(SCH_1):GND   I147 @S9S_MB_2U_LIB.S9S_MB_2U(SCH_1):PAGE90
   222    GND @S9S_MB_2U_LIB.S9S_MB_2U(SCH_1):GND   I147 @S9S_MB_2U_LIB.S9S_MB_2U(SCH_1):PAGE90
   224    GND @S9S_MB_2U_LIB.S9S_MB_2U(SCH_1):GND   I147 @S9S_MB_2U_LIB.S9S_MB_2U(SCH_1):PAGE90
   226    GND @S9S_MB_2U_LIB.S9S_MB_2U(SCH_1):GND   I147 @S9S_MB_2U_LIB.S9S_MB_2U(SCH_1):PAGE90
   228    GND @S9S_MB_2U_LIB.S9S_MB_2U(SCH_1):GND   I147 @S9S_MB_2U_LIB.S9S_MB_2U(SCH_1):PAGE90
   233    GND @S9S_MB_2U_LIB.S9S_MB_2U(SCH_1):GND   I147 @S9S_MB_2U_LIB.S9S_MB_2U(SCH_1):PAGE90
   237    GND @S9S_MB_2U_LIB.S9S_MB_2U(SCH_1):GND   I147 @S9S_MB_2U_LIB.S9S_MB_2U(SCH_1):PAGE90
   242    GND @S9S_MB_2U_LIB.S9S_MB_2U(SCH_1):GND   I147 @S9S_MB_2U_LIB.S9S_MB_2U(SCH_1):PAGE90
   244    GND @S9S_MB_2U_LIB.S9S_MB_2U(SCH_1):GND   I147 @S9S_MB_2U_LIB.S9S_MB_2U(SCH_1):PAGE90
   246    GND @S9S_MB_2U_LIB.S9S_MB_2U(SCH_1):GND   I147 @S9S_MB_2U_LIB.S9S_MB_2U(SCH_1):PAGE90
   248    GND @S9S_MB_2U_LIB.S9S_MB_2U(SCH_1):GND   I147 @S9S_MB_2U_LIB.S9S_MB_2U(SCH_1):PAGE90
   251    GND @S9S_MB_2U_LIB.S9S_MB_2U(SCH_1):GND   I147 @S9S_MB_2U_LIB.S9S_MB_2U(SCH_1):PAGE90
   253    GND @S9S_MB_2U_LIB.S9S_MB_2U(SCH_1):GND   I147 @S9S_MB_2U_LIB.S9S_MB_2U(SCH_1):PAGE90
   255    GND @S9S_MB_2U_LIB.S9S_MB_2U(SCH_1):GND   I147 @S9S_MB_2U_LIB.S9S_MB_2U(SCH_1):PAGE90
   257    GND @S9S_MB_2U_LIB.S9S_MB_2U(SCH_1):GND   I147 @S9S_MB_2U_LIB.S9S_MB_2U(SCH_1):PAGE90
   259    GND @S9S_MB_2U_LIB.S9S_MB_2U(SCH_1):GND   I147 @S9S_MB_2U_LIB.S9S_MB_2U(SCH_1):PAGE90
   262    GND @S9S_MB_2U_LIB.S9S_MB_2U(SCH_1):GND   I147 @S9S_MB_2U_LIB.S9S_MB_2U(SCH_1):PAGE90
   264    GND @S9S_MB_2U_LIB.S9S_MB_2U(SCH_1):GND   I147 @S9S_MB_2U_LIB.S9S_MB_2U(SCH_1):PAGE90
   266    GND @S9S_MB_2U_LIB.S9S_MB_2U(SCH_1):GND   I147 @S9S_MB_2U_LIB.S9S_MB_2U(SCH_1):PAGE90
   268    GND @S9S_MB_2U_LIB.S9S_MB_2U(SCH_1):GND   I147 @S9S_MB_2U_LIB.S9S_MB_2U(SCH_1):PAGE90
   270    GND @S9S_MB_2U_LIB.S9S_MB_2U(SCH_1):GND   I147 @S9S_MB_2U_LIB.S9S_MB_2U(SCH_1):PAGE90
   273    GND @S9S_MB_2U_LIB.S9S_MB_2U(SCH_1):GND   I147 @S9S_MB_2U_LIB.S9S_MB_2U(SCH_1):PAGE90
   275    GND @S9S_MB_2U_LIB.S9S_MB_2U(SCH_1):GND   I147 @S9S_MB_2U_LIB.S9S_MB_2U(SCH_1):PAGE90
   277    GND @S9S_MB_2U_LIB.S9S_MB_2U(SCH_1):GND   I147 @S9S_MB_2U_LIB.S9S_MB_2U(SCH_1):PAGE90
   279    GND @S9S_MB_2U_LIB.S9S_MB_2U(SCH_1):GND   I147 @S9S_MB_2U_LIB.S9S_MB_2U(SCH_1):PAGE90
   281    GND @S9S_MB_2U_LIB.S9S_MB_2U(SCH_1):GND   I147 @S9S_MB_2U_LIB.S9S_MB_2U(SCH_1):PAGE90
   284    GND @S9S_MB_2U_LIB.S9S_MB_2U(SCH_1):GND   I147 @S9S_MB_2U_LIB.S9S_MB_2U(SCH_1):PAGE90
   286    GND @S9S_MB_2U_LIB.S9S_MB_2U(SCH_1):GND   I147 @S9S_MB_2U_LIB.S9S_MB_2U(SCH_1):PAGE90
   288    GND @S9S_MB_2U_LIB.S9S_MB_2U(SCH_1):GND   I147 @S9S_MB_2U_LIB.S9S_MB_2U(SCH_1):PAGE90
     1 P12V_S3_AUX_CPU0_NVDIMM @S9S_MB_2U_LIB.S9S_MB_2U(SCH_1):P12V_S3_AUX_CPU0_NVDIMM   I147 @S9S_MB_2U_LIB.S9S_MB_2U(SCH_1):PAGE90
   145 P12V_S3_AUX_CPU0_NVDIMM @S9S_MB_2U_LIB.S9S_MB_2U(SCH_1):P12V_S3_AUX_CPU0_NVDIMM   I147 @S9S_MB_2U_LIB.S9S_MB_2U(SCH_1):PAGE90
   146 P12V_S3_AUX_CPU0_NVDIMM @S9S_MB_2U_LIB.S9S_MB_2U(SCH_1):P12V_S3_AUX_CPU0_NVDIMM   I147 @S9S_MB_2U_LIB.S9S_MB_2U(SCH_1):PAGE90
   230    GND @S9S_MB_2U_LIB.S9S_MB_2U(SCH_1):GND   I147 @S9S_MB_2U_LIB.S9S_MB_2U(SCH_1):PAGE90
   235    GND @S9S_MB_2U_LIB.S9S_MB_2U(SCH_1):GND   I147 @S9S_MB_2U_LIB.S9S_MB_2U(SCH_1):PAGE90
   240    GND @S9S_MB_2U_LIB.S9S_MB_2U(SCH_1):GND   I147 @S9S_MB_2U_LIB.S9S_MB_2U(SCH_1):PAGE90
   132    GND @S9S_MB_2U_LIB.S9S_MB_2U(SCH_1):GND   I147 @S9S_MB_2U_LIB.S9S_MB_2U(SCH_1):PAGE90
   136    GND @S9S_MB_2U_LIB.S9S_MB_2U(SCH_1):GND   I147 @S9S_MB_2U_LIB.S9S_MB_2U(SCH_1):PAGE90
   139    GND @S9S_MB_2U_LIB.S9S_MB_2U(SCH_1):GND   I147 @S9S_MB_2U_LIB.S9S_MB_2U(SCH_1):PAGE90
   141    GND @S9S_MB_2U_LIB.S9S_MB_2U(SCH_1):GND   I147 @S9S_MB_2U_LIB.S9S_MB_2U(SCH_1):PAGE90
    G1    GND @S9S_MB_2U_LIB.S9S_MB_2U(SCH_1):GND   I147 @S9S_MB_2U_LIB.S9S_MB_2U(SCH_1):PAGE90
    G2    GND @S9S_MB_2U_LIB.S9S_MB_2U(SCH_1):GND   I147 @S9S_MB_2U_LIB.S9S_MB_2U(SCH_1):PAGE90
    G3    GND @S9S_MB_2U_LIB.S9S_MB_2U(SCH_1):GND   I147 @S9S_MB_2U_LIB.S9S_MB_2U(SCH_1):PAGE90

 J10 SCONN288_ADR50017P087CC-SCONN2A
     3 P3V3_AUX @S9S_MB_2U_LIB.S9S_MB_2U(SCH_1):P3V3_AUX    I13 @S9S_MB_2U_LIB.S9S_MB_2U(SCH_1):PAGE91
     2 TP_CHE_CPU0_DIMM2_FRU_0 @S9S_MB_2U_LIB.S9S_MB_2U(SCH_1):TP_CHE_CPU0_DIMM2_FRU_0    I13 @S9S_MB_2U_LIB.S9S_MB_2U(SCH_1):PAGE91
   144 TP_CHE_CPU0_DIMM2_FRU_1 @S9S_MB_2U_LIB.S9S_MB_2U(SCH_1):TP_CHE_CPU0_DIMM2_FRU_1    I13 @S9S_MB_2U_LIB.S9S_MB_2U(SCH_1):PAGE91
   149 TP_CHE_CPU0_DIMM2_FRU_2 @S9S_MB_2U_LIB.S9S_MB_2U(SCH_1):TP_CHE_CPU0_DIMM2_FRU_2    I13 @S9S_MB_2U_LIB.S9S_MB_2U(SCH_1):PAGE91
   150 TP_CHE_CPU0_DIMM2_FRU_3 @S9S_MB_2U_LIB.S9S_MB_2U(SCH_1):TP_CHE_CPU0_DIMM2_FRU_3    I13 @S9S_MB_2U_LIB.S9S_MB_2U(SCH_1):PAGE91
   220 TP_CHE_CPU0_DIMM2_FRU_4 @S9S_MB_2U_LIB.S9S_MB_2U(SCH_1):TP_CHE_CPU0_DIMM2_FRU_4    I13 @S9S_MB_2U_LIB.S9S_MB_2U(SCH_1):PAGE91
   231 TP_CHE_CPU0_DIMM2_FRU_5 @S9S_MB_2U_LIB.S9S_MB_2U(SCH_1):TP_CHE_CPU0_DIMM2_FRU_5    I13 @S9S_MB_2U_LIB.S9S_MB_2U(SCH_1):PAGE91
   232 TP_CHE_CPU0_DIMM2_FRU_6 @S9S_MB_2U_LIB.S9S_MB_2U(SCH_1):TP_CHE_CPU0_DIMM2_FRU_6    I13 @S9S_MB_2U_LIB.S9S_MB_2U(SCH_1):PAGE91
   207 RST_M_EF_CPU0_FPGA_N @S9S_MB_2U_LIB.S9S_MB_2U(SCH_1):RST_M_EF_CPU0_FPGA_N    I13 @S9S_MB_2U_LIB.S9S_MB_2U(SCH_1):PAGE91
   147 PWRGD_CHE_CPU0_DIMM2 @S9S_MB_2U_LIB.S9S_MB_2U(SCH_1):PWRGD_CHE_CPU0_DIMM2    I13 @S9S_MB_2U_LIB.S9S_MB_2U(SCH_1):PAGE91
   227 M_E_CPU0_SB_PAR @S9S_MB_2U_LIB.S9S_MB_2U(SCH_1):M_E_CPU0_SB_PAR    I13 @S9S_MB_2U_LIB.S9S_MB_2U(SCH_1):PAGE91
    74 M_E_CPU0_SA_PAR @S9S_MB_2U_LIB.S9S_MB_2U(SCH_1):M_E_CPU0_SA_PAR    I13 @S9S_MB_2U_LIB.S9S_MB_2U(SCH_1):PAGE91
    87 M_E_CPU0_SB_RSP<1> @S9S_MB_2U_LIB.S9S_MB_2U(SCH_1):M_E_CPU0_SB_RSP(1)    I13 @S9S_MB_2U_LIB.S9S_MB_2U(SCH_1):PAGE91
    86 M_E_CPU0_SA_RSP<1> @S9S_MB_2U_LIB.S9S_MB_2U(SCH_1):M_E_CPU0_SA_RSP(1)    I13 @S9S_MB_2U_LIB.S9S_MB_2U(SCH_1):PAGE91
     5 I3C_SPD_DDREFGH_CPU0_LVC1_SDA @S9S_MB_2U_LIB.S9S_MB_2U(SCH_1):I3C_SPD_DDREFGH_CPU0_LVC1_SDA    I13 @S9S_MB_2U_LIB.S9S_MB_2U(SCH_1):PAGE91
     4 I3C_SPD_DDREFGH_CPU0_LVC1_SCL_1 @S9S_MB_2U_LIB.S9S_MB_2U(SCH_1):I3C_SPD_DDREFGH_CPU0_LVC1_SCL_R2    I13 @S9S_MB_2U_LIB.S9S_MB_2U(SCH_1):PAGE91
   148 PD_CHE_CPU0_DIMM2_SAA @S9S_MB_2U_LIB.S9S_MB_2U(SCH_1):PD_CHE_CPU0_DIMM2_SAA    I13 @S9S_MB_2U_LIB.S9S_MB_2U(SCH_1):PAGE91
   100 M_E_CPU0_SB_DQ<0> @S9S_MB_2U_LIB.S9S_MB_2U(SCH_1):M_E_CPU0_SB_DQ(0)    I13 @S9S_MB_2U_LIB.S9S_MB_2U(SCH_1):PAGE91
   102 M_E_CPU0_SB_DQ<1> @S9S_MB_2U_LIB.S9S_MB_2U(SCH_1):M_E_CPU0_SB_DQ(1)    I13 @S9S_MB_2U_LIB.S9S_MB_2U(SCH_1):PAGE91
   245 M_E_CPU0_SB_DQ<2> @S9S_MB_2U_LIB.S9S_MB_2U(SCH_1):M_E_CPU0_SB_DQ(2)    I13 @S9S_MB_2U_LIB.S9S_MB_2U(SCH_1):PAGE91
   247 M_E_CPU0_SB_DQ<3> @S9S_MB_2U_LIB.S9S_MB_2U(SCH_1):M_E_CPU0_SB_DQ(3)    I13 @S9S_MB_2U_LIB.S9S_MB_2U(SCH_1):PAGE91
   107 M_E_CPU0_SB_DQ<4> @S9S_MB_2U_LIB.S9S_MB_2U(SCH_1):M_E_CPU0_SB_DQ(4)    I13 @S9S_MB_2U_LIB.S9S_MB_2U(SCH_1):PAGE91
   109 M_E_CPU0_SB_DQ<5> @S9S_MB_2U_LIB.S9S_MB_2U(SCH_1):M_E_CPU0_SB_DQ(5)    I13 @S9S_MB_2U_LIB.S9S_MB_2U(SCH_1):PAGE91
   252 M_E_CPU0_SB_DQ<6> @S9S_MB_2U_LIB.S9S_MB_2U(SCH_1):M_E_CPU0_SB_DQ(6)    I13 @S9S_MB_2U_LIB.S9S_MB_2U(SCH_1):PAGE91
   254 M_E_CPU0_SB_DQ<7> @S9S_MB_2U_LIB.S9S_MB_2U(SCH_1):M_E_CPU0_SB_DQ(7)    I13 @S9S_MB_2U_LIB.S9S_MB_2U(SCH_1):PAGE91
   111 M_E_CPU0_SB_DQ<8> @S9S_MB_2U_LIB.S9S_MB_2U(SCH_1):M_E_CPU0_SB_DQ(8)    I13 @S9S_MB_2U_LIB.S9S_MB_2U(SCH_1):PAGE91
   113 M_E_CPU0_SB_DQ<9> @S9S_MB_2U_LIB.S9S_MB_2U(SCH_1):M_E_CPU0_SB_DQ(9)    I13 @S9S_MB_2U_LIB.S9S_MB_2U(SCH_1):PAGE91
   256 M_E_CPU0_SB_DQ<10> @S9S_MB_2U_LIB.S9S_MB_2U(SCH_1):M_E_CPU0_SB_DQ(10)    I13 @S9S_MB_2U_LIB.S9S_MB_2U(SCH_1):PAGE91
   258 M_E_CPU0_SB_DQ<11> @S9S_MB_2U_LIB.S9S_MB_2U(SCH_1):M_E_CPU0_SB_DQ(11)    I13 @S9S_MB_2U_LIB.S9S_MB_2U(SCH_1):PAGE91
   118 M_E_CPU0_SB_DQ<12> @S9S_MB_2U_LIB.S9S_MB_2U(SCH_1):M_E_CPU0_SB_DQ(12)    I13 @S9S_MB_2U_LIB.S9S_MB_2U(SCH_1):PAGE91
   120 M_E_CPU0_SB_DQ<13> @S9S_MB_2U_LIB.S9S_MB_2U(SCH_1):M_E_CPU0_SB_DQ(13)    I13 @S9S_MB_2U_LIB.S9S_MB_2U(SCH_1):PAGE91
   263 M_E_CPU0_SB_DQ<14> @S9S_MB_2U_LIB.S9S_MB_2U(SCH_1):M_E_CPU0_SB_DQ(14)    I13 @S9S_MB_2U_LIB.S9S_MB_2U(SCH_1):PAGE91
   265 M_E_CPU0_SB_DQ<15> @S9S_MB_2U_LIB.S9S_MB_2U(SCH_1):M_E_CPU0_SB_DQ(15)    I13 @S9S_MB_2U_LIB.S9S_MB_2U(SCH_1):PAGE91
   122 M_E_CPU0_SB_DQ<16> @S9S_MB_2U_LIB.S9S_MB_2U(SCH_1):M_E_CPU0_SB_DQ(16)    I13 @S9S_MB_2U_LIB.S9S_MB_2U(SCH_1):PAGE91
   124 M_E_CPU0_SB_DQ<17> @S9S_MB_2U_LIB.S9S_MB_2U(SCH_1):M_E_CPU0_SB_DQ(17)    I13 @S9S_MB_2U_LIB.S9S_MB_2U(SCH_1):PAGE91
   267 M_E_CPU0_SB_DQ<18> @S9S_MB_2U_LIB.S9S_MB_2U(SCH_1):M_E_CPU0_SB_DQ(18)    I13 @S9S_MB_2U_LIB.S9S_MB_2U(SCH_1):PAGE91
   269 M_E_CPU0_SB_DQ<19> @S9S_MB_2U_LIB.S9S_MB_2U(SCH_1):M_E_CPU0_SB_DQ(19)    I13 @S9S_MB_2U_LIB.S9S_MB_2U(SCH_1):PAGE91
   129 M_E_CPU0_SB_DQ<20> @S9S_MB_2U_LIB.S9S_MB_2U(SCH_1):M_E_CPU0_SB_DQ(20)    I13 @S9S_MB_2U_LIB.S9S_MB_2U(SCH_1):PAGE91
   131 M_E_CPU0_SB_DQ<21> @S9S_MB_2U_LIB.S9S_MB_2U(SCH_1):M_E_CPU0_SB_DQ(21)    I13 @S9S_MB_2U_LIB.S9S_MB_2U(SCH_1):PAGE91
   274 M_E_CPU0_SB_DQ<22> @S9S_MB_2U_LIB.S9S_MB_2U(SCH_1):M_E_CPU0_SB_DQ(22)    I13 @S9S_MB_2U_LIB.S9S_MB_2U(SCH_1):PAGE91
   276 M_E_CPU0_SB_DQ<23> @S9S_MB_2U_LIB.S9S_MB_2U(SCH_1):M_E_CPU0_SB_DQ(23)    I13 @S9S_MB_2U_LIB.S9S_MB_2U(SCH_1):PAGE91
   133 M_E_CPU0_SB_DQ<24> @S9S_MB_2U_LIB.S9S_MB_2U(SCH_1):M_E_CPU0_SB_DQ(24)    I13 @S9S_MB_2U_LIB.S9S_MB_2U(SCH_1):PAGE91
   135 M_E_CPU0_SB_DQ<25> @S9S_MB_2U_LIB.S9S_MB_2U(SCH_1):M_E_CPU0_SB_DQ(25)    I13 @S9S_MB_2U_LIB.S9S_MB_2U(SCH_1):PAGE91
   278 M_E_CPU0_SB_DQ<26> @S9S_MB_2U_LIB.S9S_MB_2U(SCH_1):M_E_CPU0_SB_DQ(26)    I13 @S9S_MB_2U_LIB.S9S_MB_2U(SCH_1):PAGE91
   280 M_E_CPU0_SB_DQ<27> @S9S_MB_2U_LIB.S9S_MB_2U(SCH_1):M_E_CPU0_SB_DQ(27)    I13 @S9S_MB_2U_LIB.S9S_MB_2U(SCH_1):PAGE91
   140 M_E_CPU0_SB_DQ<28> @S9S_MB_2U_LIB.S9S_MB_2U(SCH_1):M_E_CPU0_SB_DQ(28)    I13 @S9S_MB_2U_LIB.S9S_MB_2U(SCH_1):PAGE91
   142 M_E_CPU0_SB_DQ<29> @S9S_MB_2U_LIB.S9S_MB_2U(SCH_1):M_E_CPU0_SB_DQ(29)    I13 @S9S_MB_2U_LIB.S9S_MB_2U(SCH_1):PAGE91
   285 M_E_CPU0_SB_DQ<30> @S9S_MB_2U_LIB.S9S_MB_2U(SCH_1):M_E_CPU0_SB_DQ(30)    I13 @S9S_MB_2U_LIB.S9S_MB_2U(SCH_1):PAGE91
   287 M_E_CPU0_SB_DQ<31> @S9S_MB_2U_LIB.S9S_MB_2U(SCH_1):M_E_CPU0_SB_DQ(31)    I13 @S9S_MB_2U_LIB.S9S_MB_2U(SCH_1):PAGE91
     7 M_E_CPU0_SA_DQ<0> @S9S_MB_2U_LIB.S9S_MB_2U(SCH_1):M_E_CPU0_SA_DQ(0)    I13 @S9S_MB_2U_LIB.S9S_MB_2U(SCH_1):PAGE91
     9 M_E_CPU0_SA_DQ<1> @S9S_MB_2U_LIB.S9S_MB_2U(SCH_1):M_E_CPU0_SA_DQ(1)    I13 @S9S_MB_2U_LIB.S9S_MB_2U(SCH_1):PAGE91
   152 M_E_CPU0_SA_DQ<2> @S9S_MB_2U_LIB.S9S_MB_2U(SCH_1):M_E_CPU0_SA_DQ(2)    I13 @S9S_MB_2U_LIB.S9S_MB_2U(SCH_1):PAGE91
   154 M_E_CPU0_SA_DQ<3> @S9S_MB_2U_LIB.S9S_MB_2U(SCH_1):M_E_CPU0_SA_DQ(3)    I13 @S9S_MB_2U_LIB.S9S_MB_2U(SCH_1):PAGE91
    14 M_E_CPU0_SA_DQ<4> @S9S_MB_2U_LIB.S9S_MB_2U(SCH_1):M_E_CPU0_SA_DQ(4)    I13 @S9S_MB_2U_LIB.S9S_MB_2U(SCH_1):PAGE91
    16 M_E_CPU0_SA_DQ<5> @S9S_MB_2U_LIB.S9S_MB_2U(SCH_1):M_E_CPU0_SA_DQ(5)    I13 @S9S_MB_2U_LIB.S9S_MB_2U(SCH_1):PAGE91
   159 M_E_CPU0_SA_DQ<6> @S9S_MB_2U_LIB.S9S_MB_2U(SCH_1):M_E_CPU0_SA_DQ(6)    I13 @S9S_MB_2U_LIB.S9S_MB_2U(SCH_1):PAGE91
   161 M_E_CPU0_SA_DQ<7> @S9S_MB_2U_LIB.S9S_MB_2U(SCH_1):M_E_CPU0_SA_DQ(7)    I13 @S9S_MB_2U_LIB.S9S_MB_2U(SCH_1):PAGE91
    18 M_E_CPU0_SA_DQ<8> @S9S_MB_2U_LIB.S9S_MB_2U(SCH_1):M_E_CPU0_SA_DQ(8)    I13 @S9S_MB_2U_LIB.S9S_MB_2U(SCH_1):PAGE91
    20 M_E_CPU0_SA_DQ<9> @S9S_MB_2U_LIB.S9S_MB_2U(SCH_1):M_E_CPU0_SA_DQ(9)    I13 @S9S_MB_2U_LIB.S9S_MB_2U(SCH_1):PAGE91
   163 M_E_CPU0_SA_DQ<10> @S9S_MB_2U_LIB.S9S_MB_2U(SCH_1):M_E_CPU0_SA_DQ(10)    I13 @S9S_MB_2U_LIB.S9S_MB_2U(SCH_1):PAGE91
   165 M_E_CPU0_SA_DQ<11> @S9S_MB_2U_LIB.S9S_MB_2U(SCH_1):M_E_CPU0_SA_DQ(11)    I13 @S9S_MB_2U_LIB.S9S_MB_2U(SCH_1):PAGE91
    25 M_E_CPU0_SA_DQ<12> @S9S_MB_2U_LIB.S9S_MB_2U(SCH_1):M_E_CPU0_SA_DQ(12)    I13 @S9S_MB_2U_LIB.S9S_MB_2U(SCH_1):PAGE91
    27 M_E_CPU0_SA_DQ<13> @S9S_MB_2U_LIB.S9S_MB_2U(SCH_1):M_E_CPU0_SA_DQ(13)    I13 @S9S_MB_2U_LIB.S9S_MB_2U(SCH_1):PAGE91
   170 M_E_CPU0_SA_DQ<14> @S9S_MB_2U_LIB.S9S_MB_2U(SCH_1):M_E_CPU0_SA_DQ(14)    I13 @S9S_MB_2U_LIB.S9S_MB_2U(SCH_1):PAGE91
   172 M_E_CPU0_SA_DQ<15> @S9S_MB_2U_LIB.S9S_MB_2U(SCH_1):M_E_CPU0_SA_DQ(15)    I13 @S9S_MB_2U_LIB.S9S_MB_2U(SCH_1):PAGE91
    29 M_E_CPU0_SA_DQ<16> @S9S_MB_2U_LIB.S9S_MB_2U(SCH_1):M_E_CPU0_SA_DQ(16)    I13 @S9S_MB_2U_LIB.S9S_MB_2U(SCH_1):PAGE91
    31 M_E_CPU0_SA_DQ<17> @S9S_MB_2U_LIB.S9S_MB_2U(SCH_1):M_E_CPU0_SA_DQ(17)    I13 @S9S_MB_2U_LIB.S9S_MB_2U(SCH_1):PAGE91
   174 M_E_CPU0_SA_DQ<18> @S9S_MB_2U_LIB.S9S_MB_2U(SCH_1):M_E_CPU0_SA_DQ(18)    I13 @S9S_MB_2U_LIB.S9S_MB_2U(SCH_1):PAGE91
   176 M_E_CPU0_SA_DQ<19> @S9S_MB_2U_LIB.S9S_MB_2U(SCH_1):M_E_CPU0_SA_DQ(19)    I13 @S9S_MB_2U_LIB.S9S_MB_2U(SCH_1):PAGE91
    36 M_E_CPU0_SA_DQ<20> @S9S_MB_2U_LIB.S9S_MB_2U(SCH_1):M_E_CPU0_SA_DQ(20)    I13 @S9S_MB_2U_LIB.S9S_MB_2U(SCH_1):PAGE91
    38 M_E_CPU0_SA_DQ<21> @S9S_MB_2U_LIB.S9S_MB_2U(SCH_1):M_E_CPU0_SA_DQ(21)    I13 @S9S_MB_2U_LIB.S9S_MB_2U(SCH_1):PAGE91
   181 M_E_CPU0_SA_DQ<22> @S9S_MB_2U_LIB.S9S_MB_2U(SCH_1):M_E_CPU0_SA_DQ(22)    I13 @S9S_MB_2U_LIB.S9S_MB_2U(SCH_1):PAGE91
   183 M_E_CPU0_SA_DQ<23> @S9S_MB_2U_LIB.S9S_MB_2U(SCH_1):M_E_CPU0_SA_DQ(23)    I13 @S9S_MB_2U_LIB.S9S_MB_2U(SCH_1):PAGE91
    40 M_E_CPU0_SA_DQ<24> @S9S_MB_2U_LIB.S9S_MB_2U(SCH_1):M_E_CPU0_SA_DQ(24)    I13 @S9S_MB_2U_LIB.S9S_MB_2U(SCH_1):PAGE91
    42 M_E_CPU0_SA_DQ<25> @S9S_MB_2U_LIB.S9S_MB_2U(SCH_1):M_E_CPU0_SA_DQ(25)    I13 @S9S_MB_2U_LIB.S9S_MB_2U(SCH_1):PAGE91
   185 M_E_CPU0_SA_DQ<26> @S9S_MB_2U_LIB.S9S_MB_2U(SCH_1):M_E_CPU0_SA_DQ(26)    I13 @S9S_MB_2U_LIB.S9S_MB_2U(SCH_1):PAGE91
   187 M_E_CPU0_SA_DQ<27> @S9S_MB_2U_LIB.S9S_MB_2U(SCH_1):M_E_CPU0_SA_DQ(27)    I13 @S9S_MB_2U_LIB.S9S_MB_2U(SCH_1):PAGE91
    47 M_E_CPU0_SA_DQ<28> @S9S_MB_2U_LIB.S9S_MB_2U(SCH_1):M_E_CPU0_SA_DQ(28)    I13 @S9S_MB_2U_LIB.S9S_MB_2U(SCH_1):PAGE91
    49 M_E_CPU0_SA_DQ<29> @S9S_MB_2U_LIB.S9S_MB_2U(SCH_1):M_E_CPU0_SA_DQ(29)    I13 @S9S_MB_2U_LIB.S9S_MB_2U(SCH_1):PAGE91
   192 M_E_CPU0_SA_DQ<30> @S9S_MB_2U_LIB.S9S_MB_2U(SCH_1):M_E_CPU0_SA_DQ(30)    I13 @S9S_MB_2U_LIB.S9S_MB_2U(SCH_1):PAGE91
   229 M_E_CPU0_SB_CS_N<3> @S9S_MB_2U_LIB.S9S_MB_2U(SCH_1):M_E_CPU0_SB_CS_N(3)    I13 @S9S_MB_2U_LIB.S9S_MB_2U(SCH_1):PAGE91
   209 M_E_CPU0_SA_CS_N<3> @S9S_MB_2U_LIB.S9S_MB_2U(SCH_1):M_E_CPU0_SA_CS_N(3)    I13 @S9S_MB_2U_LIB.S9S_MB_2U(SCH_1):PAGE91
    84 M_E_CPU0_SB_CS_N<2> @S9S_MB_2U_LIB.S9S_MB_2U(SCH_1):M_E_CPU0_SB_CS_N(2)    I13 @S9S_MB_2U_LIB.S9S_MB_2U(SCH_1):PAGE91
    64 M_E_CPU0_SA_CS_N<2> @S9S_MB_2U_LIB.S9S_MB_2U(SCH_1):M_E_CPU0_SA_CS_N(2)    I13 @S9S_MB_2U_LIB.S9S_MB_2U(SCH_1):PAGE91
   217 M_E_CPU0_CLK_DP<1> @S9S_MB_2U_LIB.S9S_MB_2U(SCH_1):M_E_CPU0_CLK_DP(1)    I13 @S9S_MB_2U_LIB.S9S_MB_2U(SCH_1):PAGE91
   218 M_E_CPU0_CLK_DN<1> @S9S_MB_2U_LIB.S9S_MB_2U(SCH_1):M_E_CPU0_CLK_DN(1)    I13 @S9S_MB_2U_LIB.S9S_MB_2U(SCH_1):PAGE91
    96 M_E_CPU0_SB_CB<0> @S9S_MB_2U_LIB.S9S_MB_2U(SCH_1):M_E_CPU0_SB_CB(0)    I13 @S9S_MB_2U_LIB.S9S_MB_2U(SCH_1):PAGE91
    98 M_E_CPU0_SB_CB<1> @S9S_MB_2U_LIB.S9S_MB_2U(SCH_1):M_E_CPU0_SB_CB(1)    I13 @S9S_MB_2U_LIB.S9S_MB_2U(SCH_1):PAGE91
   241 M_E_CPU0_SB_CB<2> @S9S_MB_2U_LIB.S9S_MB_2U(SCH_1):M_E_CPU0_SB_CB(2)    I13 @S9S_MB_2U_LIB.S9S_MB_2U(SCH_1):PAGE91
   243 M_E_CPU0_SB_CB<3> @S9S_MB_2U_LIB.S9S_MB_2U(SCH_1):M_E_CPU0_SB_CB(3)    I13 @S9S_MB_2U_LIB.S9S_MB_2U(SCH_1):PAGE91
    89 M_E_CPU0_SB_CB<4> @S9S_MB_2U_LIB.S9S_MB_2U(SCH_1):M_E_CPU0_SB_CB(4)    I13 @S9S_MB_2U_LIB.S9S_MB_2U(SCH_1):PAGE91
    91 M_E_CPU0_SB_CB<5> @S9S_MB_2U_LIB.S9S_MB_2U(SCH_1):M_E_CPU0_SB_CB(5)    I13 @S9S_MB_2U_LIB.S9S_MB_2U(SCH_1):PAGE91
   234 M_E_CPU0_SB_CB<6> @S9S_MB_2U_LIB.S9S_MB_2U(SCH_1):M_E_CPU0_SB_CB(6)    I13 @S9S_MB_2U_LIB.S9S_MB_2U(SCH_1):PAGE91
    51 M_E_CPU0_SA_CB<0> @S9S_MB_2U_LIB.S9S_MB_2U(SCH_1):M_E_CPU0_SA_CB(0)    I13 @S9S_MB_2U_LIB.S9S_MB_2U(SCH_1):PAGE91
   196 M_E_CPU0_SA_CB<2> @S9S_MB_2U_LIB.S9S_MB_2U(SCH_1):M_E_CPU0_SA_CB(2)    I13 @S9S_MB_2U_LIB.S9S_MB_2U(SCH_1):PAGE91
   198 M_E_CPU0_SA_CB<3> @S9S_MB_2U_LIB.S9S_MB_2U(SCH_1):M_E_CPU0_SA_CB(3)    I13 @S9S_MB_2U_LIB.S9S_MB_2U(SCH_1):PAGE91
    60 M_E_CPU0_SA_CB<5> @S9S_MB_2U_LIB.S9S_MB_2U(SCH_1):M_E_CPU0_SA_CB(5)    I13 @S9S_MB_2U_LIB.S9S_MB_2U(SCH_1):PAGE91
   203 M_E_CPU0_SA_CB<6> @S9S_MB_2U_LIB.S9S_MB_2U(SCH_1):M_E_CPU0_SA_CB(6)    I13 @S9S_MB_2U_LIB.S9S_MB_2U(SCH_1):PAGE91
    82 M_E_CPU0_SB_CA<6> @S9S_MB_2U_LIB.S9S_MB_2U(SCH_1):M_E_CPU0_SB_CA(6)    I13 @S9S_MB_2U_LIB.S9S_MB_2U(SCH_1):PAGE91
    72 M_E_CPU0_SA_CA<6> @S9S_MB_2U_LIB.S9S_MB_2U(SCH_1):M_E_CPU0_SA_CA(6)    I13 @S9S_MB_2U_LIB.S9S_MB_2U(SCH_1):PAGE91
   225 M_E_CPU0_SB_CA<5> @S9S_MB_2U_LIB.S9S_MB_2U(SCH_1):M_E_CPU0_SB_CA(5)    I13 @S9S_MB_2U_LIB.S9S_MB_2U(SCH_1):PAGE91
   215 M_E_CPU0_SA_CA<5> @S9S_MB_2U_LIB.S9S_MB_2U(SCH_1):M_E_CPU0_SA_CA(5)    I13 @S9S_MB_2U_LIB.S9S_MB_2U(SCH_1):PAGE91
    80 M_E_CPU0_SB_CA<4> @S9S_MB_2U_LIB.S9S_MB_2U(SCH_1):M_E_CPU0_SB_CA(4)    I13 @S9S_MB_2U_LIB.S9S_MB_2U(SCH_1):PAGE91
    70 M_E_CPU0_SA_CA<4> @S9S_MB_2U_LIB.S9S_MB_2U(SCH_1):M_E_CPU0_SA_CA(4)    I13 @S9S_MB_2U_LIB.S9S_MB_2U(SCH_1):PAGE91
   223 M_E_CPU0_SB_CA<3> @S9S_MB_2U_LIB.S9S_MB_2U(SCH_1):M_E_CPU0_SB_CA(3)    I13 @S9S_MB_2U_LIB.S9S_MB_2U(SCH_1):PAGE91
   213 M_E_CPU0_SA_CA<3> @S9S_MB_2U_LIB.S9S_MB_2U(SCH_1):M_E_CPU0_SA_CA(3)    I13 @S9S_MB_2U_LIB.S9S_MB_2U(SCH_1):PAGE91
    78 M_E_CPU0_SB_CA<2> @S9S_MB_2U_LIB.S9S_MB_2U(SCH_1):M_E_CPU0_SB_CA(2)    I13 @S9S_MB_2U_LIB.S9S_MB_2U(SCH_1):PAGE91
    68 M_E_CPU0_SA_CA<2> @S9S_MB_2U_LIB.S9S_MB_2U(SCH_1):M_E_CPU0_SA_CA(2)    I13 @S9S_MB_2U_LIB.S9S_MB_2U(SCH_1):PAGE91
   221 M_E_CPU0_SB_CA<1> @S9S_MB_2U_LIB.S9S_MB_2U(SCH_1):M_E_CPU0_SB_CA(1)    I13 @S9S_MB_2U_LIB.S9S_MB_2U(SCH_1):PAGE91
   211 M_E_CPU0_SA_CA<1> @S9S_MB_2U_LIB.S9S_MB_2U(SCH_1):M_E_CPU0_SA_CA(1)    I13 @S9S_MB_2U_LIB.S9S_MB_2U(SCH_1):PAGE91
    76 M_E_CPU0_SB_CA<0> @S9S_MB_2U_LIB.S9S_MB_2U(SCH_1):M_E_CPU0_SB_CA(0)    I13 @S9S_MB_2U_LIB.S9S_MB_2U(SCH_1):PAGE91
    66 M_E_CPU0_SA_CA<0> @S9S_MB_2U_LIB.S9S_MB_2U(SCH_1):M_E_CPU0_SA_CA(0)    I13 @S9S_MB_2U_LIB.S9S_MB_2U(SCH_1):PAGE91
    62 M_E_CPU0_ALERT_N @S9S_MB_2U_LIB.S9S_MB_2U(SCH_1):M_E_CPU0_ALERT_N    I13 @S9S_MB_2U_LIB.S9S_MB_2U(SCH_1):PAGE91
   236 M_E_CPU0_SB_CB<7> @S9S_MB_2U_LIB.S9S_MB_2U(SCH_1):M_E_CPU0_SB_CB(7)    I13 @S9S_MB_2U_LIB.S9S_MB_2U(SCH_1):PAGE91
    53 M_E_CPU0_SA_CB<1> @S9S_MB_2U_LIB.S9S_MB_2U(SCH_1):M_E_CPU0_SA_CB(1)    I13 @S9S_MB_2U_LIB.S9S_MB_2U(SCH_1):PAGE91
    58 M_E_CPU0_SA_CB<4> @S9S_MB_2U_LIB.S9S_MB_2U(SCH_1):M_E_CPU0_SA_CB(4)    I13 @S9S_MB_2U_LIB.S9S_MB_2U(SCH_1):PAGE91
   205 M_E_CPU0_SA_CB<7> @S9S_MB_2U_LIB.S9S_MB_2U(SCH_1):M_E_CPU0_SA_CB(7)    I13 @S9S_MB_2U_LIB.S9S_MB_2U(SCH_1):PAGE91
   194 M_E_CPU0_SA_DQ<31> @S9S_MB_2U_LIB.S9S_MB_2U(SCH_1):M_E_CPU0_SA_DQ(31)    I13 @S9S_MB_2U_LIB.S9S_MB_2U(SCH_1):PAGE91
    93 M_E_CPU0_SB_DQS_DP<9> @S9S_MB_2U_LIB.S9S_MB_2U(SCH_1):M_E_CPU0_SB_DQS_DP(9)   I178 @S9S_MB_2U_LIB.S9S_MB_2U(SCH_1):PAGE91
    94 M_E_CPU0_SB_DQS_DN<9> @S9S_MB_2U_LIB.S9S_MB_2U(SCH_1):M_E_CPU0_SB_DQS_DN(9)   I178 @S9S_MB_2U_LIB.S9S_MB_2U(SCH_1):PAGE91
   201 M_E_CPU0_SA_DQS_DP<9> @S9S_MB_2U_LIB.S9S_MB_2U(SCH_1):M_E_CPU0_SA_DQS_DP(9)   I178 @S9S_MB_2U_LIB.S9S_MB_2U(SCH_1):PAGE91
   200 M_E_CPU0_SA_DQS_DN<9> @S9S_MB_2U_LIB.S9S_MB_2U(SCH_1):M_E_CPU0_SA_DQS_DN(9)   I178 @S9S_MB_2U_LIB.S9S_MB_2U(SCH_1):PAGE91
   190 M_E_CPU0_SA_DQS_DP<8> @S9S_MB_2U_LIB.S9S_MB_2U(SCH_1):M_E_CPU0_SA_DQS_DP(8)   I178 @S9S_MB_2U_LIB.S9S_MB_2U(SCH_1):PAGE91
   189 M_E_CPU0_SA_DQS_DN<8> @S9S_MB_2U_LIB.S9S_MB_2U(SCH_1):M_E_CPU0_SA_DQS_DN(8)   I178 @S9S_MB_2U_LIB.S9S_MB_2U(SCH_1):PAGE91
   271 M_E_CPU0_SB_DQS_DN<7> @S9S_MB_2U_LIB.S9S_MB_2U(SCH_1):M_E_CPU0_SB_DQS_DN(7)   I178 @S9S_MB_2U_LIB.S9S_MB_2U(SCH_1):PAGE91
   179 M_E_CPU0_SA_DQS_DP<7> @S9S_MB_2U_LIB.S9S_MB_2U(SCH_1):M_E_CPU0_SA_DQS_DP(7)   I178 @S9S_MB_2U_LIB.S9S_MB_2U(SCH_1):PAGE91
   261 M_E_CPU0_SB_DQS_DP<6> @S9S_MB_2U_LIB.S9S_MB_2U(SCH_1):M_E_CPU0_SB_DQS_DP(6)   I178 @S9S_MB_2U_LIB.S9S_MB_2U(SCH_1):PAGE91
   260 M_E_CPU0_SB_DQS_DN<6> @S9S_MB_2U_LIB.S9S_MB_2U(SCH_1):M_E_CPU0_SB_DQS_DN(6)   I178 @S9S_MB_2U_LIB.S9S_MB_2U(SCH_1):PAGE91
   167 M_E_CPU0_SA_DQS_DN<6> @S9S_MB_2U_LIB.S9S_MB_2U(SCH_1):M_E_CPU0_SA_DQS_DN(6)   I178 @S9S_MB_2U_LIB.S9S_MB_2U(SCH_1):PAGE91
   250 M_E_CPU0_SB_DQS_DP<5> @S9S_MB_2U_LIB.S9S_MB_2U(SCH_1):M_E_CPU0_SB_DQS_DP(5)   I178 @S9S_MB_2U_LIB.S9S_MB_2U(SCH_1):PAGE91
   249 M_E_CPU0_SB_DQS_DN<5> @S9S_MB_2U_LIB.S9S_MB_2U(SCH_1):M_E_CPU0_SB_DQS_DN(5)   I178 @S9S_MB_2U_LIB.S9S_MB_2U(SCH_1):PAGE91
   157 M_E_CPU0_SA_DQS_DP<5> @S9S_MB_2U_LIB.S9S_MB_2U(SCH_1):M_E_CPU0_SA_DQS_DP(5)   I178 @S9S_MB_2U_LIB.S9S_MB_2U(SCH_1):PAGE91
   156 M_E_CPU0_SA_DQS_DN<5> @S9S_MB_2U_LIB.S9S_MB_2U(SCH_1):M_E_CPU0_SA_DQS_DN(5)   I178 @S9S_MB_2U_LIB.S9S_MB_2U(SCH_1):PAGE91
   239 M_E_CPU0_SB_DQS_DP<4> @S9S_MB_2U_LIB.S9S_MB_2U(SCH_1):M_E_CPU0_SB_DQS_DP(4)   I178 @S9S_MB_2U_LIB.S9S_MB_2U(SCH_1):PAGE91
   238 M_E_CPU0_SB_DQS_DN<4> @S9S_MB_2U_LIB.S9S_MB_2U(SCH_1):M_E_CPU0_SB_DQS_DN(4)   I178 @S9S_MB_2U_LIB.S9S_MB_2U(SCH_1):PAGE91
    55 M_E_CPU0_SA_DQS_DP<4> @S9S_MB_2U_LIB.S9S_MB_2U(SCH_1):M_E_CPU0_SA_DQS_DP(4)   I178 @S9S_MB_2U_LIB.S9S_MB_2U(SCH_1):PAGE91
    56 M_E_CPU0_SA_DQS_DN<4> @S9S_MB_2U_LIB.S9S_MB_2U(SCH_1):M_E_CPU0_SA_DQS_DN(4)   I178 @S9S_MB_2U_LIB.S9S_MB_2U(SCH_1):PAGE91
   137 M_E_CPU0_SB_DQS_DP<3> @S9S_MB_2U_LIB.S9S_MB_2U(SCH_1):M_E_CPU0_SB_DQS_DP(3)   I178 @S9S_MB_2U_LIB.S9S_MB_2U(SCH_1):PAGE91
   138 M_E_CPU0_SB_DQS_DN<3> @S9S_MB_2U_LIB.S9S_MB_2U(SCH_1):M_E_CPU0_SB_DQS_DN(3)   I178 @S9S_MB_2U_LIB.S9S_MB_2U(SCH_1):PAGE91
    44 M_E_CPU0_SA_DQS_DP<3> @S9S_MB_2U_LIB.S9S_MB_2U(SCH_1):M_E_CPU0_SA_DQS_DP(3)   I178 @S9S_MB_2U_LIB.S9S_MB_2U(SCH_1):PAGE91
    45 M_E_CPU0_SA_DQS_DN<3> @S9S_MB_2U_LIB.S9S_MB_2U(SCH_1):M_E_CPU0_SA_DQS_DN(3)   I178 @S9S_MB_2U_LIB.S9S_MB_2U(SCH_1):PAGE91
   126 M_E_CPU0_SB_DQS_DP<2> @S9S_MB_2U_LIB.S9S_MB_2U(SCH_1):M_E_CPU0_SB_DQS_DP(2)   I178 @S9S_MB_2U_LIB.S9S_MB_2U(SCH_1):PAGE91
   127 M_E_CPU0_SB_DQS_DN<2> @S9S_MB_2U_LIB.S9S_MB_2U(SCH_1):M_E_CPU0_SB_DQS_DN(2)   I178 @S9S_MB_2U_LIB.S9S_MB_2U(SCH_1):PAGE91
    33 M_E_CPU0_SA_DQS_DP<2> @S9S_MB_2U_LIB.S9S_MB_2U(SCH_1):M_E_CPU0_SA_DQS_DP(2)   I178 @S9S_MB_2U_LIB.S9S_MB_2U(SCH_1):PAGE91
    34 M_E_CPU0_SA_DQS_DN<2> @S9S_MB_2U_LIB.S9S_MB_2U(SCH_1):M_E_CPU0_SA_DQS_DN(2)   I178 @S9S_MB_2U_LIB.S9S_MB_2U(SCH_1):PAGE91
   115 M_E_CPU0_SB_DQS_DP<1> @S9S_MB_2U_LIB.S9S_MB_2U(SCH_1):M_E_CPU0_SB_DQS_DP(1)   I178 @S9S_MB_2U_LIB.S9S_MB_2U(SCH_1):PAGE91
   116 M_E_CPU0_SB_DQS_DN<1> @S9S_MB_2U_LIB.S9S_MB_2U(SCH_1):M_E_CPU0_SB_DQS_DN(1)   I178 @S9S_MB_2U_LIB.S9S_MB_2U(SCH_1):PAGE91
    22 M_E_CPU0_SA_DQS_DP<1> @S9S_MB_2U_LIB.S9S_MB_2U(SCH_1):M_E_CPU0_SA_DQS_DP(1)   I178 @S9S_MB_2U_LIB.S9S_MB_2U(SCH_1):PAGE91
    23 M_E_CPU0_SA_DQS_DN<1> @S9S_MB_2U_LIB.S9S_MB_2U(SCH_1):M_E_CPU0_SA_DQS_DN(1)   I178 @S9S_MB_2U_LIB.S9S_MB_2U(SCH_1):PAGE91
   104 M_E_CPU0_SB_DQS_DP<0> @S9S_MB_2U_LIB.S9S_MB_2U(SCH_1):M_E_CPU0_SB_DQS_DP(0)   I178 @S9S_MB_2U_LIB.S9S_MB_2U(SCH_1):PAGE91
   105 M_E_CPU0_SB_DQS_DN<0> @S9S_MB_2U_LIB.S9S_MB_2U(SCH_1):M_E_CPU0_SB_DQS_DN(0)   I178 @S9S_MB_2U_LIB.S9S_MB_2U(SCH_1):PAGE91
    11 M_E_CPU0_SA_DQS_DP<0> @S9S_MB_2U_LIB.S9S_MB_2U(SCH_1):M_E_CPU0_SA_DQS_DP(0)   I178 @S9S_MB_2U_LIB.S9S_MB_2U(SCH_1):PAGE91
    12 M_E_CPU0_SA_DQS_DN<0> @S9S_MB_2U_LIB.S9S_MB_2U(SCH_1):M_E_CPU0_SA_DQS_DN(0)   I178 @S9S_MB_2U_LIB.S9S_MB_2U(SCH_1):PAGE91
   272 M_E_CPU0_SB_DQS_DP<7> @S9S_MB_2U_LIB.S9S_MB_2U(SCH_1):M_E_CPU0_SB_DQS_DP(7)   I178 @S9S_MB_2U_LIB.S9S_MB_2U(SCH_1):PAGE91
   282 M_E_CPU0_SB_DQS_DN<8> @S9S_MB_2U_LIB.S9S_MB_2U(SCH_1):M_E_CPU0_SB_DQS_DN(8)   I178 @S9S_MB_2U_LIB.S9S_MB_2U(SCH_1):PAGE91
   283 M_E_CPU0_SB_DQS_DP<8> @S9S_MB_2U_LIB.S9S_MB_2U(SCH_1):M_E_CPU0_SB_DQS_DP(8)   I178 @S9S_MB_2U_LIB.S9S_MB_2U(SCH_1):PAGE91
   168 M_E_CPU0_SA_DQS_DP<6> @S9S_MB_2U_LIB.S9S_MB_2U(SCH_1):M_E_CPU0_SA_DQS_DP(6)   I178 @S9S_MB_2U_LIB.S9S_MB_2U(SCH_1):PAGE91
   178 M_E_CPU0_SA_DQS_DN<7> @S9S_MB_2U_LIB.S9S_MB_2U(SCH_1):M_E_CPU0_SA_DQS_DN(7)   I178 @S9S_MB_2U_LIB.S9S_MB_2U(SCH_1):PAGE91
     6    GND @S9S_MB_2U_LIB.S9S_MB_2U(SCH_1):GND   I148 @S9S_MB_2U_LIB.S9S_MB_2U(SCH_1):PAGE91
     8    GND @S9S_MB_2U_LIB.S9S_MB_2U(SCH_1):GND   I148 @S9S_MB_2U_LIB.S9S_MB_2U(SCH_1):PAGE91
    10    GND @S9S_MB_2U_LIB.S9S_MB_2U(SCH_1):GND   I148 @S9S_MB_2U_LIB.S9S_MB_2U(SCH_1):PAGE91
    13    GND @S9S_MB_2U_LIB.S9S_MB_2U(SCH_1):GND   I148 @S9S_MB_2U_LIB.S9S_MB_2U(SCH_1):PAGE91
    15    GND @S9S_MB_2U_LIB.S9S_MB_2U(SCH_1):GND   I148 @S9S_MB_2U_LIB.S9S_MB_2U(SCH_1):PAGE91
    17    GND @S9S_MB_2U_LIB.S9S_MB_2U(SCH_1):GND   I148 @S9S_MB_2U_LIB.S9S_MB_2U(SCH_1):PAGE91
    19    GND @S9S_MB_2U_LIB.S9S_MB_2U(SCH_1):GND   I148 @S9S_MB_2U_LIB.S9S_MB_2U(SCH_1):PAGE91
    21    GND @S9S_MB_2U_LIB.S9S_MB_2U(SCH_1):GND   I148 @S9S_MB_2U_LIB.S9S_MB_2U(SCH_1):PAGE91
    24    GND @S9S_MB_2U_LIB.S9S_MB_2U(SCH_1):GND   I148 @S9S_MB_2U_LIB.S9S_MB_2U(SCH_1):PAGE91
    26    GND @S9S_MB_2U_LIB.S9S_MB_2U(SCH_1):GND   I148 @S9S_MB_2U_LIB.S9S_MB_2U(SCH_1):PAGE91
    28    GND @S9S_MB_2U_LIB.S9S_MB_2U(SCH_1):GND   I148 @S9S_MB_2U_LIB.S9S_MB_2U(SCH_1):PAGE91
    30    GND @S9S_MB_2U_LIB.S9S_MB_2U(SCH_1):GND   I148 @S9S_MB_2U_LIB.S9S_MB_2U(SCH_1):PAGE91
    32    GND @S9S_MB_2U_LIB.S9S_MB_2U(SCH_1):GND   I148 @S9S_MB_2U_LIB.S9S_MB_2U(SCH_1):PAGE91
    35    GND @S9S_MB_2U_LIB.S9S_MB_2U(SCH_1):GND   I148 @S9S_MB_2U_LIB.S9S_MB_2U(SCH_1):PAGE91
    37    GND @S9S_MB_2U_LIB.S9S_MB_2U(SCH_1):GND   I148 @S9S_MB_2U_LIB.S9S_MB_2U(SCH_1):PAGE91
    39    GND @S9S_MB_2U_LIB.S9S_MB_2U(SCH_1):GND   I148 @S9S_MB_2U_LIB.S9S_MB_2U(SCH_1):PAGE91
    41    GND @S9S_MB_2U_LIB.S9S_MB_2U(SCH_1):GND   I148 @S9S_MB_2U_LIB.S9S_MB_2U(SCH_1):PAGE91
    43    GND @S9S_MB_2U_LIB.S9S_MB_2U(SCH_1):GND   I148 @S9S_MB_2U_LIB.S9S_MB_2U(SCH_1):PAGE91
    46    GND @S9S_MB_2U_LIB.S9S_MB_2U(SCH_1):GND   I148 @S9S_MB_2U_LIB.S9S_MB_2U(SCH_1):PAGE91
    48    GND @S9S_MB_2U_LIB.S9S_MB_2U(SCH_1):GND   I148 @S9S_MB_2U_LIB.S9S_MB_2U(SCH_1):PAGE91
    50    GND @S9S_MB_2U_LIB.S9S_MB_2U(SCH_1):GND   I148 @S9S_MB_2U_LIB.S9S_MB_2U(SCH_1):PAGE91
    52    GND @S9S_MB_2U_LIB.S9S_MB_2U(SCH_1):GND   I148 @S9S_MB_2U_LIB.S9S_MB_2U(SCH_1):PAGE91
    54    GND @S9S_MB_2U_LIB.S9S_MB_2U(SCH_1):GND   I148 @S9S_MB_2U_LIB.S9S_MB_2U(SCH_1):PAGE91
    57    GND @S9S_MB_2U_LIB.S9S_MB_2U(SCH_1):GND   I148 @S9S_MB_2U_LIB.S9S_MB_2U(SCH_1):PAGE91
    59    GND @S9S_MB_2U_LIB.S9S_MB_2U(SCH_1):GND   I148 @S9S_MB_2U_LIB.S9S_MB_2U(SCH_1):PAGE91
    61    GND @S9S_MB_2U_LIB.S9S_MB_2U(SCH_1):GND   I148 @S9S_MB_2U_LIB.S9S_MB_2U(SCH_1):PAGE91
    63    GND @S9S_MB_2U_LIB.S9S_MB_2U(SCH_1):GND   I148 @S9S_MB_2U_LIB.S9S_MB_2U(SCH_1):PAGE91
    65    GND @S9S_MB_2U_LIB.S9S_MB_2U(SCH_1):GND   I148 @S9S_MB_2U_LIB.S9S_MB_2U(SCH_1):PAGE91
    67    GND @S9S_MB_2U_LIB.S9S_MB_2U(SCH_1):GND   I148 @S9S_MB_2U_LIB.S9S_MB_2U(SCH_1):PAGE91
    69    GND @S9S_MB_2U_LIB.S9S_MB_2U(SCH_1):GND   I148 @S9S_MB_2U_LIB.S9S_MB_2U(SCH_1):PAGE91
    71    GND @S9S_MB_2U_LIB.S9S_MB_2U(SCH_1):GND   I148 @S9S_MB_2U_LIB.S9S_MB_2U(SCH_1):PAGE91
    73    GND @S9S_MB_2U_LIB.S9S_MB_2U(SCH_1):GND   I148 @S9S_MB_2U_LIB.S9S_MB_2U(SCH_1):PAGE91
    75    GND @S9S_MB_2U_LIB.S9S_MB_2U(SCH_1):GND   I148 @S9S_MB_2U_LIB.S9S_MB_2U(SCH_1):PAGE91
    77    GND @S9S_MB_2U_LIB.S9S_MB_2U(SCH_1):GND   I148 @S9S_MB_2U_LIB.S9S_MB_2U(SCH_1):PAGE91
    79    GND @S9S_MB_2U_LIB.S9S_MB_2U(SCH_1):GND   I148 @S9S_MB_2U_LIB.S9S_MB_2U(SCH_1):PAGE91
    81    GND @S9S_MB_2U_LIB.S9S_MB_2U(SCH_1):GND   I148 @S9S_MB_2U_LIB.S9S_MB_2U(SCH_1):PAGE91
    83    GND @S9S_MB_2U_LIB.S9S_MB_2U(SCH_1):GND   I148 @S9S_MB_2U_LIB.S9S_MB_2U(SCH_1):PAGE91
    85    GND @S9S_MB_2U_LIB.S9S_MB_2U(SCH_1):GND   I148 @S9S_MB_2U_LIB.S9S_MB_2U(SCH_1):PAGE91
    88    GND @S9S_MB_2U_LIB.S9S_MB_2U(SCH_1):GND   I148 @S9S_MB_2U_LIB.S9S_MB_2U(SCH_1):PAGE91
    90    GND @S9S_MB_2U_LIB.S9S_MB_2U(SCH_1):GND   I148 @S9S_MB_2U_LIB.S9S_MB_2U(SCH_1):PAGE91
    92    GND @S9S_MB_2U_LIB.S9S_MB_2U(SCH_1):GND   I148 @S9S_MB_2U_LIB.S9S_MB_2U(SCH_1):PAGE91
    95    GND @S9S_MB_2U_LIB.S9S_MB_2U(SCH_1):GND   I148 @S9S_MB_2U_LIB.S9S_MB_2U(SCH_1):PAGE91
    97    GND @S9S_MB_2U_LIB.S9S_MB_2U(SCH_1):GND   I148 @S9S_MB_2U_LIB.S9S_MB_2U(SCH_1):PAGE91
    99    GND @S9S_MB_2U_LIB.S9S_MB_2U(SCH_1):GND   I148 @S9S_MB_2U_LIB.S9S_MB_2U(SCH_1):PAGE91
   101    GND @S9S_MB_2U_LIB.S9S_MB_2U(SCH_1):GND   I148 @S9S_MB_2U_LIB.S9S_MB_2U(SCH_1):PAGE91
   103    GND @S9S_MB_2U_LIB.S9S_MB_2U(SCH_1):GND   I148 @S9S_MB_2U_LIB.S9S_MB_2U(SCH_1):PAGE91
   106    GND @S9S_MB_2U_LIB.S9S_MB_2U(SCH_1):GND   I148 @S9S_MB_2U_LIB.S9S_MB_2U(SCH_1):PAGE91
   108    GND @S9S_MB_2U_LIB.S9S_MB_2U(SCH_1):GND   I148 @S9S_MB_2U_LIB.S9S_MB_2U(SCH_1):PAGE91
   110    GND @S9S_MB_2U_LIB.S9S_MB_2U(SCH_1):GND   I148 @S9S_MB_2U_LIB.S9S_MB_2U(SCH_1):PAGE91
   112    GND @S9S_MB_2U_LIB.S9S_MB_2U(SCH_1):GND   I148 @S9S_MB_2U_LIB.S9S_MB_2U(SCH_1):PAGE91
   114    GND @S9S_MB_2U_LIB.S9S_MB_2U(SCH_1):GND   I148 @S9S_MB_2U_LIB.S9S_MB_2U(SCH_1):PAGE91
   117    GND @S9S_MB_2U_LIB.S9S_MB_2U(SCH_1):GND   I148 @S9S_MB_2U_LIB.S9S_MB_2U(SCH_1):PAGE91
   119    GND @S9S_MB_2U_LIB.S9S_MB_2U(SCH_1):GND   I148 @S9S_MB_2U_LIB.S9S_MB_2U(SCH_1):PAGE91
   121    GND @S9S_MB_2U_LIB.S9S_MB_2U(SCH_1):GND   I148 @S9S_MB_2U_LIB.S9S_MB_2U(SCH_1):PAGE91
   123    GND @S9S_MB_2U_LIB.S9S_MB_2U(SCH_1):GND   I148 @S9S_MB_2U_LIB.S9S_MB_2U(SCH_1):PAGE91
   125    GND @S9S_MB_2U_LIB.S9S_MB_2U(SCH_1):GND   I148 @S9S_MB_2U_LIB.S9S_MB_2U(SCH_1):PAGE91
   128    GND @S9S_MB_2U_LIB.S9S_MB_2U(SCH_1):GND   I148 @S9S_MB_2U_LIB.S9S_MB_2U(SCH_1):PAGE91
   130    GND @S9S_MB_2U_LIB.S9S_MB_2U(SCH_1):GND   I148 @S9S_MB_2U_LIB.S9S_MB_2U(SCH_1):PAGE91
   134    GND @S9S_MB_2U_LIB.S9S_MB_2U(SCH_1):GND   I148 @S9S_MB_2U_LIB.S9S_MB_2U(SCH_1):PAGE91
   143    GND @S9S_MB_2U_LIB.S9S_MB_2U(SCH_1):GND   I148 @S9S_MB_2U_LIB.S9S_MB_2U(SCH_1):PAGE91
   151    GND @S9S_MB_2U_LIB.S9S_MB_2U(SCH_1):GND   I148 @S9S_MB_2U_LIB.S9S_MB_2U(SCH_1):PAGE91
   153    GND @S9S_MB_2U_LIB.S9S_MB_2U(SCH_1):GND   I148 @S9S_MB_2U_LIB.S9S_MB_2U(SCH_1):PAGE91
   155    GND @S9S_MB_2U_LIB.S9S_MB_2U(SCH_1):GND   I148 @S9S_MB_2U_LIB.S9S_MB_2U(SCH_1):PAGE91
   158    GND @S9S_MB_2U_LIB.S9S_MB_2U(SCH_1):GND   I148 @S9S_MB_2U_LIB.S9S_MB_2U(SCH_1):PAGE91
   160    GND @S9S_MB_2U_LIB.S9S_MB_2U(SCH_1):GND   I148 @S9S_MB_2U_LIB.S9S_MB_2U(SCH_1):PAGE91
   162    GND @S9S_MB_2U_LIB.S9S_MB_2U(SCH_1):GND   I148 @S9S_MB_2U_LIB.S9S_MB_2U(SCH_1):PAGE91
   164    GND @S9S_MB_2U_LIB.S9S_MB_2U(SCH_1):GND   I148 @S9S_MB_2U_LIB.S9S_MB_2U(SCH_1):PAGE91
   166    GND @S9S_MB_2U_LIB.S9S_MB_2U(SCH_1):GND   I148 @S9S_MB_2U_LIB.S9S_MB_2U(SCH_1):PAGE91
   169    GND @S9S_MB_2U_LIB.S9S_MB_2U(SCH_1):GND   I148 @S9S_MB_2U_LIB.S9S_MB_2U(SCH_1):PAGE91
   171    GND @S9S_MB_2U_LIB.S9S_MB_2U(SCH_1):GND   I148 @S9S_MB_2U_LIB.S9S_MB_2U(SCH_1):PAGE91
   173    GND @S9S_MB_2U_LIB.S9S_MB_2U(SCH_1):GND   I148 @S9S_MB_2U_LIB.S9S_MB_2U(SCH_1):PAGE91
   175    GND @S9S_MB_2U_LIB.S9S_MB_2U(SCH_1):GND   I148 @S9S_MB_2U_LIB.S9S_MB_2U(SCH_1):PAGE91
   177    GND @S9S_MB_2U_LIB.S9S_MB_2U(SCH_1):GND   I148 @S9S_MB_2U_LIB.S9S_MB_2U(SCH_1):PAGE91
   180    GND @S9S_MB_2U_LIB.S9S_MB_2U(SCH_1):GND   I148 @S9S_MB_2U_LIB.S9S_MB_2U(SCH_1):PAGE91
   182    GND @S9S_MB_2U_LIB.S9S_MB_2U(SCH_1):GND   I148 @S9S_MB_2U_LIB.S9S_MB_2U(SCH_1):PAGE91
   184    GND @S9S_MB_2U_LIB.S9S_MB_2U(SCH_1):GND   I148 @S9S_MB_2U_LIB.S9S_MB_2U(SCH_1):PAGE91
   186    GND @S9S_MB_2U_LIB.S9S_MB_2U(SCH_1):GND   I148 @S9S_MB_2U_LIB.S9S_MB_2U(SCH_1):PAGE91
   188    GND @S9S_MB_2U_LIB.S9S_MB_2U(SCH_1):GND   I148 @S9S_MB_2U_LIB.S9S_MB_2U(SCH_1):PAGE91
   191    GND @S9S_MB_2U_LIB.S9S_MB_2U(SCH_1):GND   I148 @S9S_MB_2U_LIB.S9S_MB_2U(SCH_1):PAGE91
   193    GND @S9S_MB_2U_LIB.S9S_MB_2U(SCH_1):GND   I148 @S9S_MB_2U_LIB.S9S_MB_2U(SCH_1):PAGE91
   195    GND @S9S_MB_2U_LIB.S9S_MB_2U(SCH_1):GND   I148 @S9S_MB_2U_LIB.S9S_MB_2U(SCH_1):PAGE91
   197    GND @S9S_MB_2U_LIB.S9S_MB_2U(SCH_1):GND   I148 @S9S_MB_2U_LIB.S9S_MB_2U(SCH_1):PAGE91
   199    GND @S9S_MB_2U_LIB.S9S_MB_2U(SCH_1):GND   I148 @S9S_MB_2U_LIB.S9S_MB_2U(SCH_1):PAGE91
   202    GND @S9S_MB_2U_LIB.S9S_MB_2U(SCH_1):GND   I148 @S9S_MB_2U_LIB.S9S_MB_2U(SCH_1):PAGE91
   204    GND @S9S_MB_2U_LIB.S9S_MB_2U(SCH_1):GND   I148 @S9S_MB_2U_LIB.S9S_MB_2U(SCH_1):PAGE91
   206    GND @S9S_MB_2U_LIB.S9S_MB_2U(SCH_1):GND   I148 @S9S_MB_2U_LIB.S9S_MB_2U(SCH_1):PAGE91
   208    GND @S9S_MB_2U_LIB.S9S_MB_2U(SCH_1):GND   I148 @S9S_MB_2U_LIB.S9S_MB_2U(SCH_1):PAGE91
   210    GND @S9S_MB_2U_LIB.S9S_MB_2U(SCH_1):GND   I148 @S9S_MB_2U_LIB.S9S_MB_2U(SCH_1):PAGE91
   212    GND @S9S_MB_2U_LIB.S9S_MB_2U(SCH_1):GND   I148 @S9S_MB_2U_LIB.S9S_MB_2U(SCH_1):PAGE91
   214    GND @S9S_MB_2U_LIB.S9S_MB_2U(SCH_1):GND   I148 @S9S_MB_2U_LIB.S9S_MB_2U(SCH_1):PAGE91
   216    GND @S9S_MB_2U_LIB.S9S_MB_2U(SCH_1):GND   I148 @S9S_MB_2U_LIB.S9S_MB_2U(SCH_1):PAGE91
   219    GND @S9S_MB_2U_LIB.S9S_MB_2U(SCH_1):GND   I148 @S9S_MB_2U_LIB.S9S_MB_2U(SCH_1):PAGE91
   222    GND @S9S_MB_2U_LIB.S9S_MB_2U(SCH_1):GND   I148 @S9S_MB_2U_LIB.S9S_MB_2U(SCH_1):PAGE91
   224    GND @S9S_MB_2U_LIB.S9S_MB_2U(SCH_1):GND   I148 @S9S_MB_2U_LIB.S9S_MB_2U(SCH_1):PAGE91
   226    GND @S9S_MB_2U_LIB.S9S_MB_2U(SCH_1):GND   I148 @S9S_MB_2U_LIB.S9S_MB_2U(SCH_1):PAGE91
   228    GND @S9S_MB_2U_LIB.S9S_MB_2U(SCH_1):GND   I148 @S9S_MB_2U_LIB.S9S_MB_2U(SCH_1):PAGE91
   233    GND @S9S_MB_2U_LIB.S9S_MB_2U(SCH_1):GND   I148 @S9S_MB_2U_LIB.S9S_MB_2U(SCH_1):PAGE91
   237    GND @S9S_MB_2U_LIB.S9S_MB_2U(SCH_1):GND   I148 @S9S_MB_2U_LIB.S9S_MB_2U(SCH_1):PAGE91
   242    GND @S9S_MB_2U_LIB.S9S_MB_2U(SCH_1):GND   I148 @S9S_MB_2U_LIB.S9S_MB_2U(SCH_1):PAGE91
   244    GND @S9S_MB_2U_LIB.S9S_MB_2U(SCH_1):GND   I148 @S9S_MB_2U_LIB.S9S_MB_2U(SCH_1):PAGE91
   246    GND @S9S_MB_2U_LIB.S9S_MB_2U(SCH_1):GND   I148 @S9S_MB_2U_LIB.S9S_MB_2U(SCH_1):PAGE91
   248    GND @S9S_MB_2U_LIB.S9S_MB_2U(SCH_1):GND   I148 @S9S_MB_2U_LIB.S9S_MB_2U(SCH_1):PAGE91
   251    GND @S9S_MB_2U_LIB.S9S_MB_2U(SCH_1):GND   I148 @S9S_MB_2U_LIB.S9S_MB_2U(SCH_1):PAGE91
   253    GND @S9S_MB_2U_LIB.S9S_MB_2U(SCH_1):GND   I148 @S9S_MB_2U_LIB.S9S_MB_2U(SCH_1):PAGE91
   255    GND @S9S_MB_2U_LIB.S9S_MB_2U(SCH_1):GND   I148 @S9S_MB_2U_LIB.S9S_MB_2U(SCH_1):PAGE91
   257    GND @S9S_MB_2U_LIB.S9S_MB_2U(SCH_1):GND   I148 @S9S_MB_2U_LIB.S9S_MB_2U(SCH_1):PAGE91
   259    GND @S9S_MB_2U_LIB.S9S_MB_2U(SCH_1):GND   I148 @S9S_MB_2U_LIB.S9S_MB_2U(SCH_1):PAGE91
   262    GND @S9S_MB_2U_LIB.S9S_MB_2U(SCH_1):GND   I148 @S9S_MB_2U_LIB.S9S_MB_2U(SCH_1):PAGE91
   264    GND @S9S_MB_2U_LIB.S9S_MB_2U(SCH_1):GND   I148 @S9S_MB_2U_LIB.S9S_MB_2U(SCH_1):PAGE91
   266    GND @S9S_MB_2U_LIB.S9S_MB_2U(SCH_1):GND   I148 @S9S_MB_2U_LIB.S9S_MB_2U(SCH_1):PAGE91
   268    GND @S9S_MB_2U_LIB.S9S_MB_2U(SCH_1):GND   I148 @S9S_MB_2U_LIB.S9S_MB_2U(SCH_1):PAGE91
   270    GND @S9S_MB_2U_LIB.S9S_MB_2U(SCH_1):GND   I148 @S9S_MB_2U_LIB.S9S_MB_2U(SCH_1):PAGE91
   273    GND @S9S_MB_2U_LIB.S9S_MB_2U(SCH_1):GND   I148 @S9S_MB_2U_LIB.S9S_MB_2U(SCH_1):PAGE91
   275    GND @S9S_MB_2U_LIB.S9S_MB_2U(SCH_1):GND   I148 @S9S_MB_2U_LIB.S9S_MB_2U(SCH_1):PAGE91
   277    GND @S9S_MB_2U_LIB.S9S_MB_2U(SCH_1):GND   I148 @S9S_MB_2U_LIB.S9S_MB_2U(SCH_1):PAGE91
   279    GND @S9S_MB_2U_LIB.S9S_MB_2U(SCH_1):GND   I148 @S9S_MB_2U_LIB.S9S_MB_2U(SCH_1):PAGE91
   281    GND @S9S_MB_2U_LIB.S9S_MB_2U(SCH_1):GND   I148 @S9S_MB_2U_LIB.S9S_MB_2U(SCH_1):PAGE91
   284    GND @S9S_MB_2U_LIB.S9S_MB_2U(SCH_1):GND   I148 @S9S_MB_2U_LIB.S9S_MB_2U(SCH_1):PAGE91
   286    GND @S9S_MB_2U_LIB.S9S_MB_2U(SCH_1):GND   I148 @S9S_MB_2U_LIB.S9S_MB_2U(SCH_1):PAGE91
   288    GND @S9S_MB_2U_LIB.S9S_MB_2U(SCH_1):GND   I148 @S9S_MB_2U_LIB.S9S_MB_2U(SCH_1):PAGE91
     1 P12V_S3_AUX_CPU0_NVDIMM @S9S_MB_2U_LIB.S9S_MB_2U(SCH_1):P12V_S3_AUX_CPU0_NVDIMM   I148 @S9S_MB_2U_LIB.S9S_MB_2U(SCH_1):PAGE91
   145 P12V_S3_AUX_CPU0_NVDIMM @S9S_MB_2U_LIB.S9S_MB_2U(SCH_1):P12V_S3_AUX_CPU0_NVDIMM   I148 @S9S_MB_2U_LIB.S9S_MB_2U(SCH_1):PAGE91
   146 P12V_S3_AUX_CPU0_NVDIMM @S9S_MB_2U_LIB.S9S_MB_2U(SCH_1):P12V_S3_AUX_CPU0_NVDIMM   I148 @S9S_MB_2U_LIB.S9S_MB_2U(SCH_1):PAGE91
   230    GND @S9S_MB_2U_LIB.S9S_MB_2U(SCH_1):GND   I148 @S9S_MB_2U_LIB.S9S_MB_2U(SCH_1):PAGE91
   235    GND @S9S_MB_2U_LIB.S9S_MB_2U(SCH_1):GND   I148 @S9S_MB_2U_LIB.S9S_MB_2U(SCH_1):PAGE91
   240    GND @S9S_MB_2U_LIB.S9S_MB_2U(SCH_1):GND   I148 @S9S_MB_2U_LIB.S9S_MB_2U(SCH_1):PAGE91
   132    GND @S9S_MB_2U_LIB.S9S_MB_2U(SCH_1):GND   I148 @S9S_MB_2U_LIB.S9S_MB_2U(SCH_1):PAGE91
   136    GND @S9S_MB_2U_LIB.S9S_MB_2U(SCH_1):GND   I148 @S9S_MB_2U_LIB.S9S_MB_2U(SCH_1):PAGE91
   139    GND @S9S_MB_2U_LIB.S9S_MB_2U(SCH_1):GND   I148 @S9S_MB_2U_LIB.S9S_MB_2U(SCH_1):PAGE91
   141    GND @S9S_MB_2U_LIB.S9S_MB_2U(SCH_1):GND   I148 @S9S_MB_2U_LIB.S9S_MB_2U(SCH_1):PAGE91
    G1    GND @S9S_MB_2U_LIB.S9S_MB_2U(SCH_1):GND   I148 @S9S_MB_2U_LIB.S9S_MB_2U(SCH_1):PAGE91
    G2    GND @S9S_MB_2U_LIB.S9S_MB_2U(SCH_1):GND   I148 @S9S_MB_2U_LIB.S9S_MB_2U(SCH_1):PAGE91
    G3    GND @S9S_MB_2U_LIB.S9S_MB_2U(SCH_1):GND   I148 @S9S_MB_2U_LIB.S9S_MB_2U(SCH_1):PAGE91

 J11 SCONN288_ADR50017P130CC-SCONN2A
     3 P3V3_AUX @S9S_MB_2U_LIB.S9S_MB_2U(SCH_1):P3V3_AUX    I25 @S9S_MB_2U_LIB.S9S_MB_2U(SCH_1):PAGE92
     2 TP_CHF_CPU0_DIMM1_FRU_0 @S9S_MB_2U_LIB.S9S_MB_2U(SCH_1):TP_CHF_CPU0_DIMM1_FRU_0    I25 @S9S_MB_2U_LIB.S9S_MB_2U(SCH_1):PAGE92
   144 TP_CHF_CPU0_DIMM1_FRU_1 @S9S_MB_2U_LIB.S9S_MB_2U(SCH_1):TP_CHF_CPU0_DIMM1_FRU_1    I25 @S9S_MB_2U_LIB.S9S_MB_2U(SCH_1):PAGE92
   149 TP_CHF_CPU0_DIMM1_FRU_2 @S9S_MB_2U_LIB.S9S_MB_2U(SCH_1):TP_CHF_CPU0_DIMM1_FRU_2    I25 @S9S_MB_2U_LIB.S9S_MB_2U(SCH_1):PAGE92
   150 TP_CHF_CPU0_DIMM1_FRU_3 @S9S_MB_2U_LIB.S9S_MB_2U(SCH_1):TP_CHF_CPU0_DIMM1_FRU_3    I25 @S9S_MB_2U_LIB.S9S_MB_2U(SCH_1):PAGE92
   220 TP_CHF_CPU0_DIMM1_FRU_4 @S9S_MB_2U_LIB.S9S_MB_2U(SCH_1):TP_CHF_CPU0_DIMM1_FRU_4    I25 @S9S_MB_2U_LIB.S9S_MB_2U(SCH_1):PAGE92
   231 TP_CHF_CPU0_DIMM1_FRU_5 @S9S_MB_2U_LIB.S9S_MB_2U(SCH_1):TP_CHF_CPU0_DIMM1_FRU_5    I25 @S9S_MB_2U_LIB.S9S_MB_2U(SCH_1):PAGE92
   232 TP_CHF_CPU0_DIMM1_FRU_6 @S9S_MB_2U_LIB.S9S_MB_2U(SCH_1):TP_CHF_CPU0_DIMM1_FRU_6    I25 @S9S_MB_2U_LIB.S9S_MB_2U(SCH_1):PAGE92
   207 RST_M_EF_CPU0_FPGA_N @S9S_MB_2U_LIB.S9S_MB_2U(SCH_1):RST_M_EF_CPU0_FPGA_N    I25 @S9S_MB_2U_LIB.S9S_MB_2U(SCH_1):PAGE92
   147 PWRGD_CHF_CPU0_DIMM1 @S9S_MB_2U_LIB.S9S_MB_2U(SCH_1):PWRGD_CHF_CPU0_DIMM1    I25 @S9S_MB_2U_LIB.S9S_MB_2U(SCH_1):PAGE92
   227 M_F_CPU0_SB_PAR @S9S_MB_2U_LIB.S9S_MB_2U(SCH_1):M_F_CPU0_SB_PAR    I25 @S9S_MB_2U_LIB.S9S_MB_2U(SCH_1):PAGE92
    74 M_F_CPU0_SA_PAR @S9S_MB_2U_LIB.S9S_MB_2U(SCH_1):M_F_CPU0_SA_PAR    I25 @S9S_MB_2U_LIB.S9S_MB_2U(SCH_1):PAGE92
    87 M_F_CPU0_SB_RSP<0> @S9S_MB_2U_LIB.S9S_MB_2U(SCH_1):M_F_CPU0_SB_RSP(0)    I25 @S9S_MB_2U_LIB.S9S_MB_2U(SCH_1):PAGE92
    86 M_F_CPU0_SA_RSP<0> @S9S_MB_2U_LIB.S9S_MB_2U(SCH_1):M_F_CPU0_SA_RSP(0)    I25 @S9S_MB_2U_LIB.S9S_MB_2U(SCH_1):PAGE92
     5 I3C_SPD_DDREFGH_CPU0_LVC1_SDA @S9S_MB_2U_LIB.S9S_MB_2U(SCH_1):I3C_SPD_DDREFGH_CPU0_LVC1_SDA    I25 @S9S_MB_2U_LIB.S9S_MB_2U(SCH_1):PAGE92
     4 I3C_SPD_DDREFGH_CPU0_LVC1_SCL_2 @S9S_MB_2U_LIB.S9S_MB_2U(SCH_1):I3C_SPD_DDREFGH_CPU0_LVC1_SCL_R3    I25 @S9S_MB_2U_LIB.S9S_MB_2U(SCH_1):PAGE92
   148 PD_CHF_CPU0_DIMM1_SAA @S9S_MB_2U_LIB.S9S_MB_2U(SCH_1):PD_CHF_CPU0_DIMM1_SAA    I25 @S9S_MB_2U_LIB.S9S_MB_2U(SCH_1):PAGE92
   100 M_F_CPU0_SB_DQ<0> @S9S_MB_2U_LIB.S9S_MB_2U(SCH_1):M_F_CPU0_SB_DQ(0)    I25 @S9S_MB_2U_LIB.S9S_MB_2U(SCH_1):PAGE92
   102 M_F_CPU0_SB_DQ<1> @S9S_MB_2U_LIB.S9S_MB_2U(SCH_1):M_F_CPU0_SB_DQ(1)    I25 @S9S_MB_2U_LIB.S9S_MB_2U(SCH_1):PAGE92
   245 M_F_CPU0_SB_DQ<2> @S9S_MB_2U_LIB.S9S_MB_2U(SCH_1):M_F_CPU0_SB_DQ(2)    I25 @S9S_MB_2U_LIB.S9S_MB_2U(SCH_1):PAGE92
   247 M_F_CPU0_SB_DQ<3> @S9S_MB_2U_LIB.S9S_MB_2U(SCH_1):M_F_CPU0_SB_DQ(3)    I25 @S9S_MB_2U_LIB.S9S_MB_2U(SCH_1):PAGE92
   107 M_F_CPU0_SB_DQ<4> @S9S_MB_2U_LIB.S9S_MB_2U(SCH_1):M_F_CPU0_SB_DQ(4)    I25 @S9S_MB_2U_LIB.S9S_MB_2U(SCH_1):PAGE92
   109 M_F_CPU0_SB_DQ<5> @S9S_MB_2U_LIB.S9S_MB_2U(SCH_1):M_F_CPU0_SB_DQ(5)    I25 @S9S_MB_2U_LIB.S9S_MB_2U(SCH_1):PAGE92
   252 M_F_CPU0_SB_DQ<6> @S9S_MB_2U_LIB.S9S_MB_2U(SCH_1):M_F_CPU0_SB_DQ(6)    I25 @S9S_MB_2U_LIB.S9S_MB_2U(SCH_1):PAGE92
   254 M_F_CPU0_SB_DQ<7> @S9S_MB_2U_LIB.S9S_MB_2U(SCH_1):M_F_CPU0_SB_DQ(7)    I25 @S9S_MB_2U_LIB.S9S_MB_2U(SCH_1):PAGE92
   111 M_F_CPU0_SB_DQ<8> @S9S_MB_2U_LIB.S9S_MB_2U(SCH_1):M_F_CPU0_SB_DQ(8)    I25 @S9S_MB_2U_LIB.S9S_MB_2U(SCH_1):PAGE92
   113 M_F_CPU0_SB_DQ<9> @S9S_MB_2U_LIB.S9S_MB_2U(SCH_1):M_F_CPU0_SB_DQ(9)    I25 @S9S_MB_2U_LIB.S9S_MB_2U(SCH_1):PAGE92
   256 M_F_CPU0_SB_DQ<10> @S9S_MB_2U_LIB.S9S_MB_2U(SCH_1):M_F_CPU0_SB_DQ(10)    I25 @S9S_MB_2U_LIB.S9S_MB_2U(SCH_1):PAGE92
   258 M_F_CPU0_SB_DQ<11> @S9S_MB_2U_LIB.S9S_MB_2U(SCH_1):M_F_CPU0_SB_DQ(11)    I25 @S9S_MB_2U_LIB.S9S_MB_2U(SCH_1):PAGE92
   118 M_F_CPU0_SB_DQ<12> @S9S_MB_2U_LIB.S9S_MB_2U(SCH_1):M_F_CPU0_SB_DQ(12)    I25 @S9S_MB_2U_LIB.S9S_MB_2U(SCH_1):PAGE92
   120 M_F_CPU0_SB_DQ<13> @S9S_MB_2U_LIB.S9S_MB_2U(SCH_1):M_F_CPU0_SB_DQ(13)    I25 @S9S_MB_2U_LIB.S9S_MB_2U(SCH_1):PAGE92
   263 M_F_CPU0_SB_DQ<14> @S9S_MB_2U_LIB.S9S_MB_2U(SCH_1):M_F_CPU0_SB_DQ(14)    I25 @S9S_MB_2U_LIB.S9S_MB_2U(SCH_1):PAGE92
   265 M_F_CPU0_SB_DQ<15> @S9S_MB_2U_LIB.S9S_MB_2U(SCH_1):M_F_CPU0_SB_DQ(15)    I25 @S9S_MB_2U_LIB.S9S_MB_2U(SCH_1):PAGE92
   122 M_F_CPU0_SB_DQ<16> @S9S_MB_2U_LIB.S9S_MB_2U(SCH_1):M_F_CPU0_SB_DQ(16)    I25 @S9S_MB_2U_LIB.S9S_MB_2U(SCH_1):PAGE92
   124 M_F_CPU0_SB_DQ<17> @S9S_MB_2U_LIB.S9S_MB_2U(SCH_1):M_F_CPU0_SB_DQ(17)    I25 @S9S_MB_2U_LIB.S9S_MB_2U(SCH_1):PAGE92
   267 M_F_CPU0_SB_DQ<18> @S9S_MB_2U_LIB.S9S_MB_2U(SCH_1):M_F_CPU0_SB_DQ(18)    I25 @S9S_MB_2U_LIB.S9S_MB_2U(SCH_1):PAGE92
   269 M_F_CPU0_SB_DQ<19> @S9S_MB_2U_LIB.S9S_MB_2U(SCH_1):M_F_CPU0_SB_DQ(19)    I25 @S9S_MB_2U_LIB.S9S_MB_2U(SCH_1):PAGE92
   129 M_F_CPU0_SB_DQ<20> @S9S_MB_2U_LIB.S9S_MB_2U(SCH_1):M_F_CPU0_SB_DQ(20)    I25 @S9S_MB_2U_LIB.S9S_MB_2U(SCH_1):PAGE92
   131 M_F_CPU0_SB_DQ<21> @S9S_MB_2U_LIB.S9S_MB_2U(SCH_1):M_F_CPU0_SB_DQ(21)    I25 @S9S_MB_2U_LIB.S9S_MB_2U(SCH_1):PAGE92
   274 M_F_CPU0_SB_DQ<22> @S9S_MB_2U_LIB.S9S_MB_2U(SCH_1):M_F_CPU0_SB_DQ(22)    I25 @S9S_MB_2U_LIB.S9S_MB_2U(SCH_1):PAGE92
   276 M_F_CPU0_SB_DQ<23> @S9S_MB_2U_LIB.S9S_MB_2U(SCH_1):M_F_CPU0_SB_DQ(23)    I25 @S9S_MB_2U_LIB.S9S_MB_2U(SCH_1):PAGE92
   133 M_F_CPU0_SB_DQ<24> @S9S_MB_2U_LIB.S9S_MB_2U(SCH_1):M_F_CPU0_SB_DQ(24)    I25 @S9S_MB_2U_LIB.S9S_MB_2U(SCH_1):PAGE92
   135 M_F_CPU0_SB_DQ<25> @S9S_MB_2U_LIB.S9S_MB_2U(SCH_1):M_F_CPU0_SB_DQ(25)    I25 @S9S_MB_2U_LIB.S9S_MB_2U(SCH_1):PAGE92
   278 M_F_CPU0_SB_DQ<26> @S9S_MB_2U_LIB.S9S_MB_2U(SCH_1):M_F_CPU0_SB_DQ(26)    I25 @S9S_MB_2U_LIB.S9S_MB_2U(SCH_1):PAGE92
   280 M_F_CPU0_SB_DQ<27> @S9S_MB_2U_LIB.S9S_MB_2U(SCH_1):M_F_CPU0_SB_DQ(27)    I25 @S9S_MB_2U_LIB.S9S_MB_2U(SCH_1):PAGE92
   140 M_F_CPU0_SB_DQ<28> @S9S_MB_2U_LIB.S9S_MB_2U(SCH_1):M_F_CPU0_SB_DQ(28)    I25 @S9S_MB_2U_LIB.S9S_MB_2U(SCH_1):PAGE92
   142 M_F_CPU0_SB_DQ<29> @S9S_MB_2U_LIB.S9S_MB_2U(SCH_1):M_F_CPU0_SB_DQ(29)    I25 @S9S_MB_2U_LIB.S9S_MB_2U(SCH_1):PAGE92
   285 M_F_CPU0_SB_DQ<30> @S9S_MB_2U_LIB.S9S_MB_2U(SCH_1):M_F_CPU0_SB_DQ(30)    I25 @S9S_MB_2U_LIB.S9S_MB_2U(SCH_1):PAGE92
   287 M_F_CPU0_SB_DQ<31> @S9S_MB_2U_LIB.S9S_MB_2U(SCH_1):M_F_CPU0_SB_DQ(31)    I25 @S9S_MB_2U_LIB.S9S_MB_2U(SCH_1):PAGE92
     7 M_F_CPU0_SA_DQ<0> @S9S_MB_2U_LIB.S9S_MB_2U(SCH_1):M_F_CPU0_SA_DQ(0)    I25 @S9S_MB_2U_LIB.S9S_MB_2U(SCH_1):PAGE92
     9 M_F_CPU0_SA_DQ<1> @S9S_MB_2U_LIB.S9S_MB_2U(SCH_1):M_F_CPU0_SA_DQ(1)    I25 @S9S_MB_2U_LIB.S9S_MB_2U(SCH_1):PAGE92
   152 M_F_CPU0_SA_DQ<2> @S9S_MB_2U_LIB.S9S_MB_2U(SCH_1):M_F_CPU0_SA_DQ(2)    I25 @S9S_MB_2U_LIB.S9S_MB_2U(SCH_1):PAGE92
   154 M_F_CPU0_SA_DQ<3> @S9S_MB_2U_LIB.S9S_MB_2U(SCH_1):M_F_CPU0_SA_DQ(3)    I25 @S9S_MB_2U_LIB.S9S_MB_2U(SCH_1):PAGE92
    14 M_F_CPU0_SA_DQ<4> @S9S_MB_2U_LIB.S9S_MB_2U(SCH_1):M_F_CPU0_SA_DQ(4)    I25 @S9S_MB_2U_LIB.S9S_MB_2U(SCH_1):PAGE92
    16 M_F_CPU0_SA_DQ<5> @S9S_MB_2U_LIB.S9S_MB_2U(SCH_1):M_F_CPU0_SA_DQ(5)    I25 @S9S_MB_2U_LIB.S9S_MB_2U(SCH_1):PAGE92
   159 M_F_CPU0_SA_DQ<6> @S9S_MB_2U_LIB.S9S_MB_2U(SCH_1):M_F_CPU0_SA_DQ(6)    I25 @S9S_MB_2U_LIB.S9S_MB_2U(SCH_1):PAGE92
   161 M_F_CPU0_SA_DQ<7> @S9S_MB_2U_LIB.S9S_MB_2U(SCH_1):M_F_CPU0_SA_DQ(7)    I25 @S9S_MB_2U_LIB.S9S_MB_2U(SCH_1):PAGE92
    18 M_F_CPU0_SA_DQ<8> @S9S_MB_2U_LIB.S9S_MB_2U(SCH_1):M_F_CPU0_SA_DQ(8)    I25 @S9S_MB_2U_LIB.S9S_MB_2U(SCH_1):PAGE92
    20 M_F_CPU0_SA_DQ<9> @S9S_MB_2U_LIB.S9S_MB_2U(SCH_1):M_F_CPU0_SA_DQ(9)    I25 @S9S_MB_2U_LIB.S9S_MB_2U(SCH_1):PAGE92
   163 M_F_CPU0_SA_DQ<10> @S9S_MB_2U_LIB.S9S_MB_2U(SCH_1):M_F_CPU0_SA_DQ(10)    I25 @S9S_MB_2U_LIB.S9S_MB_2U(SCH_1):PAGE92
   165 M_F_CPU0_SA_DQ<11> @S9S_MB_2U_LIB.S9S_MB_2U(SCH_1):M_F_CPU0_SA_DQ(11)    I25 @S9S_MB_2U_LIB.S9S_MB_2U(SCH_1):PAGE92
    25 M_F_CPU0_SA_DQ<12> @S9S_MB_2U_LIB.S9S_MB_2U(SCH_1):M_F_CPU0_SA_DQ(12)    I25 @S9S_MB_2U_LIB.S9S_MB_2U(SCH_1):PAGE92
    27 M_F_CPU0_SA_DQ<13> @S9S_MB_2U_LIB.S9S_MB_2U(SCH_1):M_F_CPU0_SA_DQ(13)    I25 @S9S_MB_2U_LIB.S9S_MB_2U(SCH_1):PAGE92
   170 M_F_CPU0_SA_DQ<14> @S9S_MB_2U_LIB.S9S_MB_2U(SCH_1):M_F_CPU0_SA_DQ(14)    I25 @S9S_MB_2U_LIB.S9S_MB_2U(SCH_1):PAGE92
   172 M_F_CPU0_SA_DQ<15> @S9S_MB_2U_LIB.S9S_MB_2U(SCH_1):M_F_CPU0_SA_DQ(15)    I25 @S9S_MB_2U_LIB.S9S_MB_2U(SCH_1):PAGE92
    29 M_F_CPU0_SA_DQ<16> @S9S_MB_2U_LIB.S9S_MB_2U(SCH_1):M_F_CPU0_SA_DQ(16)    I25 @S9S_MB_2U_LIB.S9S_MB_2U(SCH_1):PAGE92
    31 M_F_CPU0_SA_DQ<17> @S9S_MB_2U_LIB.S9S_MB_2U(SCH_1):M_F_CPU0_SA_DQ(17)    I25 @S9S_MB_2U_LIB.S9S_MB_2U(SCH_1):PAGE92
   174 M_F_CPU0_SA_DQ<18> @S9S_MB_2U_LIB.S9S_MB_2U(SCH_1):M_F_CPU0_SA_DQ(18)    I25 @S9S_MB_2U_LIB.S9S_MB_2U(SCH_1):PAGE92
   176 M_F_CPU0_SA_DQ<19> @S9S_MB_2U_LIB.S9S_MB_2U(SCH_1):M_F_CPU0_SA_DQ(19)    I25 @S9S_MB_2U_LIB.S9S_MB_2U(SCH_1):PAGE92
    36 M_F_CPU0_SA_DQ<20> @S9S_MB_2U_LIB.S9S_MB_2U(SCH_1):M_F_CPU0_SA_DQ(20)    I25 @S9S_MB_2U_LIB.S9S_MB_2U(SCH_1):PAGE92
    38 M_F_CPU0_SA_DQ<21> @S9S_MB_2U_LIB.S9S_MB_2U(SCH_1):M_F_CPU0_SA_DQ(21)    I25 @S9S_MB_2U_LIB.S9S_MB_2U(SCH_1):PAGE92
   181 M_F_CPU0_SA_DQ<22> @S9S_MB_2U_LIB.S9S_MB_2U(SCH_1):M_F_CPU0_SA_DQ(22)    I25 @S9S_MB_2U_LIB.S9S_MB_2U(SCH_1):PAGE92
   183 M_F_CPU0_SA_DQ<23> @S9S_MB_2U_LIB.S9S_MB_2U(SCH_1):M_F_CPU0_SA_DQ(23)    I25 @S9S_MB_2U_LIB.S9S_MB_2U(SCH_1):PAGE92
    40 M_F_CPU0_SA_DQ<24> @S9S_MB_2U_LIB.S9S_MB_2U(SCH_1):M_F_CPU0_SA_DQ(24)    I25 @S9S_MB_2U_LIB.S9S_MB_2U(SCH_1):PAGE92
    42 M_F_CPU0_SA_DQ<25> @S9S_MB_2U_LIB.S9S_MB_2U(SCH_1):M_F_CPU0_SA_DQ(25)    I25 @S9S_MB_2U_LIB.S9S_MB_2U(SCH_1):PAGE92
   185 M_F_CPU0_SA_DQ<26> @S9S_MB_2U_LIB.S9S_MB_2U(SCH_1):M_F_CPU0_SA_DQ(26)    I25 @S9S_MB_2U_LIB.S9S_MB_2U(SCH_1):PAGE92
   187 M_F_CPU0_SA_DQ<27> @S9S_MB_2U_LIB.S9S_MB_2U(SCH_1):M_F_CPU0_SA_DQ(27)    I25 @S9S_MB_2U_LIB.S9S_MB_2U(SCH_1):PAGE92
    47 M_F_CPU0_SA_DQ<28> @S9S_MB_2U_LIB.S9S_MB_2U(SCH_1):M_F_CPU0_SA_DQ(28)    I25 @S9S_MB_2U_LIB.S9S_MB_2U(SCH_1):PAGE92
    49 M_F_CPU0_SA_DQ<29> @S9S_MB_2U_LIB.S9S_MB_2U(SCH_1):M_F_CPU0_SA_DQ(29)    I25 @S9S_MB_2U_LIB.S9S_MB_2U(SCH_1):PAGE92
   192 M_F_CPU0_SA_DQ<30> @S9S_MB_2U_LIB.S9S_MB_2U(SCH_1):M_F_CPU0_SA_DQ(30)    I25 @S9S_MB_2U_LIB.S9S_MB_2U(SCH_1):PAGE92
   229 M_F_CPU0_SB_CS_N<1> @S9S_MB_2U_LIB.S9S_MB_2U(SCH_1):M_F_CPU0_SB_CS_N(1)    I25 @S9S_MB_2U_LIB.S9S_MB_2U(SCH_1):PAGE92
   209 M_F_CPU0_SA_CS_N<1> @S9S_MB_2U_LIB.S9S_MB_2U(SCH_1):M_F_CPU0_SA_CS_N(1)    I25 @S9S_MB_2U_LIB.S9S_MB_2U(SCH_1):PAGE92
    84 M_F_CPU0_SB_CS_N<0> @S9S_MB_2U_LIB.S9S_MB_2U(SCH_1):M_F_CPU0_SB_CS_N(0)    I25 @S9S_MB_2U_LIB.S9S_MB_2U(SCH_1):PAGE92
    64 M_F_CPU0_SA_CS_N<0> @S9S_MB_2U_LIB.S9S_MB_2U(SCH_1):M_F_CPU0_SA_CS_N(0)    I25 @S9S_MB_2U_LIB.S9S_MB_2U(SCH_1):PAGE92
   217 M_F_CPU0_CLK_DP<0> @S9S_MB_2U_LIB.S9S_MB_2U(SCH_1):M_F_CPU0_CLK_DP(0)    I25 @S9S_MB_2U_LIB.S9S_MB_2U(SCH_1):PAGE92
   218 M_F_CPU0_CLK_DN<0> @S9S_MB_2U_LIB.S9S_MB_2U(SCH_1):M_F_CPU0_CLK_DN(0)    I25 @S9S_MB_2U_LIB.S9S_MB_2U(SCH_1):PAGE92
    96 M_F_CPU0_SB_CB<0> @S9S_MB_2U_LIB.S9S_MB_2U(SCH_1):M_F_CPU0_SB_CB(0)    I25 @S9S_MB_2U_LIB.S9S_MB_2U(SCH_1):PAGE92
    98 M_F_CPU0_SB_CB<1> @S9S_MB_2U_LIB.S9S_MB_2U(SCH_1):M_F_CPU0_SB_CB(1)    I25 @S9S_MB_2U_LIB.S9S_MB_2U(SCH_1):PAGE92
   241 M_F_CPU0_SB_CB<2> @S9S_MB_2U_LIB.S9S_MB_2U(SCH_1):M_F_CPU0_SB_CB(2)    I25 @S9S_MB_2U_LIB.S9S_MB_2U(SCH_1):PAGE92
   243 M_F_CPU0_SB_CB<3> @S9S_MB_2U_LIB.S9S_MB_2U(SCH_1):M_F_CPU0_SB_CB(3)    I25 @S9S_MB_2U_LIB.S9S_MB_2U(SCH_1):PAGE92
    89 M_F_CPU0_SB_CB<4> @S9S_MB_2U_LIB.S9S_MB_2U(SCH_1):M_F_CPU0_SB_CB(4)    I25 @S9S_MB_2U_LIB.S9S_MB_2U(SCH_1):PAGE92
    91 M_F_CPU0_SB_CB<5> @S9S_MB_2U_LIB.S9S_MB_2U(SCH_1):M_F_CPU0_SB_CB(5)    I25 @S9S_MB_2U_LIB.S9S_MB_2U(SCH_1):PAGE92
   234 M_F_CPU0_SB_CB<6> @S9S_MB_2U_LIB.S9S_MB_2U(SCH_1):M_F_CPU0_SB_CB(6)    I25 @S9S_MB_2U_LIB.S9S_MB_2U(SCH_1):PAGE92
    51 M_F_CPU0_SA_CB<0> @S9S_MB_2U_LIB.S9S_MB_2U(SCH_1):M_F_CPU0_SA_CB(0)    I25 @S9S_MB_2U_LIB.S9S_MB_2U(SCH_1):PAGE92
   196 M_F_CPU0_SA_CB<2> @S9S_MB_2U_LIB.S9S_MB_2U(SCH_1):M_F_CPU0_SA_CB(2)    I25 @S9S_MB_2U_LIB.S9S_MB_2U(SCH_1):PAGE92
   198 M_F_CPU0_SA_CB<3> @S9S_MB_2U_LIB.S9S_MB_2U(SCH_1):M_F_CPU0_SA_CB(3)    I25 @S9S_MB_2U_LIB.S9S_MB_2U(SCH_1):PAGE92
    60 M_F_CPU0_SA_CB<5> @S9S_MB_2U_LIB.S9S_MB_2U(SCH_1):M_F_CPU0_SA_CB(5)    I25 @S9S_MB_2U_LIB.S9S_MB_2U(SCH_1):PAGE92
   203 M_F_CPU0_SA_CB<6> @S9S_MB_2U_LIB.S9S_MB_2U(SCH_1):M_F_CPU0_SA_CB(6)    I25 @S9S_MB_2U_LIB.S9S_MB_2U(SCH_1):PAGE92
    82 M_F_CPU0_SB_CA<6> @S9S_MB_2U_LIB.S9S_MB_2U(SCH_1):M_F_CPU0_SB_CA(6)    I25 @S9S_MB_2U_LIB.S9S_MB_2U(SCH_1):PAGE92
    72 M_F_CPU0_SA_CA<6> @S9S_MB_2U_LIB.S9S_MB_2U(SCH_1):M_F_CPU0_SA_CA(6)    I25 @S9S_MB_2U_LIB.S9S_MB_2U(SCH_1):PAGE92
   225 M_F_CPU0_SB_CA<5> @S9S_MB_2U_LIB.S9S_MB_2U(SCH_1):M_F_CPU0_SB_CA(5)    I25 @S9S_MB_2U_LIB.S9S_MB_2U(SCH_1):PAGE92
   215 M_F_CPU0_SA_CA<5> @S9S_MB_2U_LIB.S9S_MB_2U(SCH_1):M_F_CPU0_SA_CA(5)    I25 @S9S_MB_2U_LIB.S9S_MB_2U(SCH_1):PAGE92
    80 M_F_CPU0_SB_CA<4> @S9S_MB_2U_LIB.S9S_MB_2U(SCH_1):M_F_CPU0_SB_CA(4)    I25 @S9S_MB_2U_LIB.S9S_MB_2U(SCH_1):PAGE92
    70 M_F_CPU0_SA_CA<4> @S9S_MB_2U_LIB.S9S_MB_2U(SCH_1):M_F_CPU0_SA_CA(4)    I25 @S9S_MB_2U_LIB.S9S_MB_2U(SCH_1):PAGE92
   223 M_F_CPU0_SB_CA<3> @S9S_MB_2U_LIB.S9S_MB_2U(SCH_1):M_F_CPU0_SB_CA(3)    I25 @S9S_MB_2U_LIB.S9S_MB_2U(SCH_1):PAGE92
   213 M_F_CPU0_SA_CA<3> @S9S_MB_2U_LIB.S9S_MB_2U(SCH_1):M_F_CPU0_SA_CA(3)    I25 @S9S_MB_2U_LIB.S9S_MB_2U(SCH_1):PAGE92
    78 M_F_CPU0_SB_CA<2> @S9S_MB_2U_LIB.S9S_MB_2U(SCH_1):M_F_CPU0_SB_CA(2)    I25 @S9S_MB_2U_LIB.S9S_MB_2U(SCH_1):PAGE92
    68 M_F_CPU0_SA_CA<2> @S9S_MB_2U_LIB.S9S_MB_2U(SCH_1):M_F_CPU0_SA_CA(2)    I25 @S9S_MB_2U_LIB.S9S_MB_2U(SCH_1):PAGE92
   221 M_F_CPU0_SB_CA<1> @S9S_MB_2U_LIB.S9S_MB_2U(SCH_1):M_F_CPU0_SB_CA(1)    I25 @S9S_MB_2U_LIB.S9S_MB_2U(SCH_1):PAGE92
   211 M_F_CPU0_SA_CA<1> @S9S_MB_2U_LIB.S9S_MB_2U(SCH_1):M_F_CPU0_SA_CA(1)    I25 @S9S_MB_2U_LIB.S9S_MB_2U(SCH_1):PAGE92
    76 M_F_CPU0_SB_CA<0> @S9S_MB_2U_LIB.S9S_MB_2U(SCH_1):M_F_CPU0_SB_CA(0)    I25 @S9S_MB_2U_LIB.S9S_MB_2U(SCH_1):PAGE92
    66 M_F_CPU0_SA_CA<0> @S9S_MB_2U_LIB.S9S_MB_2U(SCH_1):M_F_CPU0_SA_CA(0)    I25 @S9S_MB_2U_LIB.S9S_MB_2U(SCH_1):PAGE92
    62 M_F_CPU0_ALERT_N @S9S_MB_2U_LIB.S9S_MB_2U(SCH_1):M_F_CPU0_ALERT_N    I25 @S9S_MB_2U_LIB.S9S_MB_2U(SCH_1):PAGE92
   236 M_F_CPU0_SB_CB<7> @S9S_MB_2U_LIB.S9S_MB_2U(SCH_1):M_F_CPU0_SB_CB(7)    I25 @S9S_MB_2U_LIB.S9S_MB_2U(SCH_1):PAGE92
    53 M_F_CPU0_SA_CB<1> @S9S_MB_2U_LIB.S9S_MB_2U(SCH_1):M_F_CPU0_SA_CB(1)    I25 @S9S_MB_2U_LIB.S9S_MB_2U(SCH_1):PAGE92
    58 M_F_CPU0_SA_CB<4> @S9S_MB_2U_LIB.S9S_MB_2U(SCH_1):M_F_CPU0_SA_CB(4)    I25 @S9S_MB_2U_LIB.S9S_MB_2U(SCH_1):PAGE92
   205 M_F_CPU0_SA_CB<7> @S9S_MB_2U_LIB.S9S_MB_2U(SCH_1):M_F_CPU0_SA_CB(7)    I25 @S9S_MB_2U_LIB.S9S_MB_2U(SCH_1):PAGE92
   194 M_F_CPU0_SA_DQ<31> @S9S_MB_2U_LIB.S9S_MB_2U(SCH_1):M_F_CPU0_SA_DQ(31)    I25 @S9S_MB_2U_LIB.S9S_MB_2U(SCH_1):PAGE92
    93 M_F_CPU0_SB_DQS_DP<9> @S9S_MB_2U_LIB.S9S_MB_2U(SCH_1):M_F_CPU0_SB_DQS_DP(9)   I178 @S9S_MB_2U_LIB.S9S_MB_2U(SCH_1):PAGE92
    94 M_F_CPU0_SB_DQS_DN<9> @S9S_MB_2U_LIB.S9S_MB_2U(SCH_1):M_F_CPU0_SB_DQS_DN(9)   I178 @S9S_MB_2U_LIB.S9S_MB_2U(SCH_1):PAGE92
   201 M_F_CPU0_SA_DQS_DP<9> @S9S_MB_2U_LIB.S9S_MB_2U(SCH_1):M_F_CPU0_SA_DQS_DP(9)   I178 @S9S_MB_2U_LIB.S9S_MB_2U(SCH_1):PAGE92
   200 M_F_CPU0_SA_DQS_DN<9> @S9S_MB_2U_LIB.S9S_MB_2U(SCH_1):M_F_CPU0_SA_DQS_DN(9)   I178 @S9S_MB_2U_LIB.S9S_MB_2U(SCH_1):PAGE92
   190 M_F_CPU0_SA_DQS_DP<8> @S9S_MB_2U_LIB.S9S_MB_2U(SCH_1):M_F_CPU0_SA_DQS_DP(8)   I178 @S9S_MB_2U_LIB.S9S_MB_2U(SCH_1):PAGE92
   189 M_F_CPU0_SA_DQS_DN<8> @S9S_MB_2U_LIB.S9S_MB_2U(SCH_1):M_F_CPU0_SA_DQS_DN(8)   I178 @S9S_MB_2U_LIB.S9S_MB_2U(SCH_1):PAGE92
   271 M_F_CPU0_SB_DQS_DN<7> @S9S_MB_2U_LIB.S9S_MB_2U(SCH_1):M_F_CPU0_SB_DQS_DN(7)   I178 @S9S_MB_2U_LIB.S9S_MB_2U(SCH_1):PAGE92
   179 M_F_CPU0_SA_DQS_DP<7> @S9S_MB_2U_LIB.S9S_MB_2U(SCH_1):M_F_CPU0_SA_DQS_DP(7)   I178 @S9S_MB_2U_LIB.S9S_MB_2U(SCH_1):PAGE92
   261 M_F_CPU0_SB_DQS_DP<6> @S9S_MB_2U_LIB.S9S_MB_2U(SCH_1):M_F_CPU0_SB_DQS_DP(6)   I178 @S9S_MB_2U_LIB.S9S_MB_2U(SCH_1):PAGE92
   260 M_F_CPU0_SB_DQS_DN<6> @S9S_MB_2U_LIB.S9S_MB_2U(SCH_1):M_F_CPU0_SB_DQS_DN(6)   I178 @S9S_MB_2U_LIB.S9S_MB_2U(SCH_1):PAGE92
   167 M_F_CPU0_SA_DQS_DN<6> @S9S_MB_2U_LIB.S9S_MB_2U(SCH_1):M_F_CPU0_SA_DQS_DN(6)   I178 @S9S_MB_2U_LIB.S9S_MB_2U(SCH_1):PAGE92
   250 M_F_CPU0_SB_DQS_DP<5> @S9S_MB_2U_LIB.S9S_MB_2U(SCH_1):M_F_CPU0_SB_DQS_DP(5)   I178 @S9S_MB_2U_LIB.S9S_MB_2U(SCH_1):PAGE92
   249 M_F_CPU0_SB_DQS_DN<5> @S9S_MB_2U_LIB.S9S_MB_2U(SCH_1):M_F_CPU0_SB_DQS_DN(5)   I178 @S9S_MB_2U_LIB.S9S_MB_2U(SCH_1):PAGE92
   157 M_F_CPU0_SA_DQS_DP<5> @S9S_MB_2U_LIB.S9S_MB_2U(SCH_1):M_F_CPU0_SA_DQS_DP(5)   I178 @S9S_MB_2U_LIB.S9S_MB_2U(SCH_1):PAGE92
   156 M_F_CPU0_SA_DQS_DN<5> @S9S_MB_2U_LIB.S9S_MB_2U(SCH_1):M_F_CPU0_SA_DQS_DN(5)   I178 @S9S_MB_2U_LIB.S9S_MB_2U(SCH_1):PAGE92
   239 M_F_CPU0_SB_DQS_DP<4> @S9S_MB_2U_LIB.S9S_MB_2U(SCH_1):M_F_CPU0_SB_DQS_DP(4)   I178 @S9S_MB_2U_LIB.S9S_MB_2U(SCH_1):PAGE92
   238 M_F_CPU0_SB_DQS_DN<4> @S9S_MB_2U_LIB.S9S_MB_2U(SCH_1):M_F_CPU0_SB_DQS_DN(4)   I178 @S9S_MB_2U_LIB.S9S_MB_2U(SCH_1):PAGE92
    55 M_F_CPU0_SA_DQS_DP<4> @S9S_MB_2U_LIB.S9S_MB_2U(SCH_1):M_F_CPU0_SA_DQS_DP(4)   I178 @S9S_MB_2U_LIB.S9S_MB_2U(SCH_1):PAGE92
    56 M_F_CPU0_SA_DQS_DN<4> @S9S_MB_2U_LIB.S9S_MB_2U(SCH_1):M_F_CPU0_SA_DQS_DN(4)   I178 @S9S_MB_2U_LIB.S9S_MB_2U(SCH_1):PAGE92
   137 M_F_CPU0_SB_DQS_DP<3> @S9S_MB_2U_LIB.S9S_MB_2U(SCH_1):M_F_CPU0_SB_DQS_DP(3)   I178 @S9S_MB_2U_LIB.S9S_MB_2U(SCH_1):PAGE92
   138 M_F_CPU0_SB_DQS_DN<3> @S9S_MB_2U_LIB.S9S_MB_2U(SCH_1):M_F_CPU0_SB_DQS_DN(3)   I178 @S9S_MB_2U_LIB.S9S_MB_2U(SCH_1):PAGE92
    44 M_F_CPU0_SA_DQS_DP<3> @S9S_MB_2U_LIB.S9S_MB_2U(SCH_1):M_F_CPU0_SA_DQS_DP(3)   I178 @S9S_MB_2U_LIB.S9S_MB_2U(SCH_1):PAGE92
    45 M_F_CPU0_SA_DQS_DN<3> @S9S_MB_2U_LIB.S9S_MB_2U(SCH_1):M_F_CPU0_SA_DQS_DN(3)   I178 @S9S_MB_2U_LIB.S9S_MB_2U(SCH_1):PAGE92
   126 M_F_CPU0_SB_DQS_DP<2> @S9S_MB_2U_LIB.S9S_MB_2U(SCH_1):M_F_CPU0_SB_DQS_DP(2)   I178 @S9S_MB_2U_LIB.S9S_MB_2U(SCH_1):PAGE92
   127 M_F_CPU0_SB_DQS_DN<2> @S9S_MB_2U_LIB.S9S_MB_2U(SCH_1):M_F_CPU0_SB_DQS_DN(2)   I178 @S9S_MB_2U_LIB.S9S_MB_2U(SCH_1):PAGE92
    33 M_F_CPU0_SA_DQS_DP<2> @S9S_MB_2U_LIB.S9S_MB_2U(SCH_1):M_F_CPU0_SA_DQS_DP(2)   I178 @S9S_MB_2U_LIB.S9S_MB_2U(SCH_1):PAGE92
    34 M_F_CPU0_SA_DQS_DN<2> @S9S_MB_2U_LIB.S9S_MB_2U(SCH_1):M_F_CPU0_SA_DQS_DN(2)   I178 @S9S_MB_2U_LIB.S9S_MB_2U(SCH_1):PAGE92
   115 M_F_CPU0_SB_DQS_DP<1> @S9S_MB_2U_LIB.S9S_MB_2U(SCH_1):M_F_CPU0_SB_DQS_DP(1)   I178 @S9S_MB_2U_LIB.S9S_MB_2U(SCH_1):PAGE92
   116 M_F_CPU0_SB_DQS_DN<1> @S9S_MB_2U_LIB.S9S_MB_2U(SCH_1):M_F_CPU0_SB_DQS_DN(1)   I178 @S9S_MB_2U_LIB.S9S_MB_2U(SCH_1):PAGE92
    22 M_F_CPU0_SA_DQS_DP<1> @S9S_MB_2U_LIB.S9S_MB_2U(SCH_1):M_F_CPU0_SA_DQS_DP(1)   I178 @S9S_MB_2U_LIB.S9S_MB_2U(SCH_1):PAGE92
    23 M_F_CPU0_SA_DQS_DN<1> @S9S_MB_2U_LIB.S9S_MB_2U(SCH_1):M_F_CPU0_SA_DQS_DN(1)   I178 @S9S_MB_2U_LIB.S9S_MB_2U(SCH_1):PAGE92
   104 M_F_CPU0_SB_DQS_DP<0> @S9S_MB_2U_LIB.S9S_MB_2U(SCH_1):M_F_CPU0_SB_DQS_DP(0)   I178 @S9S_MB_2U_LIB.S9S_MB_2U(SCH_1):PAGE92
   105 M_F_CPU0_SB_DQS_DN<0> @S9S_MB_2U_LIB.S9S_MB_2U(SCH_1):M_F_CPU0_SB_DQS_DN(0)   I178 @S9S_MB_2U_LIB.S9S_MB_2U(SCH_1):PAGE92
    11 M_F_CPU0_SA_DQS_DP<0> @S9S_MB_2U_LIB.S9S_MB_2U(SCH_1):M_F_CPU0_SA_DQS_DP(0)   I178 @S9S_MB_2U_LIB.S9S_MB_2U(SCH_1):PAGE92
    12 M_F_CPU0_SA_DQS_DN<0> @S9S_MB_2U_LIB.S9S_MB_2U(SCH_1):M_F_CPU0_SA_DQS_DN(0)   I178 @S9S_MB_2U_LIB.S9S_MB_2U(SCH_1):PAGE92
   272 M_F_CPU0_SB_DQS_DP<7> @S9S_MB_2U_LIB.S9S_MB_2U(SCH_1):M_F_CPU0_SB_DQS_DP(7)   I178 @S9S_MB_2U_LIB.S9S_MB_2U(SCH_1):PAGE92
   282 M_F_CPU0_SB_DQS_DN<8> @S9S_MB_2U_LIB.S9S_MB_2U(SCH_1):M_F_CPU0_SB_DQS_DN(8)   I178 @S9S_MB_2U_LIB.S9S_MB_2U(SCH_1):PAGE92
   283 M_F_CPU0_SB_DQS_DP<8> @S9S_MB_2U_LIB.S9S_MB_2U(SCH_1):M_F_CPU0_SB_DQS_DP(8)   I178 @S9S_MB_2U_LIB.S9S_MB_2U(SCH_1):PAGE92
   168 M_F_CPU0_SA_DQS_DP<6> @S9S_MB_2U_LIB.S9S_MB_2U(SCH_1):M_F_CPU0_SA_DQS_DP(6)   I178 @S9S_MB_2U_LIB.S9S_MB_2U(SCH_1):PAGE92
   178 M_F_CPU0_SA_DQS_DN<7> @S9S_MB_2U_LIB.S9S_MB_2U(SCH_1):M_F_CPU0_SA_DQS_DN(7)   I178 @S9S_MB_2U_LIB.S9S_MB_2U(SCH_1):PAGE92
     6    GND @S9S_MB_2U_LIB.S9S_MB_2U(SCH_1):GND   I175 @S9S_MB_2U_LIB.S9S_MB_2U(SCH_1):PAGE92
     8    GND @S9S_MB_2U_LIB.S9S_MB_2U(SCH_1):GND   I175 @S9S_MB_2U_LIB.S9S_MB_2U(SCH_1):PAGE92
    10    GND @S9S_MB_2U_LIB.S9S_MB_2U(SCH_1):GND   I175 @S9S_MB_2U_LIB.S9S_MB_2U(SCH_1):PAGE92
    13    GND @S9S_MB_2U_LIB.S9S_MB_2U(SCH_1):GND   I175 @S9S_MB_2U_LIB.S9S_MB_2U(SCH_1):PAGE92
    15    GND @S9S_MB_2U_LIB.S9S_MB_2U(SCH_1):GND   I175 @S9S_MB_2U_LIB.S9S_MB_2U(SCH_1):PAGE92
    17    GND @S9S_MB_2U_LIB.S9S_MB_2U(SCH_1):GND   I175 @S9S_MB_2U_LIB.S9S_MB_2U(SCH_1):PAGE92
    19    GND @S9S_MB_2U_LIB.S9S_MB_2U(SCH_1):GND   I175 @S9S_MB_2U_LIB.S9S_MB_2U(SCH_1):PAGE92
    21    GND @S9S_MB_2U_LIB.S9S_MB_2U(SCH_1):GND   I175 @S9S_MB_2U_LIB.S9S_MB_2U(SCH_1):PAGE92
    24    GND @S9S_MB_2U_LIB.S9S_MB_2U(SCH_1):GND   I175 @S9S_MB_2U_LIB.S9S_MB_2U(SCH_1):PAGE92
    26    GND @S9S_MB_2U_LIB.S9S_MB_2U(SCH_1):GND   I175 @S9S_MB_2U_LIB.S9S_MB_2U(SCH_1):PAGE92
    28    GND @S9S_MB_2U_LIB.S9S_MB_2U(SCH_1):GND   I175 @S9S_MB_2U_LIB.S9S_MB_2U(SCH_1):PAGE92
    30    GND @S9S_MB_2U_LIB.S9S_MB_2U(SCH_1):GND   I175 @S9S_MB_2U_LIB.S9S_MB_2U(SCH_1):PAGE92
    32    GND @S9S_MB_2U_LIB.S9S_MB_2U(SCH_1):GND   I175 @S9S_MB_2U_LIB.S9S_MB_2U(SCH_1):PAGE92
    35    GND @S9S_MB_2U_LIB.S9S_MB_2U(SCH_1):GND   I175 @S9S_MB_2U_LIB.S9S_MB_2U(SCH_1):PAGE92
    37    GND @S9S_MB_2U_LIB.S9S_MB_2U(SCH_1):GND   I175 @S9S_MB_2U_LIB.S9S_MB_2U(SCH_1):PAGE92
    39    GND @S9S_MB_2U_LIB.S9S_MB_2U(SCH_1):GND   I175 @S9S_MB_2U_LIB.S9S_MB_2U(SCH_1):PAGE92
    41    GND @S9S_MB_2U_LIB.S9S_MB_2U(SCH_1):GND   I175 @S9S_MB_2U_LIB.S9S_MB_2U(SCH_1):PAGE92
    43    GND @S9S_MB_2U_LIB.S9S_MB_2U(SCH_1):GND   I175 @S9S_MB_2U_LIB.S9S_MB_2U(SCH_1):PAGE92
    46    GND @S9S_MB_2U_LIB.S9S_MB_2U(SCH_1):GND   I175 @S9S_MB_2U_LIB.S9S_MB_2U(SCH_1):PAGE92
    48    GND @S9S_MB_2U_LIB.S9S_MB_2U(SCH_1):GND   I175 @S9S_MB_2U_LIB.S9S_MB_2U(SCH_1):PAGE92
    50    GND @S9S_MB_2U_LIB.S9S_MB_2U(SCH_1):GND   I175 @S9S_MB_2U_LIB.S9S_MB_2U(SCH_1):PAGE92
    52    GND @S9S_MB_2U_LIB.S9S_MB_2U(SCH_1):GND   I175 @S9S_MB_2U_LIB.S9S_MB_2U(SCH_1):PAGE92
    54    GND @S9S_MB_2U_LIB.S9S_MB_2U(SCH_1):GND   I175 @S9S_MB_2U_LIB.S9S_MB_2U(SCH_1):PAGE92
    57    GND @S9S_MB_2U_LIB.S9S_MB_2U(SCH_1):GND   I175 @S9S_MB_2U_LIB.S9S_MB_2U(SCH_1):PAGE92
    59    GND @S9S_MB_2U_LIB.S9S_MB_2U(SCH_1):GND   I175 @S9S_MB_2U_LIB.S9S_MB_2U(SCH_1):PAGE92
    61    GND @S9S_MB_2U_LIB.S9S_MB_2U(SCH_1):GND   I175 @S9S_MB_2U_LIB.S9S_MB_2U(SCH_1):PAGE92
    63    GND @S9S_MB_2U_LIB.S9S_MB_2U(SCH_1):GND   I175 @S9S_MB_2U_LIB.S9S_MB_2U(SCH_1):PAGE92
    65    GND @S9S_MB_2U_LIB.S9S_MB_2U(SCH_1):GND   I175 @S9S_MB_2U_LIB.S9S_MB_2U(SCH_1):PAGE92
    67    GND @S9S_MB_2U_LIB.S9S_MB_2U(SCH_1):GND   I175 @S9S_MB_2U_LIB.S9S_MB_2U(SCH_1):PAGE92
    69    GND @S9S_MB_2U_LIB.S9S_MB_2U(SCH_1):GND   I175 @S9S_MB_2U_LIB.S9S_MB_2U(SCH_1):PAGE92
    71    GND @S9S_MB_2U_LIB.S9S_MB_2U(SCH_1):GND   I175 @S9S_MB_2U_LIB.S9S_MB_2U(SCH_1):PAGE92
    73    GND @S9S_MB_2U_LIB.S9S_MB_2U(SCH_1):GND   I175 @S9S_MB_2U_LIB.S9S_MB_2U(SCH_1):PAGE92
    75    GND @S9S_MB_2U_LIB.S9S_MB_2U(SCH_1):GND   I175 @S9S_MB_2U_LIB.S9S_MB_2U(SCH_1):PAGE92
    77    GND @S9S_MB_2U_LIB.S9S_MB_2U(SCH_1):GND   I175 @S9S_MB_2U_LIB.S9S_MB_2U(SCH_1):PAGE92
    79    GND @S9S_MB_2U_LIB.S9S_MB_2U(SCH_1):GND   I175 @S9S_MB_2U_LIB.S9S_MB_2U(SCH_1):PAGE92
    81    GND @S9S_MB_2U_LIB.S9S_MB_2U(SCH_1):GND   I175 @S9S_MB_2U_LIB.S9S_MB_2U(SCH_1):PAGE92
    83    GND @S9S_MB_2U_LIB.S9S_MB_2U(SCH_1):GND   I175 @S9S_MB_2U_LIB.S9S_MB_2U(SCH_1):PAGE92
    85    GND @S9S_MB_2U_LIB.S9S_MB_2U(SCH_1):GND   I175 @S9S_MB_2U_LIB.S9S_MB_2U(SCH_1):PAGE92
    88    GND @S9S_MB_2U_LIB.S9S_MB_2U(SCH_1):GND   I175 @S9S_MB_2U_LIB.S9S_MB_2U(SCH_1):PAGE92
    90    GND @S9S_MB_2U_LIB.S9S_MB_2U(SCH_1):GND   I175 @S9S_MB_2U_LIB.S9S_MB_2U(SCH_1):PAGE92
    92    GND @S9S_MB_2U_LIB.S9S_MB_2U(SCH_1):GND   I175 @S9S_MB_2U_LIB.S9S_MB_2U(SCH_1):PAGE92
    95    GND @S9S_MB_2U_LIB.S9S_MB_2U(SCH_1):GND   I175 @S9S_MB_2U_LIB.S9S_MB_2U(SCH_1):PAGE92
    97    GND @S9S_MB_2U_LIB.S9S_MB_2U(SCH_1):GND   I175 @S9S_MB_2U_LIB.S9S_MB_2U(SCH_1):PAGE92
    99    GND @S9S_MB_2U_LIB.S9S_MB_2U(SCH_1):GND   I175 @S9S_MB_2U_LIB.S9S_MB_2U(SCH_1):PAGE92
   101    GND @S9S_MB_2U_LIB.S9S_MB_2U(SCH_1):GND   I175 @S9S_MB_2U_LIB.S9S_MB_2U(SCH_1):PAGE92
   103    GND @S9S_MB_2U_LIB.S9S_MB_2U(SCH_1):GND   I175 @S9S_MB_2U_LIB.S9S_MB_2U(SCH_1):PAGE92
   106    GND @S9S_MB_2U_LIB.S9S_MB_2U(SCH_1):GND   I175 @S9S_MB_2U_LIB.S9S_MB_2U(SCH_1):PAGE92
   108    GND @S9S_MB_2U_LIB.S9S_MB_2U(SCH_1):GND   I175 @S9S_MB_2U_LIB.S9S_MB_2U(SCH_1):PAGE92
   110    GND @S9S_MB_2U_LIB.S9S_MB_2U(SCH_1):GND   I175 @S9S_MB_2U_LIB.S9S_MB_2U(SCH_1):PAGE92
   112    GND @S9S_MB_2U_LIB.S9S_MB_2U(SCH_1):GND   I175 @S9S_MB_2U_LIB.S9S_MB_2U(SCH_1):PAGE92
   114    GND @S9S_MB_2U_LIB.S9S_MB_2U(SCH_1):GND   I175 @S9S_MB_2U_LIB.S9S_MB_2U(SCH_1):PAGE92
   117    GND @S9S_MB_2U_LIB.S9S_MB_2U(SCH_1):GND   I175 @S9S_MB_2U_LIB.S9S_MB_2U(SCH_1):PAGE92
   119    GND @S9S_MB_2U_LIB.S9S_MB_2U(SCH_1):GND   I175 @S9S_MB_2U_LIB.S9S_MB_2U(SCH_1):PAGE92
   121    GND @S9S_MB_2U_LIB.S9S_MB_2U(SCH_1):GND   I175 @S9S_MB_2U_LIB.S9S_MB_2U(SCH_1):PAGE92
   123    GND @S9S_MB_2U_LIB.S9S_MB_2U(SCH_1):GND   I175 @S9S_MB_2U_LIB.S9S_MB_2U(SCH_1):PAGE92
   125    GND @S9S_MB_2U_LIB.S9S_MB_2U(SCH_1):GND   I175 @S9S_MB_2U_LIB.S9S_MB_2U(SCH_1):PAGE92
   128    GND @S9S_MB_2U_LIB.S9S_MB_2U(SCH_1):GND   I175 @S9S_MB_2U_LIB.S9S_MB_2U(SCH_1):PAGE92
   130    GND @S9S_MB_2U_LIB.S9S_MB_2U(SCH_1):GND   I175 @S9S_MB_2U_LIB.S9S_MB_2U(SCH_1):PAGE92
   134    GND @S9S_MB_2U_LIB.S9S_MB_2U(SCH_1):GND   I175 @S9S_MB_2U_LIB.S9S_MB_2U(SCH_1):PAGE92
   143    GND @S9S_MB_2U_LIB.S9S_MB_2U(SCH_1):GND   I175 @S9S_MB_2U_LIB.S9S_MB_2U(SCH_1):PAGE92
   151    GND @S9S_MB_2U_LIB.S9S_MB_2U(SCH_1):GND   I175 @S9S_MB_2U_LIB.S9S_MB_2U(SCH_1):PAGE92
   153    GND @S9S_MB_2U_LIB.S9S_MB_2U(SCH_1):GND   I175 @S9S_MB_2U_LIB.S9S_MB_2U(SCH_1):PAGE92
   155    GND @S9S_MB_2U_LIB.S9S_MB_2U(SCH_1):GND   I175 @S9S_MB_2U_LIB.S9S_MB_2U(SCH_1):PAGE92
   158    GND @S9S_MB_2U_LIB.S9S_MB_2U(SCH_1):GND   I175 @S9S_MB_2U_LIB.S9S_MB_2U(SCH_1):PAGE92
   160    GND @S9S_MB_2U_LIB.S9S_MB_2U(SCH_1):GND   I175 @S9S_MB_2U_LIB.S9S_MB_2U(SCH_1):PAGE92
   162    GND @S9S_MB_2U_LIB.S9S_MB_2U(SCH_1):GND   I175 @S9S_MB_2U_LIB.S9S_MB_2U(SCH_1):PAGE92
   164    GND @S9S_MB_2U_LIB.S9S_MB_2U(SCH_1):GND   I175 @S9S_MB_2U_LIB.S9S_MB_2U(SCH_1):PAGE92
   166    GND @S9S_MB_2U_LIB.S9S_MB_2U(SCH_1):GND   I175 @S9S_MB_2U_LIB.S9S_MB_2U(SCH_1):PAGE92
   169    GND @S9S_MB_2U_LIB.S9S_MB_2U(SCH_1):GND   I175 @S9S_MB_2U_LIB.S9S_MB_2U(SCH_1):PAGE92
   171    GND @S9S_MB_2U_LIB.S9S_MB_2U(SCH_1):GND   I175 @S9S_MB_2U_LIB.S9S_MB_2U(SCH_1):PAGE92
   173    GND @S9S_MB_2U_LIB.S9S_MB_2U(SCH_1):GND   I175 @S9S_MB_2U_LIB.S9S_MB_2U(SCH_1):PAGE92
   175    GND @S9S_MB_2U_LIB.S9S_MB_2U(SCH_1):GND   I175 @S9S_MB_2U_LIB.S9S_MB_2U(SCH_1):PAGE92
   177    GND @S9S_MB_2U_LIB.S9S_MB_2U(SCH_1):GND   I175 @S9S_MB_2U_LIB.S9S_MB_2U(SCH_1):PAGE92
   180    GND @S9S_MB_2U_LIB.S9S_MB_2U(SCH_1):GND   I175 @S9S_MB_2U_LIB.S9S_MB_2U(SCH_1):PAGE92
   182    GND @S9S_MB_2U_LIB.S9S_MB_2U(SCH_1):GND   I175 @S9S_MB_2U_LIB.S9S_MB_2U(SCH_1):PAGE92
   184    GND @S9S_MB_2U_LIB.S9S_MB_2U(SCH_1):GND   I175 @S9S_MB_2U_LIB.S9S_MB_2U(SCH_1):PAGE92
   186    GND @S9S_MB_2U_LIB.S9S_MB_2U(SCH_1):GND   I175 @S9S_MB_2U_LIB.S9S_MB_2U(SCH_1):PAGE92
   188    GND @S9S_MB_2U_LIB.S9S_MB_2U(SCH_1):GND   I175 @S9S_MB_2U_LIB.S9S_MB_2U(SCH_1):PAGE92
   191    GND @S9S_MB_2U_LIB.S9S_MB_2U(SCH_1):GND   I175 @S9S_MB_2U_LIB.S9S_MB_2U(SCH_1):PAGE92
   193    GND @S9S_MB_2U_LIB.S9S_MB_2U(SCH_1):GND   I175 @S9S_MB_2U_LIB.S9S_MB_2U(SCH_1):PAGE92
   195    GND @S9S_MB_2U_LIB.S9S_MB_2U(SCH_1):GND   I175 @S9S_MB_2U_LIB.S9S_MB_2U(SCH_1):PAGE92
   197    GND @S9S_MB_2U_LIB.S9S_MB_2U(SCH_1):GND   I175 @S9S_MB_2U_LIB.S9S_MB_2U(SCH_1):PAGE92
   199    GND @S9S_MB_2U_LIB.S9S_MB_2U(SCH_1):GND   I175 @S9S_MB_2U_LIB.S9S_MB_2U(SCH_1):PAGE92
   202    GND @S9S_MB_2U_LIB.S9S_MB_2U(SCH_1):GND   I175 @S9S_MB_2U_LIB.S9S_MB_2U(SCH_1):PAGE92
   204    GND @S9S_MB_2U_LIB.S9S_MB_2U(SCH_1):GND   I175 @S9S_MB_2U_LIB.S9S_MB_2U(SCH_1):PAGE92
   206    GND @S9S_MB_2U_LIB.S9S_MB_2U(SCH_1):GND   I175 @S9S_MB_2U_LIB.S9S_MB_2U(SCH_1):PAGE92
   208    GND @S9S_MB_2U_LIB.S9S_MB_2U(SCH_1):GND   I175 @S9S_MB_2U_LIB.S9S_MB_2U(SCH_1):PAGE92
   210    GND @S9S_MB_2U_LIB.S9S_MB_2U(SCH_1):GND   I175 @S9S_MB_2U_LIB.S9S_MB_2U(SCH_1):PAGE92
   212    GND @S9S_MB_2U_LIB.S9S_MB_2U(SCH_1):GND   I175 @S9S_MB_2U_LIB.S9S_MB_2U(SCH_1):PAGE92
   214    GND @S9S_MB_2U_LIB.S9S_MB_2U(SCH_1):GND   I175 @S9S_MB_2U_LIB.S9S_MB_2U(SCH_1):PAGE92
   216    GND @S9S_MB_2U_LIB.S9S_MB_2U(SCH_1):GND   I175 @S9S_MB_2U_LIB.S9S_MB_2U(SCH_1):PAGE92
   219    GND @S9S_MB_2U_LIB.S9S_MB_2U(SCH_1):GND   I175 @S9S_MB_2U_LIB.S9S_MB_2U(SCH_1):PAGE92
   222    GND @S9S_MB_2U_LIB.S9S_MB_2U(SCH_1):GND   I175 @S9S_MB_2U_LIB.S9S_MB_2U(SCH_1):PAGE92
   224    GND @S9S_MB_2U_LIB.S9S_MB_2U(SCH_1):GND   I175 @S9S_MB_2U_LIB.S9S_MB_2U(SCH_1):PAGE92
   226    GND @S9S_MB_2U_LIB.S9S_MB_2U(SCH_1):GND   I175 @S9S_MB_2U_LIB.S9S_MB_2U(SCH_1):PAGE92
   228    GND @S9S_MB_2U_LIB.S9S_MB_2U(SCH_1):GND   I175 @S9S_MB_2U_LIB.S9S_MB_2U(SCH_1):PAGE92
   233    GND @S9S_MB_2U_LIB.S9S_MB_2U(SCH_1):GND   I175 @S9S_MB_2U_LIB.S9S_MB_2U(SCH_1):PAGE92
   237    GND @S9S_MB_2U_LIB.S9S_MB_2U(SCH_1):GND   I175 @S9S_MB_2U_LIB.S9S_MB_2U(SCH_1):PAGE92
   242    GND @S9S_MB_2U_LIB.S9S_MB_2U(SCH_1):GND   I175 @S9S_MB_2U_LIB.S9S_MB_2U(SCH_1):PAGE92
   244    GND @S9S_MB_2U_LIB.S9S_MB_2U(SCH_1):GND   I175 @S9S_MB_2U_LIB.S9S_MB_2U(SCH_1):PAGE92
   246    GND @S9S_MB_2U_LIB.S9S_MB_2U(SCH_1):GND   I175 @S9S_MB_2U_LIB.S9S_MB_2U(SCH_1):PAGE92
   248    GND @S9S_MB_2U_LIB.S9S_MB_2U(SCH_1):GND   I175 @S9S_MB_2U_LIB.S9S_MB_2U(SCH_1):PAGE92
   251    GND @S9S_MB_2U_LIB.S9S_MB_2U(SCH_1):GND   I175 @S9S_MB_2U_LIB.S9S_MB_2U(SCH_1):PAGE92
   253    GND @S9S_MB_2U_LIB.S9S_MB_2U(SCH_1):GND   I175 @S9S_MB_2U_LIB.S9S_MB_2U(SCH_1):PAGE92
   255    GND @S9S_MB_2U_LIB.S9S_MB_2U(SCH_1):GND   I175 @S9S_MB_2U_LIB.S9S_MB_2U(SCH_1):PAGE92
   257    GND @S9S_MB_2U_LIB.S9S_MB_2U(SCH_1):GND   I175 @S9S_MB_2U_LIB.S9S_MB_2U(SCH_1):PAGE92
   259    GND @S9S_MB_2U_LIB.S9S_MB_2U(SCH_1):GND   I175 @S9S_MB_2U_LIB.S9S_MB_2U(SCH_1):PAGE92
   262    GND @S9S_MB_2U_LIB.S9S_MB_2U(SCH_1):GND   I175 @S9S_MB_2U_LIB.S9S_MB_2U(SCH_1):PAGE92
   264    GND @S9S_MB_2U_LIB.S9S_MB_2U(SCH_1):GND   I175 @S9S_MB_2U_LIB.S9S_MB_2U(SCH_1):PAGE92
   266    GND @S9S_MB_2U_LIB.S9S_MB_2U(SCH_1):GND   I175 @S9S_MB_2U_LIB.S9S_MB_2U(SCH_1):PAGE92
   268    GND @S9S_MB_2U_LIB.S9S_MB_2U(SCH_1):GND   I175 @S9S_MB_2U_LIB.S9S_MB_2U(SCH_1):PAGE92
   270    GND @S9S_MB_2U_LIB.S9S_MB_2U(SCH_1):GND   I175 @S9S_MB_2U_LIB.S9S_MB_2U(SCH_1):PAGE92
   273    GND @S9S_MB_2U_LIB.S9S_MB_2U(SCH_1):GND   I175 @S9S_MB_2U_LIB.S9S_MB_2U(SCH_1):PAGE92
   275    GND @S9S_MB_2U_LIB.S9S_MB_2U(SCH_1):GND   I175 @S9S_MB_2U_LIB.S9S_MB_2U(SCH_1):PAGE92
   277    GND @S9S_MB_2U_LIB.S9S_MB_2U(SCH_1):GND   I175 @S9S_MB_2U_LIB.S9S_MB_2U(SCH_1):PAGE92
   279    GND @S9S_MB_2U_LIB.S9S_MB_2U(SCH_1):GND   I175 @S9S_MB_2U_LIB.S9S_MB_2U(SCH_1):PAGE92
   281    GND @S9S_MB_2U_LIB.S9S_MB_2U(SCH_1):GND   I175 @S9S_MB_2U_LIB.S9S_MB_2U(SCH_1):PAGE92
   284    GND @S9S_MB_2U_LIB.S9S_MB_2U(SCH_1):GND   I175 @S9S_MB_2U_LIB.S9S_MB_2U(SCH_1):PAGE92
   286    GND @S9S_MB_2U_LIB.S9S_MB_2U(SCH_1):GND   I175 @S9S_MB_2U_LIB.S9S_MB_2U(SCH_1):PAGE92
   288    GND @S9S_MB_2U_LIB.S9S_MB_2U(SCH_1):GND   I175 @S9S_MB_2U_LIB.S9S_MB_2U(SCH_1):PAGE92
     1 P12V_S3_AUX_CPU0_NVDIMM @S9S_MB_2U_LIB.S9S_MB_2U(SCH_1):P12V_S3_AUX_CPU0_NVDIMM   I175 @S9S_MB_2U_LIB.S9S_MB_2U(SCH_1):PAGE92
   145 P12V_S3_AUX_CPU0_NVDIMM @S9S_MB_2U_LIB.S9S_MB_2U(SCH_1):P12V_S3_AUX_CPU0_NVDIMM   I175 @S9S_MB_2U_LIB.S9S_MB_2U(SCH_1):PAGE92
   146 P12V_S3_AUX_CPU0_NVDIMM @S9S_MB_2U_LIB.S9S_MB_2U(SCH_1):P12V_S3_AUX_CPU0_NVDIMM   I175 @S9S_MB_2U_LIB.S9S_MB_2U(SCH_1):PAGE92
   230    GND @S9S_MB_2U_LIB.S9S_MB_2U(SCH_1):GND   I175 @S9S_MB_2U_LIB.S9S_MB_2U(SCH_1):PAGE92
   235    GND @S9S_MB_2U_LIB.S9S_MB_2U(SCH_1):GND   I175 @S9S_MB_2U_LIB.S9S_MB_2U(SCH_1):PAGE92
   240    GND @S9S_MB_2U_LIB.S9S_MB_2U(SCH_1):GND   I175 @S9S_MB_2U_LIB.S9S_MB_2U(SCH_1):PAGE92
   132    GND @S9S_MB_2U_LIB.S9S_MB_2U(SCH_1):GND   I175 @S9S_MB_2U_LIB.S9S_MB_2U(SCH_1):PAGE92
   136    GND @S9S_MB_2U_LIB.S9S_MB_2U(SCH_1):GND   I175 @S9S_MB_2U_LIB.S9S_MB_2U(SCH_1):PAGE92
   139    GND @S9S_MB_2U_LIB.S9S_MB_2U(SCH_1):GND   I175 @S9S_MB_2U_LIB.S9S_MB_2U(SCH_1):PAGE92
   141    GND @S9S_MB_2U_LIB.S9S_MB_2U(SCH_1):GND   I175 @S9S_MB_2U_LIB.S9S_MB_2U(SCH_1):PAGE92
    G1    GND @S9S_MB_2U_LIB.S9S_MB_2U(SCH_1):GND   I175 @S9S_MB_2U_LIB.S9S_MB_2U(SCH_1):PAGE92
    G2    GND @S9S_MB_2U_LIB.S9S_MB_2U(SCH_1):GND   I175 @S9S_MB_2U_LIB.S9S_MB_2U(SCH_1):PAGE92
    G3    GND @S9S_MB_2U_LIB.S9S_MB_2U(SCH_1):GND   I175 @S9S_MB_2U_LIB.S9S_MB_2U(SCH_1):PAGE92

 J12 SCONN288_ADR50017P087CC-SCONN2A
     3 P3V3_AUX @S9S_MB_2U_LIB.S9S_MB_2U(SCH_1):P3V3_AUX    I24 @S9S_MB_2U_LIB.S9S_MB_2U(SCH_1):PAGE93
     2 TP_CHF_CPU0_DIMM2_FRU_0 @S9S_MB_2U_LIB.S9S_MB_2U(SCH_1):TP_CHF_CPU0_DIMM2_FRU_0    I24 @S9S_MB_2U_LIB.S9S_MB_2U(SCH_1):PAGE93
   144 TP_CHF_CPU0_DIMM2_FRU_1 @S9S_MB_2U_LIB.S9S_MB_2U(SCH_1):TP_CHF_CPU0_DIMM2_FRU_1    I24 @S9S_MB_2U_LIB.S9S_MB_2U(SCH_1):PAGE93
   149 TP_CHF_CPU0_DIMM2_FRU_2 @S9S_MB_2U_LIB.S9S_MB_2U(SCH_1):TP_CHF_CPU0_DIMM2_FRU_2    I24 @S9S_MB_2U_LIB.S9S_MB_2U(SCH_1):PAGE93
   150 TP_CHF_CPU0_DIMM2_FRU_3 @S9S_MB_2U_LIB.S9S_MB_2U(SCH_1):TP_CHF_CPU0_DIMM2_FRU_3    I24 @S9S_MB_2U_LIB.S9S_MB_2U(SCH_1):PAGE93
   220 TP_CHF_CPU0_DIMM2_FRU_4 @S9S_MB_2U_LIB.S9S_MB_2U(SCH_1):TP_CHF_CPU0_DIMM2_FRU_4    I24 @S9S_MB_2U_LIB.S9S_MB_2U(SCH_1):PAGE93
   231 TP_CHF_CPU0_DIMM2_FRU_5 @S9S_MB_2U_LIB.S9S_MB_2U(SCH_1):TP_CHF_CPU0_DIMM2_FRU_5    I24 @S9S_MB_2U_LIB.S9S_MB_2U(SCH_1):PAGE93
   232 TP_CHF_CPU0_DIMM2_FRU_6 @S9S_MB_2U_LIB.S9S_MB_2U(SCH_1):TP_CHF_CPU0_DIMM2_FRU_6    I24 @S9S_MB_2U_LIB.S9S_MB_2U(SCH_1):PAGE93
   207 RST_M_EF_CPU0_FPGA_N @S9S_MB_2U_LIB.S9S_MB_2U(SCH_1):RST_M_EF_CPU0_FPGA_N    I24 @S9S_MB_2U_LIB.S9S_MB_2U(SCH_1):PAGE93
   147 PWRGD_CHF_CPU0_DIMM2 @S9S_MB_2U_LIB.S9S_MB_2U(SCH_1):PWRGD_CHF_CPU0_DIMM2    I24 @S9S_MB_2U_LIB.S9S_MB_2U(SCH_1):PAGE93
   227 M_F_CPU0_SB_PAR @S9S_MB_2U_LIB.S9S_MB_2U(SCH_1):M_F_CPU0_SB_PAR    I24 @S9S_MB_2U_LIB.S9S_MB_2U(SCH_1):PAGE93
    74 M_F_CPU0_SA_PAR @S9S_MB_2U_LIB.S9S_MB_2U(SCH_1):M_F_CPU0_SA_PAR    I24 @S9S_MB_2U_LIB.S9S_MB_2U(SCH_1):PAGE93
    87 M_F_CPU0_SB_RSP<1> @S9S_MB_2U_LIB.S9S_MB_2U(SCH_1):M_F_CPU0_SB_RSP(1)    I24 @S9S_MB_2U_LIB.S9S_MB_2U(SCH_1):PAGE93
    86 M_F_CPU0_SA_RSP<1> @S9S_MB_2U_LIB.S9S_MB_2U(SCH_1):M_F_CPU0_SA_RSP(1)    I24 @S9S_MB_2U_LIB.S9S_MB_2U(SCH_1):PAGE93
     5 I3C_SPD_DDREFGH_CPU0_LVC1_SDA @S9S_MB_2U_LIB.S9S_MB_2U(SCH_1):I3C_SPD_DDREFGH_CPU0_LVC1_SDA    I24 @S9S_MB_2U_LIB.S9S_MB_2U(SCH_1):PAGE93
     4 I3C_SPD_DDREFGH_CPU0_LVC1_SCL_3 @S9S_MB_2U_LIB.S9S_MB_2U(SCH_1):I3C_SPD_DDREFGH_CPU0_LVC1_SCL_R4    I24 @S9S_MB_2U_LIB.S9S_MB_2U(SCH_1):PAGE93
   148 PD_CHF_CPU0_DIMM2_SAA @S9S_MB_2U_LIB.S9S_MB_2U(SCH_1):PD_CHF_CPU0_DIMM2_SAA    I24 @S9S_MB_2U_LIB.S9S_MB_2U(SCH_1):PAGE93
   100 M_F_CPU0_SB_DQ<0> @S9S_MB_2U_LIB.S9S_MB_2U(SCH_1):M_F_CPU0_SB_DQ(0)    I24 @S9S_MB_2U_LIB.S9S_MB_2U(SCH_1):PAGE93
   102 M_F_CPU0_SB_DQ<1> @S9S_MB_2U_LIB.S9S_MB_2U(SCH_1):M_F_CPU0_SB_DQ(1)    I24 @S9S_MB_2U_LIB.S9S_MB_2U(SCH_1):PAGE93
   245 M_F_CPU0_SB_DQ<2> @S9S_MB_2U_LIB.S9S_MB_2U(SCH_1):M_F_CPU0_SB_DQ(2)    I24 @S9S_MB_2U_LIB.S9S_MB_2U(SCH_1):PAGE93
   247 M_F_CPU0_SB_DQ<3> @S9S_MB_2U_LIB.S9S_MB_2U(SCH_1):M_F_CPU0_SB_DQ(3)    I24 @S9S_MB_2U_LIB.S9S_MB_2U(SCH_1):PAGE93
   107 M_F_CPU0_SB_DQ<4> @S9S_MB_2U_LIB.S9S_MB_2U(SCH_1):M_F_CPU0_SB_DQ(4)    I24 @S9S_MB_2U_LIB.S9S_MB_2U(SCH_1):PAGE93
   109 M_F_CPU0_SB_DQ<5> @S9S_MB_2U_LIB.S9S_MB_2U(SCH_1):M_F_CPU0_SB_DQ(5)    I24 @S9S_MB_2U_LIB.S9S_MB_2U(SCH_1):PAGE93
   252 M_F_CPU0_SB_DQ<6> @S9S_MB_2U_LIB.S9S_MB_2U(SCH_1):M_F_CPU0_SB_DQ(6)    I24 @S9S_MB_2U_LIB.S9S_MB_2U(SCH_1):PAGE93
   254 M_F_CPU0_SB_DQ<7> @S9S_MB_2U_LIB.S9S_MB_2U(SCH_1):M_F_CPU0_SB_DQ(7)    I24 @S9S_MB_2U_LIB.S9S_MB_2U(SCH_1):PAGE93
   111 M_F_CPU0_SB_DQ<8> @S9S_MB_2U_LIB.S9S_MB_2U(SCH_1):M_F_CPU0_SB_DQ(8)    I24 @S9S_MB_2U_LIB.S9S_MB_2U(SCH_1):PAGE93
   113 M_F_CPU0_SB_DQ<9> @S9S_MB_2U_LIB.S9S_MB_2U(SCH_1):M_F_CPU0_SB_DQ(9)    I24 @S9S_MB_2U_LIB.S9S_MB_2U(SCH_1):PAGE93
   256 M_F_CPU0_SB_DQ<10> @S9S_MB_2U_LIB.S9S_MB_2U(SCH_1):M_F_CPU0_SB_DQ(10)    I24 @S9S_MB_2U_LIB.S9S_MB_2U(SCH_1):PAGE93
   258 M_F_CPU0_SB_DQ<11> @S9S_MB_2U_LIB.S9S_MB_2U(SCH_1):M_F_CPU0_SB_DQ(11)    I24 @S9S_MB_2U_LIB.S9S_MB_2U(SCH_1):PAGE93
   118 M_F_CPU0_SB_DQ<12> @S9S_MB_2U_LIB.S9S_MB_2U(SCH_1):M_F_CPU0_SB_DQ(12)    I24 @S9S_MB_2U_LIB.S9S_MB_2U(SCH_1):PAGE93
   120 M_F_CPU0_SB_DQ<13> @S9S_MB_2U_LIB.S9S_MB_2U(SCH_1):M_F_CPU0_SB_DQ(13)    I24 @S9S_MB_2U_LIB.S9S_MB_2U(SCH_1):PAGE93
   263 M_F_CPU0_SB_DQ<14> @S9S_MB_2U_LIB.S9S_MB_2U(SCH_1):M_F_CPU0_SB_DQ(14)    I24 @S9S_MB_2U_LIB.S9S_MB_2U(SCH_1):PAGE93
   265 M_F_CPU0_SB_DQ<15> @S9S_MB_2U_LIB.S9S_MB_2U(SCH_1):M_F_CPU0_SB_DQ(15)    I24 @S9S_MB_2U_LIB.S9S_MB_2U(SCH_1):PAGE93
   122 M_F_CPU0_SB_DQ<16> @S9S_MB_2U_LIB.S9S_MB_2U(SCH_1):M_F_CPU0_SB_DQ(16)    I24 @S9S_MB_2U_LIB.S9S_MB_2U(SCH_1):PAGE93
   124 M_F_CPU0_SB_DQ<17> @S9S_MB_2U_LIB.S9S_MB_2U(SCH_1):M_F_CPU0_SB_DQ(17)    I24 @S9S_MB_2U_LIB.S9S_MB_2U(SCH_1):PAGE93
   267 M_F_CPU0_SB_DQ<18> @S9S_MB_2U_LIB.S9S_MB_2U(SCH_1):M_F_CPU0_SB_DQ(18)    I24 @S9S_MB_2U_LIB.S9S_MB_2U(SCH_1):PAGE93
   269 M_F_CPU0_SB_DQ<19> @S9S_MB_2U_LIB.S9S_MB_2U(SCH_1):M_F_CPU0_SB_DQ(19)    I24 @S9S_MB_2U_LIB.S9S_MB_2U(SCH_1):PAGE93
   129 M_F_CPU0_SB_DQ<20> @S9S_MB_2U_LIB.S9S_MB_2U(SCH_1):M_F_CPU0_SB_DQ(20)    I24 @S9S_MB_2U_LIB.S9S_MB_2U(SCH_1):PAGE93
   131 M_F_CPU0_SB_DQ<21> @S9S_MB_2U_LIB.S9S_MB_2U(SCH_1):M_F_CPU0_SB_DQ(21)    I24 @S9S_MB_2U_LIB.S9S_MB_2U(SCH_1):PAGE93
   274 M_F_CPU0_SB_DQ<22> @S9S_MB_2U_LIB.S9S_MB_2U(SCH_1):M_F_CPU0_SB_DQ(22)    I24 @S9S_MB_2U_LIB.S9S_MB_2U(SCH_1):PAGE93
   276 M_F_CPU0_SB_DQ<23> @S9S_MB_2U_LIB.S9S_MB_2U(SCH_1):M_F_CPU0_SB_DQ(23)    I24 @S9S_MB_2U_LIB.S9S_MB_2U(SCH_1):PAGE93
   133 M_F_CPU0_SB_DQ<24> @S9S_MB_2U_LIB.S9S_MB_2U(SCH_1):M_F_CPU0_SB_DQ(24)    I24 @S9S_MB_2U_LIB.S9S_MB_2U(SCH_1):PAGE93
   135 M_F_CPU0_SB_DQ<25> @S9S_MB_2U_LIB.S9S_MB_2U(SCH_1):M_F_CPU0_SB_DQ(25)    I24 @S9S_MB_2U_LIB.S9S_MB_2U(SCH_1):PAGE93
   278 M_F_CPU0_SB_DQ<26> @S9S_MB_2U_LIB.S9S_MB_2U(SCH_1):M_F_CPU0_SB_DQ(26)    I24 @S9S_MB_2U_LIB.S9S_MB_2U(SCH_1):PAGE93
   280 M_F_CPU0_SB_DQ<27> @S9S_MB_2U_LIB.S9S_MB_2U(SCH_1):M_F_CPU0_SB_DQ(27)    I24 @S9S_MB_2U_LIB.S9S_MB_2U(SCH_1):PAGE93
   140 M_F_CPU0_SB_DQ<28> @S9S_MB_2U_LIB.S9S_MB_2U(SCH_1):M_F_CPU0_SB_DQ(28)    I24 @S9S_MB_2U_LIB.S9S_MB_2U(SCH_1):PAGE93
   142 M_F_CPU0_SB_DQ<29> @S9S_MB_2U_LIB.S9S_MB_2U(SCH_1):M_F_CPU0_SB_DQ(29)    I24 @S9S_MB_2U_LIB.S9S_MB_2U(SCH_1):PAGE93
   285 M_F_CPU0_SB_DQ<30> @S9S_MB_2U_LIB.S9S_MB_2U(SCH_1):M_F_CPU0_SB_DQ(30)    I24 @S9S_MB_2U_LIB.S9S_MB_2U(SCH_1):PAGE93
   287 M_F_CPU0_SB_DQ<31> @S9S_MB_2U_LIB.S9S_MB_2U(SCH_1):M_F_CPU0_SB_DQ(31)    I24 @S9S_MB_2U_LIB.S9S_MB_2U(SCH_1):PAGE93
     7 M_F_CPU0_SA_DQ<0> @S9S_MB_2U_LIB.S9S_MB_2U(SCH_1):M_F_CPU0_SA_DQ(0)    I24 @S9S_MB_2U_LIB.S9S_MB_2U(SCH_1):PAGE93
     9 M_F_CPU0_SA_DQ<1> @S9S_MB_2U_LIB.S9S_MB_2U(SCH_1):M_F_CPU0_SA_DQ(1)    I24 @S9S_MB_2U_LIB.S9S_MB_2U(SCH_1):PAGE93
   152 M_F_CPU0_SA_DQ<2> @S9S_MB_2U_LIB.S9S_MB_2U(SCH_1):M_F_CPU0_SA_DQ(2)    I24 @S9S_MB_2U_LIB.S9S_MB_2U(SCH_1):PAGE93
   154 M_F_CPU0_SA_DQ<3> @S9S_MB_2U_LIB.S9S_MB_2U(SCH_1):M_F_CPU0_SA_DQ(3)    I24 @S9S_MB_2U_LIB.S9S_MB_2U(SCH_1):PAGE93
    14 M_F_CPU0_SA_DQ<4> @S9S_MB_2U_LIB.S9S_MB_2U(SCH_1):M_F_CPU0_SA_DQ(4)    I24 @S9S_MB_2U_LIB.S9S_MB_2U(SCH_1):PAGE93
    16 M_F_CPU0_SA_DQ<5> @S9S_MB_2U_LIB.S9S_MB_2U(SCH_1):M_F_CPU0_SA_DQ(5)    I24 @S9S_MB_2U_LIB.S9S_MB_2U(SCH_1):PAGE93
   159 M_F_CPU0_SA_DQ<6> @S9S_MB_2U_LIB.S9S_MB_2U(SCH_1):M_F_CPU0_SA_DQ(6)    I24 @S9S_MB_2U_LIB.S9S_MB_2U(SCH_1):PAGE93
   161 M_F_CPU0_SA_DQ<7> @S9S_MB_2U_LIB.S9S_MB_2U(SCH_1):M_F_CPU0_SA_DQ(7)    I24 @S9S_MB_2U_LIB.S9S_MB_2U(SCH_1):PAGE93
    18 M_F_CPU0_SA_DQ<8> @S9S_MB_2U_LIB.S9S_MB_2U(SCH_1):M_F_CPU0_SA_DQ(8)    I24 @S9S_MB_2U_LIB.S9S_MB_2U(SCH_1):PAGE93
    20 M_F_CPU0_SA_DQ<9> @S9S_MB_2U_LIB.S9S_MB_2U(SCH_1):M_F_CPU0_SA_DQ(9)    I24 @S9S_MB_2U_LIB.S9S_MB_2U(SCH_1):PAGE93
   163 M_F_CPU0_SA_DQ<10> @S9S_MB_2U_LIB.S9S_MB_2U(SCH_1):M_F_CPU0_SA_DQ(10)    I24 @S9S_MB_2U_LIB.S9S_MB_2U(SCH_1):PAGE93
   165 M_F_CPU0_SA_DQ<11> @S9S_MB_2U_LIB.S9S_MB_2U(SCH_1):M_F_CPU0_SA_DQ(11)    I24 @S9S_MB_2U_LIB.S9S_MB_2U(SCH_1):PAGE93
    25 M_F_CPU0_SA_DQ<12> @S9S_MB_2U_LIB.S9S_MB_2U(SCH_1):M_F_CPU0_SA_DQ(12)    I24 @S9S_MB_2U_LIB.S9S_MB_2U(SCH_1):PAGE93
    27 M_F_CPU0_SA_DQ<13> @S9S_MB_2U_LIB.S9S_MB_2U(SCH_1):M_F_CPU0_SA_DQ(13)    I24 @S9S_MB_2U_LIB.S9S_MB_2U(SCH_1):PAGE93
   170 M_F_CPU0_SA_DQ<14> @S9S_MB_2U_LIB.S9S_MB_2U(SCH_1):M_F_CPU0_SA_DQ(14)    I24 @S9S_MB_2U_LIB.S9S_MB_2U(SCH_1):PAGE93
   172 M_F_CPU0_SA_DQ<15> @S9S_MB_2U_LIB.S9S_MB_2U(SCH_1):M_F_CPU0_SA_DQ(15)    I24 @S9S_MB_2U_LIB.S9S_MB_2U(SCH_1):PAGE93
    29 M_F_CPU0_SA_DQ<16> @S9S_MB_2U_LIB.S9S_MB_2U(SCH_1):M_F_CPU0_SA_DQ(16)    I24 @S9S_MB_2U_LIB.S9S_MB_2U(SCH_1):PAGE93
    31 M_F_CPU0_SA_DQ<17> @S9S_MB_2U_LIB.S9S_MB_2U(SCH_1):M_F_CPU0_SA_DQ(17)    I24 @S9S_MB_2U_LIB.S9S_MB_2U(SCH_1):PAGE93
   174 M_F_CPU0_SA_DQ<18> @S9S_MB_2U_LIB.S9S_MB_2U(SCH_1):M_F_CPU0_SA_DQ(18)    I24 @S9S_MB_2U_LIB.S9S_MB_2U(SCH_1):PAGE93
   176 M_F_CPU0_SA_DQ<19> @S9S_MB_2U_LIB.S9S_MB_2U(SCH_1):M_F_CPU0_SA_DQ(19)    I24 @S9S_MB_2U_LIB.S9S_MB_2U(SCH_1):PAGE93
    36 M_F_CPU0_SA_DQ<20> @S9S_MB_2U_LIB.S9S_MB_2U(SCH_1):M_F_CPU0_SA_DQ(20)    I24 @S9S_MB_2U_LIB.S9S_MB_2U(SCH_1):PAGE93
    38 M_F_CPU0_SA_DQ<21> @S9S_MB_2U_LIB.S9S_MB_2U(SCH_1):M_F_CPU0_SA_DQ(21)    I24 @S9S_MB_2U_LIB.S9S_MB_2U(SCH_1):PAGE93
   181 M_F_CPU0_SA_DQ<22> @S9S_MB_2U_LIB.S9S_MB_2U(SCH_1):M_F_CPU0_SA_DQ(22)    I24 @S9S_MB_2U_LIB.S9S_MB_2U(SCH_1):PAGE93
   183 M_F_CPU0_SA_DQ<23> @S9S_MB_2U_LIB.S9S_MB_2U(SCH_1):M_F_CPU0_SA_DQ(23)    I24 @S9S_MB_2U_LIB.S9S_MB_2U(SCH_1):PAGE93
    40 M_F_CPU0_SA_DQ<24> @S9S_MB_2U_LIB.S9S_MB_2U(SCH_1):M_F_CPU0_SA_DQ(24)    I24 @S9S_MB_2U_LIB.S9S_MB_2U(SCH_1):PAGE93
    42 M_F_CPU0_SA_DQ<25> @S9S_MB_2U_LIB.S9S_MB_2U(SCH_1):M_F_CPU0_SA_DQ(25)    I24 @S9S_MB_2U_LIB.S9S_MB_2U(SCH_1):PAGE93
   185 M_F_CPU0_SA_DQ<26> @S9S_MB_2U_LIB.S9S_MB_2U(SCH_1):M_F_CPU0_SA_DQ(26)    I24 @S9S_MB_2U_LIB.S9S_MB_2U(SCH_1):PAGE93
   187 M_F_CPU0_SA_DQ<27> @S9S_MB_2U_LIB.S9S_MB_2U(SCH_1):M_F_CPU0_SA_DQ(27)    I24 @S9S_MB_2U_LIB.S9S_MB_2U(SCH_1):PAGE93
    47 M_F_CPU0_SA_DQ<28> @S9S_MB_2U_LIB.S9S_MB_2U(SCH_1):M_F_CPU0_SA_DQ(28)    I24 @S9S_MB_2U_LIB.S9S_MB_2U(SCH_1):PAGE93
    49 M_F_CPU0_SA_DQ<29> @S9S_MB_2U_LIB.S9S_MB_2U(SCH_1):M_F_CPU0_SA_DQ(29)    I24 @S9S_MB_2U_LIB.S9S_MB_2U(SCH_1):PAGE93
   192 M_F_CPU0_SA_DQ<30> @S9S_MB_2U_LIB.S9S_MB_2U(SCH_1):M_F_CPU0_SA_DQ(30)    I24 @S9S_MB_2U_LIB.S9S_MB_2U(SCH_1):PAGE93
   229 M_F_CPU0_SB_CS_N<3> @S9S_MB_2U_LIB.S9S_MB_2U(SCH_1):M_F_CPU0_SB_CS_N(3)    I24 @S9S_MB_2U_LIB.S9S_MB_2U(SCH_1):PAGE93
   209 M_F_CPU0_SA_CS_N<3> @S9S_MB_2U_LIB.S9S_MB_2U(SCH_1):M_F_CPU0_SA_CS_N(3)    I24 @S9S_MB_2U_LIB.S9S_MB_2U(SCH_1):PAGE93
    84 M_F_CPU0_SB_CS_N<2> @S9S_MB_2U_LIB.S9S_MB_2U(SCH_1):M_F_CPU0_SB_CS_N(2)    I24 @S9S_MB_2U_LIB.S9S_MB_2U(SCH_1):PAGE93
    64 M_F_CPU0_SA_CS_N<2> @S9S_MB_2U_LIB.S9S_MB_2U(SCH_1):M_F_CPU0_SA_CS_N(2)    I24 @S9S_MB_2U_LIB.S9S_MB_2U(SCH_1):PAGE93
   217 M_F_CPU0_CLK_DP<1> @S9S_MB_2U_LIB.S9S_MB_2U(SCH_1):M_F_CPU0_CLK_DP(1)    I24 @S9S_MB_2U_LIB.S9S_MB_2U(SCH_1):PAGE93
   218 M_F_CPU0_CLK_DN<1> @S9S_MB_2U_LIB.S9S_MB_2U(SCH_1):M_F_CPU0_CLK_DN(1)    I24 @S9S_MB_2U_LIB.S9S_MB_2U(SCH_1):PAGE93
    96 M_F_CPU0_SB_CB<0> @S9S_MB_2U_LIB.S9S_MB_2U(SCH_1):M_F_CPU0_SB_CB(0)    I24 @S9S_MB_2U_LIB.S9S_MB_2U(SCH_1):PAGE93
    98 M_F_CPU0_SB_CB<1> @S9S_MB_2U_LIB.S9S_MB_2U(SCH_1):M_F_CPU0_SB_CB(1)    I24 @S9S_MB_2U_LIB.S9S_MB_2U(SCH_1):PAGE93
   241 M_F_CPU0_SB_CB<2> @S9S_MB_2U_LIB.S9S_MB_2U(SCH_1):M_F_CPU0_SB_CB(2)    I24 @S9S_MB_2U_LIB.S9S_MB_2U(SCH_1):PAGE93
   243 M_F_CPU0_SB_CB<3> @S9S_MB_2U_LIB.S9S_MB_2U(SCH_1):M_F_CPU0_SB_CB(3)    I24 @S9S_MB_2U_LIB.S9S_MB_2U(SCH_1):PAGE93
    89 M_F_CPU0_SB_CB<4> @S9S_MB_2U_LIB.S9S_MB_2U(SCH_1):M_F_CPU0_SB_CB(4)    I24 @S9S_MB_2U_LIB.S9S_MB_2U(SCH_1):PAGE93
    91 M_F_CPU0_SB_CB<5> @S9S_MB_2U_LIB.S9S_MB_2U(SCH_1):M_F_CPU0_SB_CB(5)    I24 @S9S_MB_2U_LIB.S9S_MB_2U(SCH_1):PAGE93
   234 M_F_CPU0_SB_CB<6> @S9S_MB_2U_LIB.S9S_MB_2U(SCH_1):M_F_CPU0_SB_CB(6)    I24 @S9S_MB_2U_LIB.S9S_MB_2U(SCH_1):PAGE93
    51 M_F_CPU0_SA_CB<0> @S9S_MB_2U_LIB.S9S_MB_2U(SCH_1):M_F_CPU0_SA_CB(0)    I24 @S9S_MB_2U_LIB.S9S_MB_2U(SCH_1):PAGE93
   196 M_F_CPU0_SA_CB<2> @S9S_MB_2U_LIB.S9S_MB_2U(SCH_1):M_F_CPU0_SA_CB(2)    I24 @S9S_MB_2U_LIB.S9S_MB_2U(SCH_1):PAGE93
   198 M_F_CPU0_SA_CB<3> @S9S_MB_2U_LIB.S9S_MB_2U(SCH_1):M_F_CPU0_SA_CB(3)    I24 @S9S_MB_2U_LIB.S9S_MB_2U(SCH_1):PAGE93
    60 M_F_CPU0_SA_CB<5> @S9S_MB_2U_LIB.S9S_MB_2U(SCH_1):M_F_CPU0_SA_CB(5)    I24 @S9S_MB_2U_LIB.S9S_MB_2U(SCH_1):PAGE93
   203 M_F_CPU0_SA_CB<6> @S9S_MB_2U_LIB.S9S_MB_2U(SCH_1):M_F_CPU0_SA_CB(6)    I24 @S9S_MB_2U_LIB.S9S_MB_2U(SCH_1):PAGE93
    82 M_F_CPU0_SB_CA<6> @S9S_MB_2U_LIB.S9S_MB_2U(SCH_1):M_F_CPU0_SB_CA(6)    I24 @S9S_MB_2U_LIB.S9S_MB_2U(SCH_1):PAGE93
    72 M_F_CPU0_SA_CA<6> @S9S_MB_2U_LIB.S9S_MB_2U(SCH_1):M_F_CPU0_SA_CA(6)    I24 @S9S_MB_2U_LIB.S9S_MB_2U(SCH_1):PAGE93
   225 M_F_CPU0_SB_CA<5> @S9S_MB_2U_LIB.S9S_MB_2U(SCH_1):M_F_CPU0_SB_CA(5)    I24 @S9S_MB_2U_LIB.S9S_MB_2U(SCH_1):PAGE93
   215 M_F_CPU0_SA_CA<5> @S9S_MB_2U_LIB.S9S_MB_2U(SCH_1):M_F_CPU0_SA_CA(5)    I24 @S9S_MB_2U_LIB.S9S_MB_2U(SCH_1):PAGE93
    80 M_F_CPU0_SB_CA<4> @S9S_MB_2U_LIB.S9S_MB_2U(SCH_1):M_F_CPU0_SB_CA(4)    I24 @S9S_MB_2U_LIB.S9S_MB_2U(SCH_1):PAGE93
    70 M_F_CPU0_SA_CA<4> @S9S_MB_2U_LIB.S9S_MB_2U(SCH_1):M_F_CPU0_SA_CA(4)    I24 @S9S_MB_2U_LIB.S9S_MB_2U(SCH_1):PAGE93
   223 M_F_CPU0_SB_CA<3> @S9S_MB_2U_LIB.S9S_MB_2U(SCH_1):M_F_CPU0_SB_CA(3)    I24 @S9S_MB_2U_LIB.S9S_MB_2U(SCH_1):PAGE93
   213 M_F_CPU0_SA_CA<3> @S9S_MB_2U_LIB.S9S_MB_2U(SCH_1):M_F_CPU0_SA_CA(3)    I24 @S9S_MB_2U_LIB.S9S_MB_2U(SCH_1):PAGE93
    78 M_F_CPU0_SB_CA<2> @S9S_MB_2U_LIB.S9S_MB_2U(SCH_1):M_F_CPU0_SB_CA(2)    I24 @S9S_MB_2U_LIB.S9S_MB_2U(SCH_1):PAGE93
    68 M_F_CPU0_SA_CA<2> @S9S_MB_2U_LIB.S9S_MB_2U(SCH_1):M_F_CPU0_SA_CA(2)    I24 @S9S_MB_2U_LIB.S9S_MB_2U(SCH_1):PAGE93
   221 M_F_CPU0_SB_CA<1> @S9S_MB_2U_LIB.S9S_MB_2U(SCH_1):M_F_CPU0_SB_CA(1)    I24 @S9S_MB_2U_LIB.S9S_MB_2U(SCH_1):PAGE93
   211 M_F_CPU0_SA_CA<1> @S9S_MB_2U_LIB.S9S_MB_2U(SCH_1):M_F_CPU0_SA_CA(1)    I24 @S9S_MB_2U_LIB.S9S_MB_2U(SCH_1):PAGE93
    76 M_F_CPU0_SB_CA<0> @S9S_MB_2U_LIB.S9S_MB_2U(SCH_1):M_F_CPU0_SB_CA(0)    I24 @S9S_MB_2U_LIB.S9S_MB_2U(SCH_1):PAGE93
    66 M_F_CPU0_SA_CA<0> @S9S_MB_2U_LIB.S9S_MB_2U(SCH_1):M_F_CPU0_SA_CA(0)    I24 @S9S_MB_2U_LIB.S9S_MB_2U(SCH_1):PAGE93
    62 M_F_CPU0_ALERT_N @S9S_MB_2U_LIB.S9S_MB_2U(SCH_1):M_F_CPU0_ALERT_N    I24 @S9S_MB_2U_LIB.S9S_MB_2U(SCH_1):PAGE93
   236 M_F_CPU0_SB_CB<7> @S9S_MB_2U_LIB.S9S_MB_2U(SCH_1):M_F_CPU0_SB_CB(7)    I24 @S9S_MB_2U_LIB.S9S_MB_2U(SCH_1):PAGE93
    53 M_F_CPU0_SA_CB<1> @S9S_MB_2U_LIB.S9S_MB_2U(SCH_1):M_F_CPU0_SA_CB(1)    I24 @S9S_MB_2U_LIB.S9S_MB_2U(SCH_1):PAGE93
    58 M_F_CPU0_SA_CB<4> @S9S_MB_2U_LIB.S9S_MB_2U(SCH_1):M_F_CPU0_SA_CB(4)    I24 @S9S_MB_2U_LIB.S9S_MB_2U(SCH_1):PAGE93
   205 M_F_CPU0_SA_CB<7> @S9S_MB_2U_LIB.S9S_MB_2U(SCH_1):M_F_CPU0_SA_CB(7)    I24 @S9S_MB_2U_LIB.S9S_MB_2U(SCH_1):PAGE93
   194 M_F_CPU0_SA_DQ<31> @S9S_MB_2U_LIB.S9S_MB_2U(SCH_1):M_F_CPU0_SA_DQ(31)    I24 @S9S_MB_2U_LIB.S9S_MB_2U(SCH_1):PAGE93
    93 M_F_CPU0_SB_DQS_DP<9> @S9S_MB_2U_LIB.S9S_MB_2U(SCH_1):M_F_CPU0_SB_DQS_DP(9)   I178 @S9S_MB_2U_LIB.S9S_MB_2U(SCH_1):PAGE93
    94 M_F_CPU0_SB_DQS_DN<9> @S9S_MB_2U_LIB.S9S_MB_2U(SCH_1):M_F_CPU0_SB_DQS_DN(9)   I178 @S9S_MB_2U_LIB.S9S_MB_2U(SCH_1):PAGE93
   201 M_F_CPU0_SA_DQS_DP<9> @S9S_MB_2U_LIB.S9S_MB_2U(SCH_1):M_F_CPU0_SA_DQS_DP(9)   I178 @S9S_MB_2U_LIB.S9S_MB_2U(SCH_1):PAGE93
   200 M_F_CPU0_SA_DQS_DN<9> @S9S_MB_2U_LIB.S9S_MB_2U(SCH_1):M_F_CPU0_SA_DQS_DN(9)   I178 @S9S_MB_2U_LIB.S9S_MB_2U(SCH_1):PAGE93
   190 M_F_CPU0_SA_DQS_DP<8> @S9S_MB_2U_LIB.S9S_MB_2U(SCH_1):M_F_CPU0_SA_DQS_DP(8)   I178 @S9S_MB_2U_LIB.S9S_MB_2U(SCH_1):PAGE93
   189 M_F_CPU0_SA_DQS_DN<8> @S9S_MB_2U_LIB.S9S_MB_2U(SCH_1):M_F_CPU0_SA_DQS_DN(8)   I178 @S9S_MB_2U_LIB.S9S_MB_2U(SCH_1):PAGE93
   271 M_F_CPU0_SB_DQS_DN<7> @S9S_MB_2U_LIB.S9S_MB_2U(SCH_1):M_F_CPU0_SB_DQS_DN(7)   I178 @S9S_MB_2U_LIB.S9S_MB_2U(SCH_1):PAGE93
   179 M_F_CPU0_SA_DQS_DP<7> @S9S_MB_2U_LIB.S9S_MB_2U(SCH_1):M_F_CPU0_SA_DQS_DP(7)   I178 @S9S_MB_2U_LIB.S9S_MB_2U(SCH_1):PAGE93
   261 M_F_CPU0_SB_DQS_DP<6> @S9S_MB_2U_LIB.S9S_MB_2U(SCH_1):M_F_CPU0_SB_DQS_DP(6)   I178 @S9S_MB_2U_LIB.S9S_MB_2U(SCH_1):PAGE93
   260 M_F_CPU0_SB_DQS_DN<6> @S9S_MB_2U_LIB.S9S_MB_2U(SCH_1):M_F_CPU0_SB_DQS_DN(6)   I178 @S9S_MB_2U_LIB.S9S_MB_2U(SCH_1):PAGE93
   167 M_F_CPU0_SA_DQS_DN<6> @S9S_MB_2U_LIB.S9S_MB_2U(SCH_1):M_F_CPU0_SA_DQS_DN(6)   I178 @S9S_MB_2U_LIB.S9S_MB_2U(SCH_1):PAGE93
   250 M_F_CPU0_SB_DQS_DP<5> @S9S_MB_2U_LIB.S9S_MB_2U(SCH_1):M_F_CPU0_SB_DQS_DP(5)   I178 @S9S_MB_2U_LIB.S9S_MB_2U(SCH_1):PAGE93
   249 M_F_CPU0_SB_DQS_DN<5> @S9S_MB_2U_LIB.S9S_MB_2U(SCH_1):M_F_CPU0_SB_DQS_DN(5)   I178 @S9S_MB_2U_LIB.S9S_MB_2U(SCH_1):PAGE93
   157 M_F_CPU0_SA_DQS_DP<5> @S9S_MB_2U_LIB.S9S_MB_2U(SCH_1):M_F_CPU0_SA_DQS_DP(5)   I178 @S9S_MB_2U_LIB.S9S_MB_2U(SCH_1):PAGE93
   156 M_F_CPU0_SA_DQS_DN<5> @S9S_MB_2U_LIB.S9S_MB_2U(SCH_1):M_F_CPU0_SA_DQS_DN(5)   I178 @S9S_MB_2U_LIB.S9S_MB_2U(SCH_1):PAGE93
   239 M_F_CPU0_SB_DQS_DP<4> @S9S_MB_2U_LIB.S9S_MB_2U(SCH_1):M_F_CPU0_SB_DQS_DP(4)   I178 @S9S_MB_2U_LIB.S9S_MB_2U(SCH_1):PAGE93
   238 M_F_CPU0_SB_DQS_DN<4> @S9S_MB_2U_LIB.S9S_MB_2U(SCH_1):M_F_CPU0_SB_DQS_DN(4)   I178 @S9S_MB_2U_LIB.S9S_MB_2U(SCH_1):PAGE93
    55 M_F_CPU0_SA_DQS_DP<4> @S9S_MB_2U_LIB.S9S_MB_2U(SCH_1):M_F_CPU0_SA_DQS_DP(4)   I178 @S9S_MB_2U_LIB.S9S_MB_2U(SCH_1):PAGE93
    56 M_F_CPU0_SA_DQS_DN<4> @S9S_MB_2U_LIB.S9S_MB_2U(SCH_1):M_F_CPU0_SA_DQS_DN(4)   I178 @S9S_MB_2U_LIB.S9S_MB_2U(SCH_1):PAGE93
   137 M_F_CPU0_SB_DQS_DP<3> @S9S_MB_2U_LIB.S9S_MB_2U(SCH_1):M_F_CPU0_SB_DQS_DP(3)   I178 @S9S_MB_2U_LIB.S9S_MB_2U(SCH_1):PAGE93
   138 M_F_CPU0_SB_DQS_DN<3> @S9S_MB_2U_LIB.S9S_MB_2U(SCH_1):M_F_CPU0_SB_DQS_DN(3)   I178 @S9S_MB_2U_LIB.S9S_MB_2U(SCH_1):PAGE93
    44 M_F_CPU0_SA_DQS_DP<3> @S9S_MB_2U_LIB.S9S_MB_2U(SCH_1):M_F_CPU0_SA_DQS_DP(3)   I178 @S9S_MB_2U_LIB.S9S_MB_2U(SCH_1):PAGE93
    45 M_F_CPU0_SA_DQS_DN<3> @S9S_MB_2U_LIB.S9S_MB_2U(SCH_1):M_F_CPU0_SA_DQS_DN(3)   I178 @S9S_MB_2U_LIB.S9S_MB_2U(SCH_1):PAGE93
   126 M_F_CPU0_SB_DQS_DP<2> @S9S_MB_2U_LIB.S9S_MB_2U(SCH_1):M_F_CPU0_SB_DQS_DP(2)   I178 @S9S_MB_2U_LIB.S9S_MB_2U(SCH_1):PAGE93
   127 M_F_CPU0_SB_DQS_DN<2> @S9S_MB_2U_LIB.S9S_MB_2U(SCH_1):M_F_CPU0_SB_DQS_DN(2)   I178 @S9S_MB_2U_LIB.S9S_MB_2U(SCH_1):PAGE93
    33 M_F_CPU0_SA_DQS_DP<2> @S9S_MB_2U_LIB.S9S_MB_2U(SCH_1):M_F_CPU0_SA_DQS_DP(2)   I178 @S9S_MB_2U_LIB.S9S_MB_2U(SCH_1):PAGE93
    34 M_F_CPU0_SA_DQS_DN<2> @S9S_MB_2U_LIB.S9S_MB_2U(SCH_1):M_F_CPU0_SA_DQS_DN(2)   I178 @S9S_MB_2U_LIB.S9S_MB_2U(SCH_1):PAGE93
   115 M_F_CPU0_SB_DQS_DP<1> @S9S_MB_2U_LIB.S9S_MB_2U(SCH_1):M_F_CPU0_SB_DQS_DP(1)   I178 @S9S_MB_2U_LIB.S9S_MB_2U(SCH_1):PAGE93
   116 M_F_CPU0_SB_DQS_DN<1> @S9S_MB_2U_LIB.S9S_MB_2U(SCH_1):M_F_CPU0_SB_DQS_DN(1)   I178 @S9S_MB_2U_LIB.S9S_MB_2U(SCH_1):PAGE93
    22 M_F_CPU0_SA_DQS_DP<1> @S9S_MB_2U_LIB.S9S_MB_2U(SCH_1):M_F_CPU0_SA_DQS_DP(1)   I178 @S9S_MB_2U_LIB.S9S_MB_2U(SCH_1):PAGE93
    23 M_F_CPU0_SA_DQS_DN<1> @S9S_MB_2U_LIB.S9S_MB_2U(SCH_1):M_F_CPU0_SA_DQS_DN(1)   I178 @S9S_MB_2U_LIB.S9S_MB_2U(SCH_1):PAGE93
   104 M_F_CPU0_SB_DQS_DP<0> @S9S_MB_2U_LIB.S9S_MB_2U(SCH_1):M_F_CPU0_SB_DQS_DP(0)   I178 @S9S_MB_2U_LIB.S9S_MB_2U(SCH_1):PAGE93
   105 M_F_CPU0_SB_DQS_DN<0> @S9S_MB_2U_LIB.S9S_MB_2U(SCH_1):M_F_CPU0_SB_DQS_DN(0)   I178 @S9S_MB_2U_LIB.S9S_MB_2U(SCH_1):PAGE93
    11 M_F_CPU0_SA_DQS_DP<0> @S9S_MB_2U_LIB.S9S_MB_2U(SCH_1):M_F_CPU0_SA_DQS_DP(0)   I178 @S9S_MB_2U_LIB.S9S_MB_2U(SCH_1):PAGE93
    12 M_F_CPU0_SA_DQS_DN<0> @S9S_MB_2U_LIB.S9S_MB_2U(SCH_1):M_F_CPU0_SA_DQS_DN(0)   I178 @S9S_MB_2U_LIB.S9S_MB_2U(SCH_1):PAGE93
   272 M_F_CPU0_SB_DQS_DP<7> @S9S_MB_2U_LIB.S9S_MB_2U(SCH_1):M_F_CPU0_SB_DQS_DP(7)   I178 @S9S_MB_2U_LIB.S9S_MB_2U(SCH_1):PAGE93
   282 M_F_CPU0_SB_DQS_DN<8> @S9S_MB_2U_LIB.S9S_MB_2U(SCH_1):M_F_CPU0_SB_DQS_DN(8)   I178 @S9S_MB_2U_LIB.S9S_MB_2U(SCH_1):PAGE93
   283 M_F_CPU0_SB_DQS_DP<8> @S9S_MB_2U_LIB.S9S_MB_2U(SCH_1):M_F_CPU0_SB_DQS_DP(8)   I178 @S9S_MB_2U_LIB.S9S_MB_2U(SCH_1):PAGE93
   168 M_F_CPU0_SA_DQS_DP<6> @S9S_MB_2U_LIB.S9S_MB_2U(SCH_1):M_F_CPU0_SA_DQS_DP(6)   I178 @S9S_MB_2U_LIB.S9S_MB_2U(SCH_1):PAGE93
   178 M_F_CPU0_SA_DQS_DN<7> @S9S_MB_2U_LIB.S9S_MB_2U(SCH_1):M_F_CPU0_SA_DQS_DN(7)   I178 @S9S_MB_2U_LIB.S9S_MB_2U(SCH_1):PAGE93
     6    GND @S9S_MB_2U_LIB.S9S_MB_2U(SCH_1):GND   I175 @S9S_MB_2U_LIB.S9S_MB_2U(SCH_1):PAGE93
     8    GND @S9S_MB_2U_LIB.S9S_MB_2U(SCH_1):GND   I175 @S9S_MB_2U_LIB.S9S_MB_2U(SCH_1):PAGE93
    10    GND @S9S_MB_2U_LIB.S9S_MB_2U(SCH_1):GND   I175 @S9S_MB_2U_LIB.S9S_MB_2U(SCH_1):PAGE93
    13    GND @S9S_MB_2U_LIB.S9S_MB_2U(SCH_1):GND   I175 @S9S_MB_2U_LIB.S9S_MB_2U(SCH_1):PAGE93
    15    GND @S9S_MB_2U_LIB.S9S_MB_2U(SCH_1):GND   I175 @S9S_MB_2U_LIB.S9S_MB_2U(SCH_1):PAGE93
    17    GND @S9S_MB_2U_LIB.S9S_MB_2U(SCH_1):GND   I175 @S9S_MB_2U_LIB.S9S_MB_2U(SCH_1):PAGE93
    19    GND @S9S_MB_2U_LIB.S9S_MB_2U(SCH_1):GND   I175 @S9S_MB_2U_LIB.S9S_MB_2U(SCH_1):PAGE93
    21    GND @S9S_MB_2U_LIB.S9S_MB_2U(SCH_1):GND   I175 @S9S_MB_2U_LIB.S9S_MB_2U(SCH_1):PAGE93
    24    GND @S9S_MB_2U_LIB.S9S_MB_2U(SCH_1):GND   I175 @S9S_MB_2U_LIB.S9S_MB_2U(SCH_1):PAGE93
    26    GND @S9S_MB_2U_LIB.S9S_MB_2U(SCH_1):GND   I175 @S9S_MB_2U_LIB.S9S_MB_2U(SCH_1):PAGE93
    28    GND @S9S_MB_2U_LIB.S9S_MB_2U(SCH_1):GND   I175 @S9S_MB_2U_LIB.S9S_MB_2U(SCH_1):PAGE93
    30    GND @S9S_MB_2U_LIB.S9S_MB_2U(SCH_1):GND   I175 @S9S_MB_2U_LIB.S9S_MB_2U(SCH_1):PAGE93
    32    GND @S9S_MB_2U_LIB.S9S_MB_2U(SCH_1):GND   I175 @S9S_MB_2U_LIB.S9S_MB_2U(SCH_1):PAGE93
    35    GND @S9S_MB_2U_LIB.S9S_MB_2U(SCH_1):GND   I175 @S9S_MB_2U_LIB.S9S_MB_2U(SCH_1):PAGE93
    37    GND @S9S_MB_2U_LIB.S9S_MB_2U(SCH_1):GND   I175 @S9S_MB_2U_LIB.S9S_MB_2U(SCH_1):PAGE93
    39    GND @S9S_MB_2U_LIB.S9S_MB_2U(SCH_1):GND   I175 @S9S_MB_2U_LIB.S9S_MB_2U(SCH_1):PAGE93
    41    GND @S9S_MB_2U_LIB.S9S_MB_2U(SCH_1):GND   I175 @S9S_MB_2U_LIB.S9S_MB_2U(SCH_1):PAGE93
    43    GND @S9S_MB_2U_LIB.S9S_MB_2U(SCH_1):GND   I175 @S9S_MB_2U_LIB.S9S_MB_2U(SCH_1):PAGE93
    46    GND @S9S_MB_2U_LIB.S9S_MB_2U(SCH_1):GND   I175 @S9S_MB_2U_LIB.S9S_MB_2U(SCH_1):PAGE93
    48    GND @S9S_MB_2U_LIB.S9S_MB_2U(SCH_1):GND   I175 @S9S_MB_2U_LIB.S9S_MB_2U(SCH_1):PAGE93
    50    GND @S9S_MB_2U_LIB.S9S_MB_2U(SCH_1):GND   I175 @S9S_MB_2U_LIB.S9S_MB_2U(SCH_1):PAGE93
    52    GND @S9S_MB_2U_LIB.S9S_MB_2U(SCH_1):GND   I175 @S9S_MB_2U_LIB.S9S_MB_2U(SCH_1):PAGE93
    54    GND @S9S_MB_2U_LIB.S9S_MB_2U(SCH_1):GND   I175 @S9S_MB_2U_LIB.S9S_MB_2U(SCH_1):PAGE93
    57    GND @S9S_MB_2U_LIB.S9S_MB_2U(SCH_1):GND   I175 @S9S_MB_2U_LIB.S9S_MB_2U(SCH_1):PAGE93
    59    GND @S9S_MB_2U_LIB.S9S_MB_2U(SCH_1):GND   I175 @S9S_MB_2U_LIB.S9S_MB_2U(SCH_1):PAGE93
    61    GND @S9S_MB_2U_LIB.S9S_MB_2U(SCH_1):GND   I175 @S9S_MB_2U_LIB.S9S_MB_2U(SCH_1):PAGE93
    63    GND @S9S_MB_2U_LIB.S9S_MB_2U(SCH_1):GND   I175 @S9S_MB_2U_LIB.S9S_MB_2U(SCH_1):PAGE93
    65    GND @S9S_MB_2U_LIB.S9S_MB_2U(SCH_1):GND   I175 @S9S_MB_2U_LIB.S9S_MB_2U(SCH_1):PAGE93
    67    GND @S9S_MB_2U_LIB.S9S_MB_2U(SCH_1):GND   I175 @S9S_MB_2U_LIB.S9S_MB_2U(SCH_1):PAGE93
    69    GND @S9S_MB_2U_LIB.S9S_MB_2U(SCH_1):GND   I175 @S9S_MB_2U_LIB.S9S_MB_2U(SCH_1):PAGE93
    71    GND @S9S_MB_2U_LIB.S9S_MB_2U(SCH_1):GND   I175 @S9S_MB_2U_LIB.S9S_MB_2U(SCH_1):PAGE93
    73    GND @S9S_MB_2U_LIB.S9S_MB_2U(SCH_1):GND   I175 @S9S_MB_2U_LIB.S9S_MB_2U(SCH_1):PAGE93
    75    GND @S9S_MB_2U_LIB.S9S_MB_2U(SCH_1):GND   I175 @S9S_MB_2U_LIB.S9S_MB_2U(SCH_1):PAGE93
    77    GND @S9S_MB_2U_LIB.S9S_MB_2U(SCH_1):GND   I175 @S9S_MB_2U_LIB.S9S_MB_2U(SCH_1):PAGE93
    79    GND @S9S_MB_2U_LIB.S9S_MB_2U(SCH_1):GND   I175 @S9S_MB_2U_LIB.S9S_MB_2U(SCH_1):PAGE93
    81    GND @S9S_MB_2U_LIB.S9S_MB_2U(SCH_1):GND   I175 @S9S_MB_2U_LIB.S9S_MB_2U(SCH_1):PAGE93
    83    GND @S9S_MB_2U_LIB.S9S_MB_2U(SCH_1):GND   I175 @S9S_MB_2U_LIB.S9S_MB_2U(SCH_1):PAGE93
    85    GND @S9S_MB_2U_LIB.S9S_MB_2U(SCH_1):GND   I175 @S9S_MB_2U_LIB.S9S_MB_2U(SCH_1):PAGE93
    88    GND @S9S_MB_2U_LIB.S9S_MB_2U(SCH_1):GND   I175 @S9S_MB_2U_LIB.S9S_MB_2U(SCH_1):PAGE93
    90    GND @S9S_MB_2U_LIB.S9S_MB_2U(SCH_1):GND   I175 @S9S_MB_2U_LIB.S9S_MB_2U(SCH_1):PAGE93
    92    GND @S9S_MB_2U_LIB.S9S_MB_2U(SCH_1):GND   I175 @S9S_MB_2U_LIB.S9S_MB_2U(SCH_1):PAGE93
    95    GND @S9S_MB_2U_LIB.S9S_MB_2U(SCH_1):GND   I175 @S9S_MB_2U_LIB.S9S_MB_2U(SCH_1):PAGE93
    97    GND @S9S_MB_2U_LIB.S9S_MB_2U(SCH_1):GND   I175 @S9S_MB_2U_LIB.S9S_MB_2U(SCH_1):PAGE93
    99    GND @S9S_MB_2U_LIB.S9S_MB_2U(SCH_1):GND   I175 @S9S_MB_2U_LIB.S9S_MB_2U(SCH_1):PAGE93
   101    GND @S9S_MB_2U_LIB.S9S_MB_2U(SCH_1):GND   I175 @S9S_MB_2U_LIB.S9S_MB_2U(SCH_1):PAGE93
   103    GND @S9S_MB_2U_LIB.S9S_MB_2U(SCH_1):GND   I175 @S9S_MB_2U_LIB.S9S_MB_2U(SCH_1):PAGE93
   106    GND @S9S_MB_2U_LIB.S9S_MB_2U(SCH_1):GND   I175 @S9S_MB_2U_LIB.S9S_MB_2U(SCH_1):PAGE93
   108    GND @S9S_MB_2U_LIB.S9S_MB_2U(SCH_1):GND   I175 @S9S_MB_2U_LIB.S9S_MB_2U(SCH_1):PAGE93
   110    GND @S9S_MB_2U_LIB.S9S_MB_2U(SCH_1):GND   I175 @S9S_MB_2U_LIB.S9S_MB_2U(SCH_1):PAGE93
   112    GND @S9S_MB_2U_LIB.S9S_MB_2U(SCH_1):GND   I175 @S9S_MB_2U_LIB.S9S_MB_2U(SCH_1):PAGE93
   114    GND @S9S_MB_2U_LIB.S9S_MB_2U(SCH_1):GND   I175 @S9S_MB_2U_LIB.S9S_MB_2U(SCH_1):PAGE93
   117    GND @S9S_MB_2U_LIB.S9S_MB_2U(SCH_1):GND   I175 @S9S_MB_2U_LIB.S9S_MB_2U(SCH_1):PAGE93
   119    GND @S9S_MB_2U_LIB.S9S_MB_2U(SCH_1):GND   I175 @S9S_MB_2U_LIB.S9S_MB_2U(SCH_1):PAGE93
   121    GND @S9S_MB_2U_LIB.S9S_MB_2U(SCH_1):GND   I175 @S9S_MB_2U_LIB.S9S_MB_2U(SCH_1):PAGE93
   123    GND @S9S_MB_2U_LIB.S9S_MB_2U(SCH_1):GND   I175 @S9S_MB_2U_LIB.S9S_MB_2U(SCH_1):PAGE93
   125    GND @S9S_MB_2U_LIB.S9S_MB_2U(SCH_1):GND   I175 @S9S_MB_2U_LIB.S9S_MB_2U(SCH_1):PAGE93
   128    GND @S9S_MB_2U_LIB.S9S_MB_2U(SCH_1):GND   I175 @S9S_MB_2U_LIB.S9S_MB_2U(SCH_1):PAGE93
   130    GND @S9S_MB_2U_LIB.S9S_MB_2U(SCH_1):GND   I175 @S9S_MB_2U_LIB.S9S_MB_2U(SCH_1):PAGE93
   134    GND @S9S_MB_2U_LIB.S9S_MB_2U(SCH_1):GND   I175 @S9S_MB_2U_LIB.S9S_MB_2U(SCH_1):PAGE93
   143    GND @S9S_MB_2U_LIB.S9S_MB_2U(SCH_1):GND   I175 @S9S_MB_2U_LIB.S9S_MB_2U(SCH_1):PAGE93
   151    GND @S9S_MB_2U_LIB.S9S_MB_2U(SCH_1):GND   I175 @S9S_MB_2U_LIB.S9S_MB_2U(SCH_1):PAGE93
   153    GND @S9S_MB_2U_LIB.S9S_MB_2U(SCH_1):GND   I175 @S9S_MB_2U_LIB.S9S_MB_2U(SCH_1):PAGE93
   155    GND @S9S_MB_2U_LIB.S9S_MB_2U(SCH_1):GND   I175 @S9S_MB_2U_LIB.S9S_MB_2U(SCH_1):PAGE93
   158    GND @S9S_MB_2U_LIB.S9S_MB_2U(SCH_1):GND   I175 @S9S_MB_2U_LIB.S9S_MB_2U(SCH_1):PAGE93
   160    GND @S9S_MB_2U_LIB.S9S_MB_2U(SCH_1):GND   I175 @S9S_MB_2U_LIB.S9S_MB_2U(SCH_1):PAGE93
   162    GND @S9S_MB_2U_LIB.S9S_MB_2U(SCH_1):GND   I175 @S9S_MB_2U_LIB.S9S_MB_2U(SCH_1):PAGE93
   164    GND @S9S_MB_2U_LIB.S9S_MB_2U(SCH_1):GND   I175 @S9S_MB_2U_LIB.S9S_MB_2U(SCH_1):PAGE93
   166    GND @S9S_MB_2U_LIB.S9S_MB_2U(SCH_1):GND   I175 @S9S_MB_2U_LIB.S9S_MB_2U(SCH_1):PAGE93
   169    GND @S9S_MB_2U_LIB.S9S_MB_2U(SCH_1):GND   I175 @S9S_MB_2U_LIB.S9S_MB_2U(SCH_1):PAGE93
   171    GND @S9S_MB_2U_LIB.S9S_MB_2U(SCH_1):GND   I175 @S9S_MB_2U_LIB.S9S_MB_2U(SCH_1):PAGE93
   173    GND @S9S_MB_2U_LIB.S9S_MB_2U(SCH_1):GND   I175 @S9S_MB_2U_LIB.S9S_MB_2U(SCH_1):PAGE93
   175    GND @S9S_MB_2U_LIB.S9S_MB_2U(SCH_1):GND   I175 @S9S_MB_2U_LIB.S9S_MB_2U(SCH_1):PAGE93
   177    GND @S9S_MB_2U_LIB.S9S_MB_2U(SCH_1):GND   I175 @S9S_MB_2U_LIB.S9S_MB_2U(SCH_1):PAGE93
   180    GND @S9S_MB_2U_LIB.S9S_MB_2U(SCH_1):GND   I175 @S9S_MB_2U_LIB.S9S_MB_2U(SCH_1):PAGE93
   182    GND @S9S_MB_2U_LIB.S9S_MB_2U(SCH_1):GND   I175 @S9S_MB_2U_LIB.S9S_MB_2U(SCH_1):PAGE93
   184    GND @S9S_MB_2U_LIB.S9S_MB_2U(SCH_1):GND   I175 @S9S_MB_2U_LIB.S9S_MB_2U(SCH_1):PAGE93
   186    GND @S9S_MB_2U_LIB.S9S_MB_2U(SCH_1):GND   I175 @S9S_MB_2U_LIB.S9S_MB_2U(SCH_1):PAGE93
   188    GND @S9S_MB_2U_LIB.S9S_MB_2U(SCH_1):GND   I175 @S9S_MB_2U_LIB.S9S_MB_2U(SCH_1):PAGE93
   191    GND @S9S_MB_2U_LIB.S9S_MB_2U(SCH_1):GND   I175 @S9S_MB_2U_LIB.S9S_MB_2U(SCH_1):PAGE93
   193    GND @S9S_MB_2U_LIB.S9S_MB_2U(SCH_1):GND   I175 @S9S_MB_2U_LIB.S9S_MB_2U(SCH_1):PAGE93
   195    GND @S9S_MB_2U_LIB.S9S_MB_2U(SCH_1):GND   I175 @S9S_MB_2U_LIB.S9S_MB_2U(SCH_1):PAGE93
   197    GND @S9S_MB_2U_LIB.S9S_MB_2U(SCH_1):GND   I175 @S9S_MB_2U_LIB.S9S_MB_2U(SCH_1):PAGE93
   199    GND @S9S_MB_2U_LIB.S9S_MB_2U(SCH_1):GND   I175 @S9S_MB_2U_LIB.S9S_MB_2U(SCH_1):PAGE93
   202    GND @S9S_MB_2U_LIB.S9S_MB_2U(SCH_1):GND   I175 @S9S_MB_2U_LIB.S9S_MB_2U(SCH_1):PAGE93
   204    GND @S9S_MB_2U_LIB.S9S_MB_2U(SCH_1):GND   I175 @S9S_MB_2U_LIB.S9S_MB_2U(SCH_1):PAGE93
   206    GND @S9S_MB_2U_LIB.S9S_MB_2U(SCH_1):GND   I175 @S9S_MB_2U_LIB.S9S_MB_2U(SCH_1):PAGE93
   208    GND @S9S_MB_2U_LIB.S9S_MB_2U(SCH_1):GND   I175 @S9S_MB_2U_LIB.S9S_MB_2U(SCH_1):PAGE93
   210    GND @S9S_MB_2U_LIB.S9S_MB_2U(SCH_1):GND   I175 @S9S_MB_2U_LIB.S9S_MB_2U(SCH_1):PAGE93
   212    GND @S9S_MB_2U_LIB.S9S_MB_2U(SCH_1):GND   I175 @S9S_MB_2U_LIB.S9S_MB_2U(SCH_1):PAGE93
   214    GND @S9S_MB_2U_LIB.S9S_MB_2U(SCH_1):GND   I175 @S9S_MB_2U_LIB.S9S_MB_2U(SCH_1):PAGE93
   216    GND @S9S_MB_2U_LIB.S9S_MB_2U(SCH_1):GND   I175 @S9S_MB_2U_LIB.S9S_MB_2U(SCH_1):PAGE93
   219    GND @S9S_MB_2U_LIB.S9S_MB_2U(SCH_1):GND   I175 @S9S_MB_2U_LIB.S9S_MB_2U(SCH_1):PAGE93
   222    GND @S9S_MB_2U_LIB.S9S_MB_2U(SCH_1):GND   I175 @S9S_MB_2U_LIB.S9S_MB_2U(SCH_1):PAGE93
   224    GND @S9S_MB_2U_LIB.S9S_MB_2U(SCH_1):GND   I175 @S9S_MB_2U_LIB.S9S_MB_2U(SCH_1):PAGE93
   226    GND @S9S_MB_2U_LIB.S9S_MB_2U(SCH_1):GND   I175 @S9S_MB_2U_LIB.S9S_MB_2U(SCH_1):PAGE93
   228    GND @S9S_MB_2U_LIB.S9S_MB_2U(SCH_1):GND   I175 @S9S_MB_2U_LIB.S9S_MB_2U(SCH_1):PAGE93
   233    GND @S9S_MB_2U_LIB.S9S_MB_2U(SCH_1):GND   I175 @S9S_MB_2U_LIB.S9S_MB_2U(SCH_1):PAGE93
   237    GND @S9S_MB_2U_LIB.S9S_MB_2U(SCH_1):GND   I175 @S9S_MB_2U_LIB.S9S_MB_2U(SCH_1):PAGE93
   242    GND @S9S_MB_2U_LIB.S9S_MB_2U(SCH_1):GND   I175 @S9S_MB_2U_LIB.S9S_MB_2U(SCH_1):PAGE93
   244    GND @S9S_MB_2U_LIB.S9S_MB_2U(SCH_1):GND   I175 @S9S_MB_2U_LIB.S9S_MB_2U(SCH_1):PAGE93
   246    GND @S9S_MB_2U_LIB.S9S_MB_2U(SCH_1):GND   I175 @S9S_MB_2U_LIB.S9S_MB_2U(SCH_1):PAGE93
   248    GND @S9S_MB_2U_LIB.S9S_MB_2U(SCH_1):GND   I175 @S9S_MB_2U_LIB.S9S_MB_2U(SCH_1):PAGE93
   251    GND @S9S_MB_2U_LIB.S9S_MB_2U(SCH_1):GND   I175 @S9S_MB_2U_LIB.S9S_MB_2U(SCH_1):PAGE93
   253    GND @S9S_MB_2U_LIB.S9S_MB_2U(SCH_1):GND   I175 @S9S_MB_2U_LIB.S9S_MB_2U(SCH_1):PAGE93
   255    GND @S9S_MB_2U_LIB.S9S_MB_2U(SCH_1):GND   I175 @S9S_MB_2U_LIB.S9S_MB_2U(SCH_1):PAGE93
   257    GND @S9S_MB_2U_LIB.S9S_MB_2U(SCH_1):GND   I175 @S9S_MB_2U_LIB.S9S_MB_2U(SCH_1):PAGE93
   259    GND @S9S_MB_2U_LIB.S9S_MB_2U(SCH_1):GND   I175 @S9S_MB_2U_LIB.S9S_MB_2U(SCH_1):PAGE93
   262    GND @S9S_MB_2U_LIB.S9S_MB_2U(SCH_1):GND   I175 @S9S_MB_2U_LIB.S9S_MB_2U(SCH_1):PAGE93
   264    GND @S9S_MB_2U_LIB.S9S_MB_2U(SCH_1):GND   I175 @S9S_MB_2U_LIB.S9S_MB_2U(SCH_1):PAGE93
   266    GND @S9S_MB_2U_LIB.S9S_MB_2U(SCH_1):GND   I175 @S9S_MB_2U_LIB.S9S_MB_2U(SCH_1):PAGE93
   268    GND @S9S_MB_2U_LIB.S9S_MB_2U(SCH_1):GND   I175 @S9S_MB_2U_LIB.S9S_MB_2U(SCH_1):PAGE93
   270    GND @S9S_MB_2U_LIB.S9S_MB_2U(SCH_1):GND   I175 @S9S_MB_2U_LIB.S9S_MB_2U(SCH_1):PAGE93
   273    GND @S9S_MB_2U_LIB.S9S_MB_2U(SCH_1):GND   I175 @S9S_MB_2U_LIB.S9S_MB_2U(SCH_1):PAGE93
   275    GND @S9S_MB_2U_LIB.S9S_MB_2U(SCH_1):GND   I175 @S9S_MB_2U_LIB.S9S_MB_2U(SCH_1):PAGE93
   277    GND @S9S_MB_2U_LIB.S9S_MB_2U(SCH_1):GND   I175 @S9S_MB_2U_LIB.S9S_MB_2U(SCH_1):PAGE93
   279    GND @S9S_MB_2U_LIB.S9S_MB_2U(SCH_1):GND   I175 @S9S_MB_2U_LIB.S9S_MB_2U(SCH_1):PAGE93
   281    GND @S9S_MB_2U_LIB.S9S_MB_2U(SCH_1):GND   I175 @S9S_MB_2U_LIB.S9S_MB_2U(SCH_1):PAGE93
   284    GND @S9S_MB_2U_LIB.S9S_MB_2U(SCH_1):GND   I175 @S9S_MB_2U_LIB.S9S_MB_2U(SCH_1):PAGE93
   286    GND @S9S_MB_2U_LIB.S9S_MB_2U(SCH_1):GND   I175 @S9S_MB_2U_LIB.S9S_MB_2U(SCH_1):PAGE93
   288    GND @S9S_MB_2U_LIB.S9S_MB_2U(SCH_1):GND   I175 @S9S_MB_2U_LIB.S9S_MB_2U(SCH_1):PAGE93
     1 P12V_S3_AUX_CPU0_NVDIMM @S9S_MB_2U_LIB.S9S_MB_2U(SCH_1):P12V_S3_AUX_CPU0_NVDIMM   I175 @S9S_MB_2U_LIB.S9S_MB_2U(SCH_1):PAGE93
   145 P12V_S3_AUX_CPU0_NVDIMM @S9S_MB_2U_LIB.S9S_MB_2U(SCH_1):P12V_S3_AUX_CPU0_NVDIMM   I175 @S9S_MB_2U_LIB.S9S_MB_2U(SCH_1):PAGE93
   146 P12V_S3_AUX_CPU0_NVDIMM @S9S_MB_2U_LIB.S9S_MB_2U(SCH_1):P12V_S3_AUX_CPU0_NVDIMM   I175 @S9S_MB_2U_LIB.S9S_MB_2U(SCH_1):PAGE93
   230    GND @S9S_MB_2U_LIB.S9S_MB_2U(SCH_1):GND   I175 @S9S_MB_2U_LIB.S9S_MB_2U(SCH_1):PAGE93
   235    GND @S9S_MB_2U_LIB.S9S_MB_2U(SCH_1):GND   I175 @S9S_MB_2U_LIB.S9S_MB_2U(SCH_1):PAGE93
   240    GND @S9S_MB_2U_LIB.S9S_MB_2U(SCH_1):GND   I175 @S9S_MB_2U_LIB.S9S_MB_2U(SCH_1):PAGE93
   132    GND @S9S_MB_2U_LIB.S9S_MB_2U(SCH_1):GND   I175 @S9S_MB_2U_LIB.S9S_MB_2U(SCH_1):PAGE93
   136    GND @S9S_MB_2U_LIB.S9S_MB_2U(SCH_1):GND   I175 @S9S_MB_2U_LIB.S9S_MB_2U(SCH_1):PAGE93
   139    GND @S9S_MB_2U_LIB.S9S_MB_2U(SCH_1):GND   I175 @S9S_MB_2U_LIB.S9S_MB_2U(SCH_1):PAGE93
   141    GND @S9S_MB_2U_LIB.S9S_MB_2U(SCH_1):GND   I175 @S9S_MB_2U_LIB.S9S_MB_2U(SCH_1):PAGE93
    G1    GND @S9S_MB_2U_LIB.S9S_MB_2U(SCH_1):GND   I175 @S9S_MB_2U_LIB.S9S_MB_2U(SCH_1):PAGE93
    G2    GND @S9S_MB_2U_LIB.S9S_MB_2U(SCH_1):GND   I175 @S9S_MB_2U_LIB.S9S_MB_2U(SCH_1):PAGE93
    G3    GND @S9S_MB_2U_LIB.S9S_MB_2U(SCH_1):GND   I175 @S9S_MB_2U_LIB.S9S_MB_2U(SCH_1):PAGE93

 J13 SCONN288_ADR50017P130CC-SCONN2A
     3 P3V3_AUX @S9S_MB_2U_LIB.S9S_MB_2U(SCH_1):P3V3_AUX    I11 @S9S_MB_2U_LIB.S9S_MB_2U(SCH_1):PAGE94
     2 TP_CHG_CPU0_DIMM1_FRU_0 @S9S_MB_2U_LIB.S9S_MB_2U(SCH_1):TP_CHG_CPU0_DIMM1_FRU_0    I11 @S9S_MB_2U_LIB.S9S_MB_2U(SCH_1):PAGE94
   144 TP_CHG_CPU0_DIMM1_FRU_1 @S9S_MB_2U_LIB.S9S_MB_2U(SCH_1):TP_CHG_CPU0_DIMM1_FRU_1    I11 @S9S_MB_2U_LIB.S9S_MB_2U(SCH_1):PAGE94
   149 TP_CHG_CPU0_DIMM1_FRU_2 @S9S_MB_2U_LIB.S9S_MB_2U(SCH_1):TP_CHG_CPU0_DIMM1_FRU_2    I11 @S9S_MB_2U_LIB.S9S_MB_2U(SCH_1):PAGE94
   150 TP_CHG_CPU0_DIMM1_FRU_3 @S9S_MB_2U_LIB.S9S_MB_2U(SCH_1):TP_CHG_CPU0_DIMM1_FRU_3    I11 @S9S_MB_2U_LIB.S9S_MB_2U(SCH_1):PAGE94
   220 TP_CHG_CPU0_DIMM1_FRU_4 @S9S_MB_2U_LIB.S9S_MB_2U(SCH_1):TP_CHG_CPU0_DIMM1_FRU_4    I11 @S9S_MB_2U_LIB.S9S_MB_2U(SCH_1):PAGE94
   231 TP_CHG_CPU0_DIMM1_FRU_5 @S9S_MB_2U_LIB.S9S_MB_2U(SCH_1):TP_CHG_CPU0_DIMM1_FRU_5    I11 @S9S_MB_2U_LIB.S9S_MB_2U(SCH_1):PAGE94
   232 TP_CHG_CPU0_DIMM1_FRU_6 @S9S_MB_2U_LIB.S9S_MB_2U(SCH_1):TP_CHG_CPU0_DIMM1_FRU_6    I11 @S9S_MB_2U_LIB.S9S_MB_2U(SCH_1):PAGE94
   207 RST_M_GH_CPU0_FPGA_N @S9S_MB_2U_LIB.S9S_MB_2U(SCH_1):RST_M_GH_CPU0_FPGA_N    I11 @S9S_MB_2U_LIB.S9S_MB_2U(SCH_1):PAGE94
   147 PWRGD_CHG_CPU0_DIMM1 @S9S_MB_2U_LIB.S9S_MB_2U(SCH_1):PWRGD_CHG_CPU0_DIMM1    I11 @S9S_MB_2U_LIB.S9S_MB_2U(SCH_1):PAGE94
   227 M_G_CPU0_SB_PAR @S9S_MB_2U_LIB.S9S_MB_2U(SCH_1):M_G_CPU0_SB_PAR    I11 @S9S_MB_2U_LIB.S9S_MB_2U(SCH_1):PAGE94
    74 M_G_CPU0_SA_PAR @S9S_MB_2U_LIB.S9S_MB_2U(SCH_1):M_G_CPU0_SA_PAR    I11 @S9S_MB_2U_LIB.S9S_MB_2U(SCH_1):PAGE94
    87 M_G_CPU0_SB_RSP<0> @S9S_MB_2U_LIB.S9S_MB_2U(SCH_1):M_G_CPU0_SB_RSP(0)    I11 @S9S_MB_2U_LIB.S9S_MB_2U(SCH_1):PAGE94
    86 M_G_CPU0_SA_RSP<0> @S9S_MB_2U_LIB.S9S_MB_2U(SCH_1):M_G_CPU0_SA_RSP(0)    I11 @S9S_MB_2U_LIB.S9S_MB_2U(SCH_1):PAGE94
     5 I3C_SPD_DDREFGH_CPU0_LVC1_SDA @S9S_MB_2U_LIB.S9S_MB_2U(SCH_1):I3C_SPD_DDREFGH_CPU0_LVC1_SDA    I11 @S9S_MB_2U_LIB.S9S_MB_2U(SCH_1):PAGE94
     4 I3C_SPD_DDREFGH_CPU0_LVC1_SCL_4 @S9S_MB_2U_LIB.S9S_MB_2U(SCH_1):I3C_SPD_DDREFGH_CPU0_LVC1_SCL_R5    I11 @S9S_MB_2U_LIB.S9S_MB_2U(SCH_1):PAGE94
   148 PD_CHG_CPU0_DIMM1_SAA @S9S_MB_2U_LIB.S9S_MB_2U(SCH_1):PD_CHG_CPU0_DIMM1_SAA    I11 @S9S_MB_2U_LIB.S9S_MB_2U(SCH_1):PAGE94
   100 M_G_CPU0_SB_DQ<0> @S9S_MB_2U_LIB.S9S_MB_2U(SCH_1):M_G_CPU0_SB_DQ(0)    I11 @S9S_MB_2U_LIB.S9S_MB_2U(SCH_1):PAGE94
   102 M_G_CPU0_SB_DQ<1> @S9S_MB_2U_LIB.S9S_MB_2U(SCH_1):M_G_CPU0_SB_DQ(1)    I11 @S9S_MB_2U_LIB.S9S_MB_2U(SCH_1):PAGE94
   245 M_G_CPU0_SB_DQ<2> @S9S_MB_2U_LIB.S9S_MB_2U(SCH_1):M_G_CPU0_SB_DQ(2)    I11 @S9S_MB_2U_LIB.S9S_MB_2U(SCH_1):PAGE94
   247 M_G_CPU0_SB_DQ<3> @S9S_MB_2U_LIB.S9S_MB_2U(SCH_1):M_G_CPU0_SB_DQ(3)    I11 @S9S_MB_2U_LIB.S9S_MB_2U(SCH_1):PAGE94
   107 M_G_CPU0_SB_DQ<4> @S9S_MB_2U_LIB.S9S_MB_2U(SCH_1):M_G_CPU0_SB_DQ(4)    I11 @S9S_MB_2U_LIB.S9S_MB_2U(SCH_1):PAGE94
   109 M_G_CPU0_SB_DQ<5> @S9S_MB_2U_LIB.S9S_MB_2U(SCH_1):M_G_CPU0_SB_DQ(5)    I11 @S9S_MB_2U_LIB.S9S_MB_2U(SCH_1):PAGE94
   252 M_G_CPU0_SB_DQ<6> @S9S_MB_2U_LIB.S9S_MB_2U(SCH_1):M_G_CPU0_SB_DQ(6)    I11 @S9S_MB_2U_LIB.S9S_MB_2U(SCH_1):PAGE94
   254 M_G_CPU0_SB_DQ<7> @S9S_MB_2U_LIB.S9S_MB_2U(SCH_1):M_G_CPU0_SB_DQ(7)    I11 @S9S_MB_2U_LIB.S9S_MB_2U(SCH_1):PAGE94
   111 M_G_CPU0_SB_DQ<8> @S9S_MB_2U_LIB.S9S_MB_2U(SCH_1):M_G_CPU0_SB_DQ(8)    I11 @S9S_MB_2U_LIB.S9S_MB_2U(SCH_1):PAGE94
   113 M_G_CPU0_SB_DQ<9> @S9S_MB_2U_LIB.S9S_MB_2U(SCH_1):M_G_CPU0_SB_DQ(9)    I11 @S9S_MB_2U_LIB.S9S_MB_2U(SCH_1):PAGE94
   256 M_G_CPU0_SB_DQ<10> @S9S_MB_2U_LIB.S9S_MB_2U(SCH_1):M_G_CPU0_SB_DQ(10)    I11 @S9S_MB_2U_LIB.S9S_MB_2U(SCH_1):PAGE94
   258 M_G_CPU0_SB_DQ<11> @S9S_MB_2U_LIB.S9S_MB_2U(SCH_1):M_G_CPU0_SB_DQ(11)    I11 @S9S_MB_2U_LIB.S9S_MB_2U(SCH_1):PAGE94
   118 M_G_CPU0_SB_DQ<12> @S9S_MB_2U_LIB.S9S_MB_2U(SCH_1):M_G_CPU0_SB_DQ(12)    I11 @S9S_MB_2U_LIB.S9S_MB_2U(SCH_1):PAGE94
   120 M_G_CPU0_SB_DQ<13> @S9S_MB_2U_LIB.S9S_MB_2U(SCH_1):M_G_CPU0_SB_DQ(13)    I11 @S9S_MB_2U_LIB.S9S_MB_2U(SCH_1):PAGE94
   263 M_G_CPU0_SB_DQ<14> @S9S_MB_2U_LIB.S9S_MB_2U(SCH_1):M_G_CPU0_SB_DQ(14)    I11 @S9S_MB_2U_LIB.S9S_MB_2U(SCH_1):PAGE94
   265 M_G_CPU0_SB_DQ<15> @S9S_MB_2U_LIB.S9S_MB_2U(SCH_1):M_G_CPU0_SB_DQ(15)    I11 @S9S_MB_2U_LIB.S9S_MB_2U(SCH_1):PAGE94
   122 M_G_CPU0_SB_DQ<16> @S9S_MB_2U_LIB.S9S_MB_2U(SCH_1):M_G_CPU0_SB_DQ(16)    I11 @S9S_MB_2U_LIB.S9S_MB_2U(SCH_1):PAGE94
   124 M_G_CPU0_SB_DQ<17> @S9S_MB_2U_LIB.S9S_MB_2U(SCH_1):M_G_CPU0_SB_DQ(17)    I11 @S9S_MB_2U_LIB.S9S_MB_2U(SCH_1):PAGE94
   267 M_G_CPU0_SB_DQ<18> @S9S_MB_2U_LIB.S9S_MB_2U(SCH_1):M_G_CPU0_SB_DQ(18)    I11 @S9S_MB_2U_LIB.S9S_MB_2U(SCH_1):PAGE94
   269 M_G_CPU0_SB_DQ<19> @S9S_MB_2U_LIB.S9S_MB_2U(SCH_1):M_G_CPU0_SB_DQ(19)    I11 @S9S_MB_2U_LIB.S9S_MB_2U(SCH_1):PAGE94
   129 M_G_CPU0_SB_DQ<20> @S9S_MB_2U_LIB.S9S_MB_2U(SCH_1):M_G_CPU0_SB_DQ(20)    I11 @S9S_MB_2U_LIB.S9S_MB_2U(SCH_1):PAGE94
   131 M_G_CPU0_SB_DQ<21> @S9S_MB_2U_LIB.S9S_MB_2U(SCH_1):M_G_CPU0_SB_DQ(21)    I11 @S9S_MB_2U_LIB.S9S_MB_2U(SCH_1):PAGE94
   274 M_G_CPU0_SB_DQ<22> @S9S_MB_2U_LIB.S9S_MB_2U(SCH_1):M_G_CPU0_SB_DQ(22)    I11 @S9S_MB_2U_LIB.S9S_MB_2U(SCH_1):PAGE94
   276 M_G_CPU0_SB_DQ<23> @S9S_MB_2U_LIB.S9S_MB_2U(SCH_1):M_G_CPU0_SB_DQ(23)    I11 @S9S_MB_2U_LIB.S9S_MB_2U(SCH_1):PAGE94
   133 M_G_CPU0_SB_DQ<24> @S9S_MB_2U_LIB.S9S_MB_2U(SCH_1):M_G_CPU0_SB_DQ(24)    I11 @S9S_MB_2U_LIB.S9S_MB_2U(SCH_1):PAGE94
   135 M_G_CPU0_SB_DQ<25> @S9S_MB_2U_LIB.S9S_MB_2U(SCH_1):M_G_CPU0_SB_DQ(25)    I11 @S9S_MB_2U_LIB.S9S_MB_2U(SCH_1):PAGE94
   278 M_G_CPU0_SB_DQ<26> @S9S_MB_2U_LIB.S9S_MB_2U(SCH_1):M_G_CPU0_SB_DQ(26)    I11 @S9S_MB_2U_LIB.S9S_MB_2U(SCH_1):PAGE94
   280 M_G_CPU0_SB_DQ<27> @S9S_MB_2U_LIB.S9S_MB_2U(SCH_1):M_G_CPU0_SB_DQ(27)    I11 @S9S_MB_2U_LIB.S9S_MB_2U(SCH_1):PAGE94
   140 M_G_CPU0_SB_DQ<28> @S9S_MB_2U_LIB.S9S_MB_2U(SCH_1):M_G_CPU0_SB_DQ(28)    I11 @S9S_MB_2U_LIB.S9S_MB_2U(SCH_1):PAGE94
   142 M_G_CPU0_SB_DQ<29> @S9S_MB_2U_LIB.S9S_MB_2U(SCH_1):M_G_CPU0_SB_DQ(29)    I11 @S9S_MB_2U_LIB.S9S_MB_2U(SCH_1):PAGE94
   285 M_G_CPU0_SB_DQ<30> @S9S_MB_2U_LIB.S9S_MB_2U(SCH_1):M_G_CPU0_SB_DQ(30)    I11 @S9S_MB_2U_LIB.S9S_MB_2U(SCH_1):PAGE94
   287 M_G_CPU0_SB_DQ<31> @S9S_MB_2U_LIB.S9S_MB_2U(SCH_1):M_G_CPU0_SB_DQ(31)    I11 @S9S_MB_2U_LIB.S9S_MB_2U(SCH_1):PAGE94
     7 M_G_CPU0_SA_DQ<0> @S9S_MB_2U_LIB.S9S_MB_2U(SCH_1):M_G_CPU0_SA_DQ(0)    I11 @S9S_MB_2U_LIB.S9S_MB_2U(SCH_1):PAGE94
     9 M_G_CPU0_SA_DQ<1> @S9S_MB_2U_LIB.S9S_MB_2U(SCH_1):M_G_CPU0_SA_DQ(1)    I11 @S9S_MB_2U_LIB.S9S_MB_2U(SCH_1):PAGE94
   152 M_G_CPU0_SA_DQ<2> @S9S_MB_2U_LIB.S9S_MB_2U(SCH_1):M_G_CPU0_SA_DQ(2)    I11 @S9S_MB_2U_LIB.S9S_MB_2U(SCH_1):PAGE94
   154 M_G_CPU0_SA_DQ<3> @S9S_MB_2U_LIB.S9S_MB_2U(SCH_1):M_G_CPU0_SA_DQ(3)    I11 @S9S_MB_2U_LIB.S9S_MB_2U(SCH_1):PAGE94
    14 M_G_CPU0_SA_DQ<4> @S9S_MB_2U_LIB.S9S_MB_2U(SCH_1):M_G_CPU0_SA_DQ(4)    I11 @S9S_MB_2U_LIB.S9S_MB_2U(SCH_1):PAGE94
    16 M_G_CPU0_SA_DQ<5> @S9S_MB_2U_LIB.S9S_MB_2U(SCH_1):M_G_CPU0_SA_DQ(5)    I11 @S9S_MB_2U_LIB.S9S_MB_2U(SCH_1):PAGE94
   159 M_G_CPU0_SA_DQ<6> @S9S_MB_2U_LIB.S9S_MB_2U(SCH_1):M_G_CPU0_SA_DQ(6)    I11 @S9S_MB_2U_LIB.S9S_MB_2U(SCH_1):PAGE94
   161 M_G_CPU0_SA_DQ<7> @S9S_MB_2U_LIB.S9S_MB_2U(SCH_1):M_G_CPU0_SA_DQ(7)    I11 @S9S_MB_2U_LIB.S9S_MB_2U(SCH_1):PAGE94
    18 M_G_CPU0_SA_DQ<8> @S9S_MB_2U_LIB.S9S_MB_2U(SCH_1):M_G_CPU0_SA_DQ(8)    I11 @S9S_MB_2U_LIB.S9S_MB_2U(SCH_1):PAGE94
    20 M_G_CPU0_SA_DQ<9> @S9S_MB_2U_LIB.S9S_MB_2U(SCH_1):M_G_CPU0_SA_DQ(9)    I11 @S9S_MB_2U_LIB.S9S_MB_2U(SCH_1):PAGE94
   163 M_G_CPU0_SA_DQ<10> @S9S_MB_2U_LIB.S9S_MB_2U(SCH_1):M_G_CPU0_SA_DQ(10)    I11 @S9S_MB_2U_LIB.S9S_MB_2U(SCH_1):PAGE94
   165 M_G_CPU0_SA_DQ<11> @S9S_MB_2U_LIB.S9S_MB_2U(SCH_1):M_G_CPU0_SA_DQ(11)    I11 @S9S_MB_2U_LIB.S9S_MB_2U(SCH_1):PAGE94
    25 M_G_CPU0_SA_DQ<12> @S9S_MB_2U_LIB.S9S_MB_2U(SCH_1):M_G_CPU0_SA_DQ(12)    I11 @S9S_MB_2U_LIB.S9S_MB_2U(SCH_1):PAGE94
    27 M_G_CPU0_SA_DQ<13> @S9S_MB_2U_LIB.S9S_MB_2U(SCH_1):M_G_CPU0_SA_DQ(13)    I11 @S9S_MB_2U_LIB.S9S_MB_2U(SCH_1):PAGE94
   170 M_G_CPU0_SA_DQ<14> @S9S_MB_2U_LIB.S9S_MB_2U(SCH_1):M_G_CPU0_SA_DQ(14)    I11 @S9S_MB_2U_LIB.S9S_MB_2U(SCH_1):PAGE94
   172 M_G_CPU0_SA_DQ<15> @S9S_MB_2U_LIB.S9S_MB_2U(SCH_1):M_G_CPU0_SA_DQ(15)    I11 @S9S_MB_2U_LIB.S9S_MB_2U(SCH_1):PAGE94
    29 M_G_CPU0_SA_DQ<16> @S9S_MB_2U_LIB.S9S_MB_2U(SCH_1):M_G_CPU0_SA_DQ(16)    I11 @S9S_MB_2U_LIB.S9S_MB_2U(SCH_1):PAGE94
    31 M_G_CPU0_SA_DQ<17> @S9S_MB_2U_LIB.S9S_MB_2U(SCH_1):M_G_CPU0_SA_DQ(17)    I11 @S9S_MB_2U_LIB.S9S_MB_2U(SCH_1):PAGE94
   174 M_G_CPU0_SA_DQ<18> @S9S_MB_2U_LIB.S9S_MB_2U(SCH_1):M_G_CPU0_SA_DQ(18)    I11 @S9S_MB_2U_LIB.S9S_MB_2U(SCH_1):PAGE94
   176 M_G_CPU0_SA_DQ<19> @S9S_MB_2U_LIB.S9S_MB_2U(SCH_1):M_G_CPU0_SA_DQ(19)    I11 @S9S_MB_2U_LIB.S9S_MB_2U(SCH_1):PAGE94
    36 M_G_CPU0_SA_DQ<20> @S9S_MB_2U_LIB.S9S_MB_2U(SCH_1):M_G_CPU0_SA_DQ(20)    I11 @S9S_MB_2U_LIB.S9S_MB_2U(SCH_1):PAGE94
    38 M_G_CPU0_SA_DQ<21> @S9S_MB_2U_LIB.S9S_MB_2U(SCH_1):M_G_CPU0_SA_DQ(21)    I11 @S9S_MB_2U_LIB.S9S_MB_2U(SCH_1):PAGE94
   181 M_G_CPU0_SA_DQ<22> @S9S_MB_2U_LIB.S9S_MB_2U(SCH_1):M_G_CPU0_SA_DQ(22)    I11 @S9S_MB_2U_LIB.S9S_MB_2U(SCH_1):PAGE94
   183 M_G_CPU0_SA_DQ<23> @S9S_MB_2U_LIB.S9S_MB_2U(SCH_1):M_G_CPU0_SA_DQ(23)    I11 @S9S_MB_2U_LIB.S9S_MB_2U(SCH_1):PAGE94
    40 M_G_CPU0_SA_DQ<24> @S9S_MB_2U_LIB.S9S_MB_2U(SCH_1):M_G_CPU0_SA_DQ(24)    I11 @S9S_MB_2U_LIB.S9S_MB_2U(SCH_1):PAGE94
    42 M_G_CPU0_SA_DQ<25> @S9S_MB_2U_LIB.S9S_MB_2U(SCH_1):M_G_CPU0_SA_DQ(25)    I11 @S9S_MB_2U_LIB.S9S_MB_2U(SCH_1):PAGE94
   185 M_G_CPU0_SA_DQ<26> @S9S_MB_2U_LIB.S9S_MB_2U(SCH_1):M_G_CPU0_SA_DQ(26)    I11 @S9S_MB_2U_LIB.S9S_MB_2U(SCH_1):PAGE94
   187 M_G_CPU0_SA_DQ<27> @S9S_MB_2U_LIB.S9S_MB_2U(SCH_1):M_G_CPU0_SA_DQ(27)    I11 @S9S_MB_2U_LIB.S9S_MB_2U(SCH_1):PAGE94
    47 M_G_CPU0_SA_DQ<28> @S9S_MB_2U_LIB.S9S_MB_2U(SCH_1):M_G_CPU0_SA_DQ(28)    I11 @S9S_MB_2U_LIB.S9S_MB_2U(SCH_1):PAGE94
    49 M_G_CPU0_SA_DQ<29> @S9S_MB_2U_LIB.S9S_MB_2U(SCH_1):M_G_CPU0_SA_DQ(29)    I11 @S9S_MB_2U_LIB.S9S_MB_2U(SCH_1):PAGE94
   192 M_G_CPU0_SA_DQ<30> @S9S_MB_2U_LIB.S9S_MB_2U(SCH_1):M_G_CPU0_SA_DQ(30)    I11 @S9S_MB_2U_LIB.S9S_MB_2U(SCH_1):PAGE94
   229 M_G_CPU0_SB_CS_N<1> @S9S_MB_2U_LIB.S9S_MB_2U(SCH_1):M_G_CPU0_SB_CS_N(1)    I11 @S9S_MB_2U_LIB.S9S_MB_2U(SCH_1):PAGE94
   209 M_G_CPU0_SA_CS_N<1> @S9S_MB_2U_LIB.S9S_MB_2U(SCH_1):M_G_CPU0_SA_CS_N(1)    I11 @S9S_MB_2U_LIB.S9S_MB_2U(SCH_1):PAGE94
    84 M_G_CPU0_SB_CS_N<0> @S9S_MB_2U_LIB.S9S_MB_2U(SCH_1):M_G_CPU0_SB_CS_N(0)    I11 @S9S_MB_2U_LIB.S9S_MB_2U(SCH_1):PAGE94
    64 M_G_CPU0_SA_CS_N<0> @S9S_MB_2U_LIB.S9S_MB_2U(SCH_1):M_G_CPU0_SA_CS_N(0)    I11 @S9S_MB_2U_LIB.S9S_MB_2U(SCH_1):PAGE94
   217 M_G_CPU0_CLK_DP<0> @S9S_MB_2U_LIB.S9S_MB_2U(SCH_1):M_G_CPU0_CLK_DP(0)    I11 @S9S_MB_2U_LIB.S9S_MB_2U(SCH_1):PAGE94
   218 M_G_CPU0_CLK_DN<0> @S9S_MB_2U_LIB.S9S_MB_2U(SCH_1):M_G_CPU0_CLK_DN(0)    I11 @S9S_MB_2U_LIB.S9S_MB_2U(SCH_1):PAGE94
    96 M_G_CPU0_SB_CB<0> @S9S_MB_2U_LIB.S9S_MB_2U(SCH_1):M_G_CPU0_SB_CB(0)    I11 @S9S_MB_2U_LIB.S9S_MB_2U(SCH_1):PAGE94
    98 M_G_CPU0_SB_CB<1> @S9S_MB_2U_LIB.S9S_MB_2U(SCH_1):M_G_CPU0_SB_CB(1)    I11 @S9S_MB_2U_LIB.S9S_MB_2U(SCH_1):PAGE94
   241 M_G_CPU0_SB_CB<2> @S9S_MB_2U_LIB.S9S_MB_2U(SCH_1):M_G_CPU0_SB_CB(2)    I11 @S9S_MB_2U_LIB.S9S_MB_2U(SCH_1):PAGE94
   243 M_G_CPU0_SB_CB<3> @S9S_MB_2U_LIB.S9S_MB_2U(SCH_1):M_G_CPU0_SB_CB(3)    I11 @S9S_MB_2U_LIB.S9S_MB_2U(SCH_1):PAGE94
    89 M_G_CPU0_SB_CB<4> @S9S_MB_2U_LIB.S9S_MB_2U(SCH_1):M_G_CPU0_SB_CB(4)    I11 @S9S_MB_2U_LIB.S9S_MB_2U(SCH_1):PAGE94
    91 M_G_CPU0_SB_CB<5> @S9S_MB_2U_LIB.S9S_MB_2U(SCH_1):M_G_CPU0_SB_CB(5)    I11 @S9S_MB_2U_LIB.S9S_MB_2U(SCH_1):PAGE94
   234 M_G_CPU0_SB_CB<6> @S9S_MB_2U_LIB.S9S_MB_2U(SCH_1):M_G_CPU0_SB_CB(6)    I11 @S9S_MB_2U_LIB.S9S_MB_2U(SCH_1):PAGE94
    51 M_G_CPU0_SA_CB<0> @S9S_MB_2U_LIB.S9S_MB_2U(SCH_1):M_G_CPU0_SA_CB(0)    I11 @S9S_MB_2U_LIB.S9S_MB_2U(SCH_1):PAGE94
   196 M_G_CPU0_SA_CB<2> @S9S_MB_2U_LIB.S9S_MB_2U(SCH_1):M_G_CPU0_SA_CB(2)    I11 @S9S_MB_2U_LIB.S9S_MB_2U(SCH_1):PAGE94
   198 M_G_CPU0_SA_CB<3> @S9S_MB_2U_LIB.S9S_MB_2U(SCH_1):M_G_CPU0_SA_CB(3)    I11 @S9S_MB_2U_LIB.S9S_MB_2U(SCH_1):PAGE94
    60 M_G_CPU0_SA_CB<5> @S9S_MB_2U_LIB.S9S_MB_2U(SCH_1):M_G_CPU0_SA_CB(5)    I11 @S9S_MB_2U_LIB.S9S_MB_2U(SCH_1):PAGE94
   203 M_G_CPU0_SA_CB<6> @S9S_MB_2U_LIB.S9S_MB_2U(SCH_1):M_G_CPU0_SA_CB(6)    I11 @S9S_MB_2U_LIB.S9S_MB_2U(SCH_1):PAGE94
    82 M_G_CPU0_SB_CA<6> @S9S_MB_2U_LIB.S9S_MB_2U(SCH_1):M_G_CPU0_SB_CA(6)    I11 @S9S_MB_2U_LIB.S9S_MB_2U(SCH_1):PAGE94
    72 M_G_CPU0_SA_CA<6> @S9S_MB_2U_LIB.S9S_MB_2U(SCH_1):M_G_CPU0_SA_CA(6)    I11 @S9S_MB_2U_LIB.S9S_MB_2U(SCH_1):PAGE94
   225 M_G_CPU0_SB_CA<5> @S9S_MB_2U_LIB.S9S_MB_2U(SCH_1):M_G_CPU0_SB_CA(5)    I11 @S9S_MB_2U_LIB.S9S_MB_2U(SCH_1):PAGE94
   215 M_G_CPU0_SA_CA<5> @S9S_MB_2U_LIB.S9S_MB_2U(SCH_1):M_G_CPU0_SA_CA(5)    I11 @S9S_MB_2U_LIB.S9S_MB_2U(SCH_1):PAGE94
    80 M_G_CPU0_SB_CA<4> @S9S_MB_2U_LIB.S9S_MB_2U(SCH_1):M_G_CPU0_SB_CA(4)    I11 @S9S_MB_2U_LIB.S9S_MB_2U(SCH_1):PAGE94
    70 M_G_CPU0_SA_CA<4> @S9S_MB_2U_LIB.S9S_MB_2U(SCH_1):M_G_CPU0_SA_CA(4)    I11 @S9S_MB_2U_LIB.S9S_MB_2U(SCH_1):PAGE94
   223 M_G_CPU0_SB_CA<3> @S9S_MB_2U_LIB.S9S_MB_2U(SCH_1):M_G_CPU0_SB_CA(3)    I11 @S9S_MB_2U_LIB.S9S_MB_2U(SCH_1):PAGE94
   213 M_G_CPU0_SA_CA<3> @S9S_MB_2U_LIB.S9S_MB_2U(SCH_1):M_G_CPU0_SA_CA(3)    I11 @S9S_MB_2U_LIB.S9S_MB_2U(SCH_1):PAGE94
    78 M_G_CPU0_SB_CA<2> @S9S_MB_2U_LIB.S9S_MB_2U(SCH_1):M_G_CPU0_SB_CA(2)    I11 @S9S_MB_2U_LIB.S9S_MB_2U(SCH_1):PAGE94
    68 M_G_CPU0_SA_CA<2> @S9S_MB_2U_LIB.S9S_MB_2U(SCH_1):M_G_CPU0_SA_CA(2)    I11 @S9S_MB_2U_LIB.S9S_MB_2U(SCH_1):PAGE94
   221 M_G_CPU0_SB_CA<1> @S9S_MB_2U_LIB.S9S_MB_2U(SCH_1):M_G_CPU0_SB_CA(1)    I11 @S9S_MB_2U_LIB.S9S_MB_2U(SCH_1):PAGE94
   211 M_G_CPU0_SA_CA<1> @S9S_MB_2U_LIB.S9S_MB_2U(SCH_1):M_G_CPU0_SA_CA(1)    I11 @S9S_MB_2U_LIB.S9S_MB_2U(SCH_1):PAGE94
    76 M_G_CPU0_SB_CA<0> @S9S_MB_2U_LIB.S9S_MB_2U(SCH_1):M_G_CPU0_SB_CA(0)    I11 @S9S_MB_2U_LIB.S9S_MB_2U(SCH_1):PAGE94
    66 M_G_CPU0_SA_CA<0> @S9S_MB_2U_LIB.S9S_MB_2U(SCH_1):M_G_CPU0_SA_CA(0)    I11 @S9S_MB_2U_LIB.S9S_MB_2U(SCH_1):PAGE94
    62 M_G_CPU0_ALERT_N @S9S_MB_2U_LIB.S9S_MB_2U(SCH_1):M_G_CPU0_ALERT_N    I11 @S9S_MB_2U_LIB.S9S_MB_2U(SCH_1):PAGE94
   236 M_G_CPU0_SB_CB<7> @S9S_MB_2U_LIB.S9S_MB_2U(SCH_1):M_G_CPU0_SB_CB(7)    I11 @S9S_MB_2U_LIB.S9S_MB_2U(SCH_1):PAGE94
    53 M_G_CPU0_SA_CB<1> @S9S_MB_2U_LIB.S9S_MB_2U(SCH_1):M_G_CPU0_SA_CB(1)    I11 @S9S_MB_2U_LIB.S9S_MB_2U(SCH_1):PAGE94
    58 M_G_CPU0_SA_CB<4> @S9S_MB_2U_LIB.S9S_MB_2U(SCH_1):M_G_CPU0_SA_CB(4)    I11 @S9S_MB_2U_LIB.S9S_MB_2U(SCH_1):PAGE94
   205 M_G_CPU0_SA_CB<7> @S9S_MB_2U_LIB.S9S_MB_2U(SCH_1):M_G_CPU0_SA_CB(7)    I11 @S9S_MB_2U_LIB.S9S_MB_2U(SCH_1):PAGE94
   194 M_G_CPU0_SA_DQ<31> @S9S_MB_2U_LIB.S9S_MB_2U(SCH_1):M_G_CPU0_SA_DQ(31)    I11 @S9S_MB_2U_LIB.S9S_MB_2U(SCH_1):PAGE94
    93 M_G_CPU0_SB_DQS_DP<9> @S9S_MB_2U_LIB.S9S_MB_2U(SCH_1):M_G_CPU0_SB_DQS_DP(9)   I178 @S9S_MB_2U_LIB.S9S_MB_2U(SCH_1):PAGE94
    94 M_G_CPU0_SB_DQS_DN<9> @S9S_MB_2U_LIB.S9S_MB_2U(SCH_1):M_G_CPU0_SB_DQS_DN(9)   I178 @S9S_MB_2U_LIB.S9S_MB_2U(SCH_1):PAGE94
   201 M_G_CPU0_SA_DQS_DP<9> @S9S_MB_2U_LIB.S9S_MB_2U(SCH_1):M_G_CPU0_SA_DQS_DP(9)   I178 @S9S_MB_2U_LIB.S9S_MB_2U(SCH_1):PAGE94
   200 M_G_CPU0_SA_DQS_DN<9> @S9S_MB_2U_LIB.S9S_MB_2U(SCH_1):M_G_CPU0_SA_DQS_DN(9)   I178 @S9S_MB_2U_LIB.S9S_MB_2U(SCH_1):PAGE94
   190 M_G_CPU0_SA_DQS_DP<8> @S9S_MB_2U_LIB.S9S_MB_2U(SCH_1):M_G_CPU0_SA_DQS_DP(8)   I178 @S9S_MB_2U_LIB.S9S_MB_2U(SCH_1):PAGE94
   189 M_G_CPU0_SA_DQS_DN<8> @S9S_MB_2U_LIB.S9S_MB_2U(SCH_1):M_G_CPU0_SA_DQS_DN(8)   I178 @S9S_MB_2U_LIB.S9S_MB_2U(SCH_1):PAGE94
   271 M_G_CPU0_SB_DQS_DN<7> @S9S_MB_2U_LIB.S9S_MB_2U(SCH_1):M_G_CPU0_SB_DQS_DN(7)   I178 @S9S_MB_2U_LIB.S9S_MB_2U(SCH_1):PAGE94
   179 M_G_CPU0_SA_DQS_DP<7> @S9S_MB_2U_LIB.S9S_MB_2U(SCH_1):M_G_CPU0_SA_DQS_DP(7)   I178 @S9S_MB_2U_LIB.S9S_MB_2U(SCH_1):PAGE94
   261 M_G_CPU0_SB_DQS_DP<6> @S9S_MB_2U_LIB.S9S_MB_2U(SCH_1):M_G_CPU0_SB_DQS_DP(6)   I178 @S9S_MB_2U_LIB.S9S_MB_2U(SCH_1):PAGE94
   260 M_G_CPU0_SB_DQS_DN<6> @S9S_MB_2U_LIB.S9S_MB_2U(SCH_1):M_G_CPU0_SB_DQS_DN(6)   I178 @S9S_MB_2U_LIB.S9S_MB_2U(SCH_1):PAGE94
   167 M_G_CPU0_SA_DQS_DN<6> @S9S_MB_2U_LIB.S9S_MB_2U(SCH_1):M_G_CPU0_SA_DQS_DN(6)   I178 @S9S_MB_2U_LIB.S9S_MB_2U(SCH_1):PAGE94
   250 M_G_CPU0_SB_DQS_DP<5> @S9S_MB_2U_LIB.S9S_MB_2U(SCH_1):M_G_CPU0_SB_DQS_DP(5)   I178 @S9S_MB_2U_LIB.S9S_MB_2U(SCH_1):PAGE94
   249 M_G_CPU0_SB_DQS_DN<5> @S9S_MB_2U_LIB.S9S_MB_2U(SCH_1):M_G_CPU0_SB_DQS_DN(5)   I178 @S9S_MB_2U_LIB.S9S_MB_2U(SCH_1):PAGE94
   157 M_G_CPU0_SA_DQS_DP<5> @S9S_MB_2U_LIB.S9S_MB_2U(SCH_1):M_G_CPU0_SA_DQS_DP(5)   I178 @S9S_MB_2U_LIB.S9S_MB_2U(SCH_1):PAGE94
   156 M_G_CPU0_SA_DQS_DN<5> @S9S_MB_2U_LIB.S9S_MB_2U(SCH_1):M_G_CPU0_SA_DQS_DN(5)   I178 @S9S_MB_2U_LIB.S9S_MB_2U(SCH_1):PAGE94
   239 M_G_CPU0_SB_DQS_DP<4> @S9S_MB_2U_LIB.S9S_MB_2U(SCH_1):M_G_CPU0_SB_DQS_DP(4)   I178 @S9S_MB_2U_LIB.S9S_MB_2U(SCH_1):PAGE94
   238 M_G_CPU0_SB_DQS_DN<4> @S9S_MB_2U_LIB.S9S_MB_2U(SCH_1):M_G_CPU0_SB_DQS_DN(4)   I178 @S9S_MB_2U_LIB.S9S_MB_2U(SCH_1):PAGE94
    55 M_G_CPU0_SA_DQS_DP<4> @S9S_MB_2U_LIB.S9S_MB_2U(SCH_1):M_G_CPU0_SA_DQS_DP(4)   I178 @S9S_MB_2U_LIB.S9S_MB_2U(SCH_1):PAGE94
    56 M_G_CPU0_SA_DQS_DN<4> @S9S_MB_2U_LIB.S9S_MB_2U(SCH_1):M_G_CPU0_SA_DQS_DN(4)   I178 @S9S_MB_2U_LIB.S9S_MB_2U(SCH_1):PAGE94
   137 M_G_CPU0_SB_DQS_DP<3> @S9S_MB_2U_LIB.S9S_MB_2U(SCH_1):M_G_CPU0_SB_DQS_DP(3)   I178 @S9S_MB_2U_LIB.S9S_MB_2U(SCH_1):PAGE94
   138 M_G_CPU0_SB_DQS_DN<3> @S9S_MB_2U_LIB.S9S_MB_2U(SCH_1):M_G_CPU0_SB_DQS_DN(3)   I178 @S9S_MB_2U_LIB.S9S_MB_2U(SCH_1):PAGE94
    44 M_G_CPU0_SA_DQS_DP<3> @S9S_MB_2U_LIB.S9S_MB_2U(SCH_1):M_G_CPU0_SA_DQS_DP(3)   I178 @S9S_MB_2U_LIB.S9S_MB_2U(SCH_1):PAGE94
    45 M_G_CPU0_SA_DQS_DN<3> @S9S_MB_2U_LIB.S9S_MB_2U(SCH_1):M_G_CPU0_SA_DQS_DN(3)   I178 @S9S_MB_2U_LIB.S9S_MB_2U(SCH_1):PAGE94
   126 M_G_CPU0_SB_DQS_DP<2> @S9S_MB_2U_LIB.S9S_MB_2U(SCH_1):M_G_CPU0_SB_DQS_DP(2)   I178 @S9S_MB_2U_LIB.S9S_MB_2U(SCH_1):PAGE94
   127 M_G_CPU0_SB_DQS_DN<2> @S9S_MB_2U_LIB.S9S_MB_2U(SCH_1):M_G_CPU0_SB_DQS_DN(2)   I178 @S9S_MB_2U_LIB.S9S_MB_2U(SCH_1):PAGE94
    33 M_G_CPU0_SA_DQS_DP<2> @S9S_MB_2U_LIB.S9S_MB_2U(SCH_1):M_G_CPU0_SA_DQS_DP(2)   I178 @S9S_MB_2U_LIB.S9S_MB_2U(SCH_1):PAGE94
    34 M_G_CPU0_SA_DQS_DN<2> @S9S_MB_2U_LIB.S9S_MB_2U(SCH_1):M_G_CPU0_SA_DQS_DN(2)   I178 @S9S_MB_2U_LIB.S9S_MB_2U(SCH_1):PAGE94
   115 M_G_CPU0_SB_DQS_DP<1> @S9S_MB_2U_LIB.S9S_MB_2U(SCH_1):M_G_CPU0_SB_DQS_DP(1)   I178 @S9S_MB_2U_LIB.S9S_MB_2U(SCH_1):PAGE94
   116 M_G_CPU0_SB_DQS_DN<1> @S9S_MB_2U_LIB.S9S_MB_2U(SCH_1):M_G_CPU0_SB_DQS_DN(1)   I178 @S9S_MB_2U_LIB.S9S_MB_2U(SCH_1):PAGE94
    22 M_G_CPU0_SA_DQS_DP<1> @S9S_MB_2U_LIB.S9S_MB_2U(SCH_1):M_G_CPU0_SA_DQS_DP(1)   I178 @S9S_MB_2U_LIB.S9S_MB_2U(SCH_1):PAGE94
    23 M_G_CPU0_SA_DQS_DN<1> @S9S_MB_2U_LIB.S9S_MB_2U(SCH_1):M_G_CPU0_SA_DQS_DN(1)   I178 @S9S_MB_2U_LIB.S9S_MB_2U(SCH_1):PAGE94
   104 M_G_CPU0_SB_DQS_DP<0> @S9S_MB_2U_LIB.S9S_MB_2U(SCH_1):M_G_CPU0_SB_DQS_DP(0)   I178 @S9S_MB_2U_LIB.S9S_MB_2U(SCH_1):PAGE94
   105 M_G_CPU0_SB_DQS_DN<0> @S9S_MB_2U_LIB.S9S_MB_2U(SCH_1):M_G_CPU0_SB_DQS_DN(0)   I178 @S9S_MB_2U_LIB.S9S_MB_2U(SCH_1):PAGE94
    11 M_G_CPU0_SA_DQS_DP<0> @S9S_MB_2U_LIB.S9S_MB_2U(SCH_1):M_G_CPU0_SA_DQS_DP(0)   I178 @S9S_MB_2U_LIB.S9S_MB_2U(SCH_1):PAGE94
    12 M_G_CPU0_SA_DQS_DN<0> @S9S_MB_2U_LIB.S9S_MB_2U(SCH_1):M_G_CPU0_SA_DQS_DN(0)   I178 @S9S_MB_2U_LIB.S9S_MB_2U(SCH_1):PAGE94
   272 M_G_CPU0_SB_DQS_DP<7> @S9S_MB_2U_LIB.S9S_MB_2U(SCH_1):M_G_CPU0_SB_DQS_DP(7)   I178 @S9S_MB_2U_LIB.S9S_MB_2U(SCH_1):PAGE94
   282 M_G_CPU0_SB_DQS_DN<8> @S9S_MB_2U_LIB.S9S_MB_2U(SCH_1):M_G_CPU0_SB_DQS_DN(8)   I178 @S9S_MB_2U_LIB.S9S_MB_2U(SCH_1):PAGE94
   283 M_G_CPU0_SB_DQS_DP<8> @S9S_MB_2U_LIB.S9S_MB_2U(SCH_1):M_G_CPU0_SB_DQS_DP(8)   I178 @S9S_MB_2U_LIB.S9S_MB_2U(SCH_1):PAGE94
   168 M_G_CPU0_SA_DQS_DP<6> @S9S_MB_2U_LIB.S9S_MB_2U(SCH_1):M_G_CPU0_SA_DQS_DP(6)   I178 @S9S_MB_2U_LIB.S9S_MB_2U(SCH_1):PAGE94
   178 M_G_CPU0_SA_DQS_DN<7> @S9S_MB_2U_LIB.S9S_MB_2U(SCH_1):M_G_CPU0_SA_DQS_DN(7)   I178 @S9S_MB_2U_LIB.S9S_MB_2U(SCH_1):PAGE94
     6    GND @S9S_MB_2U_LIB.S9S_MB_2U(SCH_1):GND   I164 @S9S_MB_2U_LIB.S9S_MB_2U(SCH_1):PAGE94
     8    GND @S9S_MB_2U_LIB.S9S_MB_2U(SCH_1):GND   I164 @S9S_MB_2U_LIB.S9S_MB_2U(SCH_1):PAGE94
    10    GND @S9S_MB_2U_LIB.S9S_MB_2U(SCH_1):GND   I164 @S9S_MB_2U_LIB.S9S_MB_2U(SCH_1):PAGE94
    13    GND @S9S_MB_2U_LIB.S9S_MB_2U(SCH_1):GND   I164 @S9S_MB_2U_LIB.S9S_MB_2U(SCH_1):PAGE94
    15    GND @S9S_MB_2U_LIB.S9S_MB_2U(SCH_1):GND   I164 @S9S_MB_2U_LIB.S9S_MB_2U(SCH_1):PAGE94
    17    GND @S9S_MB_2U_LIB.S9S_MB_2U(SCH_1):GND   I164 @S9S_MB_2U_LIB.S9S_MB_2U(SCH_1):PAGE94
    19    GND @S9S_MB_2U_LIB.S9S_MB_2U(SCH_1):GND   I164 @S9S_MB_2U_LIB.S9S_MB_2U(SCH_1):PAGE94
    21    GND @S9S_MB_2U_LIB.S9S_MB_2U(SCH_1):GND   I164 @S9S_MB_2U_LIB.S9S_MB_2U(SCH_1):PAGE94
    24    GND @S9S_MB_2U_LIB.S9S_MB_2U(SCH_1):GND   I164 @S9S_MB_2U_LIB.S9S_MB_2U(SCH_1):PAGE94
    26    GND @S9S_MB_2U_LIB.S9S_MB_2U(SCH_1):GND   I164 @S9S_MB_2U_LIB.S9S_MB_2U(SCH_1):PAGE94
    28    GND @S9S_MB_2U_LIB.S9S_MB_2U(SCH_1):GND   I164 @S9S_MB_2U_LIB.S9S_MB_2U(SCH_1):PAGE94
    30    GND @S9S_MB_2U_LIB.S9S_MB_2U(SCH_1):GND   I164 @S9S_MB_2U_LIB.S9S_MB_2U(SCH_1):PAGE94
    32    GND @S9S_MB_2U_LIB.S9S_MB_2U(SCH_1):GND   I164 @S9S_MB_2U_LIB.S9S_MB_2U(SCH_1):PAGE94
    35    GND @S9S_MB_2U_LIB.S9S_MB_2U(SCH_1):GND   I164 @S9S_MB_2U_LIB.S9S_MB_2U(SCH_1):PAGE94
    37    GND @S9S_MB_2U_LIB.S9S_MB_2U(SCH_1):GND   I164 @S9S_MB_2U_LIB.S9S_MB_2U(SCH_1):PAGE94
    39    GND @S9S_MB_2U_LIB.S9S_MB_2U(SCH_1):GND   I164 @S9S_MB_2U_LIB.S9S_MB_2U(SCH_1):PAGE94
    41    GND @S9S_MB_2U_LIB.S9S_MB_2U(SCH_1):GND   I164 @S9S_MB_2U_LIB.S9S_MB_2U(SCH_1):PAGE94
    43    GND @S9S_MB_2U_LIB.S9S_MB_2U(SCH_1):GND   I164 @S9S_MB_2U_LIB.S9S_MB_2U(SCH_1):PAGE94
    46    GND @S9S_MB_2U_LIB.S9S_MB_2U(SCH_1):GND   I164 @S9S_MB_2U_LIB.S9S_MB_2U(SCH_1):PAGE94
    48    GND @S9S_MB_2U_LIB.S9S_MB_2U(SCH_1):GND   I164 @S9S_MB_2U_LIB.S9S_MB_2U(SCH_1):PAGE94
    50    GND @S9S_MB_2U_LIB.S9S_MB_2U(SCH_1):GND   I164 @S9S_MB_2U_LIB.S9S_MB_2U(SCH_1):PAGE94
    52    GND @S9S_MB_2U_LIB.S9S_MB_2U(SCH_1):GND   I164 @S9S_MB_2U_LIB.S9S_MB_2U(SCH_1):PAGE94
    54    GND @S9S_MB_2U_LIB.S9S_MB_2U(SCH_1):GND   I164 @S9S_MB_2U_LIB.S9S_MB_2U(SCH_1):PAGE94
    57    GND @S9S_MB_2U_LIB.S9S_MB_2U(SCH_1):GND   I164 @S9S_MB_2U_LIB.S9S_MB_2U(SCH_1):PAGE94
    59    GND @S9S_MB_2U_LIB.S9S_MB_2U(SCH_1):GND   I164 @S9S_MB_2U_LIB.S9S_MB_2U(SCH_1):PAGE94
    61    GND @S9S_MB_2U_LIB.S9S_MB_2U(SCH_1):GND   I164 @S9S_MB_2U_LIB.S9S_MB_2U(SCH_1):PAGE94
    63    GND @S9S_MB_2U_LIB.S9S_MB_2U(SCH_1):GND   I164 @S9S_MB_2U_LIB.S9S_MB_2U(SCH_1):PAGE94
    65    GND @S9S_MB_2U_LIB.S9S_MB_2U(SCH_1):GND   I164 @S9S_MB_2U_LIB.S9S_MB_2U(SCH_1):PAGE94
    67    GND @S9S_MB_2U_LIB.S9S_MB_2U(SCH_1):GND   I164 @S9S_MB_2U_LIB.S9S_MB_2U(SCH_1):PAGE94
    69    GND @S9S_MB_2U_LIB.S9S_MB_2U(SCH_1):GND   I164 @S9S_MB_2U_LIB.S9S_MB_2U(SCH_1):PAGE94
    71    GND @S9S_MB_2U_LIB.S9S_MB_2U(SCH_1):GND   I164 @S9S_MB_2U_LIB.S9S_MB_2U(SCH_1):PAGE94
    73    GND @S9S_MB_2U_LIB.S9S_MB_2U(SCH_1):GND   I164 @S9S_MB_2U_LIB.S9S_MB_2U(SCH_1):PAGE94
    75    GND @S9S_MB_2U_LIB.S9S_MB_2U(SCH_1):GND   I164 @S9S_MB_2U_LIB.S9S_MB_2U(SCH_1):PAGE94
    77    GND @S9S_MB_2U_LIB.S9S_MB_2U(SCH_1):GND   I164 @S9S_MB_2U_LIB.S9S_MB_2U(SCH_1):PAGE94
    79    GND @S9S_MB_2U_LIB.S9S_MB_2U(SCH_1):GND   I164 @S9S_MB_2U_LIB.S9S_MB_2U(SCH_1):PAGE94
    81    GND @S9S_MB_2U_LIB.S9S_MB_2U(SCH_1):GND   I164 @S9S_MB_2U_LIB.S9S_MB_2U(SCH_1):PAGE94
    83    GND @S9S_MB_2U_LIB.S9S_MB_2U(SCH_1):GND   I164 @S9S_MB_2U_LIB.S9S_MB_2U(SCH_1):PAGE94
    85    GND @S9S_MB_2U_LIB.S9S_MB_2U(SCH_1):GND   I164 @S9S_MB_2U_LIB.S9S_MB_2U(SCH_1):PAGE94
    88    GND @S9S_MB_2U_LIB.S9S_MB_2U(SCH_1):GND   I164 @S9S_MB_2U_LIB.S9S_MB_2U(SCH_1):PAGE94
    90    GND @S9S_MB_2U_LIB.S9S_MB_2U(SCH_1):GND   I164 @S9S_MB_2U_LIB.S9S_MB_2U(SCH_1):PAGE94
    92    GND @S9S_MB_2U_LIB.S9S_MB_2U(SCH_1):GND   I164 @S9S_MB_2U_LIB.S9S_MB_2U(SCH_1):PAGE94
    95    GND @S9S_MB_2U_LIB.S9S_MB_2U(SCH_1):GND   I164 @S9S_MB_2U_LIB.S9S_MB_2U(SCH_1):PAGE94
    97    GND @S9S_MB_2U_LIB.S9S_MB_2U(SCH_1):GND   I164 @S9S_MB_2U_LIB.S9S_MB_2U(SCH_1):PAGE94
    99    GND @S9S_MB_2U_LIB.S9S_MB_2U(SCH_1):GND   I164 @S9S_MB_2U_LIB.S9S_MB_2U(SCH_1):PAGE94
   101    GND @S9S_MB_2U_LIB.S9S_MB_2U(SCH_1):GND   I164 @S9S_MB_2U_LIB.S9S_MB_2U(SCH_1):PAGE94
   103    GND @S9S_MB_2U_LIB.S9S_MB_2U(SCH_1):GND   I164 @S9S_MB_2U_LIB.S9S_MB_2U(SCH_1):PAGE94
   106    GND @S9S_MB_2U_LIB.S9S_MB_2U(SCH_1):GND   I164 @S9S_MB_2U_LIB.S9S_MB_2U(SCH_1):PAGE94
   108    GND @S9S_MB_2U_LIB.S9S_MB_2U(SCH_1):GND   I164 @S9S_MB_2U_LIB.S9S_MB_2U(SCH_1):PAGE94
   110    GND @S9S_MB_2U_LIB.S9S_MB_2U(SCH_1):GND   I164 @S9S_MB_2U_LIB.S9S_MB_2U(SCH_1):PAGE94
   112    GND @S9S_MB_2U_LIB.S9S_MB_2U(SCH_1):GND   I164 @S9S_MB_2U_LIB.S9S_MB_2U(SCH_1):PAGE94
   114    GND @S9S_MB_2U_LIB.S9S_MB_2U(SCH_1):GND   I164 @S9S_MB_2U_LIB.S9S_MB_2U(SCH_1):PAGE94
   117    GND @S9S_MB_2U_LIB.S9S_MB_2U(SCH_1):GND   I164 @S9S_MB_2U_LIB.S9S_MB_2U(SCH_1):PAGE94
   119    GND @S9S_MB_2U_LIB.S9S_MB_2U(SCH_1):GND   I164 @S9S_MB_2U_LIB.S9S_MB_2U(SCH_1):PAGE94
   121    GND @S9S_MB_2U_LIB.S9S_MB_2U(SCH_1):GND   I164 @S9S_MB_2U_LIB.S9S_MB_2U(SCH_1):PAGE94
   123    GND @S9S_MB_2U_LIB.S9S_MB_2U(SCH_1):GND   I164 @S9S_MB_2U_LIB.S9S_MB_2U(SCH_1):PAGE94
   125    GND @S9S_MB_2U_LIB.S9S_MB_2U(SCH_1):GND   I164 @S9S_MB_2U_LIB.S9S_MB_2U(SCH_1):PAGE94
   128    GND @S9S_MB_2U_LIB.S9S_MB_2U(SCH_1):GND   I164 @S9S_MB_2U_LIB.S9S_MB_2U(SCH_1):PAGE94
   130    GND @S9S_MB_2U_LIB.S9S_MB_2U(SCH_1):GND   I164 @S9S_MB_2U_LIB.S9S_MB_2U(SCH_1):PAGE94
   134    GND @S9S_MB_2U_LIB.S9S_MB_2U(SCH_1):GND   I164 @S9S_MB_2U_LIB.S9S_MB_2U(SCH_1):PAGE94
   143    GND @S9S_MB_2U_LIB.S9S_MB_2U(SCH_1):GND   I164 @S9S_MB_2U_LIB.S9S_MB_2U(SCH_1):PAGE94
   151    GND @S9S_MB_2U_LIB.S9S_MB_2U(SCH_1):GND   I164 @S9S_MB_2U_LIB.S9S_MB_2U(SCH_1):PAGE94
   153    GND @S9S_MB_2U_LIB.S9S_MB_2U(SCH_1):GND   I164 @S9S_MB_2U_LIB.S9S_MB_2U(SCH_1):PAGE94
   155    GND @S9S_MB_2U_LIB.S9S_MB_2U(SCH_1):GND   I164 @S9S_MB_2U_LIB.S9S_MB_2U(SCH_1):PAGE94
   158    GND @S9S_MB_2U_LIB.S9S_MB_2U(SCH_1):GND   I164 @S9S_MB_2U_LIB.S9S_MB_2U(SCH_1):PAGE94
   160    GND @S9S_MB_2U_LIB.S9S_MB_2U(SCH_1):GND   I164 @S9S_MB_2U_LIB.S9S_MB_2U(SCH_1):PAGE94
   162    GND @S9S_MB_2U_LIB.S9S_MB_2U(SCH_1):GND   I164 @S9S_MB_2U_LIB.S9S_MB_2U(SCH_1):PAGE94
   164    GND @S9S_MB_2U_LIB.S9S_MB_2U(SCH_1):GND   I164 @S9S_MB_2U_LIB.S9S_MB_2U(SCH_1):PAGE94
   166    GND @S9S_MB_2U_LIB.S9S_MB_2U(SCH_1):GND   I164 @S9S_MB_2U_LIB.S9S_MB_2U(SCH_1):PAGE94
   169    GND @S9S_MB_2U_LIB.S9S_MB_2U(SCH_1):GND   I164 @S9S_MB_2U_LIB.S9S_MB_2U(SCH_1):PAGE94
   171    GND @S9S_MB_2U_LIB.S9S_MB_2U(SCH_1):GND   I164 @S9S_MB_2U_LIB.S9S_MB_2U(SCH_1):PAGE94
   173    GND @S9S_MB_2U_LIB.S9S_MB_2U(SCH_1):GND   I164 @S9S_MB_2U_LIB.S9S_MB_2U(SCH_1):PAGE94
   175    GND @S9S_MB_2U_LIB.S9S_MB_2U(SCH_1):GND   I164 @S9S_MB_2U_LIB.S9S_MB_2U(SCH_1):PAGE94
   177    GND @S9S_MB_2U_LIB.S9S_MB_2U(SCH_1):GND   I164 @S9S_MB_2U_LIB.S9S_MB_2U(SCH_1):PAGE94
   180    GND @S9S_MB_2U_LIB.S9S_MB_2U(SCH_1):GND   I164 @S9S_MB_2U_LIB.S9S_MB_2U(SCH_1):PAGE94
   182    GND @S9S_MB_2U_LIB.S9S_MB_2U(SCH_1):GND   I164 @S9S_MB_2U_LIB.S9S_MB_2U(SCH_1):PAGE94
   184    GND @S9S_MB_2U_LIB.S9S_MB_2U(SCH_1):GND   I164 @S9S_MB_2U_LIB.S9S_MB_2U(SCH_1):PAGE94
   186    GND @S9S_MB_2U_LIB.S9S_MB_2U(SCH_1):GND   I164 @S9S_MB_2U_LIB.S9S_MB_2U(SCH_1):PAGE94
   188    GND @S9S_MB_2U_LIB.S9S_MB_2U(SCH_1):GND   I164 @S9S_MB_2U_LIB.S9S_MB_2U(SCH_1):PAGE94
   191    GND @S9S_MB_2U_LIB.S9S_MB_2U(SCH_1):GND   I164 @S9S_MB_2U_LIB.S9S_MB_2U(SCH_1):PAGE94
   193    GND @S9S_MB_2U_LIB.S9S_MB_2U(SCH_1):GND   I164 @S9S_MB_2U_LIB.S9S_MB_2U(SCH_1):PAGE94
   195    GND @S9S_MB_2U_LIB.S9S_MB_2U(SCH_1):GND   I164 @S9S_MB_2U_LIB.S9S_MB_2U(SCH_1):PAGE94
   197    GND @S9S_MB_2U_LIB.S9S_MB_2U(SCH_1):GND   I164 @S9S_MB_2U_LIB.S9S_MB_2U(SCH_1):PAGE94
   199    GND @S9S_MB_2U_LIB.S9S_MB_2U(SCH_1):GND   I164 @S9S_MB_2U_LIB.S9S_MB_2U(SCH_1):PAGE94
   202    GND @S9S_MB_2U_LIB.S9S_MB_2U(SCH_1):GND   I164 @S9S_MB_2U_LIB.S9S_MB_2U(SCH_1):PAGE94
   204    GND @S9S_MB_2U_LIB.S9S_MB_2U(SCH_1):GND   I164 @S9S_MB_2U_LIB.S9S_MB_2U(SCH_1):PAGE94
   206    GND @S9S_MB_2U_LIB.S9S_MB_2U(SCH_1):GND   I164 @S9S_MB_2U_LIB.S9S_MB_2U(SCH_1):PAGE94
   208    GND @S9S_MB_2U_LIB.S9S_MB_2U(SCH_1):GND   I164 @S9S_MB_2U_LIB.S9S_MB_2U(SCH_1):PAGE94
   210    GND @S9S_MB_2U_LIB.S9S_MB_2U(SCH_1):GND   I164 @S9S_MB_2U_LIB.S9S_MB_2U(SCH_1):PAGE94
   212    GND @S9S_MB_2U_LIB.S9S_MB_2U(SCH_1):GND   I164 @S9S_MB_2U_LIB.S9S_MB_2U(SCH_1):PAGE94
   214    GND @S9S_MB_2U_LIB.S9S_MB_2U(SCH_1):GND   I164 @S9S_MB_2U_LIB.S9S_MB_2U(SCH_1):PAGE94
   216    GND @S9S_MB_2U_LIB.S9S_MB_2U(SCH_1):GND   I164 @S9S_MB_2U_LIB.S9S_MB_2U(SCH_1):PAGE94
   219    GND @S9S_MB_2U_LIB.S9S_MB_2U(SCH_1):GND   I164 @S9S_MB_2U_LIB.S9S_MB_2U(SCH_1):PAGE94
   222    GND @S9S_MB_2U_LIB.S9S_MB_2U(SCH_1):GND   I164 @S9S_MB_2U_LIB.S9S_MB_2U(SCH_1):PAGE94
   224    GND @S9S_MB_2U_LIB.S9S_MB_2U(SCH_1):GND   I164 @S9S_MB_2U_LIB.S9S_MB_2U(SCH_1):PAGE94
   226    GND @S9S_MB_2U_LIB.S9S_MB_2U(SCH_1):GND   I164 @S9S_MB_2U_LIB.S9S_MB_2U(SCH_1):PAGE94
   228    GND @S9S_MB_2U_LIB.S9S_MB_2U(SCH_1):GND   I164 @S9S_MB_2U_LIB.S9S_MB_2U(SCH_1):PAGE94
   233    GND @S9S_MB_2U_LIB.S9S_MB_2U(SCH_1):GND   I164 @S9S_MB_2U_LIB.S9S_MB_2U(SCH_1):PAGE94
   237    GND @S9S_MB_2U_LIB.S9S_MB_2U(SCH_1):GND   I164 @S9S_MB_2U_LIB.S9S_MB_2U(SCH_1):PAGE94
   242    GND @S9S_MB_2U_LIB.S9S_MB_2U(SCH_1):GND   I164 @S9S_MB_2U_LIB.S9S_MB_2U(SCH_1):PAGE94
   244    GND @S9S_MB_2U_LIB.S9S_MB_2U(SCH_1):GND   I164 @S9S_MB_2U_LIB.S9S_MB_2U(SCH_1):PAGE94
   246    GND @S9S_MB_2U_LIB.S9S_MB_2U(SCH_1):GND   I164 @S9S_MB_2U_LIB.S9S_MB_2U(SCH_1):PAGE94
   248    GND @S9S_MB_2U_LIB.S9S_MB_2U(SCH_1):GND   I164 @S9S_MB_2U_LIB.S9S_MB_2U(SCH_1):PAGE94
   251    GND @S9S_MB_2U_LIB.S9S_MB_2U(SCH_1):GND   I164 @S9S_MB_2U_LIB.S9S_MB_2U(SCH_1):PAGE94
   253    GND @S9S_MB_2U_LIB.S9S_MB_2U(SCH_1):GND   I164 @S9S_MB_2U_LIB.S9S_MB_2U(SCH_1):PAGE94
   255    GND @S9S_MB_2U_LIB.S9S_MB_2U(SCH_1):GND   I164 @S9S_MB_2U_LIB.S9S_MB_2U(SCH_1):PAGE94
   257    GND @S9S_MB_2U_LIB.S9S_MB_2U(SCH_1):GND   I164 @S9S_MB_2U_LIB.S9S_MB_2U(SCH_1):PAGE94
   259    GND @S9S_MB_2U_LIB.S9S_MB_2U(SCH_1):GND   I164 @S9S_MB_2U_LIB.S9S_MB_2U(SCH_1):PAGE94
   262    GND @S9S_MB_2U_LIB.S9S_MB_2U(SCH_1):GND   I164 @S9S_MB_2U_LIB.S9S_MB_2U(SCH_1):PAGE94
   264    GND @S9S_MB_2U_LIB.S9S_MB_2U(SCH_1):GND   I164 @S9S_MB_2U_LIB.S9S_MB_2U(SCH_1):PAGE94
   266    GND @S9S_MB_2U_LIB.S9S_MB_2U(SCH_1):GND   I164 @S9S_MB_2U_LIB.S9S_MB_2U(SCH_1):PAGE94
   268    GND @S9S_MB_2U_LIB.S9S_MB_2U(SCH_1):GND   I164 @S9S_MB_2U_LIB.S9S_MB_2U(SCH_1):PAGE94
   270    GND @S9S_MB_2U_LIB.S9S_MB_2U(SCH_1):GND   I164 @S9S_MB_2U_LIB.S9S_MB_2U(SCH_1):PAGE94
   273    GND @S9S_MB_2U_LIB.S9S_MB_2U(SCH_1):GND   I164 @S9S_MB_2U_LIB.S9S_MB_2U(SCH_1):PAGE94
   275    GND @S9S_MB_2U_LIB.S9S_MB_2U(SCH_1):GND   I164 @S9S_MB_2U_LIB.S9S_MB_2U(SCH_1):PAGE94
   277    GND @S9S_MB_2U_LIB.S9S_MB_2U(SCH_1):GND   I164 @S9S_MB_2U_LIB.S9S_MB_2U(SCH_1):PAGE94
   279    GND @S9S_MB_2U_LIB.S9S_MB_2U(SCH_1):GND   I164 @S9S_MB_2U_LIB.S9S_MB_2U(SCH_1):PAGE94
   281    GND @S9S_MB_2U_LIB.S9S_MB_2U(SCH_1):GND   I164 @S9S_MB_2U_LIB.S9S_MB_2U(SCH_1):PAGE94
   284    GND @S9S_MB_2U_LIB.S9S_MB_2U(SCH_1):GND   I164 @S9S_MB_2U_LIB.S9S_MB_2U(SCH_1):PAGE94
   286    GND @S9S_MB_2U_LIB.S9S_MB_2U(SCH_1):GND   I164 @S9S_MB_2U_LIB.S9S_MB_2U(SCH_1):PAGE94
   288    GND @S9S_MB_2U_LIB.S9S_MB_2U(SCH_1):GND   I164 @S9S_MB_2U_LIB.S9S_MB_2U(SCH_1):PAGE94
     1 P12V_S3_AUX_CPU0_NVDIMM @S9S_MB_2U_LIB.S9S_MB_2U(SCH_1):P12V_S3_AUX_CPU0_NVDIMM   I164 @S9S_MB_2U_LIB.S9S_MB_2U(SCH_1):PAGE94
   145 P12V_S3_AUX_CPU0_NVDIMM @S9S_MB_2U_LIB.S9S_MB_2U(SCH_1):P12V_S3_AUX_CPU0_NVDIMM   I164 @S9S_MB_2U_LIB.S9S_MB_2U(SCH_1):PAGE94
   146 P12V_S3_AUX_CPU0_NVDIMM @S9S_MB_2U_LIB.S9S_MB_2U(SCH_1):P12V_S3_AUX_CPU0_NVDIMM   I164 @S9S_MB_2U_LIB.S9S_MB_2U(SCH_1):PAGE94
   230    GND @S9S_MB_2U_LIB.S9S_MB_2U(SCH_1):GND   I164 @S9S_MB_2U_LIB.S9S_MB_2U(SCH_1):PAGE94
   235    GND @S9S_MB_2U_LIB.S9S_MB_2U(SCH_1):GND   I164 @S9S_MB_2U_LIB.S9S_MB_2U(SCH_1):PAGE94
   240    GND @S9S_MB_2U_LIB.S9S_MB_2U(SCH_1):GND   I164 @S9S_MB_2U_LIB.S9S_MB_2U(SCH_1):PAGE94
   132    GND @S9S_MB_2U_LIB.S9S_MB_2U(SCH_1):GND   I164 @S9S_MB_2U_LIB.S9S_MB_2U(SCH_1):PAGE94
   136    GND @S9S_MB_2U_LIB.S9S_MB_2U(SCH_1):GND   I164 @S9S_MB_2U_LIB.S9S_MB_2U(SCH_1):PAGE94
   139    GND @S9S_MB_2U_LIB.S9S_MB_2U(SCH_1):GND   I164 @S9S_MB_2U_LIB.S9S_MB_2U(SCH_1):PAGE94
   141    GND @S9S_MB_2U_LIB.S9S_MB_2U(SCH_1):GND   I164 @S9S_MB_2U_LIB.S9S_MB_2U(SCH_1):PAGE94
    G1    GND @S9S_MB_2U_LIB.S9S_MB_2U(SCH_1):GND   I164 @S9S_MB_2U_LIB.S9S_MB_2U(SCH_1):PAGE94
    G2    GND @S9S_MB_2U_LIB.S9S_MB_2U(SCH_1):GND   I164 @S9S_MB_2U_LIB.S9S_MB_2U(SCH_1):PAGE94
    G3    GND @S9S_MB_2U_LIB.S9S_MB_2U(SCH_1):GND   I164 @S9S_MB_2U_LIB.S9S_MB_2U(SCH_1):PAGE94

 J14 SCONN288_ADR50017P087CC-SCONN2A
     3 P3V3_AUX @S9S_MB_2U_LIB.S9S_MB_2U(SCH_1):P3V3_AUX    I47 @S9S_MB_2U_LIB.S9S_MB_2U(SCH_1):PAGE95
     2 TP_CHG_CPU0_DIMM2_FRU_0 @S9S_MB_2U_LIB.S9S_MB_2U(SCH_1):TP_CHG_CPU0_DIMM2_FRU_0    I47 @S9S_MB_2U_LIB.S9S_MB_2U(SCH_1):PAGE95
   144 TP_CHG_CPU0_DIMM2_FRU_1 @S9S_MB_2U_LIB.S9S_MB_2U(SCH_1):TP_CHG_CPU0_DIMM2_FRU_1    I47 @S9S_MB_2U_LIB.S9S_MB_2U(SCH_1):PAGE95
   149 TP_CHG_CPU0_DIMM2_FRU_2 @S9S_MB_2U_LIB.S9S_MB_2U(SCH_1):TP_CHG_CPU0_DIMM2_FRU_2    I47 @S9S_MB_2U_LIB.S9S_MB_2U(SCH_1):PAGE95
   150 TP_CHG_CPU0_DIMM2_FRU_3 @S9S_MB_2U_LIB.S9S_MB_2U(SCH_1):TP_CHG_CPU0_DIMM2_FRU_3    I47 @S9S_MB_2U_LIB.S9S_MB_2U(SCH_1):PAGE95
   220 TP_CHG_CPU0_DIMM2_FRU_4 @S9S_MB_2U_LIB.S9S_MB_2U(SCH_1):TP_CHG_CPU0_DIMM2_FRU_4    I47 @S9S_MB_2U_LIB.S9S_MB_2U(SCH_1):PAGE95
   231 TP_CHG_CPU0_DIMM2_FRU_5 @S9S_MB_2U_LIB.S9S_MB_2U(SCH_1):TP_CHG_CPU0_DIMM2_FRU_5    I47 @S9S_MB_2U_LIB.S9S_MB_2U(SCH_1):PAGE95
   232 TP_CHG_CPU0_DIMM2_FRU_6 @S9S_MB_2U_LIB.S9S_MB_2U(SCH_1):TP_CHG_CPU0_DIMM2_FRU_6    I47 @S9S_MB_2U_LIB.S9S_MB_2U(SCH_1):PAGE95
   207 RST_M_GH_CPU0_FPGA_N @S9S_MB_2U_LIB.S9S_MB_2U(SCH_1):RST_M_GH_CPU0_FPGA_N    I47 @S9S_MB_2U_LIB.S9S_MB_2U(SCH_1):PAGE95
   147 PWRGD_CHG_CPU0_DIMM2 @S9S_MB_2U_LIB.S9S_MB_2U(SCH_1):PWRGD_CHG_CPU0_DIMM2    I47 @S9S_MB_2U_LIB.S9S_MB_2U(SCH_1):PAGE95
   227 M_G_CPU0_SB_PAR @S9S_MB_2U_LIB.S9S_MB_2U(SCH_1):M_G_CPU0_SB_PAR    I47 @S9S_MB_2U_LIB.S9S_MB_2U(SCH_1):PAGE95
    74 M_G_CPU0_SA_PAR @S9S_MB_2U_LIB.S9S_MB_2U(SCH_1):M_G_CPU0_SA_PAR    I47 @S9S_MB_2U_LIB.S9S_MB_2U(SCH_1):PAGE95
    87 M_G_CPU0_SB_RSP<1> @S9S_MB_2U_LIB.S9S_MB_2U(SCH_1):M_G_CPU0_SB_RSP(1)    I47 @S9S_MB_2U_LIB.S9S_MB_2U(SCH_1):PAGE95
    86 M_G_CPU0_SA_RSP<1> @S9S_MB_2U_LIB.S9S_MB_2U(SCH_1):M_G_CPU0_SA_RSP(1)    I47 @S9S_MB_2U_LIB.S9S_MB_2U(SCH_1):PAGE95
     5 I3C_SPD_DDREFGH_CPU0_LVC1_SDA @S9S_MB_2U_LIB.S9S_MB_2U(SCH_1):I3C_SPD_DDREFGH_CPU0_LVC1_SDA    I47 @S9S_MB_2U_LIB.S9S_MB_2U(SCH_1):PAGE95
     4 I3C_SPD_DDREFGH_CPU0_LVC1_SCL_5 @S9S_MB_2U_LIB.S9S_MB_2U(SCH_1):I3C_SPD_DDREFGH_CPU0_LVC1_SCL_R6    I47 @S9S_MB_2U_LIB.S9S_MB_2U(SCH_1):PAGE95
   148 PD_CHG_CPU0_DIMM2_SAA @S9S_MB_2U_LIB.S9S_MB_2U(SCH_1):PD_CHG_CPU0_DIMM2_SAA    I47 @S9S_MB_2U_LIB.S9S_MB_2U(SCH_1):PAGE95
   100 M_G_CPU0_SB_DQ<0> @S9S_MB_2U_LIB.S9S_MB_2U(SCH_1):M_G_CPU0_SB_DQ(0)    I47 @S9S_MB_2U_LIB.S9S_MB_2U(SCH_1):PAGE95
   102 M_G_CPU0_SB_DQ<1> @S9S_MB_2U_LIB.S9S_MB_2U(SCH_1):M_G_CPU0_SB_DQ(1)    I47 @S9S_MB_2U_LIB.S9S_MB_2U(SCH_1):PAGE95
   245 M_G_CPU0_SB_DQ<2> @S9S_MB_2U_LIB.S9S_MB_2U(SCH_1):M_G_CPU0_SB_DQ(2)    I47 @S9S_MB_2U_LIB.S9S_MB_2U(SCH_1):PAGE95
   247 M_G_CPU0_SB_DQ<3> @S9S_MB_2U_LIB.S9S_MB_2U(SCH_1):M_G_CPU0_SB_DQ(3)    I47 @S9S_MB_2U_LIB.S9S_MB_2U(SCH_1):PAGE95
   107 M_G_CPU0_SB_DQ<4> @S9S_MB_2U_LIB.S9S_MB_2U(SCH_1):M_G_CPU0_SB_DQ(4)    I47 @S9S_MB_2U_LIB.S9S_MB_2U(SCH_1):PAGE95
   109 M_G_CPU0_SB_DQ<5> @S9S_MB_2U_LIB.S9S_MB_2U(SCH_1):M_G_CPU0_SB_DQ(5)    I47 @S9S_MB_2U_LIB.S9S_MB_2U(SCH_1):PAGE95
   252 M_G_CPU0_SB_DQ<6> @S9S_MB_2U_LIB.S9S_MB_2U(SCH_1):M_G_CPU0_SB_DQ(6)    I47 @S9S_MB_2U_LIB.S9S_MB_2U(SCH_1):PAGE95
   254 M_G_CPU0_SB_DQ<7> @S9S_MB_2U_LIB.S9S_MB_2U(SCH_1):M_G_CPU0_SB_DQ(7)    I47 @S9S_MB_2U_LIB.S9S_MB_2U(SCH_1):PAGE95
   111 M_G_CPU0_SB_DQ<8> @S9S_MB_2U_LIB.S9S_MB_2U(SCH_1):M_G_CPU0_SB_DQ(8)    I47 @S9S_MB_2U_LIB.S9S_MB_2U(SCH_1):PAGE95
   113 M_G_CPU0_SB_DQ<9> @S9S_MB_2U_LIB.S9S_MB_2U(SCH_1):M_G_CPU0_SB_DQ(9)    I47 @S9S_MB_2U_LIB.S9S_MB_2U(SCH_1):PAGE95
   256 M_G_CPU0_SB_DQ<10> @S9S_MB_2U_LIB.S9S_MB_2U(SCH_1):M_G_CPU0_SB_DQ(10)    I47 @S9S_MB_2U_LIB.S9S_MB_2U(SCH_1):PAGE95
   258 M_G_CPU0_SB_DQ<11> @S9S_MB_2U_LIB.S9S_MB_2U(SCH_1):M_G_CPU0_SB_DQ(11)    I47 @S9S_MB_2U_LIB.S9S_MB_2U(SCH_1):PAGE95
   118 M_G_CPU0_SB_DQ<12> @S9S_MB_2U_LIB.S9S_MB_2U(SCH_1):M_G_CPU0_SB_DQ(12)    I47 @S9S_MB_2U_LIB.S9S_MB_2U(SCH_1):PAGE95
   120 M_G_CPU0_SB_DQ<13> @S9S_MB_2U_LIB.S9S_MB_2U(SCH_1):M_G_CPU0_SB_DQ(13)    I47 @S9S_MB_2U_LIB.S9S_MB_2U(SCH_1):PAGE95
   263 M_G_CPU0_SB_DQ<14> @S9S_MB_2U_LIB.S9S_MB_2U(SCH_1):M_G_CPU0_SB_DQ(14)    I47 @S9S_MB_2U_LIB.S9S_MB_2U(SCH_1):PAGE95
   265 M_G_CPU0_SB_DQ<15> @S9S_MB_2U_LIB.S9S_MB_2U(SCH_1):M_G_CPU0_SB_DQ(15)    I47 @S9S_MB_2U_LIB.S9S_MB_2U(SCH_1):PAGE95
   122 M_G_CPU0_SB_DQ<16> @S9S_MB_2U_LIB.S9S_MB_2U(SCH_1):M_G_CPU0_SB_DQ(16)    I47 @S9S_MB_2U_LIB.S9S_MB_2U(SCH_1):PAGE95
   124 M_G_CPU0_SB_DQ<17> @S9S_MB_2U_LIB.S9S_MB_2U(SCH_1):M_G_CPU0_SB_DQ(17)    I47 @S9S_MB_2U_LIB.S9S_MB_2U(SCH_1):PAGE95
   267 M_G_CPU0_SB_DQ<18> @S9S_MB_2U_LIB.S9S_MB_2U(SCH_1):M_G_CPU0_SB_DQ(18)    I47 @S9S_MB_2U_LIB.S9S_MB_2U(SCH_1):PAGE95
   269 M_G_CPU0_SB_DQ<19> @S9S_MB_2U_LIB.S9S_MB_2U(SCH_1):M_G_CPU0_SB_DQ(19)    I47 @S9S_MB_2U_LIB.S9S_MB_2U(SCH_1):PAGE95
   129 M_G_CPU0_SB_DQ<20> @S9S_MB_2U_LIB.S9S_MB_2U(SCH_1):M_G_CPU0_SB_DQ(20)    I47 @S9S_MB_2U_LIB.S9S_MB_2U(SCH_1):PAGE95
   131 M_G_CPU0_SB_DQ<21> @S9S_MB_2U_LIB.S9S_MB_2U(SCH_1):M_G_CPU0_SB_DQ(21)    I47 @S9S_MB_2U_LIB.S9S_MB_2U(SCH_1):PAGE95
   274 M_G_CPU0_SB_DQ<22> @S9S_MB_2U_LIB.S9S_MB_2U(SCH_1):M_G_CPU0_SB_DQ(22)    I47 @S9S_MB_2U_LIB.S9S_MB_2U(SCH_1):PAGE95
   276 M_G_CPU0_SB_DQ<23> @S9S_MB_2U_LIB.S9S_MB_2U(SCH_1):M_G_CPU0_SB_DQ(23)    I47 @S9S_MB_2U_LIB.S9S_MB_2U(SCH_1):PAGE95
   133 M_G_CPU0_SB_DQ<24> @S9S_MB_2U_LIB.S9S_MB_2U(SCH_1):M_G_CPU0_SB_DQ(24)    I47 @S9S_MB_2U_LIB.S9S_MB_2U(SCH_1):PAGE95
   135 M_G_CPU0_SB_DQ<25> @S9S_MB_2U_LIB.S9S_MB_2U(SCH_1):M_G_CPU0_SB_DQ(25)    I47 @S9S_MB_2U_LIB.S9S_MB_2U(SCH_1):PAGE95
   278 M_G_CPU0_SB_DQ<26> @S9S_MB_2U_LIB.S9S_MB_2U(SCH_1):M_G_CPU0_SB_DQ(26)    I47 @S9S_MB_2U_LIB.S9S_MB_2U(SCH_1):PAGE95
   280 M_G_CPU0_SB_DQ<27> @S9S_MB_2U_LIB.S9S_MB_2U(SCH_1):M_G_CPU0_SB_DQ(27)    I47 @S9S_MB_2U_LIB.S9S_MB_2U(SCH_1):PAGE95
   140 M_G_CPU0_SB_DQ<28> @S9S_MB_2U_LIB.S9S_MB_2U(SCH_1):M_G_CPU0_SB_DQ(28)    I47 @S9S_MB_2U_LIB.S9S_MB_2U(SCH_1):PAGE95
   142 M_G_CPU0_SB_DQ<29> @S9S_MB_2U_LIB.S9S_MB_2U(SCH_1):M_G_CPU0_SB_DQ(29)    I47 @S9S_MB_2U_LIB.S9S_MB_2U(SCH_1):PAGE95
   285 M_G_CPU0_SB_DQ<30> @S9S_MB_2U_LIB.S9S_MB_2U(SCH_1):M_G_CPU0_SB_DQ(30)    I47 @S9S_MB_2U_LIB.S9S_MB_2U(SCH_1):PAGE95
   287 M_G_CPU0_SB_DQ<31> @S9S_MB_2U_LIB.S9S_MB_2U(SCH_1):M_G_CPU0_SB_DQ(31)    I47 @S9S_MB_2U_LIB.S9S_MB_2U(SCH_1):PAGE95
     7 M_G_CPU0_SA_DQ<0> @S9S_MB_2U_LIB.S9S_MB_2U(SCH_1):M_G_CPU0_SA_DQ(0)    I47 @S9S_MB_2U_LIB.S9S_MB_2U(SCH_1):PAGE95
     9 M_G_CPU0_SA_DQ<1> @S9S_MB_2U_LIB.S9S_MB_2U(SCH_1):M_G_CPU0_SA_DQ(1)    I47 @S9S_MB_2U_LIB.S9S_MB_2U(SCH_1):PAGE95
   152 M_G_CPU0_SA_DQ<2> @S9S_MB_2U_LIB.S9S_MB_2U(SCH_1):M_G_CPU0_SA_DQ(2)    I47 @S9S_MB_2U_LIB.S9S_MB_2U(SCH_1):PAGE95
   154 M_G_CPU0_SA_DQ<3> @S9S_MB_2U_LIB.S9S_MB_2U(SCH_1):M_G_CPU0_SA_DQ(3)    I47 @S9S_MB_2U_LIB.S9S_MB_2U(SCH_1):PAGE95
    14 M_G_CPU0_SA_DQ<4> @S9S_MB_2U_LIB.S9S_MB_2U(SCH_1):M_G_CPU0_SA_DQ(4)    I47 @S9S_MB_2U_LIB.S9S_MB_2U(SCH_1):PAGE95
    16 M_G_CPU0_SA_DQ<5> @S9S_MB_2U_LIB.S9S_MB_2U(SCH_1):M_G_CPU0_SA_DQ(5)    I47 @S9S_MB_2U_LIB.S9S_MB_2U(SCH_1):PAGE95
   159 M_G_CPU0_SA_DQ<6> @S9S_MB_2U_LIB.S9S_MB_2U(SCH_1):M_G_CPU0_SA_DQ(6)    I47 @S9S_MB_2U_LIB.S9S_MB_2U(SCH_1):PAGE95
   161 M_G_CPU0_SA_DQ<7> @S9S_MB_2U_LIB.S9S_MB_2U(SCH_1):M_G_CPU0_SA_DQ(7)    I47 @S9S_MB_2U_LIB.S9S_MB_2U(SCH_1):PAGE95
    18 M_G_CPU0_SA_DQ<8> @S9S_MB_2U_LIB.S9S_MB_2U(SCH_1):M_G_CPU0_SA_DQ(8)    I47 @S9S_MB_2U_LIB.S9S_MB_2U(SCH_1):PAGE95
    20 M_G_CPU0_SA_DQ<9> @S9S_MB_2U_LIB.S9S_MB_2U(SCH_1):M_G_CPU0_SA_DQ(9)    I47 @S9S_MB_2U_LIB.S9S_MB_2U(SCH_1):PAGE95
   163 M_G_CPU0_SA_DQ<10> @S9S_MB_2U_LIB.S9S_MB_2U(SCH_1):M_G_CPU0_SA_DQ(10)    I47 @S9S_MB_2U_LIB.S9S_MB_2U(SCH_1):PAGE95
   165 M_G_CPU0_SA_DQ<11> @S9S_MB_2U_LIB.S9S_MB_2U(SCH_1):M_G_CPU0_SA_DQ(11)    I47 @S9S_MB_2U_LIB.S9S_MB_2U(SCH_1):PAGE95
    25 M_G_CPU0_SA_DQ<12> @S9S_MB_2U_LIB.S9S_MB_2U(SCH_1):M_G_CPU0_SA_DQ(12)    I47 @S9S_MB_2U_LIB.S9S_MB_2U(SCH_1):PAGE95
    27 M_G_CPU0_SA_DQ<13> @S9S_MB_2U_LIB.S9S_MB_2U(SCH_1):M_G_CPU0_SA_DQ(13)    I47 @S9S_MB_2U_LIB.S9S_MB_2U(SCH_1):PAGE95
   170 M_G_CPU0_SA_DQ<14> @S9S_MB_2U_LIB.S9S_MB_2U(SCH_1):M_G_CPU0_SA_DQ(14)    I47 @S9S_MB_2U_LIB.S9S_MB_2U(SCH_1):PAGE95
   172 M_G_CPU0_SA_DQ<15> @S9S_MB_2U_LIB.S9S_MB_2U(SCH_1):M_G_CPU0_SA_DQ(15)    I47 @S9S_MB_2U_LIB.S9S_MB_2U(SCH_1):PAGE95
    29 M_G_CPU0_SA_DQ<16> @S9S_MB_2U_LIB.S9S_MB_2U(SCH_1):M_G_CPU0_SA_DQ(16)    I47 @S9S_MB_2U_LIB.S9S_MB_2U(SCH_1):PAGE95
    31 M_G_CPU0_SA_DQ<17> @S9S_MB_2U_LIB.S9S_MB_2U(SCH_1):M_G_CPU0_SA_DQ(17)    I47 @S9S_MB_2U_LIB.S9S_MB_2U(SCH_1):PAGE95
   174 M_G_CPU0_SA_DQ<18> @S9S_MB_2U_LIB.S9S_MB_2U(SCH_1):M_G_CPU0_SA_DQ(18)    I47 @S9S_MB_2U_LIB.S9S_MB_2U(SCH_1):PAGE95
   176 M_G_CPU0_SA_DQ<19> @S9S_MB_2U_LIB.S9S_MB_2U(SCH_1):M_G_CPU0_SA_DQ(19)    I47 @S9S_MB_2U_LIB.S9S_MB_2U(SCH_1):PAGE95
    36 M_G_CPU0_SA_DQ<20> @S9S_MB_2U_LIB.S9S_MB_2U(SCH_1):M_G_CPU0_SA_DQ(20)    I47 @S9S_MB_2U_LIB.S9S_MB_2U(SCH_1):PAGE95
    38 M_G_CPU0_SA_DQ<21> @S9S_MB_2U_LIB.S9S_MB_2U(SCH_1):M_G_CPU0_SA_DQ(21)    I47 @S9S_MB_2U_LIB.S9S_MB_2U(SCH_1):PAGE95
   181 M_G_CPU0_SA_DQ<22> @S9S_MB_2U_LIB.S9S_MB_2U(SCH_1):M_G_CPU0_SA_DQ(22)    I47 @S9S_MB_2U_LIB.S9S_MB_2U(SCH_1):PAGE95
   183 M_G_CPU0_SA_DQ<23> @S9S_MB_2U_LIB.S9S_MB_2U(SCH_1):M_G_CPU0_SA_DQ(23)    I47 @S9S_MB_2U_LIB.S9S_MB_2U(SCH_1):PAGE95
    40 M_G_CPU0_SA_DQ<24> @S9S_MB_2U_LIB.S9S_MB_2U(SCH_1):M_G_CPU0_SA_DQ(24)    I47 @S9S_MB_2U_LIB.S9S_MB_2U(SCH_1):PAGE95
    42 M_G_CPU0_SA_DQ<25> @S9S_MB_2U_LIB.S9S_MB_2U(SCH_1):M_G_CPU0_SA_DQ(25)    I47 @S9S_MB_2U_LIB.S9S_MB_2U(SCH_1):PAGE95
   185 M_G_CPU0_SA_DQ<26> @S9S_MB_2U_LIB.S9S_MB_2U(SCH_1):M_G_CPU0_SA_DQ(26)    I47 @S9S_MB_2U_LIB.S9S_MB_2U(SCH_1):PAGE95
   187 M_G_CPU0_SA_DQ<27> @S9S_MB_2U_LIB.S9S_MB_2U(SCH_1):M_G_CPU0_SA_DQ(27)    I47 @S9S_MB_2U_LIB.S9S_MB_2U(SCH_1):PAGE95
    47 M_G_CPU0_SA_DQ<28> @S9S_MB_2U_LIB.S9S_MB_2U(SCH_1):M_G_CPU0_SA_DQ(28)    I47 @S9S_MB_2U_LIB.S9S_MB_2U(SCH_1):PAGE95
    49 M_G_CPU0_SA_DQ<29> @S9S_MB_2U_LIB.S9S_MB_2U(SCH_1):M_G_CPU0_SA_DQ(29)    I47 @S9S_MB_2U_LIB.S9S_MB_2U(SCH_1):PAGE95
   192 M_G_CPU0_SA_DQ<30> @S9S_MB_2U_LIB.S9S_MB_2U(SCH_1):M_G_CPU0_SA_DQ(30)    I47 @S9S_MB_2U_LIB.S9S_MB_2U(SCH_1):PAGE95
   229 M_G_CPU0_SB_CS_N<3> @S9S_MB_2U_LIB.S9S_MB_2U(SCH_1):M_G_CPU0_SB_CS_N(3)    I47 @S9S_MB_2U_LIB.S9S_MB_2U(SCH_1):PAGE95
   209 M_G_CPU0_SA_CS_N<3> @S9S_MB_2U_LIB.S9S_MB_2U(SCH_1):M_G_CPU0_SA_CS_N(3)    I47 @S9S_MB_2U_LIB.S9S_MB_2U(SCH_1):PAGE95
    84 M_G_CPU0_SB_CS_N<2> @S9S_MB_2U_LIB.S9S_MB_2U(SCH_1):M_G_CPU0_SB_CS_N(2)    I47 @S9S_MB_2U_LIB.S9S_MB_2U(SCH_1):PAGE95
    64 M_G_CPU0_SA_CS_N<2> @S9S_MB_2U_LIB.S9S_MB_2U(SCH_1):M_G_CPU0_SA_CS_N(2)    I47 @S9S_MB_2U_LIB.S9S_MB_2U(SCH_1):PAGE95
   217 M_G_CPU0_CLK_DP<1> @S9S_MB_2U_LIB.S9S_MB_2U(SCH_1):M_G_CPU0_CLK_DP(1)    I47 @S9S_MB_2U_LIB.S9S_MB_2U(SCH_1):PAGE95
   218 M_G_CPU0_CLK_DN<1> @S9S_MB_2U_LIB.S9S_MB_2U(SCH_1):M_G_CPU0_CLK_DN(1)    I47 @S9S_MB_2U_LIB.S9S_MB_2U(SCH_1):PAGE95
    96 M_G_CPU0_SB_CB<0> @S9S_MB_2U_LIB.S9S_MB_2U(SCH_1):M_G_CPU0_SB_CB(0)    I47 @S9S_MB_2U_LIB.S9S_MB_2U(SCH_1):PAGE95
    98 M_G_CPU0_SB_CB<1> @S9S_MB_2U_LIB.S9S_MB_2U(SCH_1):M_G_CPU0_SB_CB(1)    I47 @S9S_MB_2U_LIB.S9S_MB_2U(SCH_1):PAGE95
   241 M_G_CPU0_SB_CB<2> @S9S_MB_2U_LIB.S9S_MB_2U(SCH_1):M_G_CPU0_SB_CB(2)    I47 @S9S_MB_2U_LIB.S9S_MB_2U(SCH_1):PAGE95
   243 M_G_CPU0_SB_CB<3> @S9S_MB_2U_LIB.S9S_MB_2U(SCH_1):M_G_CPU0_SB_CB(3)    I47 @S9S_MB_2U_LIB.S9S_MB_2U(SCH_1):PAGE95
    89 M_G_CPU0_SB_CB<4> @S9S_MB_2U_LIB.S9S_MB_2U(SCH_1):M_G_CPU0_SB_CB(4)    I47 @S9S_MB_2U_LIB.S9S_MB_2U(SCH_1):PAGE95
    91 M_G_CPU0_SB_CB<5> @S9S_MB_2U_LIB.S9S_MB_2U(SCH_1):M_G_CPU0_SB_CB(5)    I47 @S9S_MB_2U_LIB.S9S_MB_2U(SCH_1):PAGE95
   234 M_G_CPU0_SB_CB<6> @S9S_MB_2U_LIB.S9S_MB_2U(SCH_1):M_G_CPU0_SB_CB(6)    I47 @S9S_MB_2U_LIB.S9S_MB_2U(SCH_1):PAGE95
    51 M_G_CPU0_SA_CB<0> @S9S_MB_2U_LIB.S9S_MB_2U(SCH_1):M_G_CPU0_SA_CB(0)    I47 @S9S_MB_2U_LIB.S9S_MB_2U(SCH_1):PAGE95
   196 M_G_CPU0_SA_CB<2> @S9S_MB_2U_LIB.S9S_MB_2U(SCH_1):M_G_CPU0_SA_CB(2)    I47 @S9S_MB_2U_LIB.S9S_MB_2U(SCH_1):PAGE95
   198 M_G_CPU0_SA_CB<3> @S9S_MB_2U_LIB.S9S_MB_2U(SCH_1):M_G_CPU0_SA_CB(3)    I47 @S9S_MB_2U_LIB.S9S_MB_2U(SCH_1):PAGE95
    60 M_G_CPU0_SA_CB<5> @S9S_MB_2U_LIB.S9S_MB_2U(SCH_1):M_G_CPU0_SA_CB(5)    I47 @S9S_MB_2U_LIB.S9S_MB_2U(SCH_1):PAGE95
   203 M_G_CPU0_SA_CB<6> @S9S_MB_2U_LIB.S9S_MB_2U(SCH_1):M_G_CPU0_SA_CB(6)    I47 @S9S_MB_2U_LIB.S9S_MB_2U(SCH_1):PAGE95
    82 M_G_CPU0_SB_CA<6> @S9S_MB_2U_LIB.S9S_MB_2U(SCH_1):M_G_CPU0_SB_CA(6)    I47 @S9S_MB_2U_LIB.S9S_MB_2U(SCH_1):PAGE95
    72 M_G_CPU0_SA_CA<6> @S9S_MB_2U_LIB.S9S_MB_2U(SCH_1):M_G_CPU0_SA_CA(6)    I47 @S9S_MB_2U_LIB.S9S_MB_2U(SCH_1):PAGE95
   225 M_G_CPU0_SB_CA<5> @S9S_MB_2U_LIB.S9S_MB_2U(SCH_1):M_G_CPU0_SB_CA(5)    I47 @S9S_MB_2U_LIB.S9S_MB_2U(SCH_1):PAGE95
   215 M_G_CPU0_SA_CA<5> @S9S_MB_2U_LIB.S9S_MB_2U(SCH_1):M_G_CPU0_SA_CA(5)    I47 @S9S_MB_2U_LIB.S9S_MB_2U(SCH_1):PAGE95
    80 M_G_CPU0_SB_CA<4> @S9S_MB_2U_LIB.S9S_MB_2U(SCH_1):M_G_CPU0_SB_CA(4)    I47 @S9S_MB_2U_LIB.S9S_MB_2U(SCH_1):PAGE95
    70 M_G_CPU0_SA_CA<4> @S9S_MB_2U_LIB.S9S_MB_2U(SCH_1):M_G_CPU0_SA_CA(4)    I47 @S9S_MB_2U_LIB.S9S_MB_2U(SCH_1):PAGE95
   223 M_G_CPU0_SB_CA<3> @S9S_MB_2U_LIB.S9S_MB_2U(SCH_1):M_G_CPU0_SB_CA(3)    I47 @S9S_MB_2U_LIB.S9S_MB_2U(SCH_1):PAGE95
   213 M_G_CPU0_SA_CA<3> @S9S_MB_2U_LIB.S9S_MB_2U(SCH_1):M_G_CPU0_SA_CA(3)    I47 @S9S_MB_2U_LIB.S9S_MB_2U(SCH_1):PAGE95
    78 M_G_CPU0_SB_CA<2> @S9S_MB_2U_LIB.S9S_MB_2U(SCH_1):M_G_CPU0_SB_CA(2)    I47 @S9S_MB_2U_LIB.S9S_MB_2U(SCH_1):PAGE95
    68 M_G_CPU0_SA_CA<2> @S9S_MB_2U_LIB.S9S_MB_2U(SCH_1):M_G_CPU0_SA_CA(2)    I47 @S9S_MB_2U_LIB.S9S_MB_2U(SCH_1):PAGE95
   221 M_G_CPU0_SB_CA<1> @S9S_MB_2U_LIB.S9S_MB_2U(SCH_1):M_G_CPU0_SB_CA(1)    I47 @S9S_MB_2U_LIB.S9S_MB_2U(SCH_1):PAGE95
   211 M_G_CPU0_SA_CA<1> @S9S_MB_2U_LIB.S9S_MB_2U(SCH_1):M_G_CPU0_SA_CA(1)    I47 @S9S_MB_2U_LIB.S9S_MB_2U(SCH_1):PAGE95
    76 M_G_CPU0_SB_CA<0> @S9S_MB_2U_LIB.S9S_MB_2U(SCH_1):M_G_CPU0_SB_CA(0)    I47 @S9S_MB_2U_LIB.S9S_MB_2U(SCH_1):PAGE95
    66 M_G_CPU0_SA_CA<0> @S9S_MB_2U_LIB.S9S_MB_2U(SCH_1):M_G_CPU0_SA_CA(0)    I47 @S9S_MB_2U_LIB.S9S_MB_2U(SCH_1):PAGE95
    62 M_G_CPU0_ALERT_N @S9S_MB_2U_LIB.S9S_MB_2U(SCH_1):M_G_CPU0_ALERT_N    I47 @S9S_MB_2U_LIB.S9S_MB_2U(SCH_1):PAGE95
   236 M_G_CPU0_SB_CB<7> @S9S_MB_2U_LIB.S9S_MB_2U(SCH_1):M_G_CPU0_SB_CB(7)    I47 @S9S_MB_2U_LIB.S9S_MB_2U(SCH_1):PAGE95
    53 M_G_CPU0_SA_CB<1> @S9S_MB_2U_LIB.S9S_MB_2U(SCH_1):M_G_CPU0_SA_CB(1)    I47 @S9S_MB_2U_LIB.S9S_MB_2U(SCH_1):PAGE95
    58 M_G_CPU0_SA_CB<4> @S9S_MB_2U_LIB.S9S_MB_2U(SCH_1):M_G_CPU0_SA_CB(4)    I47 @S9S_MB_2U_LIB.S9S_MB_2U(SCH_1):PAGE95
   205 M_G_CPU0_SA_CB<7> @S9S_MB_2U_LIB.S9S_MB_2U(SCH_1):M_G_CPU0_SA_CB(7)    I47 @S9S_MB_2U_LIB.S9S_MB_2U(SCH_1):PAGE95
   194 M_G_CPU0_SA_DQ<31> @S9S_MB_2U_LIB.S9S_MB_2U(SCH_1):M_G_CPU0_SA_DQ(31)    I47 @S9S_MB_2U_LIB.S9S_MB_2U(SCH_1):PAGE95
    93 M_G_CPU0_SB_DQS_DP<9> @S9S_MB_2U_LIB.S9S_MB_2U(SCH_1):M_G_CPU0_SB_DQS_DP(9)   I178 @S9S_MB_2U_LIB.S9S_MB_2U(SCH_1):PAGE95
    94 M_G_CPU0_SB_DQS_DN<9> @S9S_MB_2U_LIB.S9S_MB_2U(SCH_1):M_G_CPU0_SB_DQS_DN(9)   I178 @S9S_MB_2U_LIB.S9S_MB_2U(SCH_1):PAGE95
   201 M_G_CPU0_SA_DQS_DP<9> @S9S_MB_2U_LIB.S9S_MB_2U(SCH_1):M_G_CPU0_SA_DQS_DP(9)   I178 @S9S_MB_2U_LIB.S9S_MB_2U(SCH_1):PAGE95
   200 M_G_CPU0_SA_DQS_DN<9> @S9S_MB_2U_LIB.S9S_MB_2U(SCH_1):M_G_CPU0_SA_DQS_DN(9)   I178 @S9S_MB_2U_LIB.S9S_MB_2U(SCH_1):PAGE95
   190 M_G_CPU0_SA_DQS_DP<8> @S9S_MB_2U_LIB.S9S_MB_2U(SCH_1):M_G_CPU0_SA_DQS_DP(8)   I178 @S9S_MB_2U_LIB.S9S_MB_2U(SCH_1):PAGE95
   189 M_G_CPU0_SA_DQS_DN<8> @S9S_MB_2U_LIB.S9S_MB_2U(SCH_1):M_G_CPU0_SA_DQS_DN(8)   I178 @S9S_MB_2U_LIB.S9S_MB_2U(SCH_1):PAGE95
   271 M_G_CPU0_SB_DQS_DN<7> @S9S_MB_2U_LIB.S9S_MB_2U(SCH_1):M_G_CPU0_SB_DQS_DN(7)   I178 @S9S_MB_2U_LIB.S9S_MB_2U(SCH_1):PAGE95
   179 M_G_CPU0_SA_DQS_DP<7> @S9S_MB_2U_LIB.S9S_MB_2U(SCH_1):M_G_CPU0_SA_DQS_DP(7)   I178 @S9S_MB_2U_LIB.S9S_MB_2U(SCH_1):PAGE95
   261 M_G_CPU0_SB_DQS_DP<6> @S9S_MB_2U_LIB.S9S_MB_2U(SCH_1):M_G_CPU0_SB_DQS_DP(6)   I178 @S9S_MB_2U_LIB.S9S_MB_2U(SCH_1):PAGE95
   260 M_G_CPU0_SB_DQS_DN<6> @S9S_MB_2U_LIB.S9S_MB_2U(SCH_1):M_G_CPU0_SB_DQS_DN(6)   I178 @S9S_MB_2U_LIB.S9S_MB_2U(SCH_1):PAGE95
   167 M_G_CPU0_SA_DQS_DN<6> @S9S_MB_2U_LIB.S9S_MB_2U(SCH_1):M_G_CPU0_SA_DQS_DN(6)   I178 @S9S_MB_2U_LIB.S9S_MB_2U(SCH_1):PAGE95
   250 M_G_CPU0_SB_DQS_DP<5> @S9S_MB_2U_LIB.S9S_MB_2U(SCH_1):M_G_CPU0_SB_DQS_DP(5)   I178 @S9S_MB_2U_LIB.S9S_MB_2U(SCH_1):PAGE95
   249 M_G_CPU0_SB_DQS_DN<5> @S9S_MB_2U_LIB.S9S_MB_2U(SCH_1):M_G_CPU0_SB_DQS_DN(5)   I178 @S9S_MB_2U_LIB.S9S_MB_2U(SCH_1):PAGE95
   157 M_G_CPU0_SA_DQS_DP<5> @S9S_MB_2U_LIB.S9S_MB_2U(SCH_1):M_G_CPU0_SA_DQS_DP(5)   I178 @S9S_MB_2U_LIB.S9S_MB_2U(SCH_1):PAGE95
   156 M_G_CPU0_SA_DQS_DN<5> @S9S_MB_2U_LIB.S9S_MB_2U(SCH_1):M_G_CPU0_SA_DQS_DN(5)   I178 @S9S_MB_2U_LIB.S9S_MB_2U(SCH_1):PAGE95
   239 M_G_CPU0_SB_DQS_DP<4> @S9S_MB_2U_LIB.S9S_MB_2U(SCH_1):M_G_CPU0_SB_DQS_DP(4)   I178 @S9S_MB_2U_LIB.S9S_MB_2U(SCH_1):PAGE95
   238 M_G_CPU0_SB_DQS_DN<4> @S9S_MB_2U_LIB.S9S_MB_2U(SCH_1):M_G_CPU0_SB_DQS_DN(4)   I178 @S9S_MB_2U_LIB.S9S_MB_2U(SCH_1):PAGE95
    55 M_G_CPU0_SA_DQS_DP<4> @S9S_MB_2U_LIB.S9S_MB_2U(SCH_1):M_G_CPU0_SA_DQS_DP(4)   I178 @S9S_MB_2U_LIB.S9S_MB_2U(SCH_1):PAGE95
    56 M_G_CPU0_SA_DQS_DN<4> @S9S_MB_2U_LIB.S9S_MB_2U(SCH_1):M_G_CPU0_SA_DQS_DN(4)   I178 @S9S_MB_2U_LIB.S9S_MB_2U(SCH_1):PAGE95
   137 M_G_CPU0_SB_DQS_DP<3> @S9S_MB_2U_LIB.S9S_MB_2U(SCH_1):M_G_CPU0_SB_DQS_DP(3)   I178 @S9S_MB_2U_LIB.S9S_MB_2U(SCH_1):PAGE95
   138 M_G_CPU0_SB_DQS_DN<3> @S9S_MB_2U_LIB.S9S_MB_2U(SCH_1):M_G_CPU0_SB_DQS_DN(3)   I178 @S9S_MB_2U_LIB.S9S_MB_2U(SCH_1):PAGE95
    44 M_G_CPU0_SA_DQS_DP<3> @S9S_MB_2U_LIB.S9S_MB_2U(SCH_1):M_G_CPU0_SA_DQS_DP(3)   I178 @S9S_MB_2U_LIB.S9S_MB_2U(SCH_1):PAGE95
    45 M_G_CPU0_SA_DQS_DN<3> @S9S_MB_2U_LIB.S9S_MB_2U(SCH_1):M_G_CPU0_SA_DQS_DN(3)   I178 @S9S_MB_2U_LIB.S9S_MB_2U(SCH_1):PAGE95
   126 M_G_CPU0_SB_DQS_DP<2> @S9S_MB_2U_LIB.S9S_MB_2U(SCH_1):M_G_CPU0_SB_DQS_DP(2)   I178 @S9S_MB_2U_LIB.S9S_MB_2U(SCH_1):PAGE95
   127 M_G_CPU0_SB_DQS_DN<2> @S9S_MB_2U_LIB.S9S_MB_2U(SCH_1):M_G_CPU0_SB_DQS_DN(2)   I178 @S9S_MB_2U_LIB.S9S_MB_2U(SCH_1):PAGE95
    33 M_G_CPU0_SA_DQS_DP<2> @S9S_MB_2U_LIB.S9S_MB_2U(SCH_1):M_G_CPU0_SA_DQS_DP(2)   I178 @S9S_MB_2U_LIB.S9S_MB_2U(SCH_1):PAGE95
    34 M_G_CPU0_SA_DQS_DN<2> @S9S_MB_2U_LIB.S9S_MB_2U(SCH_1):M_G_CPU0_SA_DQS_DN(2)   I178 @S9S_MB_2U_LIB.S9S_MB_2U(SCH_1):PAGE95
   115 M_G_CPU0_SB_DQS_DP<1> @S9S_MB_2U_LIB.S9S_MB_2U(SCH_1):M_G_CPU0_SB_DQS_DP(1)   I178 @S9S_MB_2U_LIB.S9S_MB_2U(SCH_1):PAGE95
   116 M_G_CPU0_SB_DQS_DN<1> @S9S_MB_2U_LIB.S9S_MB_2U(SCH_1):M_G_CPU0_SB_DQS_DN(1)   I178 @S9S_MB_2U_LIB.S9S_MB_2U(SCH_1):PAGE95
    22 M_G_CPU0_SA_DQS_DP<1> @S9S_MB_2U_LIB.S9S_MB_2U(SCH_1):M_G_CPU0_SA_DQS_DP(1)   I178 @S9S_MB_2U_LIB.S9S_MB_2U(SCH_1):PAGE95
    23 M_G_CPU0_SA_DQS_DN<1> @S9S_MB_2U_LIB.S9S_MB_2U(SCH_1):M_G_CPU0_SA_DQS_DN(1)   I178 @S9S_MB_2U_LIB.S9S_MB_2U(SCH_1):PAGE95
   104 M_G_CPU0_SB_DQS_DP<0> @S9S_MB_2U_LIB.S9S_MB_2U(SCH_1):M_G_CPU0_SB_DQS_DP(0)   I178 @S9S_MB_2U_LIB.S9S_MB_2U(SCH_1):PAGE95
   105 M_G_CPU0_SB_DQS_DN<0> @S9S_MB_2U_LIB.S9S_MB_2U(SCH_1):M_G_CPU0_SB_DQS_DN(0)   I178 @S9S_MB_2U_LIB.S9S_MB_2U(SCH_1):PAGE95
    11 M_G_CPU0_SA_DQS_DP<0> @S9S_MB_2U_LIB.S9S_MB_2U(SCH_1):M_G_CPU0_SA_DQS_DP(0)   I178 @S9S_MB_2U_LIB.S9S_MB_2U(SCH_1):PAGE95
    12 M_G_CPU0_SA_DQS_DN<0> @S9S_MB_2U_LIB.S9S_MB_2U(SCH_1):M_G_CPU0_SA_DQS_DN(0)   I178 @S9S_MB_2U_LIB.S9S_MB_2U(SCH_1):PAGE95
   272 M_G_CPU0_SB_DQS_DP<7> @S9S_MB_2U_LIB.S9S_MB_2U(SCH_1):M_G_CPU0_SB_DQS_DP(7)   I178 @S9S_MB_2U_LIB.S9S_MB_2U(SCH_1):PAGE95
   282 M_G_CPU0_SB_DQS_DN<8> @S9S_MB_2U_LIB.S9S_MB_2U(SCH_1):M_G_CPU0_SB_DQS_DN(8)   I178 @S9S_MB_2U_LIB.S9S_MB_2U(SCH_1):PAGE95
   283 M_G_CPU0_SB_DQS_DP<8> @S9S_MB_2U_LIB.S9S_MB_2U(SCH_1):M_G_CPU0_SB_DQS_DP(8)   I178 @S9S_MB_2U_LIB.S9S_MB_2U(SCH_1):PAGE95
   168 M_G_CPU0_SA_DQS_DP<6> @S9S_MB_2U_LIB.S9S_MB_2U(SCH_1):M_G_CPU0_SA_DQS_DP(6)   I178 @S9S_MB_2U_LIB.S9S_MB_2U(SCH_1):PAGE95
   178 M_G_CPU0_SA_DQS_DN<7> @S9S_MB_2U_LIB.S9S_MB_2U(SCH_1):M_G_CPU0_SA_DQS_DN(7)   I178 @S9S_MB_2U_LIB.S9S_MB_2U(SCH_1):PAGE95
     6    GND @S9S_MB_2U_LIB.S9S_MB_2U(SCH_1):GND   I176 @S9S_MB_2U_LIB.S9S_MB_2U(SCH_1):PAGE95
     8    GND @S9S_MB_2U_LIB.S9S_MB_2U(SCH_1):GND   I176 @S9S_MB_2U_LIB.S9S_MB_2U(SCH_1):PAGE95
    10    GND @S9S_MB_2U_LIB.S9S_MB_2U(SCH_1):GND   I176 @S9S_MB_2U_LIB.S9S_MB_2U(SCH_1):PAGE95
    13    GND @S9S_MB_2U_LIB.S9S_MB_2U(SCH_1):GND   I176 @S9S_MB_2U_LIB.S9S_MB_2U(SCH_1):PAGE95
    15    GND @S9S_MB_2U_LIB.S9S_MB_2U(SCH_1):GND   I176 @S9S_MB_2U_LIB.S9S_MB_2U(SCH_1):PAGE95
    17    GND @S9S_MB_2U_LIB.S9S_MB_2U(SCH_1):GND   I176 @S9S_MB_2U_LIB.S9S_MB_2U(SCH_1):PAGE95
    19    GND @S9S_MB_2U_LIB.S9S_MB_2U(SCH_1):GND   I176 @S9S_MB_2U_LIB.S9S_MB_2U(SCH_1):PAGE95
    21    GND @S9S_MB_2U_LIB.S9S_MB_2U(SCH_1):GND   I176 @S9S_MB_2U_LIB.S9S_MB_2U(SCH_1):PAGE95
    24    GND @S9S_MB_2U_LIB.S9S_MB_2U(SCH_1):GND   I176 @S9S_MB_2U_LIB.S9S_MB_2U(SCH_1):PAGE95
    26    GND @S9S_MB_2U_LIB.S9S_MB_2U(SCH_1):GND   I176 @S9S_MB_2U_LIB.S9S_MB_2U(SCH_1):PAGE95
    28    GND @S9S_MB_2U_LIB.S9S_MB_2U(SCH_1):GND   I176 @S9S_MB_2U_LIB.S9S_MB_2U(SCH_1):PAGE95
    30    GND @S9S_MB_2U_LIB.S9S_MB_2U(SCH_1):GND   I176 @S9S_MB_2U_LIB.S9S_MB_2U(SCH_1):PAGE95
    32    GND @S9S_MB_2U_LIB.S9S_MB_2U(SCH_1):GND   I176 @S9S_MB_2U_LIB.S9S_MB_2U(SCH_1):PAGE95
    35    GND @S9S_MB_2U_LIB.S9S_MB_2U(SCH_1):GND   I176 @S9S_MB_2U_LIB.S9S_MB_2U(SCH_1):PAGE95
    37    GND @S9S_MB_2U_LIB.S9S_MB_2U(SCH_1):GND   I176 @S9S_MB_2U_LIB.S9S_MB_2U(SCH_1):PAGE95
    39    GND @S9S_MB_2U_LIB.S9S_MB_2U(SCH_1):GND   I176 @S9S_MB_2U_LIB.S9S_MB_2U(SCH_1):PAGE95
    41    GND @S9S_MB_2U_LIB.S9S_MB_2U(SCH_1):GND   I176 @S9S_MB_2U_LIB.S9S_MB_2U(SCH_1):PAGE95
    43    GND @S9S_MB_2U_LIB.S9S_MB_2U(SCH_1):GND   I176 @S9S_MB_2U_LIB.S9S_MB_2U(SCH_1):PAGE95
    46    GND @S9S_MB_2U_LIB.S9S_MB_2U(SCH_1):GND   I176 @S9S_MB_2U_LIB.S9S_MB_2U(SCH_1):PAGE95
    48    GND @S9S_MB_2U_LIB.S9S_MB_2U(SCH_1):GND   I176 @S9S_MB_2U_LIB.S9S_MB_2U(SCH_1):PAGE95
    50    GND @S9S_MB_2U_LIB.S9S_MB_2U(SCH_1):GND   I176 @S9S_MB_2U_LIB.S9S_MB_2U(SCH_1):PAGE95
    52    GND @S9S_MB_2U_LIB.S9S_MB_2U(SCH_1):GND   I176 @S9S_MB_2U_LIB.S9S_MB_2U(SCH_1):PAGE95
    54    GND @S9S_MB_2U_LIB.S9S_MB_2U(SCH_1):GND   I176 @S9S_MB_2U_LIB.S9S_MB_2U(SCH_1):PAGE95
    57    GND @S9S_MB_2U_LIB.S9S_MB_2U(SCH_1):GND   I176 @S9S_MB_2U_LIB.S9S_MB_2U(SCH_1):PAGE95
    59    GND @S9S_MB_2U_LIB.S9S_MB_2U(SCH_1):GND   I176 @S9S_MB_2U_LIB.S9S_MB_2U(SCH_1):PAGE95
    61    GND @S9S_MB_2U_LIB.S9S_MB_2U(SCH_1):GND   I176 @S9S_MB_2U_LIB.S9S_MB_2U(SCH_1):PAGE95
    63    GND @S9S_MB_2U_LIB.S9S_MB_2U(SCH_1):GND   I176 @S9S_MB_2U_LIB.S9S_MB_2U(SCH_1):PAGE95
    65    GND @S9S_MB_2U_LIB.S9S_MB_2U(SCH_1):GND   I176 @S9S_MB_2U_LIB.S9S_MB_2U(SCH_1):PAGE95
    67    GND @S9S_MB_2U_LIB.S9S_MB_2U(SCH_1):GND   I176 @S9S_MB_2U_LIB.S9S_MB_2U(SCH_1):PAGE95
    69    GND @S9S_MB_2U_LIB.S9S_MB_2U(SCH_1):GND   I176 @S9S_MB_2U_LIB.S9S_MB_2U(SCH_1):PAGE95
    71    GND @S9S_MB_2U_LIB.S9S_MB_2U(SCH_1):GND   I176 @S9S_MB_2U_LIB.S9S_MB_2U(SCH_1):PAGE95
    73    GND @S9S_MB_2U_LIB.S9S_MB_2U(SCH_1):GND   I176 @S9S_MB_2U_LIB.S9S_MB_2U(SCH_1):PAGE95
    75    GND @S9S_MB_2U_LIB.S9S_MB_2U(SCH_1):GND   I176 @S9S_MB_2U_LIB.S9S_MB_2U(SCH_1):PAGE95
    77    GND @S9S_MB_2U_LIB.S9S_MB_2U(SCH_1):GND   I176 @S9S_MB_2U_LIB.S9S_MB_2U(SCH_1):PAGE95
    79    GND @S9S_MB_2U_LIB.S9S_MB_2U(SCH_1):GND   I176 @S9S_MB_2U_LIB.S9S_MB_2U(SCH_1):PAGE95
    81    GND @S9S_MB_2U_LIB.S9S_MB_2U(SCH_1):GND   I176 @S9S_MB_2U_LIB.S9S_MB_2U(SCH_1):PAGE95
    83    GND @S9S_MB_2U_LIB.S9S_MB_2U(SCH_1):GND   I176 @S9S_MB_2U_LIB.S9S_MB_2U(SCH_1):PAGE95
    85    GND @S9S_MB_2U_LIB.S9S_MB_2U(SCH_1):GND   I176 @S9S_MB_2U_LIB.S9S_MB_2U(SCH_1):PAGE95
    88    GND @S9S_MB_2U_LIB.S9S_MB_2U(SCH_1):GND   I176 @S9S_MB_2U_LIB.S9S_MB_2U(SCH_1):PAGE95
    90    GND @S9S_MB_2U_LIB.S9S_MB_2U(SCH_1):GND   I176 @S9S_MB_2U_LIB.S9S_MB_2U(SCH_1):PAGE95
    92    GND @S9S_MB_2U_LIB.S9S_MB_2U(SCH_1):GND   I176 @S9S_MB_2U_LIB.S9S_MB_2U(SCH_1):PAGE95
    95    GND @S9S_MB_2U_LIB.S9S_MB_2U(SCH_1):GND   I176 @S9S_MB_2U_LIB.S9S_MB_2U(SCH_1):PAGE95
    97    GND @S9S_MB_2U_LIB.S9S_MB_2U(SCH_1):GND   I176 @S9S_MB_2U_LIB.S9S_MB_2U(SCH_1):PAGE95
    99    GND @S9S_MB_2U_LIB.S9S_MB_2U(SCH_1):GND   I176 @S9S_MB_2U_LIB.S9S_MB_2U(SCH_1):PAGE95
   101    GND @S9S_MB_2U_LIB.S9S_MB_2U(SCH_1):GND   I176 @S9S_MB_2U_LIB.S9S_MB_2U(SCH_1):PAGE95
   103    GND @S9S_MB_2U_LIB.S9S_MB_2U(SCH_1):GND   I176 @S9S_MB_2U_LIB.S9S_MB_2U(SCH_1):PAGE95
   106    GND @S9S_MB_2U_LIB.S9S_MB_2U(SCH_1):GND   I176 @S9S_MB_2U_LIB.S9S_MB_2U(SCH_1):PAGE95
   108    GND @S9S_MB_2U_LIB.S9S_MB_2U(SCH_1):GND   I176 @S9S_MB_2U_LIB.S9S_MB_2U(SCH_1):PAGE95
   110    GND @S9S_MB_2U_LIB.S9S_MB_2U(SCH_1):GND   I176 @S9S_MB_2U_LIB.S9S_MB_2U(SCH_1):PAGE95
   112    GND @S9S_MB_2U_LIB.S9S_MB_2U(SCH_1):GND   I176 @S9S_MB_2U_LIB.S9S_MB_2U(SCH_1):PAGE95
   114    GND @S9S_MB_2U_LIB.S9S_MB_2U(SCH_1):GND   I176 @S9S_MB_2U_LIB.S9S_MB_2U(SCH_1):PAGE95
   117    GND @S9S_MB_2U_LIB.S9S_MB_2U(SCH_1):GND   I176 @S9S_MB_2U_LIB.S9S_MB_2U(SCH_1):PAGE95
   119    GND @S9S_MB_2U_LIB.S9S_MB_2U(SCH_1):GND   I176 @S9S_MB_2U_LIB.S9S_MB_2U(SCH_1):PAGE95
   121    GND @S9S_MB_2U_LIB.S9S_MB_2U(SCH_1):GND   I176 @S9S_MB_2U_LIB.S9S_MB_2U(SCH_1):PAGE95
   123    GND @S9S_MB_2U_LIB.S9S_MB_2U(SCH_1):GND   I176 @S9S_MB_2U_LIB.S9S_MB_2U(SCH_1):PAGE95
   125    GND @S9S_MB_2U_LIB.S9S_MB_2U(SCH_1):GND   I176 @S9S_MB_2U_LIB.S9S_MB_2U(SCH_1):PAGE95
   128    GND @S9S_MB_2U_LIB.S9S_MB_2U(SCH_1):GND   I176 @S9S_MB_2U_LIB.S9S_MB_2U(SCH_1):PAGE95
   130    GND @S9S_MB_2U_LIB.S9S_MB_2U(SCH_1):GND   I176 @S9S_MB_2U_LIB.S9S_MB_2U(SCH_1):PAGE95
   134    GND @S9S_MB_2U_LIB.S9S_MB_2U(SCH_1):GND   I176 @S9S_MB_2U_LIB.S9S_MB_2U(SCH_1):PAGE95
   143    GND @S9S_MB_2U_LIB.S9S_MB_2U(SCH_1):GND   I176 @S9S_MB_2U_LIB.S9S_MB_2U(SCH_1):PAGE95
   151    GND @S9S_MB_2U_LIB.S9S_MB_2U(SCH_1):GND   I176 @S9S_MB_2U_LIB.S9S_MB_2U(SCH_1):PAGE95
   153    GND @S9S_MB_2U_LIB.S9S_MB_2U(SCH_1):GND   I176 @S9S_MB_2U_LIB.S9S_MB_2U(SCH_1):PAGE95
   155    GND @S9S_MB_2U_LIB.S9S_MB_2U(SCH_1):GND   I176 @S9S_MB_2U_LIB.S9S_MB_2U(SCH_1):PAGE95
   158    GND @S9S_MB_2U_LIB.S9S_MB_2U(SCH_1):GND   I176 @S9S_MB_2U_LIB.S9S_MB_2U(SCH_1):PAGE95
   160    GND @S9S_MB_2U_LIB.S9S_MB_2U(SCH_1):GND   I176 @S9S_MB_2U_LIB.S9S_MB_2U(SCH_1):PAGE95
   162    GND @S9S_MB_2U_LIB.S9S_MB_2U(SCH_1):GND   I176 @S9S_MB_2U_LIB.S9S_MB_2U(SCH_1):PAGE95
   164    GND @S9S_MB_2U_LIB.S9S_MB_2U(SCH_1):GND   I176 @S9S_MB_2U_LIB.S9S_MB_2U(SCH_1):PAGE95
   166    GND @S9S_MB_2U_LIB.S9S_MB_2U(SCH_1):GND   I176 @S9S_MB_2U_LIB.S9S_MB_2U(SCH_1):PAGE95
   169    GND @S9S_MB_2U_LIB.S9S_MB_2U(SCH_1):GND   I176 @S9S_MB_2U_LIB.S9S_MB_2U(SCH_1):PAGE95
   171    GND @S9S_MB_2U_LIB.S9S_MB_2U(SCH_1):GND   I176 @S9S_MB_2U_LIB.S9S_MB_2U(SCH_1):PAGE95
   173    GND @S9S_MB_2U_LIB.S9S_MB_2U(SCH_1):GND   I176 @S9S_MB_2U_LIB.S9S_MB_2U(SCH_1):PAGE95
   175    GND @S9S_MB_2U_LIB.S9S_MB_2U(SCH_1):GND   I176 @S9S_MB_2U_LIB.S9S_MB_2U(SCH_1):PAGE95
   177    GND @S9S_MB_2U_LIB.S9S_MB_2U(SCH_1):GND   I176 @S9S_MB_2U_LIB.S9S_MB_2U(SCH_1):PAGE95
   180    GND @S9S_MB_2U_LIB.S9S_MB_2U(SCH_1):GND   I176 @S9S_MB_2U_LIB.S9S_MB_2U(SCH_1):PAGE95
   182    GND @S9S_MB_2U_LIB.S9S_MB_2U(SCH_1):GND   I176 @S9S_MB_2U_LIB.S9S_MB_2U(SCH_1):PAGE95
   184    GND @S9S_MB_2U_LIB.S9S_MB_2U(SCH_1):GND   I176 @S9S_MB_2U_LIB.S9S_MB_2U(SCH_1):PAGE95
   186    GND @S9S_MB_2U_LIB.S9S_MB_2U(SCH_1):GND   I176 @S9S_MB_2U_LIB.S9S_MB_2U(SCH_1):PAGE95
   188    GND @S9S_MB_2U_LIB.S9S_MB_2U(SCH_1):GND   I176 @S9S_MB_2U_LIB.S9S_MB_2U(SCH_1):PAGE95
   191    GND @S9S_MB_2U_LIB.S9S_MB_2U(SCH_1):GND   I176 @S9S_MB_2U_LIB.S9S_MB_2U(SCH_1):PAGE95
   193    GND @S9S_MB_2U_LIB.S9S_MB_2U(SCH_1):GND   I176 @S9S_MB_2U_LIB.S9S_MB_2U(SCH_1):PAGE95
   195    GND @S9S_MB_2U_LIB.S9S_MB_2U(SCH_1):GND   I176 @S9S_MB_2U_LIB.S9S_MB_2U(SCH_1):PAGE95
   197    GND @S9S_MB_2U_LIB.S9S_MB_2U(SCH_1):GND   I176 @S9S_MB_2U_LIB.S9S_MB_2U(SCH_1):PAGE95
   199    GND @S9S_MB_2U_LIB.S9S_MB_2U(SCH_1):GND   I176 @S9S_MB_2U_LIB.S9S_MB_2U(SCH_1):PAGE95
   202    GND @S9S_MB_2U_LIB.S9S_MB_2U(SCH_1):GND   I176 @S9S_MB_2U_LIB.S9S_MB_2U(SCH_1):PAGE95
   204    GND @S9S_MB_2U_LIB.S9S_MB_2U(SCH_1):GND   I176 @S9S_MB_2U_LIB.S9S_MB_2U(SCH_1):PAGE95
   206    GND @S9S_MB_2U_LIB.S9S_MB_2U(SCH_1):GND   I176 @S9S_MB_2U_LIB.S9S_MB_2U(SCH_1):PAGE95
   208    GND @S9S_MB_2U_LIB.S9S_MB_2U(SCH_1):GND   I176 @S9S_MB_2U_LIB.S9S_MB_2U(SCH_1):PAGE95
   210    GND @S9S_MB_2U_LIB.S9S_MB_2U(SCH_1):GND   I176 @S9S_MB_2U_LIB.S9S_MB_2U(SCH_1):PAGE95
   212    GND @S9S_MB_2U_LIB.S9S_MB_2U(SCH_1):GND   I176 @S9S_MB_2U_LIB.S9S_MB_2U(SCH_1):PAGE95
   214    GND @S9S_MB_2U_LIB.S9S_MB_2U(SCH_1):GND   I176 @S9S_MB_2U_LIB.S9S_MB_2U(SCH_1):PAGE95
   216    GND @S9S_MB_2U_LIB.S9S_MB_2U(SCH_1):GND   I176 @S9S_MB_2U_LIB.S9S_MB_2U(SCH_1):PAGE95
   219    GND @S9S_MB_2U_LIB.S9S_MB_2U(SCH_1):GND   I176 @S9S_MB_2U_LIB.S9S_MB_2U(SCH_1):PAGE95
   222    GND @S9S_MB_2U_LIB.S9S_MB_2U(SCH_1):GND   I176 @S9S_MB_2U_LIB.S9S_MB_2U(SCH_1):PAGE95
   224    GND @S9S_MB_2U_LIB.S9S_MB_2U(SCH_1):GND   I176 @S9S_MB_2U_LIB.S9S_MB_2U(SCH_1):PAGE95
   226    GND @S9S_MB_2U_LIB.S9S_MB_2U(SCH_1):GND   I176 @S9S_MB_2U_LIB.S9S_MB_2U(SCH_1):PAGE95
   228    GND @S9S_MB_2U_LIB.S9S_MB_2U(SCH_1):GND   I176 @S9S_MB_2U_LIB.S9S_MB_2U(SCH_1):PAGE95
   233    GND @S9S_MB_2U_LIB.S9S_MB_2U(SCH_1):GND   I176 @S9S_MB_2U_LIB.S9S_MB_2U(SCH_1):PAGE95
   237    GND @S9S_MB_2U_LIB.S9S_MB_2U(SCH_1):GND   I176 @S9S_MB_2U_LIB.S9S_MB_2U(SCH_1):PAGE95
   242    GND @S9S_MB_2U_LIB.S9S_MB_2U(SCH_1):GND   I176 @S9S_MB_2U_LIB.S9S_MB_2U(SCH_1):PAGE95
   244    GND @S9S_MB_2U_LIB.S9S_MB_2U(SCH_1):GND   I176 @S9S_MB_2U_LIB.S9S_MB_2U(SCH_1):PAGE95
   246    GND @S9S_MB_2U_LIB.S9S_MB_2U(SCH_1):GND   I176 @S9S_MB_2U_LIB.S9S_MB_2U(SCH_1):PAGE95
   248    GND @S9S_MB_2U_LIB.S9S_MB_2U(SCH_1):GND   I176 @S9S_MB_2U_LIB.S9S_MB_2U(SCH_1):PAGE95
   251    GND @S9S_MB_2U_LIB.S9S_MB_2U(SCH_1):GND   I176 @S9S_MB_2U_LIB.S9S_MB_2U(SCH_1):PAGE95
   253    GND @S9S_MB_2U_LIB.S9S_MB_2U(SCH_1):GND   I176 @S9S_MB_2U_LIB.S9S_MB_2U(SCH_1):PAGE95
   255    GND @S9S_MB_2U_LIB.S9S_MB_2U(SCH_1):GND   I176 @S9S_MB_2U_LIB.S9S_MB_2U(SCH_1):PAGE95
   257    GND @S9S_MB_2U_LIB.S9S_MB_2U(SCH_1):GND   I176 @S9S_MB_2U_LIB.S9S_MB_2U(SCH_1):PAGE95
   259    GND @S9S_MB_2U_LIB.S9S_MB_2U(SCH_1):GND   I176 @S9S_MB_2U_LIB.S9S_MB_2U(SCH_1):PAGE95
   262    GND @S9S_MB_2U_LIB.S9S_MB_2U(SCH_1):GND   I176 @S9S_MB_2U_LIB.S9S_MB_2U(SCH_1):PAGE95
   264    GND @S9S_MB_2U_LIB.S9S_MB_2U(SCH_1):GND   I176 @S9S_MB_2U_LIB.S9S_MB_2U(SCH_1):PAGE95
   266    GND @S9S_MB_2U_LIB.S9S_MB_2U(SCH_1):GND   I176 @S9S_MB_2U_LIB.S9S_MB_2U(SCH_1):PAGE95
   268    GND @S9S_MB_2U_LIB.S9S_MB_2U(SCH_1):GND   I176 @S9S_MB_2U_LIB.S9S_MB_2U(SCH_1):PAGE95
   270    GND @S9S_MB_2U_LIB.S9S_MB_2U(SCH_1):GND   I176 @S9S_MB_2U_LIB.S9S_MB_2U(SCH_1):PAGE95
   273    GND @S9S_MB_2U_LIB.S9S_MB_2U(SCH_1):GND   I176 @S9S_MB_2U_LIB.S9S_MB_2U(SCH_1):PAGE95
   275    GND @S9S_MB_2U_LIB.S9S_MB_2U(SCH_1):GND   I176 @S9S_MB_2U_LIB.S9S_MB_2U(SCH_1):PAGE95
   277    GND @S9S_MB_2U_LIB.S9S_MB_2U(SCH_1):GND   I176 @S9S_MB_2U_LIB.S9S_MB_2U(SCH_1):PAGE95
   279    GND @S9S_MB_2U_LIB.S9S_MB_2U(SCH_1):GND   I176 @S9S_MB_2U_LIB.S9S_MB_2U(SCH_1):PAGE95
   281    GND @S9S_MB_2U_LIB.S9S_MB_2U(SCH_1):GND   I176 @S9S_MB_2U_LIB.S9S_MB_2U(SCH_1):PAGE95
   284    GND @S9S_MB_2U_LIB.S9S_MB_2U(SCH_1):GND   I176 @S9S_MB_2U_LIB.S9S_MB_2U(SCH_1):PAGE95
   286    GND @S9S_MB_2U_LIB.S9S_MB_2U(SCH_1):GND   I176 @S9S_MB_2U_LIB.S9S_MB_2U(SCH_1):PAGE95
   288    GND @S9S_MB_2U_LIB.S9S_MB_2U(SCH_1):GND   I176 @S9S_MB_2U_LIB.S9S_MB_2U(SCH_1):PAGE95
     1 P12V_S3_AUX_CPU0_NVDIMM @S9S_MB_2U_LIB.S9S_MB_2U(SCH_1):P12V_S3_AUX_CPU0_NVDIMM   I176 @S9S_MB_2U_LIB.S9S_MB_2U(SCH_1):PAGE95
   145 P12V_S3_AUX_CPU0_NVDIMM @S9S_MB_2U_LIB.S9S_MB_2U(SCH_1):P12V_S3_AUX_CPU0_NVDIMM   I176 @S9S_MB_2U_LIB.S9S_MB_2U(SCH_1):PAGE95
   146 P12V_S3_AUX_CPU0_NVDIMM @S9S_MB_2U_LIB.S9S_MB_2U(SCH_1):P12V_S3_AUX_CPU0_NVDIMM   I176 @S9S_MB_2U_LIB.S9S_MB_2U(SCH_1):PAGE95
   230    GND @S9S_MB_2U_LIB.S9S_MB_2U(SCH_1):GND   I176 @S9S_MB_2U_LIB.S9S_MB_2U(SCH_1):PAGE95
   235    GND @S9S_MB_2U_LIB.S9S_MB_2U(SCH_1):GND   I176 @S9S_MB_2U_LIB.S9S_MB_2U(SCH_1):PAGE95
   240    GND @S9S_MB_2U_LIB.S9S_MB_2U(SCH_1):GND   I176 @S9S_MB_2U_LIB.S9S_MB_2U(SCH_1):PAGE95
   132    GND @S9S_MB_2U_LIB.S9S_MB_2U(SCH_1):GND   I176 @S9S_MB_2U_LIB.S9S_MB_2U(SCH_1):PAGE95
   136    GND @S9S_MB_2U_LIB.S9S_MB_2U(SCH_1):GND   I176 @S9S_MB_2U_LIB.S9S_MB_2U(SCH_1):PAGE95
   139    GND @S9S_MB_2U_LIB.S9S_MB_2U(SCH_1):GND   I176 @S9S_MB_2U_LIB.S9S_MB_2U(SCH_1):PAGE95
   141    GND @S9S_MB_2U_LIB.S9S_MB_2U(SCH_1):GND   I176 @S9S_MB_2U_LIB.S9S_MB_2U(SCH_1):PAGE95
    G1    GND @S9S_MB_2U_LIB.S9S_MB_2U(SCH_1):GND   I176 @S9S_MB_2U_LIB.S9S_MB_2U(SCH_1):PAGE95
    G2    GND @S9S_MB_2U_LIB.S9S_MB_2U(SCH_1):GND   I176 @S9S_MB_2U_LIB.S9S_MB_2U(SCH_1):PAGE95
    G3    GND @S9S_MB_2U_LIB.S9S_MB_2U(SCH_1):GND   I176 @S9S_MB_2U_LIB.S9S_MB_2U(SCH_1):PAGE95

 J15 SCONN288_ADR50017P130CC-SCONN2A
     3 P3V3_AUX @S9S_MB_2U_LIB.S9S_MB_2U(SCH_1):P3V3_AUX    I48 @S9S_MB_2U_LIB.S9S_MB_2U(SCH_1):PAGE96
     2 TP_CHH_CPU0_DIMM1_FRU_0 @S9S_MB_2U_LIB.S9S_MB_2U(SCH_1):TP_CHH_CPU0_DIMM1_FRU_0    I48 @S9S_MB_2U_LIB.S9S_MB_2U(SCH_1):PAGE96
   144 TP_CHH_CPU0_DIMM1_FRU_1 @S9S_MB_2U_LIB.S9S_MB_2U(SCH_1):TP_CHH_CPU0_DIMM1_FRU_1    I48 @S9S_MB_2U_LIB.S9S_MB_2U(SCH_1):PAGE96
   149 TP_CHH_CPU0_DIMM1_FRU_2 @S9S_MB_2U_LIB.S9S_MB_2U(SCH_1):TP_CHH_CPU0_DIMM1_FRU_2    I48 @S9S_MB_2U_LIB.S9S_MB_2U(SCH_1):PAGE96
   150 TP_CHH_CPU0_DIMM1_FRU_3 @S9S_MB_2U_LIB.S9S_MB_2U(SCH_1):TP_CHH_CPU0_DIMM1_FRU_3    I48 @S9S_MB_2U_LIB.S9S_MB_2U(SCH_1):PAGE96
   220 TP_CHH_CPU0_DIMM1_FRU_4 @S9S_MB_2U_LIB.S9S_MB_2U(SCH_1):TP_CHH_CPU0_DIMM1_FRU_4    I48 @S9S_MB_2U_LIB.S9S_MB_2U(SCH_1):PAGE96
   231 TP_CHH_CPU0_DIMM1_FRU_5 @S9S_MB_2U_LIB.S9S_MB_2U(SCH_1):TP_CHH_CPU0_DIMM1_FRU_5    I48 @S9S_MB_2U_LIB.S9S_MB_2U(SCH_1):PAGE96
   232 TP_CHH_CPU0_DIMM1_FRU_6 @S9S_MB_2U_LIB.S9S_MB_2U(SCH_1):TP_CHH_CPU0_DIMM1_FRU_6    I48 @S9S_MB_2U_LIB.S9S_MB_2U(SCH_1):PAGE96
   207 RST_M_GH_CPU0_FPGA_N @S9S_MB_2U_LIB.S9S_MB_2U(SCH_1):RST_M_GH_CPU0_FPGA_N    I48 @S9S_MB_2U_LIB.S9S_MB_2U(SCH_1):PAGE96
   147 PWRGD_CHH_CPU0_DIMM1 @S9S_MB_2U_LIB.S9S_MB_2U(SCH_1):PWRGD_CHH_CPU0_DIMM1    I48 @S9S_MB_2U_LIB.S9S_MB_2U(SCH_1):PAGE96
   227 M_H_CPU0_SB_PAR @S9S_MB_2U_LIB.S9S_MB_2U(SCH_1):M_H_CPU0_SB_PAR    I48 @S9S_MB_2U_LIB.S9S_MB_2U(SCH_1):PAGE96
    74 M_H_CPU0_SA_PAR @S9S_MB_2U_LIB.S9S_MB_2U(SCH_1):M_H_CPU0_SA_PAR    I48 @S9S_MB_2U_LIB.S9S_MB_2U(SCH_1):PAGE96
    87 M_H_CPU0_SB_RSP<0> @S9S_MB_2U_LIB.S9S_MB_2U(SCH_1):M_H_CPU0_SB_RSP(0)    I48 @S9S_MB_2U_LIB.S9S_MB_2U(SCH_1):PAGE96
    86 M_H_CPU0_SA_RSP<0> @S9S_MB_2U_LIB.S9S_MB_2U(SCH_1):M_H_CPU0_SA_RSP(0)    I48 @S9S_MB_2U_LIB.S9S_MB_2U(SCH_1):PAGE96
     5 I3C_SPD_DDREFGH_CPU0_LVC1_SDA @S9S_MB_2U_LIB.S9S_MB_2U(SCH_1):I3C_SPD_DDREFGH_CPU0_LVC1_SDA    I48 @S9S_MB_2U_LIB.S9S_MB_2U(SCH_1):PAGE96
     4 I3C_SPD_DDREFGH_CPU0_LVC1_SCL_6 @S9S_MB_2U_LIB.S9S_MB_2U(SCH_1):I3C_SPD_DDREFGH_CPU0_LVC1_SCL_R7    I48 @S9S_MB_2U_LIB.S9S_MB_2U(SCH_1):PAGE96
   148 PD_CHH_CPU0_DIMM1_SAA @S9S_MB_2U_LIB.S9S_MB_2U(SCH_1):PD_CHH_CPU0_DIMM1_SAA    I48 @S9S_MB_2U_LIB.S9S_MB_2U(SCH_1):PAGE96
   100 M_H_CPU0_SB_DQ<0> @S9S_MB_2U_LIB.S9S_MB_2U(SCH_1):M_H_CPU0_SB_DQ(0)    I48 @S9S_MB_2U_LIB.S9S_MB_2U(SCH_1):PAGE96
   102 M_H_CPU0_SB_DQ<1> @S9S_MB_2U_LIB.S9S_MB_2U(SCH_1):M_H_CPU0_SB_DQ(1)    I48 @S9S_MB_2U_LIB.S9S_MB_2U(SCH_1):PAGE96
   245 M_H_CPU0_SB_DQ<2> @S9S_MB_2U_LIB.S9S_MB_2U(SCH_1):M_H_CPU0_SB_DQ(2)    I48 @S9S_MB_2U_LIB.S9S_MB_2U(SCH_1):PAGE96
   247 M_H_CPU0_SB_DQ<3> @S9S_MB_2U_LIB.S9S_MB_2U(SCH_1):M_H_CPU0_SB_DQ(3)    I48 @S9S_MB_2U_LIB.S9S_MB_2U(SCH_1):PAGE96
   107 M_H_CPU0_SB_DQ<4> @S9S_MB_2U_LIB.S9S_MB_2U(SCH_1):M_H_CPU0_SB_DQ(4)    I48 @S9S_MB_2U_LIB.S9S_MB_2U(SCH_1):PAGE96
   109 M_H_CPU0_SB_DQ<5> @S9S_MB_2U_LIB.S9S_MB_2U(SCH_1):M_H_CPU0_SB_DQ(5)    I48 @S9S_MB_2U_LIB.S9S_MB_2U(SCH_1):PAGE96
   252 M_H_CPU0_SB_DQ<6> @S9S_MB_2U_LIB.S9S_MB_2U(SCH_1):M_H_CPU0_SB_DQ(6)    I48 @S9S_MB_2U_LIB.S9S_MB_2U(SCH_1):PAGE96
   254 M_H_CPU0_SB_DQ<7> @S9S_MB_2U_LIB.S9S_MB_2U(SCH_1):M_H_CPU0_SB_DQ(7)    I48 @S9S_MB_2U_LIB.S9S_MB_2U(SCH_1):PAGE96
   111 M_H_CPU0_SB_DQ<8> @S9S_MB_2U_LIB.S9S_MB_2U(SCH_1):M_H_CPU0_SB_DQ(8)    I48 @S9S_MB_2U_LIB.S9S_MB_2U(SCH_1):PAGE96
   113 M_H_CPU0_SB_DQ<9> @S9S_MB_2U_LIB.S9S_MB_2U(SCH_1):M_H_CPU0_SB_DQ(9)    I48 @S9S_MB_2U_LIB.S9S_MB_2U(SCH_1):PAGE96
   256 M_H_CPU0_SB_DQ<10> @S9S_MB_2U_LIB.S9S_MB_2U(SCH_1):M_H_CPU0_SB_DQ(10)    I48 @S9S_MB_2U_LIB.S9S_MB_2U(SCH_1):PAGE96
   258 M_H_CPU0_SB_DQ<11> @S9S_MB_2U_LIB.S9S_MB_2U(SCH_1):M_H_CPU0_SB_DQ(11)    I48 @S9S_MB_2U_LIB.S9S_MB_2U(SCH_1):PAGE96
   118 M_H_CPU0_SB_DQ<12> @S9S_MB_2U_LIB.S9S_MB_2U(SCH_1):M_H_CPU0_SB_DQ(12)    I48 @S9S_MB_2U_LIB.S9S_MB_2U(SCH_1):PAGE96
   120 M_H_CPU0_SB_DQ<13> @S9S_MB_2U_LIB.S9S_MB_2U(SCH_1):M_H_CPU0_SB_DQ(13)    I48 @S9S_MB_2U_LIB.S9S_MB_2U(SCH_1):PAGE96
   263 M_H_CPU0_SB_DQ<14> @S9S_MB_2U_LIB.S9S_MB_2U(SCH_1):M_H_CPU0_SB_DQ(14)    I48 @S9S_MB_2U_LIB.S9S_MB_2U(SCH_1):PAGE96
   265 M_H_CPU0_SB_DQ<15> @S9S_MB_2U_LIB.S9S_MB_2U(SCH_1):M_H_CPU0_SB_DQ(15)    I48 @S9S_MB_2U_LIB.S9S_MB_2U(SCH_1):PAGE96
   122 M_H_CPU0_SB_DQ<16> @S9S_MB_2U_LIB.S9S_MB_2U(SCH_1):M_H_CPU0_SB_DQ(16)    I48 @S9S_MB_2U_LIB.S9S_MB_2U(SCH_1):PAGE96
   124 M_H_CPU0_SB_DQ<17> @S9S_MB_2U_LIB.S9S_MB_2U(SCH_1):M_H_CPU0_SB_DQ(17)    I48 @S9S_MB_2U_LIB.S9S_MB_2U(SCH_1):PAGE96
   267 M_H_CPU0_SB_DQ<18> @S9S_MB_2U_LIB.S9S_MB_2U(SCH_1):M_H_CPU0_SB_DQ(18)    I48 @S9S_MB_2U_LIB.S9S_MB_2U(SCH_1):PAGE96
   269 M_H_CPU0_SB_DQ<19> @S9S_MB_2U_LIB.S9S_MB_2U(SCH_1):M_H_CPU0_SB_DQ(19)    I48 @S9S_MB_2U_LIB.S9S_MB_2U(SCH_1):PAGE96
   129 M_H_CPU0_SB_DQ<20> @S9S_MB_2U_LIB.S9S_MB_2U(SCH_1):M_H_CPU0_SB_DQ(20)    I48 @S9S_MB_2U_LIB.S9S_MB_2U(SCH_1):PAGE96
   131 M_H_CPU0_SB_DQ<21> @S9S_MB_2U_LIB.S9S_MB_2U(SCH_1):M_H_CPU0_SB_DQ(21)    I48 @S9S_MB_2U_LIB.S9S_MB_2U(SCH_1):PAGE96
   274 M_H_CPU0_SB_DQ<22> @S9S_MB_2U_LIB.S9S_MB_2U(SCH_1):M_H_CPU0_SB_DQ(22)    I48 @S9S_MB_2U_LIB.S9S_MB_2U(SCH_1):PAGE96
   276 M_H_CPU0_SB_DQ<23> @S9S_MB_2U_LIB.S9S_MB_2U(SCH_1):M_H_CPU0_SB_DQ(23)    I48 @S9S_MB_2U_LIB.S9S_MB_2U(SCH_1):PAGE96
   133 M_H_CPU0_SB_DQ<24> @S9S_MB_2U_LIB.S9S_MB_2U(SCH_1):M_H_CPU0_SB_DQ(24)    I48 @S9S_MB_2U_LIB.S9S_MB_2U(SCH_1):PAGE96
   135 M_H_CPU0_SB_DQ<25> @S9S_MB_2U_LIB.S9S_MB_2U(SCH_1):M_H_CPU0_SB_DQ(25)    I48 @S9S_MB_2U_LIB.S9S_MB_2U(SCH_1):PAGE96
   278 M_H_CPU0_SB_DQ<26> @S9S_MB_2U_LIB.S9S_MB_2U(SCH_1):M_H_CPU0_SB_DQ(26)    I48 @S9S_MB_2U_LIB.S9S_MB_2U(SCH_1):PAGE96
   280 M_H_CPU0_SB_DQ<27> @S9S_MB_2U_LIB.S9S_MB_2U(SCH_1):M_H_CPU0_SB_DQ(27)    I48 @S9S_MB_2U_LIB.S9S_MB_2U(SCH_1):PAGE96
   140 M_H_CPU0_SB_DQ<28> @S9S_MB_2U_LIB.S9S_MB_2U(SCH_1):M_H_CPU0_SB_DQ(28)    I48 @S9S_MB_2U_LIB.S9S_MB_2U(SCH_1):PAGE96
   142 M_H_CPU0_SB_DQ<29> @S9S_MB_2U_LIB.S9S_MB_2U(SCH_1):M_H_CPU0_SB_DQ(29)    I48 @S9S_MB_2U_LIB.S9S_MB_2U(SCH_1):PAGE96
   285 M_H_CPU0_SB_DQ<30> @S9S_MB_2U_LIB.S9S_MB_2U(SCH_1):M_H_CPU0_SB_DQ(30)    I48 @S9S_MB_2U_LIB.S9S_MB_2U(SCH_1):PAGE96
   287 M_H_CPU0_SB_DQ<31> @S9S_MB_2U_LIB.S9S_MB_2U(SCH_1):M_H_CPU0_SB_DQ(31)    I48 @S9S_MB_2U_LIB.S9S_MB_2U(SCH_1):PAGE96
     7 M_H_CPU0_SA_DQ<0> @S9S_MB_2U_LIB.S9S_MB_2U(SCH_1):M_H_CPU0_SA_DQ(0)    I48 @S9S_MB_2U_LIB.S9S_MB_2U(SCH_1):PAGE96
     9 M_H_CPU0_SA_DQ<1> @S9S_MB_2U_LIB.S9S_MB_2U(SCH_1):M_H_CPU0_SA_DQ(1)    I48 @S9S_MB_2U_LIB.S9S_MB_2U(SCH_1):PAGE96
   152 M_H_CPU0_SA_DQ<2> @S9S_MB_2U_LIB.S9S_MB_2U(SCH_1):M_H_CPU0_SA_DQ(2)    I48 @S9S_MB_2U_LIB.S9S_MB_2U(SCH_1):PAGE96
   154 M_H_CPU0_SA_DQ<3> @S9S_MB_2U_LIB.S9S_MB_2U(SCH_1):M_H_CPU0_SA_DQ(3)    I48 @S9S_MB_2U_LIB.S9S_MB_2U(SCH_1):PAGE96
    14 M_H_CPU0_SA_DQ<4> @S9S_MB_2U_LIB.S9S_MB_2U(SCH_1):M_H_CPU0_SA_DQ(4)    I48 @S9S_MB_2U_LIB.S9S_MB_2U(SCH_1):PAGE96
    16 M_H_CPU0_SA_DQ<5> @S9S_MB_2U_LIB.S9S_MB_2U(SCH_1):M_H_CPU0_SA_DQ(5)    I48 @S9S_MB_2U_LIB.S9S_MB_2U(SCH_1):PAGE96
   159 M_H_CPU0_SA_DQ<6> @S9S_MB_2U_LIB.S9S_MB_2U(SCH_1):M_H_CPU0_SA_DQ(6)    I48 @S9S_MB_2U_LIB.S9S_MB_2U(SCH_1):PAGE96
   161 M_H_CPU0_SA_DQ<7> @S9S_MB_2U_LIB.S9S_MB_2U(SCH_1):M_H_CPU0_SA_DQ(7)    I48 @S9S_MB_2U_LIB.S9S_MB_2U(SCH_1):PAGE96
    18 M_H_CPU0_SA_DQ<8> @S9S_MB_2U_LIB.S9S_MB_2U(SCH_1):M_H_CPU0_SA_DQ(8)    I48 @S9S_MB_2U_LIB.S9S_MB_2U(SCH_1):PAGE96
    20 M_H_CPU0_SA_DQ<9> @S9S_MB_2U_LIB.S9S_MB_2U(SCH_1):M_H_CPU0_SA_DQ(9)    I48 @S9S_MB_2U_LIB.S9S_MB_2U(SCH_1):PAGE96
   163 M_H_CPU0_SA_DQ<10> @S9S_MB_2U_LIB.S9S_MB_2U(SCH_1):M_H_CPU0_SA_DQ(10)    I48 @S9S_MB_2U_LIB.S9S_MB_2U(SCH_1):PAGE96
   165 M_H_CPU0_SA_DQ<11> @S9S_MB_2U_LIB.S9S_MB_2U(SCH_1):M_H_CPU0_SA_DQ(11)    I48 @S9S_MB_2U_LIB.S9S_MB_2U(SCH_1):PAGE96
    25 M_H_CPU0_SA_DQ<12> @S9S_MB_2U_LIB.S9S_MB_2U(SCH_1):M_H_CPU0_SA_DQ(12)    I48 @S9S_MB_2U_LIB.S9S_MB_2U(SCH_1):PAGE96
    27 M_H_CPU0_SA_DQ<13> @S9S_MB_2U_LIB.S9S_MB_2U(SCH_1):M_H_CPU0_SA_DQ(13)    I48 @S9S_MB_2U_LIB.S9S_MB_2U(SCH_1):PAGE96
   170 M_H_CPU0_SA_DQ<14> @S9S_MB_2U_LIB.S9S_MB_2U(SCH_1):M_H_CPU0_SA_DQ(14)    I48 @S9S_MB_2U_LIB.S9S_MB_2U(SCH_1):PAGE96
   172 M_H_CPU0_SA_DQ<15> @S9S_MB_2U_LIB.S9S_MB_2U(SCH_1):M_H_CPU0_SA_DQ(15)    I48 @S9S_MB_2U_LIB.S9S_MB_2U(SCH_1):PAGE96
    29 M_H_CPU0_SA_DQ<16> @S9S_MB_2U_LIB.S9S_MB_2U(SCH_1):M_H_CPU0_SA_DQ(16)    I48 @S9S_MB_2U_LIB.S9S_MB_2U(SCH_1):PAGE96
    31 M_H_CPU0_SA_DQ<17> @S9S_MB_2U_LIB.S9S_MB_2U(SCH_1):M_H_CPU0_SA_DQ(17)    I48 @S9S_MB_2U_LIB.S9S_MB_2U(SCH_1):PAGE96
   174 M_H_CPU0_SA_DQ<18> @S9S_MB_2U_LIB.S9S_MB_2U(SCH_1):M_H_CPU0_SA_DQ(18)    I48 @S9S_MB_2U_LIB.S9S_MB_2U(SCH_1):PAGE96
   176 M_H_CPU0_SA_DQ<19> @S9S_MB_2U_LIB.S9S_MB_2U(SCH_1):M_H_CPU0_SA_DQ(19)    I48 @S9S_MB_2U_LIB.S9S_MB_2U(SCH_1):PAGE96
    36 M_H_CPU0_SA_DQ<20> @S9S_MB_2U_LIB.S9S_MB_2U(SCH_1):M_H_CPU0_SA_DQ(20)    I48 @S9S_MB_2U_LIB.S9S_MB_2U(SCH_1):PAGE96
    38 M_H_CPU0_SA_DQ<21> @S9S_MB_2U_LIB.S9S_MB_2U(SCH_1):M_H_CPU0_SA_DQ(21)    I48 @S9S_MB_2U_LIB.S9S_MB_2U(SCH_1):PAGE96
   181 M_H_CPU0_SA_DQ<22> @S9S_MB_2U_LIB.S9S_MB_2U(SCH_1):M_H_CPU0_SA_DQ(22)    I48 @S9S_MB_2U_LIB.S9S_MB_2U(SCH_1):PAGE96
   183 M_H_CPU0_SA_DQ<23> @S9S_MB_2U_LIB.S9S_MB_2U(SCH_1):M_H_CPU0_SA_DQ(23)    I48 @S9S_MB_2U_LIB.S9S_MB_2U(SCH_1):PAGE96
    40 M_H_CPU0_SA_DQ<24> @S9S_MB_2U_LIB.S9S_MB_2U(SCH_1):M_H_CPU0_SA_DQ(24)    I48 @S9S_MB_2U_LIB.S9S_MB_2U(SCH_1):PAGE96
    42 M_H_CPU0_SA_DQ<25> @S9S_MB_2U_LIB.S9S_MB_2U(SCH_1):M_H_CPU0_SA_DQ(25)    I48 @S9S_MB_2U_LIB.S9S_MB_2U(SCH_1):PAGE96
   185 M_H_CPU0_SA_DQ<26> @S9S_MB_2U_LIB.S9S_MB_2U(SCH_1):M_H_CPU0_SA_DQ(26)    I48 @S9S_MB_2U_LIB.S9S_MB_2U(SCH_1):PAGE96
   187 M_H_CPU0_SA_DQ<27> @S9S_MB_2U_LIB.S9S_MB_2U(SCH_1):M_H_CPU0_SA_DQ(27)    I48 @S9S_MB_2U_LIB.S9S_MB_2U(SCH_1):PAGE96
    47 M_H_CPU0_SA_DQ<28> @S9S_MB_2U_LIB.S9S_MB_2U(SCH_1):M_H_CPU0_SA_DQ(28)    I48 @S9S_MB_2U_LIB.S9S_MB_2U(SCH_1):PAGE96
    49 M_H_CPU0_SA_DQ<29> @S9S_MB_2U_LIB.S9S_MB_2U(SCH_1):M_H_CPU0_SA_DQ(29)    I48 @S9S_MB_2U_LIB.S9S_MB_2U(SCH_1):PAGE96
   192 M_H_CPU0_SA_DQ<30> @S9S_MB_2U_LIB.S9S_MB_2U(SCH_1):M_H_CPU0_SA_DQ(30)    I48 @S9S_MB_2U_LIB.S9S_MB_2U(SCH_1):PAGE96
   229 M_H_CPU0_SB_CS_N<1> @S9S_MB_2U_LIB.S9S_MB_2U(SCH_1):M_H_CPU0_SB_CS_N(1)    I48 @S9S_MB_2U_LIB.S9S_MB_2U(SCH_1):PAGE96
   209 M_H_CPU0_SA_CS_N<1> @S9S_MB_2U_LIB.S9S_MB_2U(SCH_1):M_H_CPU0_SA_CS_N(1)    I48 @S9S_MB_2U_LIB.S9S_MB_2U(SCH_1):PAGE96
    84 M_H_CPU0_SB_CS_N<0> @S9S_MB_2U_LIB.S9S_MB_2U(SCH_1):M_H_CPU0_SB_CS_N(0)    I48 @S9S_MB_2U_LIB.S9S_MB_2U(SCH_1):PAGE96
    64 M_H_CPU0_SA_CS_N<0> @S9S_MB_2U_LIB.S9S_MB_2U(SCH_1):M_H_CPU0_SA_CS_N(0)    I48 @S9S_MB_2U_LIB.S9S_MB_2U(SCH_1):PAGE96
   217 M_H_CPU0_CLK_DP<0> @S9S_MB_2U_LIB.S9S_MB_2U(SCH_1):M_H_CPU0_CLK_DP(0)    I48 @S9S_MB_2U_LIB.S9S_MB_2U(SCH_1):PAGE96
   218 M_H_CPU0_CLK_DN<0> @S9S_MB_2U_LIB.S9S_MB_2U(SCH_1):M_H_CPU0_CLK_DN(0)    I48 @S9S_MB_2U_LIB.S9S_MB_2U(SCH_1):PAGE96
    96 M_H_CPU0_SB_CB<0> @S9S_MB_2U_LIB.S9S_MB_2U(SCH_1):M_H_CPU0_SB_CB(0)    I48 @S9S_MB_2U_LIB.S9S_MB_2U(SCH_1):PAGE96
    98 M_H_CPU0_SB_CB<1> @S9S_MB_2U_LIB.S9S_MB_2U(SCH_1):M_H_CPU0_SB_CB(1)    I48 @S9S_MB_2U_LIB.S9S_MB_2U(SCH_1):PAGE96
   241 M_H_CPU0_SB_CB<2> @S9S_MB_2U_LIB.S9S_MB_2U(SCH_1):M_H_CPU0_SB_CB(2)    I48 @S9S_MB_2U_LIB.S9S_MB_2U(SCH_1):PAGE96
   243 M_H_CPU0_SB_CB<3> @S9S_MB_2U_LIB.S9S_MB_2U(SCH_1):M_H_CPU0_SB_CB(3)    I48 @S9S_MB_2U_LIB.S9S_MB_2U(SCH_1):PAGE96
    89 M_H_CPU0_SB_CB<4> @S9S_MB_2U_LIB.S9S_MB_2U(SCH_1):M_H_CPU0_SB_CB(4)    I48 @S9S_MB_2U_LIB.S9S_MB_2U(SCH_1):PAGE96
    91 M_H_CPU0_SB_CB<5> @S9S_MB_2U_LIB.S9S_MB_2U(SCH_1):M_H_CPU0_SB_CB(5)    I48 @S9S_MB_2U_LIB.S9S_MB_2U(SCH_1):PAGE96
   234 M_H_CPU0_SB_CB<6> @S9S_MB_2U_LIB.S9S_MB_2U(SCH_1):M_H_CPU0_SB_CB(6)    I48 @S9S_MB_2U_LIB.S9S_MB_2U(SCH_1):PAGE96
    51 M_H_CPU0_SA_CB<0> @S9S_MB_2U_LIB.S9S_MB_2U(SCH_1):M_H_CPU0_SA_CB(0)    I48 @S9S_MB_2U_LIB.S9S_MB_2U(SCH_1):PAGE96
   196 M_H_CPU0_SA_CB<2> @S9S_MB_2U_LIB.S9S_MB_2U(SCH_1):M_H_CPU0_SA_CB(2)    I48 @S9S_MB_2U_LIB.S9S_MB_2U(SCH_1):PAGE96
   198 M_H_CPU0_SA_CB<3> @S9S_MB_2U_LIB.S9S_MB_2U(SCH_1):M_H_CPU0_SA_CB(3)    I48 @S9S_MB_2U_LIB.S9S_MB_2U(SCH_1):PAGE96
    60 M_H_CPU0_SA_CB<5> @S9S_MB_2U_LIB.S9S_MB_2U(SCH_1):M_H_CPU0_SA_CB(5)    I48 @S9S_MB_2U_LIB.S9S_MB_2U(SCH_1):PAGE96
   203 M_H_CPU0_SA_CB<6> @S9S_MB_2U_LIB.S9S_MB_2U(SCH_1):M_H_CPU0_SA_CB(6)    I48 @S9S_MB_2U_LIB.S9S_MB_2U(SCH_1):PAGE96
    82 M_H_CPU0_SB_CA<6> @S9S_MB_2U_LIB.S9S_MB_2U(SCH_1):M_H_CPU0_SB_CA(6)    I48 @S9S_MB_2U_LIB.S9S_MB_2U(SCH_1):PAGE96
    72 M_H_CPU0_SA_CA<6> @S9S_MB_2U_LIB.S9S_MB_2U(SCH_1):M_H_CPU0_SA_CA(6)    I48 @S9S_MB_2U_LIB.S9S_MB_2U(SCH_1):PAGE96
   225 M_H_CPU0_SB_CA<5> @S9S_MB_2U_LIB.S9S_MB_2U(SCH_1):M_H_CPU0_SB_CA(5)    I48 @S9S_MB_2U_LIB.S9S_MB_2U(SCH_1):PAGE96
   215 M_H_CPU0_SA_CA<5> @S9S_MB_2U_LIB.S9S_MB_2U(SCH_1):M_H_CPU0_SA_CA(5)    I48 @S9S_MB_2U_LIB.S9S_MB_2U(SCH_1):PAGE96
    80 M_H_CPU0_SB_CA<4> @S9S_MB_2U_LIB.S9S_MB_2U(SCH_1):M_H_CPU0_SB_CA(4)    I48 @S9S_MB_2U_LIB.S9S_MB_2U(SCH_1):PAGE96
    70 M_H_CPU0_SA_CA<4> @S9S_MB_2U_LIB.S9S_MB_2U(SCH_1):M_H_CPU0_SA_CA(4)    I48 @S9S_MB_2U_LIB.S9S_MB_2U(SCH_1):PAGE96
   223 M_H_CPU0_SB_CA<3> @S9S_MB_2U_LIB.S9S_MB_2U(SCH_1):M_H_CPU0_SB_CA(3)    I48 @S9S_MB_2U_LIB.S9S_MB_2U(SCH_1):PAGE96
   213 M_H_CPU0_SA_CA<3> @S9S_MB_2U_LIB.S9S_MB_2U(SCH_1):M_H_CPU0_SA_CA(3)    I48 @S9S_MB_2U_LIB.S9S_MB_2U(SCH_1):PAGE96
    78 M_H_CPU0_SB_CA<2> @S9S_MB_2U_LIB.S9S_MB_2U(SCH_1):M_H_CPU0_SB_CA(2)    I48 @S9S_MB_2U_LIB.S9S_MB_2U(SCH_1):PAGE96
    68 M_H_CPU0_SA_CA<2> @S9S_MB_2U_LIB.S9S_MB_2U(SCH_1):M_H_CPU0_SA_CA(2)    I48 @S9S_MB_2U_LIB.S9S_MB_2U(SCH_1):PAGE96
   221 M_H_CPU0_SB_CA<1> @S9S_MB_2U_LIB.S9S_MB_2U(SCH_1):M_H_CPU0_SB_CA(1)    I48 @S9S_MB_2U_LIB.S9S_MB_2U(SCH_1):PAGE96
   211 M_H_CPU0_SA_CA<1> @S9S_MB_2U_LIB.S9S_MB_2U(SCH_1):M_H_CPU0_SA_CA(1)    I48 @S9S_MB_2U_LIB.S9S_MB_2U(SCH_1):PAGE96
    76 M_H_CPU0_SB_CA<0> @S9S_MB_2U_LIB.S9S_MB_2U(SCH_1):M_H_CPU0_SB_CA(0)    I48 @S9S_MB_2U_LIB.S9S_MB_2U(SCH_1):PAGE96
    66 M_H_CPU0_SA_CA<0> @S9S_MB_2U_LIB.S9S_MB_2U(SCH_1):M_H_CPU0_SA_CA(0)    I48 @S9S_MB_2U_LIB.S9S_MB_2U(SCH_1):PAGE96
    62 M_H_CPU0_ALERT_N @S9S_MB_2U_LIB.S9S_MB_2U(SCH_1):M_H_CPU0_ALERT_N    I48 @S9S_MB_2U_LIB.S9S_MB_2U(SCH_1):PAGE96
   236 M_H_CPU0_SB_CB<7> @S9S_MB_2U_LIB.S9S_MB_2U(SCH_1):M_H_CPU0_SB_CB(7)    I48 @S9S_MB_2U_LIB.S9S_MB_2U(SCH_1):PAGE96
    53 M_H_CPU0_SA_CB<1> @S9S_MB_2U_LIB.S9S_MB_2U(SCH_1):M_H_CPU0_SA_CB(1)    I48 @S9S_MB_2U_LIB.S9S_MB_2U(SCH_1):PAGE96
    58 M_H_CPU0_SA_CB<4> @S9S_MB_2U_LIB.S9S_MB_2U(SCH_1):M_H_CPU0_SA_CB(4)    I48 @S9S_MB_2U_LIB.S9S_MB_2U(SCH_1):PAGE96
   205 M_H_CPU0_SA_CB<7> @S9S_MB_2U_LIB.S9S_MB_2U(SCH_1):M_H_CPU0_SA_CB(7)    I48 @S9S_MB_2U_LIB.S9S_MB_2U(SCH_1):PAGE96
   194 M_H_CPU0_SA_DQ<31> @S9S_MB_2U_LIB.S9S_MB_2U(SCH_1):M_H_CPU0_SA_DQ(31)    I48 @S9S_MB_2U_LIB.S9S_MB_2U(SCH_1):PAGE96
    93 M_H_CPU0_SB_DQS_DP<9> @S9S_MB_2U_LIB.S9S_MB_2U(SCH_1):M_H_CPU0_SB_DQS_DP(9)   I178 @S9S_MB_2U_LIB.S9S_MB_2U(SCH_1):PAGE96
    94 M_H_CPU0_SB_DQS_DN<9> @S9S_MB_2U_LIB.S9S_MB_2U(SCH_1):M_H_CPU0_SB_DQS_DN(9)   I178 @S9S_MB_2U_LIB.S9S_MB_2U(SCH_1):PAGE96
   201 M_H_CPU0_SA_DQS_DP<9> @S9S_MB_2U_LIB.S9S_MB_2U(SCH_1):M_H_CPU0_SA_DQS_DP(9)   I178 @S9S_MB_2U_LIB.S9S_MB_2U(SCH_1):PAGE96
   200 M_H_CPU0_SA_DQS_DN<9> @S9S_MB_2U_LIB.S9S_MB_2U(SCH_1):M_H_CPU0_SA_DQS_DN(9)   I178 @S9S_MB_2U_LIB.S9S_MB_2U(SCH_1):PAGE96
   190 M_H_CPU0_SA_DQS_DP<8> @S9S_MB_2U_LIB.S9S_MB_2U(SCH_1):M_H_CPU0_SA_DQS_DP(8)   I178 @S9S_MB_2U_LIB.S9S_MB_2U(SCH_1):PAGE96
   189 M_H_CPU0_SA_DQS_DN<8> @S9S_MB_2U_LIB.S9S_MB_2U(SCH_1):M_H_CPU0_SA_DQS_DN(8)   I178 @S9S_MB_2U_LIB.S9S_MB_2U(SCH_1):PAGE96
   271 M_H_CPU0_SB_DQS_DN<7> @S9S_MB_2U_LIB.S9S_MB_2U(SCH_1):M_H_CPU0_SB_DQS_DN(7)   I178 @S9S_MB_2U_LIB.S9S_MB_2U(SCH_1):PAGE96
   179 M_H_CPU0_SA_DQS_DP<7> @S9S_MB_2U_LIB.S9S_MB_2U(SCH_1):M_H_CPU0_SA_DQS_DP(7)   I178 @S9S_MB_2U_LIB.S9S_MB_2U(SCH_1):PAGE96
   261 M_H_CPU0_SB_DQS_DP<6> @S9S_MB_2U_LIB.S9S_MB_2U(SCH_1):M_H_CPU0_SB_DQS_DP(6)   I178 @S9S_MB_2U_LIB.S9S_MB_2U(SCH_1):PAGE96
   260 M_H_CPU0_SB_DQS_DN<6> @S9S_MB_2U_LIB.S9S_MB_2U(SCH_1):M_H_CPU0_SB_DQS_DN(6)   I178 @S9S_MB_2U_LIB.S9S_MB_2U(SCH_1):PAGE96
   167 M_H_CPU0_SA_DQS_DN<6> @S9S_MB_2U_LIB.S9S_MB_2U(SCH_1):M_H_CPU0_SA_DQS_DN(6)   I178 @S9S_MB_2U_LIB.S9S_MB_2U(SCH_1):PAGE96
   250 M_H_CPU0_SB_DQS_DP<5> @S9S_MB_2U_LIB.S9S_MB_2U(SCH_1):M_H_CPU0_SB_DQS_DP(5)   I178 @S9S_MB_2U_LIB.S9S_MB_2U(SCH_1):PAGE96
   249 M_H_CPU0_SB_DQS_DN<5> @S9S_MB_2U_LIB.S9S_MB_2U(SCH_1):M_H_CPU0_SB_DQS_DN(5)   I178 @S9S_MB_2U_LIB.S9S_MB_2U(SCH_1):PAGE96
   157 M_H_CPU0_SA_DQS_DP<5> @S9S_MB_2U_LIB.S9S_MB_2U(SCH_1):M_H_CPU0_SA_DQS_DP(5)   I178 @S9S_MB_2U_LIB.S9S_MB_2U(SCH_1):PAGE96
   156 M_H_CPU0_SA_DQS_DN<5> @S9S_MB_2U_LIB.S9S_MB_2U(SCH_1):M_H_CPU0_SA_DQS_DN(5)   I178 @S9S_MB_2U_LIB.S9S_MB_2U(SCH_1):PAGE96
   239 M_H_CPU0_SB_DQS_DP<4> @S9S_MB_2U_LIB.S9S_MB_2U(SCH_1):M_H_CPU0_SB_DQS_DP(4)   I178 @S9S_MB_2U_LIB.S9S_MB_2U(SCH_1):PAGE96
   238 M_H_CPU0_SB_DQS_DN<4> @S9S_MB_2U_LIB.S9S_MB_2U(SCH_1):M_H_CPU0_SB_DQS_DN(4)   I178 @S9S_MB_2U_LIB.S9S_MB_2U(SCH_1):PAGE96
    55 M_H_CPU0_SA_DQS_DP<4> @S9S_MB_2U_LIB.S9S_MB_2U(SCH_1):M_H_CPU0_SA_DQS_DP(4)   I178 @S9S_MB_2U_LIB.S9S_MB_2U(SCH_1):PAGE96
    56 M_H_CPU0_SA_DQS_DN<4> @S9S_MB_2U_LIB.S9S_MB_2U(SCH_1):M_H_CPU0_SA_DQS_DN(4)   I178 @S9S_MB_2U_LIB.S9S_MB_2U(SCH_1):PAGE96
   137 M_H_CPU0_SB_DQS_DP<3> @S9S_MB_2U_LIB.S9S_MB_2U(SCH_1):M_H_CPU0_SB_DQS_DP(3)   I178 @S9S_MB_2U_LIB.S9S_MB_2U(SCH_1):PAGE96
   138 M_H_CPU0_SB_DQS_DN<3> @S9S_MB_2U_LIB.S9S_MB_2U(SCH_1):M_H_CPU0_SB_DQS_DN(3)   I178 @S9S_MB_2U_LIB.S9S_MB_2U(SCH_1):PAGE96
    44 M_H_CPU0_SA_DQS_DP<3> @S9S_MB_2U_LIB.S9S_MB_2U(SCH_1):M_H_CPU0_SA_DQS_DP(3)   I178 @S9S_MB_2U_LIB.S9S_MB_2U(SCH_1):PAGE96
    45 M_H_CPU0_SA_DQS_DN<3> @S9S_MB_2U_LIB.S9S_MB_2U(SCH_1):M_H_CPU0_SA_DQS_DN(3)   I178 @S9S_MB_2U_LIB.S9S_MB_2U(SCH_1):PAGE96
   126 M_H_CPU0_SB_DQS_DP<2> @S9S_MB_2U_LIB.S9S_MB_2U(SCH_1):M_H_CPU0_SB_DQS_DP(2)   I178 @S9S_MB_2U_LIB.S9S_MB_2U(SCH_1):PAGE96
   127 M_H_CPU0_SB_DQS_DN<2> @S9S_MB_2U_LIB.S9S_MB_2U(SCH_1):M_H_CPU0_SB_DQS_DN(2)   I178 @S9S_MB_2U_LIB.S9S_MB_2U(SCH_1):PAGE96
    33 M_H_CPU0_SA_DQS_DP<2> @S9S_MB_2U_LIB.S9S_MB_2U(SCH_1):M_H_CPU0_SA_DQS_DP(2)   I178 @S9S_MB_2U_LIB.S9S_MB_2U(SCH_1):PAGE96
    34 M_H_CPU0_SA_DQS_DN<2> @S9S_MB_2U_LIB.S9S_MB_2U(SCH_1):M_H_CPU0_SA_DQS_DN(2)   I178 @S9S_MB_2U_LIB.S9S_MB_2U(SCH_1):PAGE96
   115 M_H_CPU0_SB_DQS_DP<1> @S9S_MB_2U_LIB.S9S_MB_2U(SCH_1):M_H_CPU0_SB_DQS_DP(1)   I178 @S9S_MB_2U_LIB.S9S_MB_2U(SCH_1):PAGE96
   116 M_H_CPU0_SB_DQS_DN<1> @S9S_MB_2U_LIB.S9S_MB_2U(SCH_1):M_H_CPU0_SB_DQS_DN(1)   I178 @S9S_MB_2U_LIB.S9S_MB_2U(SCH_1):PAGE96
    22 M_H_CPU0_SA_DQS_DP<1> @S9S_MB_2U_LIB.S9S_MB_2U(SCH_1):M_H_CPU0_SA_DQS_DP(1)   I178 @S9S_MB_2U_LIB.S9S_MB_2U(SCH_1):PAGE96
    23 M_H_CPU0_SA_DQS_DN<1> @S9S_MB_2U_LIB.S9S_MB_2U(SCH_1):M_H_CPU0_SA_DQS_DN(1)   I178 @S9S_MB_2U_LIB.S9S_MB_2U(SCH_1):PAGE96
   104 M_H_CPU0_SB_DQS_DP<0> @S9S_MB_2U_LIB.S9S_MB_2U(SCH_1):M_H_CPU0_SB_DQS_DP(0)   I178 @S9S_MB_2U_LIB.S9S_MB_2U(SCH_1):PAGE96
   105 M_H_CPU0_SB_DQS_DN<0> @S9S_MB_2U_LIB.S9S_MB_2U(SCH_1):M_H_CPU0_SB_DQS_DN(0)   I178 @S9S_MB_2U_LIB.S9S_MB_2U(SCH_1):PAGE96
    11 M_H_CPU0_SA_DQS_DP<0> @S9S_MB_2U_LIB.S9S_MB_2U(SCH_1):M_H_CPU0_SA_DQS_DP(0)   I178 @S9S_MB_2U_LIB.S9S_MB_2U(SCH_1):PAGE96
    12 M_H_CPU0_SA_DQS_DN<0> @S9S_MB_2U_LIB.S9S_MB_2U(SCH_1):M_H_CPU0_SA_DQS_DN(0)   I178 @S9S_MB_2U_LIB.S9S_MB_2U(SCH_1):PAGE96
   272 M_H_CPU0_SB_DQS_DP<7> @S9S_MB_2U_LIB.S9S_MB_2U(SCH_1):M_H_CPU0_SB_DQS_DP(7)   I178 @S9S_MB_2U_LIB.S9S_MB_2U(SCH_1):PAGE96
   282 M_H_CPU0_SB_DQS_DN<8> @S9S_MB_2U_LIB.S9S_MB_2U(SCH_1):M_H_CPU0_SB_DQS_DN(8)   I178 @S9S_MB_2U_LIB.S9S_MB_2U(SCH_1):PAGE96
   283 M_H_CPU0_SB_DQS_DP<8> @S9S_MB_2U_LIB.S9S_MB_2U(SCH_1):M_H_CPU0_SB_DQS_DP(8)   I178 @S9S_MB_2U_LIB.S9S_MB_2U(SCH_1):PAGE96
   168 M_H_CPU0_SA_DQS_DP<6> @S9S_MB_2U_LIB.S9S_MB_2U(SCH_1):M_H_CPU0_SA_DQS_DP(6)   I178 @S9S_MB_2U_LIB.S9S_MB_2U(SCH_1):PAGE96
   178 M_H_CPU0_SA_DQS_DN<7> @S9S_MB_2U_LIB.S9S_MB_2U(SCH_1):M_H_CPU0_SA_DQS_DN(7)   I178 @S9S_MB_2U_LIB.S9S_MB_2U(SCH_1):PAGE96
     6    GND @S9S_MB_2U_LIB.S9S_MB_2U(SCH_1):GND   I176 @S9S_MB_2U_LIB.S9S_MB_2U(SCH_1):PAGE96
     8    GND @S9S_MB_2U_LIB.S9S_MB_2U(SCH_1):GND   I176 @S9S_MB_2U_LIB.S9S_MB_2U(SCH_1):PAGE96
    10    GND @S9S_MB_2U_LIB.S9S_MB_2U(SCH_1):GND   I176 @S9S_MB_2U_LIB.S9S_MB_2U(SCH_1):PAGE96
    13    GND @S9S_MB_2U_LIB.S9S_MB_2U(SCH_1):GND   I176 @S9S_MB_2U_LIB.S9S_MB_2U(SCH_1):PAGE96
    15    GND @S9S_MB_2U_LIB.S9S_MB_2U(SCH_1):GND   I176 @S9S_MB_2U_LIB.S9S_MB_2U(SCH_1):PAGE96
    17    GND @S9S_MB_2U_LIB.S9S_MB_2U(SCH_1):GND   I176 @S9S_MB_2U_LIB.S9S_MB_2U(SCH_1):PAGE96
    19    GND @S9S_MB_2U_LIB.S9S_MB_2U(SCH_1):GND   I176 @S9S_MB_2U_LIB.S9S_MB_2U(SCH_1):PAGE96
    21    GND @S9S_MB_2U_LIB.S9S_MB_2U(SCH_1):GND   I176 @S9S_MB_2U_LIB.S9S_MB_2U(SCH_1):PAGE96
    24    GND @S9S_MB_2U_LIB.S9S_MB_2U(SCH_1):GND   I176 @S9S_MB_2U_LIB.S9S_MB_2U(SCH_1):PAGE96
    26    GND @S9S_MB_2U_LIB.S9S_MB_2U(SCH_1):GND   I176 @S9S_MB_2U_LIB.S9S_MB_2U(SCH_1):PAGE96
    28    GND @S9S_MB_2U_LIB.S9S_MB_2U(SCH_1):GND   I176 @S9S_MB_2U_LIB.S9S_MB_2U(SCH_1):PAGE96
    30    GND @S9S_MB_2U_LIB.S9S_MB_2U(SCH_1):GND   I176 @S9S_MB_2U_LIB.S9S_MB_2U(SCH_1):PAGE96
    32    GND @S9S_MB_2U_LIB.S9S_MB_2U(SCH_1):GND   I176 @S9S_MB_2U_LIB.S9S_MB_2U(SCH_1):PAGE96
    35    GND @S9S_MB_2U_LIB.S9S_MB_2U(SCH_1):GND   I176 @S9S_MB_2U_LIB.S9S_MB_2U(SCH_1):PAGE96
    37    GND @S9S_MB_2U_LIB.S9S_MB_2U(SCH_1):GND   I176 @S9S_MB_2U_LIB.S9S_MB_2U(SCH_1):PAGE96
    39    GND @S9S_MB_2U_LIB.S9S_MB_2U(SCH_1):GND   I176 @S9S_MB_2U_LIB.S9S_MB_2U(SCH_1):PAGE96
    41    GND @S9S_MB_2U_LIB.S9S_MB_2U(SCH_1):GND   I176 @S9S_MB_2U_LIB.S9S_MB_2U(SCH_1):PAGE96
    43    GND @S9S_MB_2U_LIB.S9S_MB_2U(SCH_1):GND   I176 @S9S_MB_2U_LIB.S9S_MB_2U(SCH_1):PAGE96
    46    GND @S9S_MB_2U_LIB.S9S_MB_2U(SCH_1):GND   I176 @S9S_MB_2U_LIB.S9S_MB_2U(SCH_1):PAGE96
    48    GND @S9S_MB_2U_LIB.S9S_MB_2U(SCH_1):GND   I176 @S9S_MB_2U_LIB.S9S_MB_2U(SCH_1):PAGE96
    50    GND @S9S_MB_2U_LIB.S9S_MB_2U(SCH_1):GND   I176 @S9S_MB_2U_LIB.S9S_MB_2U(SCH_1):PAGE96
    52    GND @S9S_MB_2U_LIB.S9S_MB_2U(SCH_1):GND   I176 @S9S_MB_2U_LIB.S9S_MB_2U(SCH_1):PAGE96
    54    GND @S9S_MB_2U_LIB.S9S_MB_2U(SCH_1):GND   I176 @S9S_MB_2U_LIB.S9S_MB_2U(SCH_1):PAGE96
    57    GND @S9S_MB_2U_LIB.S9S_MB_2U(SCH_1):GND   I176 @S9S_MB_2U_LIB.S9S_MB_2U(SCH_1):PAGE96
    59    GND @S9S_MB_2U_LIB.S9S_MB_2U(SCH_1):GND   I176 @S9S_MB_2U_LIB.S9S_MB_2U(SCH_1):PAGE96
    61    GND @S9S_MB_2U_LIB.S9S_MB_2U(SCH_1):GND   I176 @S9S_MB_2U_LIB.S9S_MB_2U(SCH_1):PAGE96
    63    GND @S9S_MB_2U_LIB.S9S_MB_2U(SCH_1):GND   I176 @S9S_MB_2U_LIB.S9S_MB_2U(SCH_1):PAGE96
    65    GND @S9S_MB_2U_LIB.S9S_MB_2U(SCH_1):GND   I176 @S9S_MB_2U_LIB.S9S_MB_2U(SCH_1):PAGE96
    67    GND @S9S_MB_2U_LIB.S9S_MB_2U(SCH_1):GND   I176 @S9S_MB_2U_LIB.S9S_MB_2U(SCH_1):PAGE96
    69    GND @S9S_MB_2U_LIB.S9S_MB_2U(SCH_1):GND   I176 @S9S_MB_2U_LIB.S9S_MB_2U(SCH_1):PAGE96
    71    GND @S9S_MB_2U_LIB.S9S_MB_2U(SCH_1):GND   I176 @S9S_MB_2U_LIB.S9S_MB_2U(SCH_1):PAGE96
    73    GND @S9S_MB_2U_LIB.S9S_MB_2U(SCH_1):GND   I176 @S9S_MB_2U_LIB.S9S_MB_2U(SCH_1):PAGE96
    75    GND @S9S_MB_2U_LIB.S9S_MB_2U(SCH_1):GND   I176 @S9S_MB_2U_LIB.S9S_MB_2U(SCH_1):PAGE96
    77    GND @S9S_MB_2U_LIB.S9S_MB_2U(SCH_1):GND   I176 @S9S_MB_2U_LIB.S9S_MB_2U(SCH_1):PAGE96
    79    GND @S9S_MB_2U_LIB.S9S_MB_2U(SCH_1):GND   I176 @S9S_MB_2U_LIB.S9S_MB_2U(SCH_1):PAGE96
    81    GND @S9S_MB_2U_LIB.S9S_MB_2U(SCH_1):GND   I176 @S9S_MB_2U_LIB.S9S_MB_2U(SCH_1):PAGE96
    83    GND @S9S_MB_2U_LIB.S9S_MB_2U(SCH_1):GND   I176 @S9S_MB_2U_LIB.S9S_MB_2U(SCH_1):PAGE96
    85    GND @S9S_MB_2U_LIB.S9S_MB_2U(SCH_1):GND   I176 @S9S_MB_2U_LIB.S9S_MB_2U(SCH_1):PAGE96
    88    GND @S9S_MB_2U_LIB.S9S_MB_2U(SCH_1):GND   I176 @S9S_MB_2U_LIB.S9S_MB_2U(SCH_1):PAGE96
    90    GND @S9S_MB_2U_LIB.S9S_MB_2U(SCH_1):GND   I176 @S9S_MB_2U_LIB.S9S_MB_2U(SCH_1):PAGE96
    92    GND @S9S_MB_2U_LIB.S9S_MB_2U(SCH_1):GND   I176 @S9S_MB_2U_LIB.S9S_MB_2U(SCH_1):PAGE96
    95    GND @S9S_MB_2U_LIB.S9S_MB_2U(SCH_1):GND   I176 @S9S_MB_2U_LIB.S9S_MB_2U(SCH_1):PAGE96
    97    GND @S9S_MB_2U_LIB.S9S_MB_2U(SCH_1):GND   I176 @S9S_MB_2U_LIB.S9S_MB_2U(SCH_1):PAGE96
    99    GND @S9S_MB_2U_LIB.S9S_MB_2U(SCH_1):GND   I176 @S9S_MB_2U_LIB.S9S_MB_2U(SCH_1):PAGE96
   101    GND @S9S_MB_2U_LIB.S9S_MB_2U(SCH_1):GND   I176 @S9S_MB_2U_LIB.S9S_MB_2U(SCH_1):PAGE96
   103    GND @S9S_MB_2U_LIB.S9S_MB_2U(SCH_1):GND   I176 @S9S_MB_2U_LIB.S9S_MB_2U(SCH_1):PAGE96
   106    GND @S9S_MB_2U_LIB.S9S_MB_2U(SCH_1):GND   I176 @S9S_MB_2U_LIB.S9S_MB_2U(SCH_1):PAGE96
   108    GND @S9S_MB_2U_LIB.S9S_MB_2U(SCH_1):GND   I176 @S9S_MB_2U_LIB.S9S_MB_2U(SCH_1):PAGE96
   110    GND @S9S_MB_2U_LIB.S9S_MB_2U(SCH_1):GND   I176 @S9S_MB_2U_LIB.S9S_MB_2U(SCH_1):PAGE96
   112    GND @S9S_MB_2U_LIB.S9S_MB_2U(SCH_1):GND   I176 @S9S_MB_2U_LIB.S9S_MB_2U(SCH_1):PAGE96
   114    GND @S9S_MB_2U_LIB.S9S_MB_2U(SCH_1):GND   I176 @S9S_MB_2U_LIB.S9S_MB_2U(SCH_1):PAGE96
   117    GND @S9S_MB_2U_LIB.S9S_MB_2U(SCH_1):GND   I176 @S9S_MB_2U_LIB.S9S_MB_2U(SCH_1):PAGE96
   119    GND @S9S_MB_2U_LIB.S9S_MB_2U(SCH_1):GND   I176 @S9S_MB_2U_LIB.S9S_MB_2U(SCH_1):PAGE96
   121    GND @S9S_MB_2U_LIB.S9S_MB_2U(SCH_1):GND   I176 @S9S_MB_2U_LIB.S9S_MB_2U(SCH_1):PAGE96
   123    GND @S9S_MB_2U_LIB.S9S_MB_2U(SCH_1):GND   I176 @S9S_MB_2U_LIB.S9S_MB_2U(SCH_1):PAGE96
   125    GND @S9S_MB_2U_LIB.S9S_MB_2U(SCH_1):GND   I176 @S9S_MB_2U_LIB.S9S_MB_2U(SCH_1):PAGE96
   128    GND @S9S_MB_2U_LIB.S9S_MB_2U(SCH_1):GND   I176 @S9S_MB_2U_LIB.S9S_MB_2U(SCH_1):PAGE96
   130    GND @S9S_MB_2U_LIB.S9S_MB_2U(SCH_1):GND   I176 @S9S_MB_2U_LIB.S9S_MB_2U(SCH_1):PAGE96
   134    GND @S9S_MB_2U_LIB.S9S_MB_2U(SCH_1):GND   I176 @S9S_MB_2U_LIB.S9S_MB_2U(SCH_1):PAGE96
   143    GND @S9S_MB_2U_LIB.S9S_MB_2U(SCH_1):GND   I176 @S9S_MB_2U_LIB.S9S_MB_2U(SCH_1):PAGE96
   151    GND @S9S_MB_2U_LIB.S9S_MB_2U(SCH_1):GND   I176 @S9S_MB_2U_LIB.S9S_MB_2U(SCH_1):PAGE96
   153    GND @S9S_MB_2U_LIB.S9S_MB_2U(SCH_1):GND   I176 @S9S_MB_2U_LIB.S9S_MB_2U(SCH_1):PAGE96
   155    GND @S9S_MB_2U_LIB.S9S_MB_2U(SCH_1):GND   I176 @S9S_MB_2U_LIB.S9S_MB_2U(SCH_1):PAGE96
   158    GND @S9S_MB_2U_LIB.S9S_MB_2U(SCH_1):GND   I176 @S9S_MB_2U_LIB.S9S_MB_2U(SCH_1):PAGE96
   160    GND @S9S_MB_2U_LIB.S9S_MB_2U(SCH_1):GND   I176 @S9S_MB_2U_LIB.S9S_MB_2U(SCH_1):PAGE96
   162    GND @S9S_MB_2U_LIB.S9S_MB_2U(SCH_1):GND   I176 @S9S_MB_2U_LIB.S9S_MB_2U(SCH_1):PAGE96
   164    GND @S9S_MB_2U_LIB.S9S_MB_2U(SCH_1):GND   I176 @S9S_MB_2U_LIB.S9S_MB_2U(SCH_1):PAGE96
   166    GND @S9S_MB_2U_LIB.S9S_MB_2U(SCH_1):GND   I176 @S9S_MB_2U_LIB.S9S_MB_2U(SCH_1):PAGE96
   169    GND @S9S_MB_2U_LIB.S9S_MB_2U(SCH_1):GND   I176 @S9S_MB_2U_LIB.S9S_MB_2U(SCH_1):PAGE96
   171    GND @S9S_MB_2U_LIB.S9S_MB_2U(SCH_1):GND   I176 @S9S_MB_2U_LIB.S9S_MB_2U(SCH_1):PAGE96
   173    GND @S9S_MB_2U_LIB.S9S_MB_2U(SCH_1):GND   I176 @S9S_MB_2U_LIB.S9S_MB_2U(SCH_1):PAGE96
   175    GND @S9S_MB_2U_LIB.S9S_MB_2U(SCH_1):GND   I176 @S9S_MB_2U_LIB.S9S_MB_2U(SCH_1):PAGE96
   177    GND @S9S_MB_2U_LIB.S9S_MB_2U(SCH_1):GND   I176 @S9S_MB_2U_LIB.S9S_MB_2U(SCH_1):PAGE96
   180    GND @S9S_MB_2U_LIB.S9S_MB_2U(SCH_1):GND   I176 @S9S_MB_2U_LIB.S9S_MB_2U(SCH_1):PAGE96
   182    GND @S9S_MB_2U_LIB.S9S_MB_2U(SCH_1):GND   I176 @S9S_MB_2U_LIB.S9S_MB_2U(SCH_1):PAGE96
   184    GND @S9S_MB_2U_LIB.S9S_MB_2U(SCH_1):GND   I176 @S9S_MB_2U_LIB.S9S_MB_2U(SCH_1):PAGE96
   186    GND @S9S_MB_2U_LIB.S9S_MB_2U(SCH_1):GND   I176 @S9S_MB_2U_LIB.S9S_MB_2U(SCH_1):PAGE96
   188    GND @S9S_MB_2U_LIB.S9S_MB_2U(SCH_1):GND   I176 @S9S_MB_2U_LIB.S9S_MB_2U(SCH_1):PAGE96
   191    GND @S9S_MB_2U_LIB.S9S_MB_2U(SCH_1):GND   I176 @S9S_MB_2U_LIB.S9S_MB_2U(SCH_1):PAGE96
   193    GND @S9S_MB_2U_LIB.S9S_MB_2U(SCH_1):GND   I176 @S9S_MB_2U_LIB.S9S_MB_2U(SCH_1):PAGE96
   195    GND @S9S_MB_2U_LIB.S9S_MB_2U(SCH_1):GND   I176 @S9S_MB_2U_LIB.S9S_MB_2U(SCH_1):PAGE96
   197    GND @S9S_MB_2U_LIB.S9S_MB_2U(SCH_1):GND   I176 @S9S_MB_2U_LIB.S9S_MB_2U(SCH_1):PAGE96
   199    GND @S9S_MB_2U_LIB.S9S_MB_2U(SCH_1):GND   I176 @S9S_MB_2U_LIB.S9S_MB_2U(SCH_1):PAGE96
   202    GND @S9S_MB_2U_LIB.S9S_MB_2U(SCH_1):GND   I176 @S9S_MB_2U_LIB.S9S_MB_2U(SCH_1):PAGE96
   204    GND @S9S_MB_2U_LIB.S9S_MB_2U(SCH_1):GND   I176 @S9S_MB_2U_LIB.S9S_MB_2U(SCH_1):PAGE96
   206    GND @S9S_MB_2U_LIB.S9S_MB_2U(SCH_1):GND   I176 @S9S_MB_2U_LIB.S9S_MB_2U(SCH_1):PAGE96
   208    GND @S9S_MB_2U_LIB.S9S_MB_2U(SCH_1):GND   I176 @S9S_MB_2U_LIB.S9S_MB_2U(SCH_1):PAGE96
   210    GND @S9S_MB_2U_LIB.S9S_MB_2U(SCH_1):GND   I176 @S9S_MB_2U_LIB.S9S_MB_2U(SCH_1):PAGE96
   212    GND @S9S_MB_2U_LIB.S9S_MB_2U(SCH_1):GND   I176 @S9S_MB_2U_LIB.S9S_MB_2U(SCH_1):PAGE96
   214    GND @S9S_MB_2U_LIB.S9S_MB_2U(SCH_1):GND   I176 @S9S_MB_2U_LIB.S9S_MB_2U(SCH_1):PAGE96
   216    GND @S9S_MB_2U_LIB.S9S_MB_2U(SCH_1):GND   I176 @S9S_MB_2U_LIB.S9S_MB_2U(SCH_1):PAGE96
   219    GND @S9S_MB_2U_LIB.S9S_MB_2U(SCH_1):GND   I176 @S9S_MB_2U_LIB.S9S_MB_2U(SCH_1):PAGE96
   222    GND @S9S_MB_2U_LIB.S9S_MB_2U(SCH_1):GND   I176 @S9S_MB_2U_LIB.S9S_MB_2U(SCH_1):PAGE96
   224    GND @S9S_MB_2U_LIB.S9S_MB_2U(SCH_1):GND   I176 @S9S_MB_2U_LIB.S9S_MB_2U(SCH_1):PAGE96
   226    GND @S9S_MB_2U_LIB.S9S_MB_2U(SCH_1):GND   I176 @S9S_MB_2U_LIB.S9S_MB_2U(SCH_1):PAGE96
   228    GND @S9S_MB_2U_LIB.S9S_MB_2U(SCH_1):GND   I176 @S9S_MB_2U_LIB.S9S_MB_2U(SCH_1):PAGE96
   233    GND @S9S_MB_2U_LIB.S9S_MB_2U(SCH_1):GND   I176 @S9S_MB_2U_LIB.S9S_MB_2U(SCH_1):PAGE96
   237    GND @S9S_MB_2U_LIB.S9S_MB_2U(SCH_1):GND   I176 @S9S_MB_2U_LIB.S9S_MB_2U(SCH_1):PAGE96
   242    GND @S9S_MB_2U_LIB.S9S_MB_2U(SCH_1):GND   I176 @S9S_MB_2U_LIB.S9S_MB_2U(SCH_1):PAGE96
   244    GND @S9S_MB_2U_LIB.S9S_MB_2U(SCH_1):GND   I176 @S9S_MB_2U_LIB.S9S_MB_2U(SCH_1):PAGE96
   246    GND @S9S_MB_2U_LIB.S9S_MB_2U(SCH_1):GND   I176 @S9S_MB_2U_LIB.S9S_MB_2U(SCH_1):PAGE96
   248    GND @S9S_MB_2U_LIB.S9S_MB_2U(SCH_1):GND   I176 @S9S_MB_2U_LIB.S9S_MB_2U(SCH_1):PAGE96
   251    GND @S9S_MB_2U_LIB.S9S_MB_2U(SCH_1):GND   I176 @S9S_MB_2U_LIB.S9S_MB_2U(SCH_1):PAGE96
   253    GND @S9S_MB_2U_LIB.S9S_MB_2U(SCH_1):GND   I176 @S9S_MB_2U_LIB.S9S_MB_2U(SCH_1):PAGE96
   255    GND @S9S_MB_2U_LIB.S9S_MB_2U(SCH_1):GND   I176 @S9S_MB_2U_LIB.S9S_MB_2U(SCH_1):PAGE96
   257    GND @S9S_MB_2U_LIB.S9S_MB_2U(SCH_1):GND   I176 @S9S_MB_2U_LIB.S9S_MB_2U(SCH_1):PAGE96
   259    GND @S9S_MB_2U_LIB.S9S_MB_2U(SCH_1):GND   I176 @S9S_MB_2U_LIB.S9S_MB_2U(SCH_1):PAGE96
   262    GND @S9S_MB_2U_LIB.S9S_MB_2U(SCH_1):GND   I176 @S9S_MB_2U_LIB.S9S_MB_2U(SCH_1):PAGE96
   264    GND @S9S_MB_2U_LIB.S9S_MB_2U(SCH_1):GND   I176 @S9S_MB_2U_LIB.S9S_MB_2U(SCH_1):PAGE96
   266    GND @S9S_MB_2U_LIB.S9S_MB_2U(SCH_1):GND   I176 @S9S_MB_2U_LIB.S9S_MB_2U(SCH_1):PAGE96
   268    GND @S9S_MB_2U_LIB.S9S_MB_2U(SCH_1):GND   I176 @S9S_MB_2U_LIB.S9S_MB_2U(SCH_1):PAGE96
   270    GND @S9S_MB_2U_LIB.S9S_MB_2U(SCH_1):GND   I176 @S9S_MB_2U_LIB.S9S_MB_2U(SCH_1):PAGE96
   273    GND @S9S_MB_2U_LIB.S9S_MB_2U(SCH_1):GND   I176 @S9S_MB_2U_LIB.S9S_MB_2U(SCH_1):PAGE96
   275    GND @S9S_MB_2U_LIB.S9S_MB_2U(SCH_1):GND   I176 @S9S_MB_2U_LIB.S9S_MB_2U(SCH_1):PAGE96
   277    GND @S9S_MB_2U_LIB.S9S_MB_2U(SCH_1):GND   I176 @S9S_MB_2U_LIB.S9S_MB_2U(SCH_1):PAGE96
   279    GND @S9S_MB_2U_LIB.S9S_MB_2U(SCH_1):GND   I176 @S9S_MB_2U_LIB.S9S_MB_2U(SCH_1):PAGE96
   281    GND @S9S_MB_2U_LIB.S9S_MB_2U(SCH_1):GND   I176 @S9S_MB_2U_LIB.S9S_MB_2U(SCH_1):PAGE96
   284    GND @S9S_MB_2U_LIB.S9S_MB_2U(SCH_1):GND   I176 @S9S_MB_2U_LIB.S9S_MB_2U(SCH_1):PAGE96
   286    GND @S9S_MB_2U_LIB.S9S_MB_2U(SCH_1):GND   I176 @S9S_MB_2U_LIB.S9S_MB_2U(SCH_1):PAGE96
   288    GND @S9S_MB_2U_LIB.S9S_MB_2U(SCH_1):GND   I176 @S9S_MB_2U_LIB.S9S_MB_2U(SCH_1):PAGE96
     1 P12V_S3_AUX_CPU0_NVDIMM @S9S_MB_2U_LIB.S9S_MB_2U(SCH_1):P12V_S3_AUX_CPU0_NVDIMM   I176 @S9S_MB_2U_LIB.S9S_MB_2U(SCH_1):PAGE96
   145 P12V_S3_AUX_CPU0_NVDIMM @S9S_MB_2U_LIB.S9S_MB_2U(SCH_1):P12V_S3_AUX_CPU0_NVDIMM   I176 @S9S_MB_2U_LIB.S9S_MB_2U(SCH_1):PAGE96
   146 P12V_S3_AUX_CPU0_NVDIMM @S9S_MB_2U_LIB.S9S_MB_2U(SCH_1):P12V_S3_AUX_CPU0_NVDIMM   I176 @S9S_MB_2U_LIB.S9S_MB_2U(SCH_1):PAGE96
   230    GND @S9S_MB_2U_LIB.S9S_MB_2U(SCH_1):GND   I176 @S9S_MB_2U_LIB.S9S_MB_2U(SCH_1):PAGE96
   235    GND @S9S_MB_2U_LIB.S9S_MB_2U(SCH_1):GND   I176 @S9S_MB_2U_LIB.S9S_MB_2U(SCH_1):PAGE96
   240    GND @S9S_MB_2U_LIB.S9S_MB_2U(SCH_1):GND   I176 @S9S_MB_2U_LIB.S9S_MB_2U(SCH_1):PAGE96
   132    GND @S9S_MB_2U_LIB.S9S_MB_2U(SCH_1):GND   I176 @S9S_MB_2U_LIB.S9S_MB_2U(SCH_1):PAGE96
   136    GND @S9S_MB_2U_LIB.S9S_MB_2U(SCH_1):GND   I176 @S9S_MB_2U_LIB.S9S_MB_2U(SCH_1):PAGE96
   139    GND @S9S_MB_2U_LIB.S9S_MB_2U(SCH_1):GND   I176 @S9S_MB_2U_LIB.S9S_MB_2U(SCH_1):PAGE96
   141    GND @S9S_MB_2U_LIB.S9S_MB_2U(SCH_1):GND   I176 @S9S_MB_2U_LIB.S9S_MB_2U(SCH_1):PAGE96
    G1    GND @S9S_MB_2U_LIB.S9S_MB_2U(SCH_1):GND   I176 @S9S_MB_2U_LIB.S9S_MB_2U(SCH_1):PAGE96
    G2    GND @S9S_MB_2U_LIB.S9S_MB_2U(SCH_1):GND   I176 @S9S_MB_2U_LIB.S9S_MB_2U(SCH_1):PAGE96
    G3    GND @S9S_MB_2U_LIB.S9S_MB_2U(SCH_1):GND   I176 @S9S_MB_2U_LIB.S9S_MB_2U(SCH_1):PAGE96

 J16 SCONN288_ADR50017P087CC-SCONN2A
     3 P3V3_AUX @S9S_MB_2U_LIB.S9S_MB_2U(SCH_1):P3V3_AUX     I6 @S9S_MB_2U_LIB.S9S_MB_2U(SCH_1):PAGE97
     2 TP_CHH_CPU0_DIMM2_FRU_0 @S9S_MB_2U_LIB.S9S_MB_2U(SCH_1):TP_CHH_CPU0_DIMM2_FRU_0     I6 @S9S_MB_2U_LIB.S9S_MB_2U(SCH_1):PAGE97
   144 TP_CHH_CPU0_DIMM2_FRU_1 @S9S_MB_2U_LIB.S9S_MB_2U(SCH_1):TP_CHH_CPU0_DIMM2_FRU_1     I6 @S9S_MB_2U_LIB.S9S_MB_2U(SCH_1):PAGE97
   149 TP_CHH_CPU0_DIMM2_FRU_2 @S9S_MB_2U_LIB.S9S_MB_2U(SCH_1):TP_CHH_CPU0_DIMM2_FRU_2     I6 @S9S_MB_2U_LIB.S9S_MB_2U(SCH_1):PAGE97
   150 TP_CHH_CPU0_DIMM2_FRU_3 @S9S_MB_2U_LIB.S9S_MB_2U(SCH_1):TP_CHH_CPU0_DIMM2_FRU_3     I6 @S9S_MB_2U_LIB.S9S_MB_2U(SCH_1):PAGE97
   220 TP_CHH_CPU0_DIMM2_FRU_4 @S9S_MB_2U_LIB.S9S_MB_2U(SCH_1):TP_CHH_CPU0_DIMM2_FRU_4     I6 @S9S_MB_2U_LIB.S9S_MB_2U(SCH_1):PAGE97
   231 TP_CHH_CPU0_DIMM2_FRU_5 @S9S_MB_2U_LIB.S9S_MB_2U(SCH_1):TP_CHH_CPU0_DIMM2_FRU_5     I6 @S9S_MB_2U_LIB.S9S_MB_2U(SCH_1):PAGE97
   232 TP_CHH_CPU0_DIMM2_FRU_6 @S9S_MB_2U_LIB.S9S_MB_2U(SCH_1):TP_CHH_CPU0_DIMM2_FRU_6     I6 @S9S_MB_2U_LIB.S9S_MB_2U(SCH_1):PAGE97
   207 RST_M_GH_CPU0_FPGA_N @S9S_MB_2U_LIB.S9S_MB_2U(SCH_1):RST_M_GH_CPU0_FPGA_N     I6 @S9S_MB_2U_LIB.S9S_MB_2U(SCH_1):PAGE97
   147 PWRGD_CHH_CPU0_DIMM2 @S9S_MB_2U_LIB.S9S_MB_2U(SCH_1):PWRGD_CHH_CPU0_DIMM2     I6 @S9S_MB_2U_LIB.S9S_MB_2U(SCH_1):PAGE97
   227 M_H_CPU0_SB_PAR @S9S_MB_2U_LIB.S9S_MB_2U(SCH_1):M_H_CPU0_SB_PAR     I6 @S9S_MB_2U_LIB.S9S_MB_2U(SCH_1):PAGE97
    74 M_H_CPU0_SA_PAR @S9S_MB_2U_LIB.S9S_MB_2U(SCH_1):M_H_CPU0_SA_PAR     I6 @S9S_MB_2U_LIB.S9S_MB_2U(SCH_1):PAGE97
    87 M_H_CPU0_SB_RSP<1> @S9S_MB_2U_LIB.S9S_MB_2U(SCH_1):M_H_CPU0_SB_RSP(1)     I6 @S9S_MB_2U_LIB.S9S_MB_2U(SCH_1):PAGE97
    86 M_H_CPU0_SA_RSP<1> @S9S_MB_2U_LIB.S9S_MB_2U(SCH_1):M_H_CPU0_SA_RSP(1)     I6 @S9S_MB_2U_LIB.S9S_MB_2U(SCH_1):PAGE97
     5 I3C_SPD_DDREFGH_CPU0_LVC1_SDA @S9S_MB_2U_LIB.S9S_MB_2U(SCH_1):I3C_SPD_DDREFGH_CPU0_LVC1_SDA     I6 @S9S_MB_2U_LIB.S9S_MB_2U(SCH_1):PAGE97
     4 I3C_SPD_DDREFGH_CPU0_LVC1_SCL_7 @S9S_MB_2U_LIB.S9S_MB_2U(SCH_1):I3C_SPD_DDREFGH_CPU0_LVC1_SCL_R8     I6 @S9S_MB_2U_LIB.S9S_MB_2U(SCH_1):PAGE97
   148 PD_CHH_CPU0_DIMM2_SAA @S9S_MB_2U_LIB.S9S_MB_2U(SCH_1):PD_CHH_CPU0_DIMM2_SAA     I6 @S9S_MB_2U_LIB.S9S_MB_2U(SCH_1):PAGE97
   100 M_H_CPU0_SB_DQ<0> @S9S_MB_2U_LIB.S9S_MB_2U(SCH_1):M_H_CPU0_SB_DQ(0)     I6 @S9S_MB_2U_LIB.S9S_MB_2U(SCH_1):PAGE97
   102 M_H_CPU0_SB_DQ<1> @S9S_MB_2U_LIB.S9S_MB_2U(SCH_1):M_H_CPU0_SB_DQ(1)     I6 @S9S_MB_2U_LIB.S9S_MB_2U(SCH_1):PAGE97
   245 M_H_CPU0_SB_DQ<2> @S9S_MB_2U_LIB.S9S_MB_2U(SCH_1):M_H_CPU0_SB_DQ(2)     I6 @S9S_MB_2U_LIB.S9S_MB_2U(SCH_1):PAGE97
   247 M_H_CPU0_SB_DQ<3> @S9S_MB_2U_LIB.S9S_MB_2U(SCH_1):M_H_CPU0_SB_DQ(3)     I6 @S9S_MB_2U_LIB.S9S_MB_2U(SCH_1):PAGE97
   107 M_H_CPU0_SB_DQ<4> @S9S_MB_2U_LIB.S9S_MB_2U(SCH_1):M_H_CPU0_SB_DQ(4)     I6 @S9S_MB_2U_LIB.S9S_MB_2U(SCH_1):PAGE97
   109 M_H_CPU0_SB_DQ<5> @S9S_MB_2U_LIB.S9S_MB_2U(SCH_1):M_H_CPU0_SB_DQ(5)     I6 @S9S_MB_2U_LIB.S9S_MB_2U(SCH_1):PAGE97
   252 M_H_CPU0_SB_DQ<6> @S9S_MB_2U_LIB.S9S_MB_2U(SCH_1):M_H_CPU0_SB_DQ(6)     I6 @S9S_MB_2U_LIB.S9S_MB_2U(SCH_1):PAGE97
   254 M_H_CPU0_SB_DQ<7> @S9S_MB_2U_LIB.S9S_MB_2U(SCH_1):M_H_CPU0_SB_DQ(7)     I6 @S9S_MB_2U_LIB.S9S_MB_2U(SCH_1):PAGE97
   111 M_H_CPU0_SB_DQ<8> @S9S_MB_2U_LIB.S9S_MB_2U(SCH_1):M_H_CPU0_SB_DQ(8)     I6 @S9S_MB_2U_LIB.S9S_MB_2U(SCH_1):PAGE97
   113 M_H_CPU0_SB_DQ<9> @S9S_MB_2U_LIB.S9S_MB_2U(SCH_1):M_H_CPU0_SB_DQ(9)     I6 @S9S_MB_2U_LIB.S9S_MB_2U(SCH_1):PAGE97
   256 M_H_CPU0_SB_DQ<10> @S9S_MB_2U_LIB.S9S_MB_2U(SCH_1):M_H_CPU0_SB_DQ(10)     I6 @S9S_MB_2U_LIB.S9S_MB_2U(SCH_1):PAGE97
   258 M_H_CPU0_SB_DQ<11> @S9S_MB_2U_LIB.S9S_MB_2U(SCH_1):M_H_CPU0_SB_DQ(11)     I6 @S9S_MB_2U_LIB.S9S_MB_2U(SCH_1):PAGE97
   118 M_H_CPU0_SB_DQ<12> @S9S_MB_2U_LIB.S9S_MB_2U(SCH_1):M_H_CPU0_SB_DQ(12)     I6 @S9S_MB_2U_LIB.S9S_MB_2U(SCH_1):PAGE97
   120 M_H_CPU0_SB_DQ<13> @S9S_MB_2U_LIB.S9S_MB_2U(SCH_1):M_H_CPU0_SB_DQ(13)     I6 @S9S_MB_2U_LIB.S9S_MB_2U(SCH_1):PAGE97
   263 M_H_CPU0_SB_DQ<14> @S9S_MB_2U_LIB.S9S_MB_2U(SCH_1):M_H_CPU0_SB_DQ(14)     I6 @S9S_MB_2U_LIB.S9S_MB_2U(SCH_1):PAGE97
   265 M_H_CPU0_SB_DQ<15> @S9S_MB_2U_LIB.S9S_MB_2U(SCH_1):M_H_CPU0_SB_DQ(15)     I6 @S9S_MB_2U_LIB.S9S_MB_2U(SCH_1):PAGE97
   122 M_H_CPU0_SB_DQ<16> @S9S_MB_2U_LIB.S9S_MB_2U(SCH_1):M_H_CPU0_SB_DQ(16)     I6 @S9S_MB_2U_LIB.S9S_MB_2U(SCH_1):PAGE97
   124 M_H_CPU0_SB_DQ<17> @S9S_MB_2U_LIB.S9S_MB_2U(SCH_1):M_H_CPU0_SB_DQ(17)     I6 @S9S_MB_2U_LIB.S9S_MB_2U(SCH_1):PAGE97
   267 M_H_CPU0_SB_DQ<18> @S9S_MB_2U_LIB.S9S_MB_2U(SCH_1):M_H_CPU0_SB_DQ(18)     I6 @S9S_MB_2U_LIB.S9S_MB_2U(SCH_1):PAGE97
   269 M_H_CPU0_SB_DQ<19> @S9S_MB_2U_LIB.S9S_MB_2U(SCH_1):M_H_CPU0_SB_DQ(19)     I6 @S9S_MB_2U_LIB.S9S_MB_2U(SCH_1):PAGE97
   129 M_H_CPU0_SB_DQ<20> @S9S_MB_2U_LIB.S9S_MB_2U(SCH_1):M_H_CPU0_SB_DQ(20)     I6 @S9S_MB_2U_LIB.S9S_MB_2U(SCH_1):PAGE97
   131 M_H_CPU0_SB_DQ<21> @S9S_MB_2U_LIB.S9S_MB_2U(SCH_1):M_H_CPU0_SB_DQ(21)     I6 @S9S_MB_2U_LIB.S9S_MB_2U(SCH_1):PAGE97
   274 M_H_CPU0_SB_DQ<22> @S9S_MB_2U_LIB.S9S_MB_2U(SCH_1):M_H_CPU0_SB_DQ(22)     I6 @S9S_MB_2U_LIB.S9S_MB_2U(SCH_1):PAGE97
   276 M_H_CPU0_SB_DQ<23> @S9S_MB_2U_LIB.S9S_MB_2U(SCH_1):M_H_CPU0_SB_DQ(23)     I6 @S9S_MB_2U_LIB.S9S_MB_2U(SCH_1):PAGE97
   133 M_H_CPU0_SB_DQ<24> @S9S_MB_2U_LIB.S9S_MB_2U(SCH_1):M_H_CPU0_SB_DQ(24)     I6 @S9S_MB_2U_LIB.S9S_MB_2U(SCH_1):PAGE97
   135 M_H_CPU0_SB_DQ<25> @S9S_MB_2U_LIB.S9S_MB_2U(SCH_1):M_H_CPU0_SB_DQ(25)     I6 @S9S_MB_2U_LIB.S9S_MB_2U(SCH_1):PAGE97
   278 M_H_CPU0_SB_DQ<26> @S9S_MB_2U_LIB.S9S_MB_2U(SCH_1):M_H_CPU0_SB_DQ(26)     I6 @S9S_MB_2U_LIB.S9S_MB_2U(SCH_1):PAGE97
   280 M_H_CPU0_SB_DQ<27> @S9S_MB_2U_LIB.S9S_MB_2U(SCH_1):M_H_CPU0_SB_DQ(27)     I6 @S9S_MB_2U_LIB.S9S_MB_2U(SCH_1):PAGE97
   140 M_H_CPU0_SB_DQ<28> @S9S_MB_2U_LIB.S9S_MB_2U(SCH_1):M_H_CPU0_SB_DQ(28)     I6 @S9S_MB_2U_LIB.S9S_MB_2U(SCH_1):PAGE97
   142 M_H_CPU0_SB_DQ<29> @S9S_MB_2U_LIB.S9S_MB_2U(SCH_1):M_H_CPU0_SB_DQ(29)     I6 @S9S_MB_2U_LIB.S9S_MB_2U(SCH_1):PAGE97
   285 M_H_CPU0_SB_DQ<30> @S9S_MB_2U_LIB.S9S_MB_2U(SCH_1):M_H_CPU0_SB_DQ(30)     I6 @S9S_MB_2U_LIB.S9S_MB_2U(SCH_1):PAGE97
   287 M_H_CPU0_SB_DQ<31> @S9S_MB_2U_LIB.S9S_MB_2U(SCH_1):M_H_CPU0_SB_DQ(31)     I6 @S9S_MB_2U_LIB.S9S_MB_2U(SCH_1):PAGE97
     7 M_H_CPU0_SA_DQ<0> @S9S_MB_2U_LIB.S9S_MB_2U(SCH_1):M_H_CPU0_SA_DQ(0)     I6 @S9S_MB_2U_LIB.S9S_MB_2U(SCH_1):PAGE97
     9 M_H_CPU0_SA_DQ<1> @S9S_MB_2U_LIB.S9S_MB_2U(SCH_1):M_H_CPU0_SA_DQ(1)     I6 @S9S_MB_2U_LIB.S9S_MB_2U(SCH_1):PAGE97
   152 M_H_CPU0_SA_DQ<2> @S9S_MB_2U_LIB.S9S_MB_2U(SCH_1):M_H_CPU0_SA_DQ(2)     I6 @S9S_MB_2U_LIB.S9S_MB_2U(SCH_1):PAGE97
   154 M_H_CPU0_SA_DQ<3> @S9S_MB_2U_LIB.S9S_MB_2U(SCH_1):M_H_CPU0_SA_DQ(3)     I6 @S9S_MB_2U_LIB.S9S_MB_2U(SCH_1):PAGE97
    14 M_H_CPU0_SA_DQ<4> @S9S_MB_2U_LIB.S9S_MB_2U(SCH_1):M_H_CPU0_SA_DQ(4)     I6 @S9S_MB_2U_LIB.S9S_MB_2U(SCH_1):PAGE97
    16 M_H_CPU0_SA_DQ<5> @S9S_MB_2U_LIB.S9S_MB_2U(SCH_1):M_H_CPU0_SA_DQ(5)     I6 @S9S_MB_2U_LIB.S9S_MB_2U(SCH_1):PAGE97
   159 M_H_CPU0_SA_DQ<6> @S9S_MB_2U_LIB.S9S_MB_2U(SCH_1):M_H_CPU0_SA_DQ(6)     I6 @S9S_MB_2U_LIB.S9S_MB_2U(SCH_1):PAGE97
   161 M_H_CPU0_SA_DQ<7> @S9S_MB_2U_LIB.S9S_MB_2U(SCH_1):M_H_CPU0_SA_DQ(7)     I6 @S9S_MB_2U_LIB.S9S_MB_2U(SCH_1):PAGE97
    18 M_H_CPU0_SA_DQ<8> @S9S_MB_2U_LIB.S9S_MB_2U(SCH_1):M_H_CPU0_SA_DQ(8)     I6 @S9S_MB_2U_LIB.S9S_MB_2U(SCH_1):PAGE97
    20 M_H_CPU0_SA_DQ<9> @S9S_MB_2U_LIB.S9S_MB_2U(SCH_1):M_H_CPU0_SA_DQ(9)     I6 @S9S_MB_2U_LIB.S9S_MB_2U(SCH_1):PAGE97
   163 M_H_CPU0_SA_DQ<10> @S9S_MB_2U_LIB.S9S_MB_2U(SCH_1):M_H_CPU0_SA_DQ(10)     I6 @S9S_MB_2U_LIB.S9S_MB_2U(SCH_1):PAGE97
   165 M_H_CPU0_SA_DQ<11> @S9S_MB_2U_LIB.S9S_MB_2U(SCH_1):M_H_CPU0_SA_DQ(11)     I6 @S9S_MB_2U_LIB.S9S_MB_2U(SCH_1):PAGE97
    25 M_H_CPU0_SA_DQ<12> @S9S_MB_2U_LIB.S9S_MB_2U(SCH_1):M_H_CPU0_SA_DQ(12)     I6 @S9S_MB_2U_LIB.S9S_MB_2U(SCH_1):PAGE97
    27 M_H_CPU0_SA_DQ<13> @S9S_MB_2U_LIB.S9S_MB_2U(SCH_1):M_H_CPU0_SA_DQ(13)     I6 @S9S_MB_2U_LIB.S9S_MB_2U(SCH_1):PAGE97
   170 M_H_CPU0_SA_DQ<14> @S9S_MB_2U_LIB.S9S_MB_2U(SCH_1):M_H_CPU0_SA_DQ(14)     I6 @S9S_MB_2U_LIB.S9S_MB_2U(SCH_1):PAGE97
   172 M_H_CPU0_SA_DQ<15> @S9S_MB_2U_LIB.S9S_MB_2U(SCH_1):M_H_CPU0_SA_DQ(15)     I6 @S9S_MB_2U_LIB.S9S_MB_2U(SCH_1):PAGE97
    29 M_H_CPU0_SA_DQ<16> @S9S_MB_2U_LIB.S9S_MB_2U(SCH_1):M_H_CPU0_SA_DQ(16)     I6 @S9S_MB_2U_LIB.S9S_MB_2U(SCH_1):PAGE97
    31 M_H_CPU0_SA_DQ<17> @S9S_MB_2U_LIB.S9S_MB_2U(SCH_1):M_H_CPU0_SA_DQ(17)     I6 @S9S_MB_2U_LIB.S9S_MB_2U(SCH_1):PAGE97
   174 M_H_CPU0_SA_DQ<18> @S9S_MB_2U_LIB.S9S_MB_2U(SCH_1):M_H_CPU0_SA_DQ(18)     I6 @S9S_MB_2U_LIB.S9S_MB_2U(SCH_1):PAGE97
   176 M_H_CPU0_SA_DQ<19> @S9S_MB_2U_LIB.S9S_MB_2U(SCH_1):M_H_CPU0_SA_DQ(19)     I6 @S9S_MB_2U_LIB.S9S_MB_2U(SCH_1):PAGE97
    36 M_H_CPU0_SA_DQ<20> @S9S_MB_2U_LIB.S9S_MB_2U(SCH_1):M_H_CPU0_SA_DQ(20)     I6 @S9S_MB_2U_LIB.S9S_MB_2U(SCH_1):PAGE97
    38 M_H_CPU0_SA_DQ<21> @S9S_MB_2U_LIB.S9S_MB_2U(SCH_1):M_H_CPU0_SA_DQ(21)     I6 @S9S_MB_2U_LIB.S9S_MB_2U(SCH_1):PAGE97
   181 M_H_CPU0_SA_DQ<22> @S9S_MB_2U_LIB.S9S_MB_2U(SCH_1):M_H_CPU0_SA_DQ(22)     I6 @S9S_MB_2U_LIB.S9S_MB_2U(SCH_1):PAGE97
   183 M_H_CPU0_SA_DQ<23> @S9S_MB_2U_LIB.S9S_MB_2U(SCH_1):M_H_CPU0_SA_DQ(23)     I6 @S9S_MB_2U_LIB.S9S_MB_2U(SCH_1):PAGE97
    40 M_H_CPU0_SA_DQ<24> @S9S_MB_2U_LIB.S9S_MB_2U(SCH_1):M_H_CPU0_SA_DQ(24)     I6 @S9S_MB_2U_LIB.S9S_MB_2U(SCH_1):PAGE97
    42 M_H_CPU0_SA_DQ<25> @S9S_MB_2U_LIB.S9S_MB_2U(SCH_1):M_H_CPU0_SA_DQ(25)     I6 @S9S_MB_2U_LIB.S9S_MB_2U(SCH_1):PAGE97
   185 M_H_CPU0_SA_DQ<26> @S9S_MB_2U_LIB.S9S_MB_2U(SCH_1):M_H_CPU0_SA_DQ(26)     I6 @S9S_MB_2U_LIB.S9S_MB_2U(SCH_1):PAGE97
   187 M_H_CPU0_SA_DQ<27> @S9S_MB_2U_LIB.S9S_MB_2U(SCH_1):M_H_CPU0_SA_DQ(27)     I6 @S9S_MB_2U_LIB.S9S_MB_2U(SCH_1):PAGE97
    47 M_H_CPU0_SA_DQ<28> @S9S_MB_2U_LIB.S9S_MB_2U(SCH_1):M_H_CPU0_SA_DQ(28)     I6 @S9S_MB_2U_LIB.S9S_MB_2U(SCH_1):PAGE97
    49 M_H_CPU0_SA_DQ<29> @S9S_MB_2U_LIB.S9S_MB_2U(SCH_1):M_H_CPU0_SA_DQ(29)     I6 @S9S_MB_2U_LIB.S9S_MB_2U(SCH_1):PAGE97
   192 M_H_CPU0_SA_DQ<30> @S9S_MB_2U_LIB.S9S_MB_2U(SCH_1):M_H_CPU0_SA_DQ(30)     I6 @S9S_MB_2U_LIB.S9S_MB_2U(SCH_1):PAGE97
   229 M_H_CPU0_SB_CS_N<3> @S9S_MB_2U_LIB.S9S_MB_2U(SCH_1):M_H_CPU0_SB_CS_N(3)     I6 @S9S_MB_2U_LIB.S9S_MB_2U(SCH_1):PAGE97
   209 M_H_CPU0_SA_CS_N<3> @S9S_MB_2U_LIB.S9S_MB_2U(SCH_1):M_H_CPU0_SA_CS_N(3)     I6 @S9S_MB_2U_LIB.S9S_MB_2U(SCH_1):PAGE97
    84 M_H_CPU0_SB_CS_N<2> @S9S_MB_2U_LIB.S9S_MB_2U(SCH_1):M_H_CPU0_SB_CS_N(2)     I6 @S9S_MB_2U_LIB.S9S_MB_2U(SCH_1):PAGE97
    64 M_H_CPU0_SA_CS_N<2> @S9S_MB_2U_LIB.S9S_MB_2U(SCH_1):M_H_CPU0_SA_CS_N(2)     I6 @S9S_MB_2U_LIB.S9S_MB_2U(SCH_1):PAGE97
   217 M_H_CPU0_CLK_DP<1> @S9S_MB_2U_LIB.S9S_MB_2U(SCH_1):M_H_CPU0_CLK_DP(1)     I6 @S9S_MB_2U_LIB.S9S_MB_2U(SCH_1):PAGE97
   218 M_H_CPU0_CLK_DN<1> @S9S_MB_2U_LIB.S9S_MB_2U(SCH_1):M_H_CPU0_CLK_DN(1)     I6 @S9S_MB_2U_LIB.S9S_MB_2U(SCH_1):PAGE97
    96 M_H_CPU0_SB_CB<0> @S9S_MB_2U_LIB.S9S_MB_2U(SCH_1):M_H_CPU0_SB_CB(0)     I6 @S9S_MB_2U_LIB.S9S_MB_2U(SCH_1):PAGE97
    98 M_H_CPU0_SB_CB<1> @S9S_MB_2U_LIB.S9S_MB_2U(SCH_1):M_H_CPU0_SB_CB(1)     I6 @S9S_MB_2U_LIB.S9S_MB_2U(SCH_1):PAGE97
   241 M_H_CPU0_SB_CB<2> @S9S_MB_2U_LIB.S9S_MB_2U(SCH_1):M_H_CPU0_SB_CB(2)     I6 @S9S_MB_2U_LIB.S9S_MB_2U(SCH_1):PAGE97
   243 M_H_CPU0_SB_CB<3> @S9S_MB_2U_LIB.S9S_MB_2U(SCH_1):M_H_CPU0_SB_CB(3)     I6 @S9S_MB_2U_LIB.S9S_MB_2U(SCH_1):PAGE97
    89 M_H_CPU0_SB_CB<4> @S9S_MB_2U_LIB.S9S_MB_2U(SCH_1):M_H_CPU0_SB_CB(4)     I6 @S9S_MB_2U_LIB.S9S_MB_2U(SCH_1):PAGE97
    91 M_H_CPU0_SB_CB<5> @S9S_MB_2U_LIB.S9S_MB_2U(SCH_1):M_H_CPU0_SB_CB(5)     I6 @S9S_MB_2U_LIB.S9S_MB_2U(SCH_1):PAGE97
   234 M_H_CPU0_SB_CB<6> @S9S_MB_2U_LIB.S9S_MB_2U(SCH_1):M_H_CPU0_SB_CB(6)     I6 @S9S_MB_2U_LIB.S9S_MB_2U(SCH_1):PAGE97
    51 M_H_CPU0_SA_CB<0> @S9S_MB_2U_LIB.S9S_MB_2U(SCH_1):M_H_CPU0_SA_CB(0)     I6 @S9S_MB_2U_LIB.S9S_MB_2U(SCH_1):PAGE97
   196 M_H_CPU0_SA_CB<2> @S9S_MB_2U_LIB.S9S_MB_2U(SCH_1):M_H_CPU0_SA_CB(2)     I6 @S9S_MB_2U_LIB.S9S_MB_2U(SCH_1):PAGE97
   198 M_H_CPU0_SA_CB<3> @S9S_MB_2U_LIB.S9S_MB_2U(SCH_1):M_H_CPU0_SA_CB(3)     I6 @S9S_MB_2U_LIB.S9S_MB_2U(SCH_1):PAGE97
    60 M_H_CPU0_SA_CB<5> @S9S_MB_2U_LIB.S9S_MB_2U(SCH_1):M_H_CPU0_SA_CB(5)     I6 @S9S_MB_2U_LIB.S9S_MB_2U(SCH_1):PAGE97
   203 M_H_CPU0_SA_CB<6> @S9S_MB_2U_LIB.S9S_MB_2U(SCH_1):M_H_CPU0_SA_CB(6)     I6 @S9S_MB_2U_LIB.S9S_MB_2U(SCH_1):PAGE97
    82 M_H_CPU0_SB_CA<6> @S9S_MB_2U_LIB.S9S_MB_2U(SCH_1):M_H_CPU0_SB_CA(6)     I6 @S9S_MB_2U_LIB.S9S_MB_2U(SCH_1):PAGE97
    72 M_H_CPU0_SA_CA<6> @S9S_MB_2U_LIB.S9S_MB_2U(SCH_1):M_H_CPU0_SA_CA(6)     I6 @S9S_MB_2U_LIB.S9S_MB_2U(SCH_1):PAGE97
   225 M_H_CPU0_SB_CA<5> @S9S_MB_2U_LIB.S9S_MB_2U(SCH_1):M_H_CPU0_SB_CA(5)     I6 @S9S_MB_2U_LIB.S9S_MB_2U(SCH_1):PAGE97
   215 M_H_CPU0_SA_CA<5> @S9S_MB_2U_LIB.S9S_MB_2U(SCH_1):M_H_CPU0_SA_CA(5)     I6 @S9S_MB_2U_LIB.S9S_MB_2U(SCH_1):PAGE97
    80 M_H_CPU0_SB_CA<4> @S9S_MB_2U_LIB.S9S_MB_2U(SCH_1):M_H_CPU0_SB_CA(4)     I6 @S9S_MB_2U_LIB.S9S_MB_2U(SCH_1):PAGE97
    70 M_H_CPU0_SA_CA<4> @S9S_MB_2U_LIB.S9S_MB_2U(SCH_1):M_H_CPU0_SA_CA(4)     I6 @S9S_MB_2U_LIB.S9S_MB_2U(SCH_1):PAGE97
   223 M_H_CPU0_SB_CA<3> @S9S_MB_2U_LIB.S9S_MB_2U(SCH_1):M_H_CPU0_SB_CA(3)     I6 @S9S_MB_2U_LIB.S9S_MB_2U(SCH_1):PAGE97
   213 M_H_CPU0_SA_CA<3> @S9S_MB_2U_LIB.S9S_MB_2U(SCH_1):M_H_CPU0_SA_CA(3)     I6 @S9S_MB_2U_LIB.S9S_MB_2U(SCH_1):PAGE97
    78 M_H_CPU0_SB_CA<2> @S9S_MB_2U_LIB.S9S_MB_2U(SCH_1):M_H_CPU0_SB_CA(2)     I6 @S9S_MB_2U_LIB.S9S_MB_2U(SCH_1):PAGE97
    68 M_H_CPU0_SA_CA<2> @S9S_MB_2U_LIB.S9S_MB_2U(SCH_1):M_H_CPU0_SA_CA(2)     I6 @S9S_MB_2U_LIB.S9S_MB_2U(SCH_1):PAGE97
   221 M_H_CPU0_SB_CA<1> @S9S_MB_2U_LIB.S9S_MB_2U(SCH_1):M_H_CPU0_SB_CA(1)     I6 @S9S_MB_2U_LIB.S9S_MB_2U(SCH_1):PAGE97
   211 M_H_CPU0_SA_CA<1> @S9S_MB_2U_LIB.S9S_MB_2U(SCH_1):M_H_CPU0_SA_CA(1)     I6 @S9S_MB_2U_LIB.S9S_MB_2U(SCH_1):PAGE97
    76 M_H_CPU0_SB_CA<0> @S9S_MB_2U_LIB.S9S_MB_2U(SCH_1):M_H_CPU0_SB_CA(0)     I6 @S9S_MB_2U_LIB.S9S_MB_2U(SCH_1):PAGE97
    66 M_H_CPU0_SA_CA<0> @S9S_MB_2U_LIB.S9S_MB_2U(SCH_1):M_H_CPU0_SA_CA(0)     I6 @S9S_MB_2U_LIB.S9S_MB_2U(SCH_1):PAGE97
    62 M_H_CPU0_ALERT_N @S9S_MB_2U_LIB.S9S_MB_2U(SCH_1):M_H_CPU0_ALERT_N     I6 @S9S_MB_2U_LIB.S9S_MB_2U(SCH_1):PAGE97
   236 M_H_CPU0_SB_CB<7> @S9S_MB_2U_LIB.S9S_MB_2U(SCH_1):M_H_CPU0_SB_CB(7)     I6 @S9S_MB_2U_LIB.S9S_MB_2U(SCH_1):PAGE97
    53 M_H_CPU0_SA_CB<1> @S9S_MB_2U_LIB.S9S_MB_2U(SCH_1):M_H_CPU0_SA_CB(1)     I6 @S9S_MB_2U_LIB.S9S_MB_2U(SCH_1):PAGE97
    58 M_H_CPU0_SA_CB<4> @S9S_MB_2U_LIB.S9S_MB_2U(SCH_1):M_H_CPU0_SA_CB(4)     I6 @S9S_MB_2U_LIB.S9S_MB_2U(SCH_1):PAGE97
   205 M_H_CPU0_SA_CB<7> @S9S_MB_2U_LIB.S9S_MB_2U(SCH_1):M_H_CPU0_SA_CB(7)     I6 @S9S_MB_2U_LIB.S9S_MB_2U(SCH_1):PAGE97
   194 M_H_CPU0_SA_DQ<31> @S9S_MB_2U_LIB.S9S_MB_2U(SCH_1):M_H_CPU0_SA_DQ(31)     I6 @S9S_MB_2U_LIB.S9S_MB_2U(SCH_1):PAGE97
    93 M_H_CPU0_SB_DQS_DP<9> @S9S_MB_2U_LIB.S9S_MB_2U(SCH_1):M_H_CPU0_SB_DQS_DP(9)   I178 @S9S_MB_2U_LIB.S9S_MB_2U(SCH_1):PAGE97
    94 M_H_CPU0_SB_DQS_DN<9> @S9S_MB_2U_LIB.S9S_MB_2U(SCH_1):M_H_CPU0_SB_DQS_DN(9)   I178 @S9S_MB_2U_LIB.S9S_MB_2U(SCH_1):PAGE97
   201 M_H_CPU0_SA_DQS_DP<9> @S9S_MB_2U_LIB.S9S_MB_2U(SCH_1):M_H_CPU0_SA_DQS_DP(9)   I178 @S9S_MB_2U_LIB.S9S_MB_2U(SCH_1):PAGE97
   200 M_H_CPU0_SA_DQS_DN<9> @S9S_MB_2U_LIB.S9S_MB_2U(SCH_1):M_H_CPU0_SA_DQS_DN(9)   I178 @S9S_MB_2U_LIB.S9S_MB_2U(SCH_1):PAGE97
   190 M_H_CPU0_SA_DQS_DP<8> @S9S_MB_2U_LIB.S9S_MB_2U(SCH_1):M_H_CPU0_SA_DQS_DP(8)   I178 @S9S_MB_2U_LIB.S9S_MB_2U(SCH_1):PAGE97
   189 M_H_CPU0_SA_DQS_DN<8> @S9S_MB_2U_LIB.S9S_MB_2U(SCH_1):M_H_CPU0_SA_DQS_DN(8)   I178 @S9S_MB_2U_LIB.S9S_MB_2U(SCH_1):PAGE97
   271 M_H_CPU0_SB_DQS_DN<7> @S9S_MB_2U_LIB.S9S_MB_2U(SCH_1):M_H_CPU0_SB_DQS_DN(7)   I178 @S9S_MB_2U_LIB.S9S_MB_2U(SCH_1):PAGE97
   179 M_H_CPU0_SA_DQS_DP<7> @S9S_MB_2U_LIB.S9S_MB_2U(SCH_1):M_H_CPU0_SA_DQS_DP(7)   I178 @S9S_MB_2U_LIB.S9S_MB_2U(SCH_1):PAGE97
   261 M_H_CPU0_SB_DQS_DP<6> @S9S_MB_2U_LIB.S9S_MB_2U(SCH_1):M_H_CPU0_SB_DQS_DP(6)   I178 @S9S_MB_2U_LIB.S9S_MB_2U(SCH_1):PAGE97
   260 M_H_CPU0_SB_DQS_DN<6> @S9S_MB_2U_LIB.S9S_MB_2U(SCH_1):M_H_CPU0_SB_DQS_DN(6)   I178 @S9S_MB_2U_LIB.S9S_MB_2U(SCH_1):PAGE97
   167 M_H_CPU0_SA_DQS_DN<6> @S9S_MB_2U_LIB.S9S_MB_2U(SCH_1):M_H_CPU0_SA_DQS_DN(6)   I178 @S9S_MB_2U_LIB.S9S_MB_2U(SCH_1):PAGE97
   250 M_H_CPU0_SB_DQS_DP<5> @S9S_MB_2U_LIB.S9S_MB_2U(SCH_1):M_H_CPU0_SB_DQS_DP(5)   I178 @S9S_MB_2U_LIB.S9S_MB_2U(SCH_1):PAGE97
   249 M_H_CPU0_SB_DQS_DN<5> @S9S_MB_2U_LIB.S9S_MB_2U(SCH_1):M_H_CPU0_SB_DQS_DN(5)   I178 @S9S_MB_2U_LIB.S9S_MB_2U(SCH_1):PAGE97
   157 M_H_CPU0_SA_DQS_DP<5> @S9S_MB_2U_LIB.S9S_MB_2U(SCH_1):M_H_CPU0_SA_DQS_DP(5)   I178 @S9S_MB_2U_LIB.S9S_MB_2U(SCH_1):PAGE97
   156 M_H_CPU0_SA_DQS_DN<5> @S9S_MB_2U_LIB.S9S_MB_2U(SCH_1):M_H_CPU0_SA_DQS_DN(5)   I178 @S9S_MB_2U_LIB.S9S_MB_2U(SCH_1):PAGE97
   239 M_H_CPU0_SB_DQS_DP<4> @S9S_MB_2U_LIB.S9S_MB_2U(SCH_1):M_H_CPU0_SB_DQS_DP(4)   I178 @S9S_MB_2U_LIB.S9S_MB_2U(SCH_1):PAGE97
   238 M_H_CPU0_SB_DQS_DN<4> @S9S_MB_2U_LIB.S9S_MB_2U(SCH_1):M_H_CPU0_SB_DQS_DN(4)   I178 @S9S_MB_2U_LIB.S9S_MB_2U(SCH_1):PAGE97
    55 M_H_CPU0_SA_DQS_DP<4> @S9S_MB_2U_LIB.S9S_MB_2U(SCH_1):M_H_CPU0_SA_DQS_DP(4)   I178 @S9S_MB_2U_LIB.S9S_MB_2U(SCH_1):PAGE97
    56 M_H_CPU0_SA_DQS_DN<4> @S9S_MB_2U_LIB.S9S_MB_2U(SCH_1):M_H_CPU0_SA_DQS_DN(4)   I178 @S9S_MB_2U_LIB.S9S_MB_2U(SCH_1):PAGE97
   137 M_H_CPU0_SB_DQS_DP<3> @S9S_MB_2U_LIB.S9S_MB_2U(SCH_1):M_H_CPU0_SB_DQS_DP(3)   I178 @S9S_MB_2U_LIB.S9S_MB_2U(SCH_1):PAGE97
   138 M_H_CPU0_SB_DQS_DN<3> @S9S_MB_2U_LIB.S9S_MB_2U(SCH_1):M_H_CPU0_SB_DQS_DN(3)   I178 @S9S_MB_2U_LIB.S9S_MB_2U(SCH_1):PAGE97
    44 M_H_CPU0_SA_DQS_DP<3> @S9S_MB_2U_LIB.S9S_MB_2U(SCH_1):M_H_CPU0_SA_DQS_DP(3)   I178 @S9S_MB_2U_LIB.S9S_MB_2U(SCH_1):PAGE97
    45 M_H_CPU0_SA_DQS_DN<3> @S9S_MB_2U_LIB.S9S_MB_2U(SCH_1):M_H_CPU0_SA_DQS_DN(3)   I178 @S9S_MB_2U_LIB.S9S_MB_2U(SCH_1):PAGE97
   126 M_H_CPU0_SB_DQS_DP<2> @S9S_MB_2U_LIB.S9S_MB_2U(SCH_1):M_H_CPU0_SB_DQS_DP(2)   I178 @S9S_MB_2U_LIB.S9S_MB_2U(SCH_1):PAGE97
   127 M_H_CPU0_SB_DQS_DN<2> @S9S_MB_2U_LIB.S9S_MB_2U(SCH_1):M_H_CPU0_SB_DQS_DN(2)   I178 @S9S_MB_2U_LIB.S9S_MB_2U(SCH_1):PAGE97
    33 M_H_CPU0_SA_DQS_DP<2> @S9S_MB_2U_LIB.S9S_MB_2U(SCH_1):M_H_CPU0_SA_DQS_DP(2)   I178 @S9S_MB_2U_LIB.S9S_MB_2U(SCH_1):PAGE97
    34 M_H_CPU0_SA_DQS_DN<2> @S9S_MB_2U_LIB.S9S_MB_2U(SCH_1):M_H_CPU0_SA_DQS_DN(2)   I178 @S9S_MB_2U_LIB.S9S_MB_2U(SCH_1):PAGE97
   115 M_H_CPU0_SB_DQS_DP<1> @S9S_MB_2U_LIB.S9S_MB_2U(SCH_1):M_H_CPU0_SB_DQS_DP(1)   I178 @S9S_MB_2U_LIB.S9S_MB_2U(SCH_1):PAGE97
   116 M_H_CPU0_SB_DQS_DN<1> @S9S_MB_2U_LIB.S9S_MB_2U(SCH_1):M_H_CPU0_SB_DQS_DN(1)   I178 @S9S_MB_2U_LIB.S9S_MB_2U(SCH_1):PAGE97
    22 M_H_CPU0_SA_DQS_DP<1> @S9S_MB_2U_LIB.S9S_MB_2U(SCH_1):M_H_CPU0_SA_DQS_DP(1)   I178 @S9S_MB_2U_LIB.S9S_MB_2U(SCH_1):PAGE97
    23 M_H_CPU0_SA_DQS_DN<1> @S9S_MB_2U_LIB.S9S_MB_2U(SCH_1):M_H_CPU0_SA_DQS_DN(1)   I178 @S9S_MB_2U_LIB.S9S_MB_2U(SCH_1):PAGE97
   104 M_H_CPU0_SB_DQS_DP<0> @S9S_MB_2U_LIB.S9S_MB_2U(SCH_1):M_H_CPU0_SB_DQS_DP(0)   I178 @S9S_MB_2U_LIB.S9S_MB_2U(SCH_1):PAGE97
   105 M_H_CPU0_SB_DQS_DN<0> @S9S_MB_2U_LIB.S9S_MB_2U(SCH_1):M_H_CPU0_SB_DQS_DN(0)   I178 @S9S_MB_2U_LIB.S9S_MB_2U(SCH_1):PAGE97
    11 M_H_CPU0_SA_DQS_DP<0> @S9S_MB_2U_LIB.S9S_MB_2U(SCH_1):M_H_CPU0_SA_DQS_DP(0)   I178 @S9S_MB_2U_LIB.S9S_MB_2U(SCH_1):PAGE97
    12 M_H_CPU0_SA_DQS_DN<0> @S9S_MB_2U_LIB.S9S_MB_2U(SCH_1):M_H_CPU0_SA_DQS_DN(0)   I178 @S9S_MB_2U_LIB.S9S_MB_2U(SCH_1):PAGE97
   272 M_H_CPU0_SB_DQS_DP<7> @S9S_MB_2U_LIB.S9S_MB_2U(SCH_1):M_H_CPU0_SB_DQS_DP(7)   I178 @S9S_MB_2U_LIB.S9S_MB_2U(SCH_1):PAGE97
   282 M_H_CPU0_SB_DQS_DN<8> @S9S_MB_2U_LIB.S9S_MB_2U(SCH_1):M_H_CPU0_SB_DQS_DN(8)   I178 @S9S_MB_2U_LIB.S9S_MB_2U(SCH_1):PAGE97
   283 M_H_CPU0_SB_DQS_DP<8> @S9S_MB_2U_LIB.S9S_MB_2U(SCH_1):M_H_CPU0_SB_DQS_DP(8)   I178 @S9S_MB_2U_LIB.S9S_MB_2U(SCH_1):PAGE97
   168 M_H_CPU0_SA_DQS_DP<6> @S9S_MB_2U_LIB.S9S_MB_2U(SCH_1):M_H_CPU0_SA_DQS_DP(6)   I178 @S9S_MB_2U_LIB.S9S_MB_2U(SCH_1):PAGE97
   178 M_H_CPU0_SA_DQS_DN<7> @S9S_MB_2U_LIB.S9S_MB_2U(SCH_1):M_H_CPU0_SA_DQS_DN(7)   I178 @S9S_MB_2U_LIB.S9S_MB_2U(SCH_1):PAGE97
     6    GND @S9S_MB_2U_LIB.S9S_MB_2U(SCH_1):GND    I64 @S9S_MB_2U_LIB.S9S_MB_2U(SCH_1):PAGE97
     8    GND @S9S_MB_2U_LIB.S9S_MB_2U(SCH_1):GND    I64 @S9S_MB_2U_LIB.S9S_MB_2U(SCH_1):PAGE97
    10    GND @S9S_MB_2U_LIB.S9S_MB_2U(SCH_1):GND    I64 @S9S_MB_2U_LIB.S9S_MB_2U(SCH_1):PAGE97
    13    GND @S9S_MB_2U_LIB.S9S_MB_2U(SCH_1):GND    I64 @S9S_MB_2U_LIB.S9S_MB_2U(SCH_1):PAGE97
    15    GND @S9S_MB_2U_LIB.S9S_MB_2U(SCH_1):GND    I64 @S9S_MB_2U_LIB.S9S_MB_2U(SCH_1):PAGE97
    17    GND @S9S_MB_2U_LIB.S9S_MB_2U(SCH_1):GND    I64 @S9S_MB_2U_LIB.S9S_MB_2U(SCH_1):PAGE97
    19    GND @S9S_MB_2U_LIB.S9S_MB_2U(SCH_1):GND    I64 @S9S_MB_2U_LIB.S9S_MB_2U(SCH_1):PAGE97
    21    GND @S9S_MB_2U_LIB.S9S_MB_2U(SCH_1):GND    I64 @S9S_MB_2U_LIB.S9S_MB_2U(SCH_1):PAGE97
    24    GND @S9S_MB_2U_LIB.S9S_MB_2U(SCH_1):GND    I64 @S9S_MB_2U_LIB.S9S_MB_2U(SCH_1):PAGE97
    26    GND @S9S_MB_2U_LIB.S9S_MB_2U(SCH_1):GND    I64 @S9S_MB_2U_LIB.S9S_MB_2U(SCH_1):PAGE97
    28    GND @S9S_MB_2U_LIB.S9S_MB_2U(SCH_1):GND    I64 @S9S_MB_2U_LIB.S9S_MB_2U(SCH_1):PAGE97
    30    GND @S9S_MB_2U_LIB.S9S_MB_2U(SCH_1):GND    I64 @S9S_MB_2U_LIB.S9S_MB_2U(SCH_1):PAGE97
    32    GND @S9S_MB_2U_LIB.S9S_MB_2U(SCH_1):GND    I64 @S9S_MB_2U_LIB.S9S_MB_2U(SCH_1):PAGE97
    35    GND @S9S_MB_2U_LIB.S9S_MB_2U(SCH_1):GND    I64 @S9S_MB_2U_LIB.S9S_MB_2U(SCH_1):PAGE97
    37    GND @S9S_MB_2U_LIB.S9S_MB_2U(SCH_1):GND    I64 @S9S_MB_2U_LIB.S9S_MB_2U(SCH_1):PAGE97
    39    GND @S9S_MB_2U_LIB.S9S_MB_2U(SCH_1):GND    I64 @S9S_MB_2U_LIB.S9S_MB_2U(SCH_1):PAGE97
    41    GND @S9S_MB_2U_LIB.S9S_MB_2U(SCH_1):GND    I64 @S9S_MB_2U_LIB.S9S_MB_2U(SCH_1):PAGE97
    43    GND @S9S_MB_2U_LIB.S9S_MB_2U(SCH_1):GND    I64 @S9S_MB_2U_LIB.S9S_MB_2U(SCH_1):PAGE97
    46    GND @S9S_MB_2U_LIB.S9S_MB_2U(SCH_1):GND    I64 @S9S_MB_2U_LIB.S9S_MB_2U(SCH_1):PAGE97
    48    GND @S9S_MB_2U_LIB.S9S_MB_2U(SCH_1):GND    I64 @S9S_MB_2U_LIB.S9S_MB_2U(SCH_1):PAGE97
    50    GND @S9S_MB_2U_LIB.S9S_MB_2U(SCH_1):GND    I64 @S9S_MB_2U_LIB.S9S_MB_2U(SCH_1):PAGE97
    52    GND @S9S_MB_2U_LIB.S9S_MB_2U(SCH_1):GND    I64 @S9S_MB_2U_LIB.S9S_MB_2U(SCH_1):PAGE97
    54    GND @S9S_MB_2U_LIB.S9S_MB_2U(SCH_1):GND    I64 @S9S_MB_2U_LIB.S9S_MB_2U(SCH_1):PAGE97
    57    GND @S9S_MB_2U_LIB.S9S_MB_2U(SCH_1):GND    I64 @S9S_MB_2U_LIB.S9S_MB_2U(SCH_1):PAGE97
    59    GND @S9S_MB_2U_LIB.S9S_MB_2U(SCH_1):GND    I64 @S9S_MB_2U_LIB.S9S_MB_2U(SCH_1):PAGE97
    61    GND @S9S_MB_2U_LIB.S9S_MB_2U(SCH_1):GND    I64 @S9S_MB_2U_LIB.S9S_MB_2U(SCH_1):PAGE97
    63    GND @S9S_MB_2U_LIB.S9S_MB_2U(SCH_1):GND    I64 @S9S_MB_2U_LIB.S9S_MB_2U(SCH_1):PAGE97
    65    GND @S9S_MB_2U_LIB.S9S_MB_2U(SCH_1):GND    I64 @S9S_MB_2U_LIB.S9S_MB_2U(SCH_1):PAGE97
    67    GND @S9S_MB_2U_LIB.S9S_MB_2U(SCH_1):GND    I64 @S9S_MB_2U_LIB.S9S_MB_2U(SCH_1):PAGE97
    69    GND @S9S_MB_2U_LIB.S9S_MB_2U(SCH_1):GND    I64 @S9S_MB_2U_LIB.S9S_MB_2U(SCH_1):PAGE97
    71    GND @S9S_MB_2U_LIB.S9S_MB_2U(SCH_1):GND    I64 @S9S_MB_2U_LIB.S9S_MB_2U(SCH_1):PAGE97
    73    GND @S9S_MB_2U_LIB.S9S_MB_2U(SCH_1):GND    I64 @S9S_MB_2U_LIB.S9S_MB_2U(SCH_1):PAGE97
    75    GND @S9S_MB_2U_LIB.S9S_MB_2U(SCH_1):GND    I64 @S9S_MB_2U_LIB.S9S_MB_2U(SCH_1):PAGE97
    77    GND @S9S_MB_2U_LIB.S9S_MB_2U(SCH_1):GND    I64 @S9S_MB_2U_LIB.S9S_MB_2U(SCH_1):PAGE97
    79    GND @S9S_MB_2U_LIB.S9S_MB_2U(SCH_1):GND    I64 @S9S_MB_2U_LIB.S9S_MB_2U(SCH_1):PAGE97
    81    GND @S9S_MB_2U_LIB.S9S_MB_2U(SCH_1):GND    I64 @S9S_MB_2U_LIB.S9S_MB_2U(SCH_1):PAGE97
    83    GND @S9S_MB_2U_LIB.S9S_MB_2U(SCH_1):GND    I64 @S9S_MB_2U_LIB.S9S_MB_2U(SCH_1):PAGE97
    85    GND @S9S_MB_2U_LIB.S9S_MB_2U(SCH_1):GND    I64 @S9S_MB_2U_LIB.S9S_MB_2U(SCH_1):PAGE97
    88    GND @S9S_MB_2U_LIB.S9S_MB_2U(SCH_1):GND    I64 @S9S_MB_2U_LIB.S9S_MB_2U(SCH_1):PAGE97
    90    GND @S9S_MB_2U_LIB.S9S_MB_2U(SCH_1):GND    I64 @S9S_MB_2U_LIB.S9S_MB_2U(SCH_1):PAGE97
    92    GND @S9S_MB_2U_LIB.S9S_MB_2U(SCH_1):GND    I64 @S9S_MB_2U_LIB.S9S_MB_2U(SCH_1):PAGE97
    95    GND @S9S_MB_2U_LIB.S9S_MB_2U(SCH_1):GND    I64 @S9S_MB_2U_LIB.S9S_MB_2U(SCH_1):PAGE97
    97    GND @S9S_MB_2U_LIB.S9S_MB_2U(SCH_1):GND    I64 @S9S_MB_2U_LIB.S9S_MB_2U(SCH_1):PAGE97
    99    GND @S9S_MB_2U_LIB.S9S_MB_2U(SCH_1):GND    I64 @S9S_MB_2U_LIB.S9S_MB_2U(SCH_1):PAGE97
   101    GND @S9S_MB_2U_LIB.S9S_MB_2U(SCH_1):GND    I64 @S9S_MB_2U_LIB.S9S_MB_2U(SCH_1):PAGE97
   103    GND @S9S_MB_2U_LIB.S9S_MB_2U(SCH_1):GND    I64 @S9S_MB_2U_LIB.S9S_MB_2U(SCH_1):PAGE97
   106    GND @S9S_MB_2U_LIB.S9S_MB_2U(SCH_1):GND    I64 @S9S_MB_2U_LIB.S9S_MB_2U(SCH_1):PAGE97
   108    GND @S9S_MB_2U_LIB.S9S_MB_2U(SCH_1):GND    I64 @S9S_MB_2U_LIB.S9S_MB_2U(SCH_1):PAGE97
   110    GND @S9S_MB_2U_LIB.S9S_MB_2U(SCH_1):GND    I64 @S9S_MB_2U_LIB.S9S_MB_2U(SCH_1):PAGE97
   112    GND @S9S_MB_2U_LIB.S9S_MB_2U(SCH_1):GND    I64 @S9S_MB_2U_LIB.S9S_MB_2U(SCH_1):PAGE97
   114    GND @S9S_MB_2U_LIB.S9S_MB_2U(SCH_1):GND    I64 @S9S_MB_2U_LIB.S9S_MB_2U(SCH_1):PAGE97
   117    GND @S9S_MB_2U_LIB.S9S_MB_2U(SCH_1):GND    I64 @S9S_MB_2U_LIB.S9S_MB_2U(SCH_1):PAGE97
   119    GND @S9S_MB_2U_LIB.S9S_MB_2U(SCH_1):GND    I64 @S9S_MB_2U_LIB.S9S_MB_2U(SCH_1):PAGE97
   121    GND @S9S_MB_2U_LIB.S9S_MB_2U(SCH_1):GND    I64 @S9S_MB_2U_LIB.S9S_MB_2U(SCH_1):PAGE97
   123    GND @S9S_MB_2U_LIB.S9S_MB_2U(SCH_1):GND    I64 @S9S_MB_2U_LIB.S9S_MB_2U(SCH_1):PAGE97
   125    GND @S9S_MB_2U_LIB.S9S_MB_2U(SCH_1):GND    I64 @S9S_MB_2U_LIB.S9S_MB_2U(SCH_1):PAGE97
   128    GND @S9S_MB_2U_LIB.S9S_MB_2U(SCH_1):GND    I64 @S9S_MB_2U_LIB.S9S_MB_2U(SCH_1):PAGE97
   130    GND @S9S_MB_2U_LIB.S9S_MB_2U(SCH_1):GND    I64 @S9S_MB_2U_LIB.S9S_MB_2U(SCH_1):PAGE97
   134    GND @S9S_MB_2U_LIB.S9S_MB_2U(SCH_1):GND    I64 @S9S_MB_2U_LIB.S9S_MB_2U(SCH_1):PAGE97
   143    GND @S9S_MB_2U_LIB.S9S_MB_2U(SCH_1):GND    I64 @S9S_MB_2U_LIB.S9S_MB_2U(SCH_1):PAGE97
   151    GND @S9S_MB_2U_LIB.S9S_MB_2U(SCH_1):GND    I64 @S9S_MB_2U_LIB.S9S_MB_2U(SCH_1):PAGE97
   153    GND @S9S_MB_2U_LIB.S9S_MB_2U(SCH_1):GND    I64 @S9S_MB_2U_LIB.S9S_MB_2U(SCH_1):PAGE97
   155    GND @S9S_MB_2U_LIB.S9S_MB_2U(SCH_1):GND    I64 @S9S_MB_2U_LIB.S9S_MB_2U(SCH_1):PAGE97
   158    GND @S9S_MB_2U_LIB.S9S_MB_2U(SCH_1):GND    I64 @S9S_MB_2U_LIB.S9S_MB_2U(SCH_1):PAGE97
   160    GND @S9S_MB_2U_LIB.S9S_MB_2U(SCH_1):GND    I64 @S9S_MB_2U_LIB.S9S_MB_2U(SCH_1):PAGE97
   162    GND @S9S_MB_2U_LIB.S9S_MB_2U(SCH_1):GND    I64 @S9S_MB_2U_LIB.S9S_MB_2U(SCH_1):PAGE97
   164    GND @S9S_MB_2U_LIB.S9S_MB_2U(SCH_1):GND    I64 @S9S_MB_2U_LIB.S9S_MB_2U(SCH_1):PAGE97
   166    GND @S9S_MB_2U_LIB.S9S_MB_2U(SCH_1):GND    I64 @S9S_MB_2U_LIB.S9S_MB_2U(SCH_1):PAGE97
   169    GND @S9S_MB_2U_LIB.S9S_MB_2U(SCH_1):GND    I64 @S9S_MB_2U_LIB.S9S_MB_2U(SCH_1):PAGE97
   171    GND @S9S_MB_2U_LIB.S9S_MB_2U(SCH_1):GND    I64 @S9S_MB_2U_LIB.S9S_MB_2U(SCH_1):PAGE97
   173    GND @S9S_MB_2U_LIB.S9S_MB_2U(SCH_1):GND    I64 @S9S_MB_2U_LIB.S9S_MB_2U(SCH_1):PAGE97
   175    GND @S9S_MB_2U_LIB.S9S_MB_2U(SCH_1):GND    I64 @S9S_MB_2U_LIB.S9S_MB_2U(SCH_1):PAGE97
   177    GND @S9S_MB_2U_LIB.S9S_MB_2U(SCH_1):GND    I64 @S9S_MB_2U_LIB.S9S_MB_2U(SCH_1):PAGE97
   180    GND @S9S_MB_2U_LIB.S9S_MB_2U(SCH_1):GND    I64 @S9S_MB_2U_LIB.S9S_MB_2U(SCH_1):PAGE97
   182    GND @S9S_MB_2U_LIB.S9S_MB_2U(SCH_1):GND    I64 @S9S_MB_2U_LIB.S9S_MB_2U(SCH_1):PAGE97
   184    GND @S9S_MB_2U_LIB.S9S_MB_2U(SCH_1):GND    I64 @S9S_MB_2U_LIB.S9S_MB_2U(SCH_1):PAGE97
   186    GND @S9S_MB_2U_LIB.S9S_MB_2U(SCH_1):GND    I64 @S9S_MB_2U_LIB.S9S_MB_2U(SCH_1):PAGE97
   188    GND @S9S_MB_2U_LIB.S9S_MB_2U(SCH_1):GND    I64 @S9S_MB_2U_LIB.S9S_MB_2U(SCH_1):PAGE97
   191    GND @S9S_MB_2U_LIB.S9S_MB_2U(SCH_1):GND    I64 @S9S_MB_2U_LIB.S9S_MB_2U(SCH_1):PAGE97
   193    GND @S9S_MB_2U_LIB.S9S_MB_2U(SCH_1):GND    I64 @S9S_MB_2U_LIB.S9S_MB_2U(SCH_1):PAGE97
   195    GND @S9S_MB_2U_LIB.S9S_MB_2U(SCH_1):GND    I64 @S9S_MB_2U_LIB.S9S_MB_2U(SCH_1):PAGE97
   197    GND @S9S_MB_2U_LIB.S9S_MB_2U(SCH_1):GND    I64 @S9S_MB_2U_LIB.S9S_MB_2U(SCH_1):PAGE97
   199    GND @S9S_MB_2U_LIB.S9S_MB_2U(SCH_1):GND    I64 @S9S_MB_2U_LIB.S9S_MB_2U(SCH_1):PAGE97
   202    GND @S9S_MB_2U_LIB.S9S_MB_2U(SCH_1):GND    I64 @S9S_MB_2U_LIB.S9S_MB_2U(SCH_1):PAGE97
   204    GND @S9S_MB_2U_LIB.S9S_MB_2U(SCH_1):GND    I64 @S9S_MB_2U_LIB.S9S_MB_2U(SCH_1):PAGE97
   206    GND @S9S_MB_2U_LIB.S9S_MB_2U(SCH_1):GND    I64 @S9S_MB_2U_LIB.S9S_MB_2U(SCH_1):PAGE97
   208    GND @S9S_MB_2U_LIB.S9S_MB_2U(SCH_1):GND    I64 @S9S_MB_2U_LIB.S9S_MB_2U(SCH_1):PAGE97
   210    GND @S9S_MB_2U_LIB.S9S_MB_2U(SCH_1):GND    I64 @S9S_MB_2U_LIB.S9S_MB_2U(SCH_1):PAGE97
   212    GND @S9S_MB_2U_LIB.S9S_MB_2U(SCH_1):GND    I64 @S9S_MB_2U_LIB.S9S_MB_2U(SCH_1):PAGE97
   214    GND @S9S_MB_2U_LIB.S9S_MB_2U(SCH_1):GND    I64 @S9S_MB_2U_LIB.S9S_MB_2U(SCH_1):PAGE97
   216    GND @S9S_MB_2U_LIB.S9S_MB_2U(SCH_1):GND    I64 @S9S_MB_2U_LIB.S9S_MB_2U(SCH_1):PAGE97
   219    GND @S9S_MB_2U_LIB.S9S_MB_2U(SCH_1):GND    I64 @S9S_MB_2U_LIB.S9S_MB_2U(SCH_1):PAGE97
   222    GND @S9S_MB_2U_LIB.S9S_MB_2U(SCH_1):GND    I64 @S9S_MB_2U_LIB.S9S_MB_2U(SCH_1):PAGE97
   224    GND @S9S_MB_2U_LIB.S9S_MB_2U(SCH_1):GND    I64 @S9S_MB_2U_LIB.S9S_MB_2U(SCH_1):PAGE97
   226    GND @S9S_MB_2U_LIB.S9S_MB_2U(SCH_1):GND    I64 @S9S_MB_2U_LIB.S9S_MB_2U(SCH_1):PAGE97
   228    GND @S9S_MB_2U_LIB.S9S_MB_2U(SCH_1):GND    I64 @S9S_MB_2U_LIB.S9S_MB_2U(SCH_1):PAGE97
   233    GND @S9S_MB_2U_LIB.S9S_MB_2U(SCH_1):GND    I64 @S9S_MB_2U_LIB.S9S_MB_2U(SCH_1):PAGE97
   237    GND @S9S_MB_2U_LIB.S9S_MB_2U(SCH_1):GND    I64 @S9S_MB_2U_LIB.S9S_MB_2U(SCH_1):PAGE97
   242    GND @S9S_MB_2U_LIB.S9S_MB_2U(SCH_1):GND    I64 @S9S_MB_2U_LIB.S9S_MB_2U(SCH_1):PAGE97
   244    GND @S9S_MB_2U_LIB.S9S_MB_2U(SCH_1):GND    I64 @S9S_MB_2U_LIB.S9S_MB_2U(SCH_1):PAGE97
   246    GND @S9S_MB_2U_LIB.S9S_MB_2U(SCH_1):GND    I64 @S9S_MB_2U_LIB.S9S_MB_2U(SCH_1):PAGE97
   248    GND @S9S_MB_2U_LIB.S9S_MB_2U(SCH_1):GND    I64 @S9S_MB_2U_LIB.S9S_MB_2U(SCH_1):PAGE97
   251    GND @S9S_MB_2U_LIB.S9S_MB_2U(SCH_1):GND    I64 @S9S_MB_2U_LIB.S9S_MB_2U(SCH_1):PAGE97
   253    GND @S9S_MB_2U_LIB.S9S_MB_2U(SCH_1):GND    I64 @S9S_MB_2U_LIB.S9S_MB_2U(SCH_1):PAGE97
   255    GND @S9S_MB_2U_LIB.S9S_MB_2U(SCH_1):GND    I64 @S9S_MB_2U_LIB.S9S_MB_2U(SCH_1):PAGE97
   257    GND @S9S_MB_2U_LIB.S9S_MB_2U(SCH_1):GND    I64 @S9S_MB_2U_LIB.S9S_MB_2U(SCH_1):PAGE97
   259    GND @S9S_MB_2U_LIB.S9S_MB_2U(SCH_1):GND    I64 @S9S_MB_2U_LIB.S9S_MB_2U(SCH_1):PAGE97
   262    GND @S9S_MB_2U_LIB.S9S_MB_2U(SCH_1):GND    I64 @S9S_MB_2U_LIB.S9S_MB_2U(SCH_1):PAGE97
   264    GND @S9S_MB_2U_LIB.S9S_MB_2U(SCH_1):GND    I64 @S9S_MB_2U_LIB.S9S_MB_2U(SCH_1):PAGE97
   266    GND @S9S_MB_2U_LIB.S9S_MB_2U(SCH_1):GND    I64 @S9S_MB_2U_LIB.S9S_MB_2U(SCH_1):PAGE97
   268    GND @S9S_MB_2U_LIB.S9S_MB_2U(SCH_1):GND    I64 @S9S_MB_2U_LIB.S9S_MB_2U(SCH_1):PAGE97
   270    GND @S9S_MB_2U_LIB.S9S_MB_2U(SCH_1):GND    I64 @S9S_MB_2U_LIB.S9S_MB_2U(SCH_1):PAGE97
   273    GND @S9S_MB_2U_LIB.S9S_MB_2U(SCH_1):GND    I64 @S9S_MB_2U_LIB.S9S_MB_2U(SCH_1):PAGE97
   275    GND @S9S_MB_2U_LIB.S9S_MB_2U(SCH_1):GND    I64 @S9S_MB_2U_LIB.S9S_MB_2U(SCH_1):PAGE97
   277    GND @S9S_MB_2U_LIB.S9S_MB_2U(SCH_1):GND    I64 @S9S_MB_2U_LIB.S9S_MB_2U(SCH_1):PAGE97
   279    GND @S9S_MB_2U_LIB.S9S_MB_2U(SCH_1):GND    I64 @S9S_MB_2U_LIB.S9S_MB_2U(SCH_1):PAGE97
   281    GND @S9S_MB_2U_LIB.S9S_MB_2U(SCH_1):GND    I64 @S9S_MB_2U_LIB.S9S_MB_2U(SCH_1):PAGE97
   284    GND @S9S_MB_2U_LIB.S9S_MB_2U(SCH_1):GND    I64 @S9S_MB_2U_LIB.S9S_MB_2U(SCH_1):PAGE97
   286    GND @S9S_MB_2U_LIB.S9S_MB_2U(SCH_1):GND    I64 @S9S_MB_2U_LIB.S9S_MB_2U(SCH_1):PAGE97
   288    GND @S9S_MB_2U_LIB.S9S_MB_2U(SCH_1):GND    I64 @S9S_MB_2U_LIB.S9S_MB_2U(SCH_1):PAGE97
     1 P12V_S3_AUX_CPU0_NVDIMM @S9S_MB_2U_LIB.S9S_MB_2U(SCH_1):P12V_S3_AUX_CPU0_NVDIMM    I64 @S9S_MB_2U_LIB.S9S_MB_2U(SCH_1):PAGE97
   145 P12V_S3_AUX_CPU0_NVDIMM @S9S_MB_2U_LIB.S9S_MB_2U(SCH_1):P12V_S3_AUX_CPU0_NVDIMM    I64 @S9S_MB_2U_LIB.S9S_MB_2U(SCH_1):PAGE97
   146 P12V_S3_AUX_CPU0_NVDIMM @S9S_MB_2U_LIB.S9S_MB_2U(SCH_1):P12V_S3_AUX_CPU0_NVDIMM    I64 @S9S_MB_2U_LIB.S9S_MB_2U(SCH_1):PAGE97
   230    GND @S9S_MB_2U_LIB.S9S_MB_2U(SCH_1):GND    I64 @S9S_MB_2U_LIB.S9S_MB_2U(SCH_1):PAGE97
   235    GND @S9S_MB_2U_LIB.S9S_MB_2U(SCH_1):GND    I64 @S9S_MB_2U_LIB.S9S_MB_2U(SCH_1):PAGE97
   240    GND @S9S_MB_2U_LIB.S9S_MB_2U(SCH_1):GND    I64 @S9S_MB_2U_LIB.S9S_MB_2U(SCH_1):PAGE97
   132    GND @S9S_MB_2U_LIB.S9S_MB_2U(SCH_1):GND    I64 @S9S_MB_2U_LIB.S9S_MB_2U(SCH_1):PAGE97
   136    GND @S9S_MB_2U_LIB.S9S_MB_2U(SCH_1):GND    I64 @S9S_MB_2U_LIB.S9S_MB_2U(SCH_1):PAGE97
   139    GND @S9S_MB_2U_LIB.S9S_MB_2U(SCH_1):GND    I64 @S9S_MB_2U_LIB.S9S_MB_2U(SCH_1):PAGE97
   141    GND @S9S_MB_2U_LIB.S9S_MB_2U(SCH_1):GND    I64 @S9S_MB_2U_LIB.S9S_MB_2U(SCH_1):PAGE97
    G1    GND @S9S_MB_2U_LIB.S9S_MB_2U(SCH_1):GND    I64 @S9S_MB_2U_LIB.S9S_MB_2U(SCH_1):PAGE97
    G2    GND @S9S_MB_2U_LIB.S9S_MB_2U(SCH_1):GND    I64 @S9S_MB_2U_LIB.S9S_MB_2U(SCH_1):PAGE97
    G3    GND @S9S_MB_2U_LIB.S9S_MB_2U(SCH_1):GND    I64 @S9S_MB_2U_LIB.S9S_MB_2U(SCH_1):PAGE97

 J17 SCONN288_ADR50017P130CC-SCONN2A
     3 P3V3_AUX @S9S_MB_2U_LIB.S9S_MB_2U(SCH_1):P3V3_AUX    I12 @S9S_MB_2U_LIB.S9S_MB_2U(SCH_1):PAGE98
     2 TP_CHA_CPU1_DIMM1_FRU_0 @S9S_MB_2U_LIB.S9S_MB_2U(SCH_1):TP_CHA_CPU1_DIMM1_FRU_0    I12 @S9S_MB_2U_LIB.S9S_MB_2U(SCH_1):PAGE98
   144 TP_CHA_CPU1_DIMM1_FRU_1 @S9S_MB_2U_LIB.S9S_MB_2U(SCH_1):TP_CHA_CPU1_DIMM1_FRU_1    I12 @S9S_MB_2U_LIB.S9S_MB_2U(SCH_1):PAGE98
   149 TP_CHA_CPU1_DIMM1_FRU_2 @S9S_MB_2U_LIB.S9S_MB_2U(SCH_1):TP_CHA_CPU1_DIMM1_FRU_2    I12 @S9S_MB_2U_LIB.S9S_MB_2U(SCH_1):PAGE98
   150 TP_CHA_CPU1_DIMM1_FRU_3 @S9S_MB_2U_LIB.S9S_MB_2U(SCH_1):TP_CHA_CPU1_DIMM1_FRU_3    I12 @S9S_MB_2U_LIB.S9S_MB_2U(SCH_1):PAGE98
   220 TP_CHA_CPU1_DIMM1_FRU_4 @S9S_MB_2U_LIB.S9S_MB_2U(SCH_1):TP_CHA_CPU1_DIMM1_FRU_4    I12 @S9S_MB_2U_LIB.S9S_MB_2U(SCH_1):PAGE98
   231 TP_CHA_CPU1_DIMM1_FRU_5 @S9S_MB_2U_LIB.S9S_MB_2U(SCH_1):TP_CHA_CPU1_DIMM1_FRU_5    I12 @S9S_MB_2U_LIB.S9S_MB_2U(SCH_1):PAGE98
   232 TP_CHA_CPU1_DIMM1_FRU_6 @S9S_MB_2U_LIB.S9S_MB_2U(SCH_1):TP_CHA_CPU1_DIMM1_FRU_6    I12 @S9S_MB_2U_LIB.S9S_MB_2U(SCH_1):PAGE98
   207 RST_M_AB_CPU1_FPGA_N @S9S_MB_2U_LIB.S9S_MB_2U(SCH_1):RST_M_AB_CPU1_FPGA_N    I12 @S9S_MB_2U_LIB.S9S_MB_2U(SCH_1):PAGE98
   147 PWRGD_CHA_CPU1_DIMM1 @S9S_MB_2U_LIB.S9S_MB_2U(SCH_1):PWRGD_CHA_CPU1_DIMM1    I12 @S9S_MB_2U_LIB.S9S_MB_2U(SCH_1):PAGE98
   227 M_A_CPU1_SB_PAR @S9S_MB_2U_LIB.S9S_MB_2U(SCH_1):M_A_CPU1_SB_PAR    I12 @S9S_MB_2U_LIB.S9S_MB_2U(SCH_1):PAGE98
    74 M_A_CPU1_SA_PAR @S9S_MB_2U_LIB.S9S_MB_2U(SCH_1):M_A_CPU1_SA_PAR    I12 @S9S_MB_2U_LIB.S9S_MB_2U(SCH_1):PAGE98
    87 M_A_CPU1_SB_RSP<0> @S9S_MB_2U_LIB.S9S_MB_2U(SCH_1):M_A_CPU1_SB_RSP(0)    I12 @S9S_MB_2U_LIB.S9S_MB_2U(SCH_1):PAGE98
    86 M_A_CPU1_SA_RSP<0> @S9S_MB_2U_LIB.S9S_MB_2U(SCH_1):M_A_CPU1_SA_RSP(0)    I12 @S9S_MB_2U_LIB.S9S_MB_2U(SCH_1):PAGE98
     5 I3C_SPD_DDRABCD_CPU1_LVC1_SDA @S9S_MB_2U_LIB.S9S_MB_2U(SCH_1):I3C_SPD_DDRABCD_CPU1_LVC1_SDA    I12 @S9S_MB_2U_LIB.S9S_MB_2U(SCH_1):PAGE98
     4 I3C_SPD_DDRABCD_CPU1_LVC1_SCL_R @S9S_MB_2U_LIB.S9S_MB_2U(SCH_1):I3C_SPD_DDRABCD_CPU1_LVC1_SCL_R1    I12 @S9S_MB_2U_LIB.S9S_MB_2U(SCH_1):PAGE98
   148 PD_CHA_CPU1_DIMM1_SAA @S9S_MB_2U_LIB.S9S_MB_2U(SCH_1):PD_CHA_CPU1_DIMM1_SAA    I12 @S9S_MB_2U_LIB.S9S_MB_2U(SCH_1):PAGE98
   100 M_A_CPU1_SB_DQ<0> @S9S_MB_2U_LIB.S9S_MB_2U(SCH_1):M_A_CPU1_SB_DQ(0)    I12 @S9S_MB_2U_LIB.S9S_MB_2U(SCH_1):PAGE98
   102 M_A_CPU1_SB_DQ<1> @S9S_MB_2U_LIB.S9S_MB_2U(SCH_1):M_A_CPU1_SB_DQ(1)    I12 @S9S_MB_2U_LIB.S9S_MB_2U(SCH_1):PAGE98
   245 M_A_CPU1_SB_DQ<2> @S9S_MB_2U_LIB.S9S_MB_2U(SCH_1):M_A_CPU1_SB_DQ(2)    I12 @S9S_MB_2U_LIB.S9S_MB_2U(SCH_1):PAGE98
   247 M_A_CPU1_SB_DQ<3> @S9S_MB_2U_LIB.S9S_MB_2U(SCH_1):M_A_CPU1_SB_DQ(3)    I12 @S9S_MB_2U_LIB.S9S_MB_2U(SCH_1):PAGE98
   107 M_A_CPU1_SB_DQ<4> @S9S_MB_2U_LIB.S9S_MB_2U(SCH_1):M_A_CPU1_SB_DQ(4)    I12 @S9S_MB_2U_LIB.S9S_MB_2U(SCH_1):PAGE98
   109 M_A_CPU1_SB_DQ<5> @S9S_MB_2U_LIB.S9S_MB_2U(SCH_1):M_A_CPU1_SB_DQ(5)    I12 @S9S_MB_2U_LIB.S9S_MB_2U(SCH_1):PAGE98
   252 M_A_CPU1_SB_DQ<6> @S9S_MB_2U_LIB.S9S_MB_2U(SCH_1):M_A_CPU1_SB_DQ(6)    I12 @S9S_MB_2U_LIB.S9S_MB_2U(SCH_1):PAGE98
   254 M_A_CPU1_SB_DQ<7> @S9S_MB_2U_LIB.S9S_MB_2U(SCH_1):M_A_CPU1_SB_DQ(7)    I12 @S9S_MB_2U_LIB.S9S_MB_2U(SCH_1):PAGE98
   111 M_A_CPU1_SB_DQ<8> @S9S_MB_2U_LIB.S9S_MB_2U(SCH_1):M_A_CPU1_SB_DQ(8)    I12 @S9S_MB_2U_LIB.S9S_MB_2U(SCH_1):PAGE98
   113 M_A_CPU1_SB_DQ<9> @S9S_MB_2U_LIB.S9S_MB_2U(SCH_1):M_A_CPU1_SB_DQ(9)    I12 @S9S_MB_2U_LIB.S9S_MB_2U(SCH_1):PAGE98
   256 M_A_CPU1_SB_DQ<10> @S9S_MB_2U_LIB.S9S_MB_2U(SCH_1):M_A_CPU1_SB_DQ(10)    I12 @S9S_MB_2U_LIB.S9S_MB_2U(SCH_1):PAGE98
   258 M_A_CPU1_SB_DQ<11> @S9S_MB_2U_LIB.S9S_MB_2U(SCH_1):M_A_CPU1_SB_DQ(11)    I12 @S9S_MB_2U_LIB.S9S_MB_2U(SCH_1):PAGE98
   118 M_A_CPU1_SB_DQ<12> @S9S_MB_2U_LIB.S9S_MB_2U(SCH_1):M_A_CPU1_SB_DQ(12)    I12 @S9S_MB_2U_LIB.S9S_MB_2U(SCH_1):PAGE98
   120 M_A_CPU1_SB_DQ<13> @S9S_MB_2U_LIB.S9S_MB_2U(SCH_1):M_A_CPU1_SB_DQ(13)    I12 @S9S_MB_2U_LIB.S9S_MB_2U(SCH_1):PAGE98
   263 M_A_CPU1_SB_DQ<14> @S9S_MB_2U_LIB.S9S_MB_2U(SCH_1):M_A_CPU1_SB_DQ(14)    I12 @S9S_MB_2U_LIB.S9S_MB_2U(SCH_1):PAGE98
   265 M_A_CPU1_SB_DQ<15> @S9S_MB_2U_LIB.S9S_MB_2U(SCH_1):M_A_CPU1_SB_DQ(15)    I12 @S9S_MB_2U_LIB.S9S_MB_2U(SCH_1):PAGE98
   122 M_A_CPU1_SB_DQ<16> @S9S_MB_2U_LIB.S9S_MB_2U(SCH_1):M_A_CPU1_SB_DQ(16)    I12 @S9S_MB_2U_LIB.S9S_MB_2U(SCH_1):PAGE98
   124 M_A_CPU1_SB_DQ<17> @S9S_MB_2U_LIB.S9S_MB_2U(SCH_1):M_A_CPU1_SB_DQ(17)    I12 @S9S_MB_2U_LIB.S9S_MB_2U(SCH_1):PAGE98
   267 M_A_CPU1_SB_DQ<18> @S9S_MB_2U_LIB.S9S_MB_2U(SCH_1):M_A_CPU1_SB_DQ(18)    I12 @S9S_MB_2U_LIB.S9S_MB_2U(SCH_1):PAGE98
   269 M_A_CPU1_SB_DQ<19> @S9S_MB_2U_LIB.S9S_MB_2U(SCH_1):M_A_CPU1_SB_DQ(19)    I12 @S9S_MB_2U_LIB.S9S_MB_2U(SCH_1):PAGE98
   129 M_A_CPU1_SB_DQ<20> @S9S_MB_2U_LIB.S9S_MB_2U(SCH_1):M_A_CPU1_SB_DQ(20)    I12 @S9S_MB_2U_LIB.S9S_MB_2U(SCH_1):PAGE98
   131 M_A_CPU1_SB_DQ<21> @S9S_MB_2U_LIB.S9S_MB_2U(SCH_1):M_A_CPU1_SB_DQ(21)    I12 @S9S_MB_2U_LIB.S9S_MB_2U(SCH_1):PAGE98
   274 M_A_CPU1_SB_DQ<22> @S9S_MB_2U_LIB.S9S_MB_2U(SCH_1):M_A_CPU1_SB_DQ(22)    I12 @S9S_MB_2U_LIB.S9S_MB_2U(SCH_1):PAGE98
   276 M_A_CPU1_SB_DQ<23> @S9S_MB_2U_LIB.S9S_MB_2U(SCH_1):M_A_CPU1_SB_DQ(23)    I12 @S9S_MB_2U_LIB.S9S_MB_2U(SCH_1):PAGE98
   133 M_A_CPU1_SB_DQ<24> @S9S_MB_2U_LIB.S9S_MB_2U(SCH_1):M_A_CPU1_SB_DQ(24)    I12 @S9S_MB_2U_LIB.S9S_MB_2U(SCH_1):PAGE98
   135 M_A_CPU1_SB_DQ<25> @S9S_MB_2U_LIB.S9S_MB_2U(SCH_1):M_A_CPU1_SB_DQ(25)    I12 @S9S_MB_2U_LIB.S9S_MB_2U(SCH_1):PAGE98
   278 M_A_CPU1_SB_DQ<26> @S9S_MB_2U_LIB.S9S_MB_2U(SCH_1):M_A_CPU1_SB_DQ(26)    I12 @S9S_MB_2U_LIB.S9S_MB_2U(SCH_1):PAGE98
   280 M_A_CPU1_SB_DQ<27> @S9S_MB_2U_LIB.S9S_MB_2U(SCH_1):M_A_CPU1_SB_DQ(27)    I12 @S9S_MB_2U_LIB.S9S_MB_2U(SCH_1):PAGE98
   140 M_A_CPU1_SB_DQ<28> @S9S_MB_2U_LIB.S9S_MB_2U(SCH_1):M_A_CPU1_SB_DQ(28)    I12 @S9S_MB_2U_LIB.S9S_MB_2U(SCH_1):PAGE98
   142 M_A_CPU1_SB_DQ<29> @S9S_MB_2U_LIB.S9S_MB_2U(SCH_1):M_A_CPU1_SB_DQ(29)    I12 @S9S_MB_2U_LIB.S9S_MB_2U(SCH_1):PAGE98
   285 M_A_CPU1_SB_DQ<30> @S9S_MB_2U_LIB.S9S_MB_2U(SCH_1):M_A_CPU1_SB_DQ(30)    I12 @S9S_MB_2U_LIB.S9S_MB_2U(SCH_1):PAGE98
   287 M_A_CPU1_SB_DQ<31> @S9S_MB_2U_LIB.S9S_MB_2U(SCH_1):M_A_CPU1_SB_DQ(31)    I12 @S9S_MB_2U_LIB.S9S_MB_2U(SCH_1):PAGE98
     7 M_A_CPU1_SA_DQ<0> @S9S_MB_2U_LIB.S9S_MB_2U(SCH_1):M_A_CPU1_SA_DQ(0)    I12 @S9S_MB_2U_LIB.S9S_MB_2U(SCH_1):PAGE98
     9 M_A_CPU1_SA_DQ<1> @S9S_MB_2U_LIB.S9S_MB_2U(SCH_1):M_A_CPU1_SA_DQ(1)    I12 @S9S_MB_2U_LIB.S9S_MB_2U(SCH_1):PAGE98
   152 M_A_CPU1_SA_DQ<2> @S9S_MB_2U_LIB.S9S_MB_2U(SCH_1):M_A_CPU1_SA_DQ(2)    I12 @S9S_MB_2U_LIB.S9S_MB_2U(SCH_1):PAGE98
   154 M_A_CPU1_SA_DQ<3> @S9S_MB_2U_LIB.S9S_MB_2U(SCH_1):M_A_CPU1_SA_DQ(3)    I12 @S9S_MB_2U_LIB.S9S_MB_2U(SCH_1):PAGE98
    14 M_A_CPU1_SA_DQ<4> @S9S_MB_2U_LIB.S9S_MB_2U(SCH_1):M_A_CPU1_SA_DQ(4)    I12 @S9S_MB_2U_LIB.S9S_MB_2U(SCH_1):PAGE98
    16 M_A_CPU1_SA_DQ<5> @S9S_MB_2U_LIB.S9S_MB_2U(SCH_1):M_A_CPU1_SA_DQ(5)    I12 @S9S_MB_2U_LIB.S9S_MB_2U(SCH_1):PAGE98
   159 M_A_CPU1_SA_DQ<6> @S9S_MB_2U_LIB.S9S_MB_2U(SCH_1):M_A_CPU1_SA_DQ(6)    I12 @S9S_MB_2U_LIB.S9S_MB_2U(SCH_1):PAGE98
   161 M_A_CPU1_SA_DQ<7> @S9S_MB_2U_LIB.S9S_MB_2U(SCH_1):M_A_CPU1_SA_DQ(7)    I12 @S9S_MB_2U_LIB.S9S_MB_2U(SCH_1):PAGE98
    18 M_A_CPU1_SA_DQ<8> @S9S_MB_2U_LIB.S9S_MB_2U(SCH_1):M_A_CPU1_SA_DQ(8)    I12 @S9S_MB_2U_LIB.S9S_MB_2U(SCH_1):PAGE98
    20 M_A_CPU1_SA_DQ<9> @S9S_MB_2U_LIB.S9S_MB_2U(SCH_1):M_A_CPU1_SA_DQ(9)    I12 @S9S_MB_2U_LIB.S9S_MB_2U(SCH_1):PAGE98
   163 M_A_CPU1_SA_DQ<10> @S9S_MB_2U_LIB.S9S_MB_2U(SCH_1):M_A_CPU1_SA_DQ(10)    I12 @S9S_MB_2U_LIB.S9S_MB_2U(SCH_1):PAGE98
   165 M_A_CPU1_SA_DQ<11> @S9S_MB_2U_LIB.S9S_MB_2U(SCH_1):M_A_CPU1_SA_DQ(11)    I12 @S9S_MB_2U_LIB.S9S_MB_2U(SCH_1):PAGE98
    25 M_A_CPU1_SA_DQ<12> @S9S_MB_2U_LIB.S9S_MB_2U(SCH_1):M_A_CPU1_SA_DQ(12)    I12 @S9S_MB_2U_LIB.S9S_MB_2U(SCH_1):PAGE98
    27 M_A_CPU1_SA_DQ<13> @S9S_MB_2U_LIB.S9S_MB_2U(SCH_1):M_A_CPU1_SA_DQ(13)    I12 @S9S_MB_2U_LIB.S9S_MB_2U(SCH_1):PAGE98
   170 M_A_CPU1_SA_DQ<14> @S9S_MB_2U_LIB.S9S_MB_2U(SCH_1):M_A_CPU1_SA_DQ(14)    I12 @S9S_MB_2U_LIB.S9S_MB_2U(SCH_1):PAGE98
   172 M_A_CPU1_SA_DQ<15> @S9S_MB_2U_LIB.S9S_MB_2U(SCH_1):M_A_CPU1_SA_DQ(15)    I12 @S9S_MB_2U_LIB.S9S_MB_2U(SCH_1):PAGE98
    29 M_A_CPU1_SA_DQ<16> @S9S_MB_2U_LIB.S9S_MB_2U(SCH_1):M_A_CPU1_SA_DQ(16)    I12 @S9S_MB_2U_LIB.S9S_MB_2U(SCH_1):PAGE98
    31 M_A_CPU1_SA_DQ<17> @S9S_MB_2U_LIB.S9S_MB_2U(SCH_1):M_A_CPU1_SA_DQ(17)    I12 @S9S_MB_2U_LIB.S9S_MB_2U(SCH_1):PAGE98
   174 M_A_CPU1_SA_DQ<18> @S9S_MB_2U_LIB.S9S_MB_2U(SCH_1):M_A_CPU1_SA_DQ(18)    I12 @S9S_MB_2U_LIB.S9S_MB_2U(SCH_1):PAGE98
   176 M_A_CPU1_SA_DQ<19> @S9S_MB_2U_LIB.S9S_MB_2U(SCH_1):M_A_CPU1_SA_DQ(19)    I12 @S9S_MB_2U_LIB.S9S_MB_2U(SCH_1):PAGE98
    36 M_A_CPU1_SA_DQ<20> @S9S_MB_2U_LIB.S9S_MB_2U(SCH_1):M_A_CPU1_SA_DQ(20)    I12 @S9S_MB_2U_LIB.S9S_MB_2U(SCH_1):PAGE98
    38 M_A_CPU1_SA_DQ<21> @S9S_MB_2U_LIB.S9S_MB_2U(SCH_1):M_A_CPU1_SA_DQ(21)    I12 @S9S_MB_2U_LIB.S9S_MB_2U(SCH_1):PAGE98
   181 M_A_CPU1_SA_DQ<22> @S9S_MB_2U_LIB.S9S_MB_2U(SCH_1):M_A_CPU1_SA_DQ(22)    I12 @S9S_MB_2U_LIB.S9S_MB_2U(SCH_1):PAGE98
   183 M_A_CPU1_SA_DQ<23> @S9S_MB_2U_LIB.S9S_MB_2U(SCH_1):M_A_CPU1_SA_DQ(23)    I12 @S9S_MB_2U_LIB.S9S_MB_2U(SCH_1):PAGE98
    40 M_A_CPU1_SA_DQ<24> @S9S_MB_2U_LIB.S9S_MB_2U(SCH_1):M_A_CPU1_SA_DQ(24)    I12 @S9S_MB_2U_LIB.S9S_MB_2U(SCH_1):PAGE98
    42 M_A_CPU1_SA_DQ<25> @S9S_MB_2U_LIB.S9S_MB_2U(SCH_1):M_A_CPU1_SA_DQ(25)    I12 @S9S_MB_2U_LIB.S9S_MB_2U(SCH_1):PAGE98
   185 M_A_CPU1_SA_DQ<26> @S9S_MB_2U_LIB.S9S_MB_2U(SCH_1):M_A_CPU1_SA_DQ(26)    I12 @S9S_MB_2U_LIB.S9S_MB_2U(SCH_1):PAGE98
   187 M_A_CPU1_SA_DQ<27> @S9S_MB_2U_LIB.S9S_MB_2U(SCH_1):M_A_CPU1_SA_DQ(27)    I12 @S9S_MB_2U_LIB.S9S_MB_2U(SCH_1):PAGE98
    47 M_A_CPU1_SA_DQ<28> @S9S_MB_2U_LIB.S9S_MB_2U(SCH_1):M_A_CPU1_SA_DQ(28)    I12 @S9S_MB_2U_LIB.S9S_MB_2U(SCH_1):PAGE98
    49 M_A_CPU1_SA_DQ<29> @S9S_MB_2U_LIB.S9S_MB_2U(SCH_1):M_A_CPU1_SA_DQ(29)    I12 @S9S_MB_2U_LIB.S9S_MB_2U(SCH_1):PAGE98
   192 M_A_CPU1_SA_DQ<30> @S9S_MB_2U_LIB.S9S_MB_2U(SCH_1):M_A_CPU1_SA_DQ(30)    I12 @S9S_MB_2U_LIB.S9S_MB_2U(SCH_1):PAGE98
   229 M_A_CPU1_SB_CS_N<1> @S9S_MB_2U_LIB.S9S_MB_2U(SCH_1):M_A_CPU1_SB_CS_N(1)    I12 @S9S_MB_2U_LIB.S9S_MB_2U(SCH_1):PAGE98
   209 M_A_CPU1_SA_CS_N<1> @S9S_MB_2U_LIB.S9S_MB_2U(SCH_1):M_A_CPU1_SA_CS_N(1)    I12 @S9S_MB_2U_LIB.S9S_MB_2U(SCH_1):PAGE98
    84 M_A_CPU1_SB_CS_N<0> @S9S_MB_2U_LIB.S9S_MB_2U(SCH_1):M_A_CPU1_SB_CS_N(0)    I12 @S9S_MB_2U_LIB.S9S_MB_2U(SCH_1):PAGE98
    64 M_A_CPU1_SA_CS_N<0> @S9S_MB_2U_LIB.S9S_MB_2U(SCH_1):M_A_CPU1_SA_CS_N(0)    I12 @S9S_MB_2U_LIB.S9S_MB_2U(SCH_1):PAGE98
   217 M_A_CPU1_CLK_DP<0> @S9S_MB_2U_LIB.S9S_MB_2U(SCH_1):M_A_CPU1_CLK_DP(0)    I12 @S9S_MB_2U_LIB.S9S_MB_2U(SCH_1):PAGE98
   218 M_A_CPU1_CLK_DN<0> @S9S_MB_2U_LIB.S9S_MB_2U(SCH_1):M_A_CPU1_CLK_DN(0)    I12 @S9S_MB_2U_LIB.S9S_MB_2U(SCH_1):PAGE98
    96 M_A_CPU1_SB_CB<0> @S9S_MB_2U_LIB.S9S_MB_2U(SCH_1):M_A_CPU1_SB_CB(0)    I12 @S9S_MB_2U_LIB.S9S_MB_2U(SCH_1):PAGE98
    98 M_A_CPU1_SB_CB<1> @S9S_MB_2U_LIB.S9S_MB_2U(SCH_1):M_A_CPU1_SB_CB(1)    I12 @S9S_MB_2U_LIB.S9S_MB_2U(SCH_1):PAGE98
   241 M_A_CPU1_SB_CB<2> @S9S_MB_2U_LIB.S9S_MB_2U(SCH_1):M_A_CPU1_SB_CB(2)    I12 @S9S_MB_2U_LIB.S9S_MB_2U(SCH_1):PAGE98
   243 M_A_CPU1_SB_CB<3> @S9S_MB_2U_LIB.S9S_MB_2U(SCH_1):M_A_CPU1_SB_CB(3)    I12 @S9S_MB_2U_LIB.S9S_MB_2U(SCH_1):PAGE98
    89 M_A_CPU1_SB_CB<4> @S9S_MB_2U_LIB.S9S_MB_2U(SCH_1):M_A_CPU1_SB_CB(4)    I12 @S9S_MB_2U_LIB.S9S_MB_2U(SCH_1):PAGE98
    91 M_A_CPU1_SB_CB<5> @S9S_MB_2U_LIB.S9S_MB_2U(SCH_1):M_A_CPU1_SB_CB(5)    I12 @S9S_MB_2U_LIB.S9S_MB_2U(SCH_1):PAGE98
   234 M_A_CPU1_SB_CB<6> @S9S_MB_2U_LIB.S9S_MB_2U(SCH_1):M_A_CPU1_SB_CB(6)    I12 @S9S_MB_2U_LIB.S9S_MB_2U(SCH_1):PAGE98
    51 M_A_CPU1_SA_CB<0> @S9S_MB_2U_LIB.S9S_MB_2U(SCH_1):M_A_CPU1_SA_CB(0)    I12 @S9S_MB_2U_LIB.S9S_MB_2U(SCH_1):PAGE98
   196 M_A_CPU1_SA_CB<2> @S9S_MB_2U_LIB.S9S_MB_2U(SCH_1):M_A_CPU1_SA_CB(2)    I12 @S9S_MB_2U_LIB.S9S_MB_2U(SCH_1):PAGE98
   198 M_A_CPU1_SA_CB<3> @S9S_MB_2U_LIB.S9S_MB_2U(SCH_1):M_A_CPU1_SA_CB(3)    I12 @S9S_MB_2U_LIB.S9S_MB_2U(SCH_1):PAGE98
    60 M_A_CPU1_SA_CB<5> @S9S_MB_2U_LIB.S9S_MB_2U(SCH_1):M_A_CPU1_SA_CB(5)    I12 @S9S_MB_2U_LIB.S9S_MB_2U(SCH_1):PAGE98
   203 M_A_CPU1_SA_CB<6> @S9S_MB_2U_LIB.S9S_MB_2U(SCH_1):M_A_CPU1_SA_CB(6)    I12 @S9S_MB_2U_LIB.S9S_MB_2U(SCH_1):PAGE98
    82 M_A_CPU1_SB_CA<6> @S9S_MB_2U_LIB.S9S_MB_2U(SCH_1):M_A_CPU1_SB_CA(6)    I12 @S9S_MB_2U_LIB.S9S_MB_2U(SCH_1):PAGE98
    72 M_A_CPU1_SA_CA<6> @S9S_MB_2U_LIB.S9S_MB_2U(SCH_1):M_A_CPU1_SA_CA(6)    I12 @S9S_MB_2U_LIB.S9S_MB_2U(SCH_1):PAGE98
   225 M_A_CPU1_SB_CA<5> @S9S_MB_2U_LIB.S9S_MB_2U(SCH_1):M_A_CPU1_SB_CA(5)    I12 @S9S_MB_2U_LIB.S9S_MB_2U(SCH_1):PAGE98
   215 M_A_CPU1_SA_CA<5> @S9S_MB_2U_LIB.S9S_MB_2U(SCH_1):M_A_CPU1_SA_CA(5)    I12 @S9S_MB_2U_LIB.S9S_MB_2U(SCH_1):PAGE98
    80 M_A_CPU1_SB_CA<4> @S9S_MB_2U_LIB.S9S_MB_2U(SCH_1):M_A_CPU1_SB_CA(4)    I12 @S9S_MB_2U_LIB.S9S_MB_2U(SCH_1):PAGE98
    70 M_A_CPU1_SA_CA<4> @S9S_MB_2U_LIB.S9S_MB_2U(SCH_1):M_A_CPU1_SA_CA(4)    I12 @S9S_MB_2U_LIB.S9S_MB_2U(SCH_1):PAGE98
   223 M_A_CPU1_SB_CA<3> @S9S_MB_2U_LIB.S9S_MB_2U(SCH_1):M_A_CPU1_SB_CA(3)    I12 @S9S_MB_2U_LIB.S9S_MB_2U(SCH_1):PAGE98
   213 M_A_CPU1_SA_CA<3> @S9S_MB_2U_LIB.S9S_MB_2U(SCH_1):M_A_CPU1_SA_CA(3)    I12 @S9S_MB_2U_LIB.S9S_MB_2U(SCH_1):PAGE98
    78 M_A_CPU1_SB_CA<2> @S9S_MB_2U_LIB.S9S_MB_2U(SCH_1):M_A_CPU1_SB_CA(2)    I12 @S9S_MB_2U_LIB.S9S_MB_2U(SCH_1):PAGE98
    68 M_A_CPU1_SA_CA<2> @S9S_MB_2U_LIB.S9S_MB_2U(SCH_1):M_A_CPU1_SA_CA(2)    I12 @S9S_MB_2U_LIB.S9S_MB_2U(SCH_1):PAGE98
   221 M_A_CPU1_SB_CA<1> @S9S_MB_2U_LIB.S9S_MB_2U(SCH_1):M_A_CPU1_SB_CA(1)    I12 @S9S_MB_2U_LIB.S9S_MB_2U(SCH_1):PAGE98
   211 M_A_CPU1_SA_CA<1> @S9S_MB_2U_LIB.S9S_MB_2U(SCH_1):M_A_CPU1_SA_CA(1)    I12 @S9S_MB_2U_LIB.S9S_MB_2U(SCH_1):PAGE98
    76 M_A_CPU1_SB_CA<0> @S9S_MB_2U_LIB.S9S_MB_2U(SCH_1):M_A_CPU1_SB_CA(0)    I12 @S9S_MB_2U_LIB.S9S_MB_2U(SCH_1):PAGE98
    66 M_A_CPU1_SA_CA<0> @S9S_MB_2U_LIB.S9S_MB_2U(SCH_1):M_A_CPU1_SA_CA(0)    I12 @S9S_MB_2U_LIB.S9S_MB_2U(SCH_1):PAGE98
    62 M_A_CPU1_ALERT_N @S9S_MB_2U_LIB.S9S_MB_2U(SCH_1):M_A_CPU1_ALERT_N    I12 @S9S_MB_2U_LIB.S9S_MB_2U(SCH_1):PAGE98
   236 M_A_CPU1_SB_CB<7> @S9S_MB_2U_LIB.S9S_MB_2U(SCH_1):M_A_CPU1_SB_CB(7)    I12 @S9S_MB_2U_LIB.S9S_MB_2U(SCH_1):PAGE98
    53 M_A_CPU1_SA_CB<1> @S9S_MB_2U_LIB.S9S_MB_2U(SCH_1):M_A_CPU1_SA_CB(1)    I12 @S9S_MB_2U_LIB.S9S_MB_2U(SCH_1):PAGE98
    58 M_A_CPU1_SA_CB<4> @S9S_MB_2U_LIB.S9S_MB_2U(SCH_1):M_A_CPU1_SA_CB(4)    I12 @S9S_MB_2U_LIB.S9S_MB_2U(SCH_1):PAGE98
   205 M_A_CPU1_SA_CB<7> @S9S_MB_2U_LIB.S9S_MB_2U(SCH_1):M_A_CPU1_SA_CB(7)    I12 @S9S_MB_2U_LIB.S9S_MB_2U(SCH_1):PAGE98
   194 M_A_CPU1_SA_DQ<31> @S9S_MB_2U_LIB.S9S_MB_2U(SCH_1):M_A_CPU1_SA_DQ(31)    I12 @S9S_MB_2U_LIB.S9S_MB_2U(SCH_1):PAGE98
    93 M_A_CPU1_SB_DQS_DP<9> @S9S_MB_2U_LIB.S9S_MB_2U(SCH_1):M_A_CPU1_SB_DQS_DP(9)   I178 @S9S_MB_2U_LIB.S9S_MB_2U(SCH_1):PAGE98
    94 M_A_CPU1_SB_DQS_DN<9> @S9S_MB_2U_LIB.S9S_MB_2U(SCH_1):M_A_CPU1_SB_DQS_DN(9)   I178 @S9S_MB_2U_LIB.S9S_MB_2U(SCH_1):PAGE98
   201 M_A_CPU1_SA_DQS_DP<9> @S9S_MB_2U_LIB.S9S_MB_2U(SCH_1):M_A_CPU1_SA_DQS_DP(9)   I178 @S9S_MB_2U_LIB.S9S_MB_2U(SCH_1):PAGE98
   200 M_A_CPU1_SA_DQS_DN<9> @S9S_MB_2U_LIB.S9S_MB_2U(SCH_1):M_A_CPU1_SA_DQS_DN(9)   I178 @S9S_MB_2U_LIB.S9S_MB_2U(SCH_1):PAGE98
   190 M_A_CPU1_SA_DQS_DP<8> @S9S_MB_2U_LIB.S9S_MB_2U(SCH_1):M_A_CPU1_SA_DQS_DP(8)   I178 @S9S_MB_2U_LIB.S9S_MB_2U(SCH_1):PAGE98
   189 M_A_CPU1_SA_DQS_DN<8> @S9S_MB_2U_LIB.S9S_MB_2U(SCH_1):M_A_CPU1_SA_DQS_DN(8)   I178 @S9S_MB_2U_LIB.S9S_MB_2U(SCH_1):PAGE98
   271 M_A_CPU1_SB_DQS_DN<7> @S9S_MB_2U_LIB.S9S_MB_2U(SCH_1):M_A_CPU1_SB_DQS_DN(7)   I178 @S9S_MB_2U_LIB.S9S_MB_2U(SCH_1):PAGE98
   179 M_A_CPU1_SA_DQS_DP<7> @S9S_MB_2U_LIB.S9S_MB_2U(SCH_1):M_A_CPU1_SA_DQS_DP(7)   I178 @S9S_MB_2U_LIB.S9S_MB_2U(SCH_1):PAGE98
   261 M_A_CPU1_SB_DQS_DP<6> @S9S_MB_2U_LIB.S9S_MB_2U(SCH_1):M_A_CPU1_SB_DQS_DP(6)   I178 @S9S_MB_2U_LIB.S9S_MB_2U(SCH_1):PAGE98
   260 M_A_CPU1_SB_DQS_DN<6> @S9S_MB_2U_LIB.S9S_MB_2U(SCH_1):M_A_CPU1_SB_DQS_DN(6)   I178 @S9S_MB_2U_LIB.S9S_MB_2U(SCH_1):PAGE98
   167 M_A_CPU1_SA_DQS_DN<6> @S9S_MB_2U_LIB.S9S_MB_2U(SCH_1):M_A_CPU1_SA_DQS_DN(6)   I178 @S9S_MB_2U_LIB.S9S_MB_2U(SCH_1):PAGE98
   250 M_A_CPU1_SB_DQS_DP<5> @S9S_MB_2U_LIB.S9S_MB_2U(SCH_1):M_A_CPU1_SB_DQS_DP(5)   I178 @S9S_MB_2U_LIB.S9S_MB_2U(SCH_1):PAGE98
   249 M_A_CPU1_SB_DQS_DN<5> @S9S_MB_2U_LIB.S9S_MB_2U(SCH_1):M_A_CPU1_SB_DQS_DN(5)   I178 @S9S_MB_2U_LIB.S9S_MB_2U(SCH_1):PAGE98
   157 M_A_CPU1_SA_DQS_DP<5> @S9S_MB_2U_LIB.S9S_MB_2U(SCH_1):M_A_CPU1_SA_DQS_DP(5)   I178 @S9S_MB_2U_LIB.S9S_MB_2U(SCH_1):PAGE98
   156 M_A_CPU1_SA_DQS_DN<5> @S9S_MB_2U_LIB.S9S_MB_2U(SCH_1):M_A_CPU1_SA_DQS_DN(5)   I178 @S9S_MB_2U_LIB.S9S_MB_2U(SCH_1):PAGE98
   239 M_A_CPU1_SB_DQS_DP<4> @S9S_MB_2U_LIB.S9S_MB_2U(SCH_1):M_A_CPU1_SB_DQS_DP(4)   I178 @S9S_MB_2U_LIB.S9S_MB_2U(SCH_1):PAGE98
   238 M_A_CPU1_SB_DQS_DN<4> @S9S_MB_2U_LIB.S9S_MB_2U(SCH_1):M_A_CPU1_SB_DQS_DN(4)   I178 @S9S_MB_2U_LIB.S9S_MB_2U(SCH_1):PAGE98
    55 M_A_CPU1_SA_DQS_DP<4> @S9S_MB_2U_LIB.S9S_MB_2U(SCH_1):M_A_CPU1_SA_DQS_DP(4)   I178 @S9S_MB_2U_LIB.S9S_MB_2U(SCH_1):PAGE98
    56 M_A_CPU1_SA_DQS_DN<4> @S9S_MB_2U_LIB.S9S_MB_2U(SCH_1):M_A_CPU1_SA_DQS_DN(4)   I178 @S9S_MB_2U_LIB.S9S_MB_2U(SCH_1):PAGE98
   137 M_A_CPU1_SB_DQS_DP<3> @S9S_MB_2U_LIB.S9S_MB_2U(SCH_1):M_A_CPU1_SB_DQS_DP(3)   I178 @S9S_MB_2U_LIB.S9S_MB_2U(SCH_1):PAGE98
   138 M_A_CPU1_SB_DQS_DN<3> @S9S_MB_2U_LIB.S9S_MB_2U(SCH_1):M_A_CPU1_SB_DQS_DN(3)   I178 @S9S_MB_2U_LIB.S9S_MB_2U(SCH_1):PAGE98
    44 M_A_CPU1_SA_DQS_DP<3> @S9S_MB_2U_LIB.S9S_MB_2U(SCH_1):M_A_CPU1_SA_DQS_DP(3)   I178 @S9S_MB_2U_LIB.S9S_MB_2U(SCH_1):PAGE98
    45 M_A_CPU1_SA_DQS_DN<3> @S9S_MB_2U_LIB.S9S_MB_2U(SCH_1):M_A_CPU1_SA_DQS_DN(3)   I178 @S9S_MB_2U_LIB.S9S_MB_2U(SCH_1):PAGE98
   126 M_A_CPU1_SB_DQS_DP<2> @S9S_MB_2U_LIB.S9S_MB_2U(SCH_1):M_A_CPU1_SB_DQS_DP(2)   I178 @S9S_MB_2U_LIB.S9S_MB_2U(SCH_1):PAGE98
   127 M_A_CPU1_SB_DQS_DN<2> @S9S_MB_2U_LIB.S9S_MB_2U(SCH_1):M_A_CPU1_SB_DQS_DN(2)   I178 @S9S_MB_2U_LIB.S9S_MB_2U(SCH_1):PAGE98
    33 M_A_CPU1_SA_DQS_DP<2> @S9S_MB_2U_LIB.S9S_MB_2U(SCH_1):M_A_CPU1_SA_DQS_DP(2)   I178 @S9S_MB_2U_LIB.S9S_MB_2U(SCH_1):PAGE98
    34 M_A_CPU1_SA_DQS_DN<2> @S9S_MB_2U_LIB.S9S_MB_2U(SCH_1):M_A_CPU1_SA_DQS_DN(2)   I178 @S9S_MB_2U_LIB.S9S_MB_2U(SCH_1):PAGE98
   115 M_A_CPU1_SB_DQS_DP<1> @S9S_MB_2U_LIB.S9S_MB_2U(SCH_1):M_A_CPU1_SB_DQS_DP(1)   I178 @S9S_MB_2U_LIB.S9S_MB_2U(SCH_1):PAGE98
   116 M_A_CPU1_SB_DQS_DN<1> @S9S_MB_2U_LIB.S9S_MB_2U(SCH_1):M_A_CPU1_SB_DQS_DN(1)   I178 @S9S_MB_2U_LIB.S9S_MB_2U(SCH_1):PAGE98
    22 M_A_CPU1_SA_DQS_DP<1> @S9S_MB_2U_LIB.S9S_MB_2U(SCH_1):M_A_CPU1_SA_DQS_DP(1)   I178 @S9S_MB_2U_LIB.S9S_MB_2U(SCH_1):PAGE98
    23 M_A_CPU1_SA_DQS_DN<1> @S9S_MB_2U_LIB.S9S_MB_2U(SCH_1):M_A_CPU1_SA_DQS_DN(1)   I178 @S9S_MB_2U_LIB.S9S_MB_2U(SCH_1):PAGE98
   104 M_A_CPU1_SB_DQS_DP<0> @S9S_MB_2U_LIB.S9S_MB_2U(SCH_1):M_A_CPU1_SB_DQS_DP(0)   I178 @S9S_MB_2U_LIB.S9S_MB_2U(SCH_1):PAGE98
   105 M_A_CPU1_SB_DQS_DN<0> @S9S_MB_2U_LIB.S9S_MB_2U(SCH_1):M_A_CPU1_SB_DQS_DN(0)   I178 @S9S_MB_2U_LIB.S9S_MB_2U(SCH_1):PAGE98
    11 M_A_CPU1_SA_DQS_DP<0> @S9S_MB_2U_LIB.S9S_MB_2U(SCH_1):M_A_CPU1_SA_DQS_DP(0)   I178 @S9S_MB_2U_LIB.S9S_MB_2U(SCH_1):PAGE98
    12 M_A_CPU1_SA_DQS_DN<0> @S9S_MB_2U_LIB.S9S_MB_2U(SCH_1):M_A_CPU1_SA_DQS_DN(0)   I178 @S9S_MB_2U_LIB.S9S_MB_2U(SCH_1):PAGE98
   272 M_A_CPU1_SB_DQS_DP<7> @S9S_MB_2U_LIB.S9S_MB_2U(SCH_1):M_A_CPU1_SB_DQS_DP(7)   I178 @S9S_MB_2U_LIB.S9S_MB_2U(SCH_1):PAGE98
   282 M_A_CPU1_SB_DQS_DN<8> @S9S_MB_2U_LIB.S9S_MB_2U(SCH_1):M_A_CPU1_SB_DQS_DN(8)   I178 @S9S_MB_2U_LIB.S9S_MB_2U(SCH_1):PAGE98
   283 M_A_CPU1_SB_DQS_DP<8> @S9S_MB_2U_LIB.S9S_MB_2U(SCH_1):M_A_CPU1_SB_DQS_DP(8)   I178 @S9S_MB_2U_LIB.S9S_MB_2U(SCH_1):PAGE98
   168 M_A_CPU1_SA_DQS_DP<6> @S9S_MB_2U_LIB.S9S_MB_2U(SCH_1):M_A_CPU1_SA_DQS_DP(6)   I178 @S9S_MB_2U_LIB.S9S_MB_2U(SCH_1):PAGE98
   178 M_A_CPU1_SA_DQS_DN<7> @S9S_MB_2U_LIB.S9S_MB_2U(SCH_1):M_A_CPU1_SA_DQS_DN(7)   I178 @S9S_MB_2U_LIB.S9S_MB_2U(SCH_1):PAGE98
     6    GND @S9S_MB_2U_LIB.S9S_MB_2U(SCH_1):GND   I147 @S9S_MB_2U_LIB.S9S_MB_2U(SCH_1):PAGE98
     8    GND @S9S_MB_2U_LIB.S9S_MB_2U(SCH_1):GND   I147 @S9S_MB_2U_LIB.S9S_MB_2U(SCH_1):PAGE98
    10    GND @S9S_MB_2U_LIB.S9S_MB_2U(SCH_1):GND   I147 @S9S_MB_2U_LIB.S9S_MB_2U(SCH_1):PAGE98
    13    GND @S9S_MB_2U_LIB.S9S_MB_2U(SCH_1):GND   I147 @S9S_MB_2U_LIB.S9S_MB_2U(SCH_1):PAGE98
    15    GND @S9S_MB_2U_LIB.S9S_MB_2U(SCH_1):GND   I147 @S9S_MB_2U_LIB.S9S_MB_2U(SCH_1):PAGE98
    17    GND @S9S_MB_2U_LIB.S9S_MB_2U(SCH_1):GND   I147 @S9S_MB_2U_LIB.S9S_MB_2U(SCH_1):PAGE98
    19    GND @S9S_MB_2U_LIB.S9S_MB_2U(SCH_1):GND   I147 @S9S_MB_2U_LIB.S9S_MB_2U(SCH_1):PAGE98
    21    GND @S9S_MB_2U_LIB.S9S_MB_2U(SCH_1):GND   I147 @S9S_MB_2U_LIB.S9S_MB_2U(SCH_1):PAGE98
    24    GND @S9S_MB_2U_LIB.S9S_MB_2U(SCH_1):GND   I147 @S9S_MB_2U_LIB.S9S_MB_2U(SCH_1):PAGE98
    26    GND @S9S_MB_2U_LIB.S9S_MB_2U(SCH_1):GND   I147 @S9S_MB_2U_LIB.S9S_MB_2U(SCH_1):PAGE98
    28    GND @S9S_MB_2U_LIB.S9S_MB_2U(SCH_1):GND   I147 @S9S_MB_2U_LIB.S9S_MB_2U(SCH_1):PAGE98
    30    GND @S9S_MB_2U_LIB.S9S_MB_2U(SCH_1):GND   I147 @S9S_MB_2U_LIB.S9S_MB_2U(SCH_1):PAGE98
    32    GND @S9S_MB_2U_LIB.S9S_MB_2U(SCH_1):GND   I147 @S9S_MB_2U_LIB.S9S_MB_2U(SCH_1):PAGE98
    35    GND @S9S_MB_2U_LIB.S9S_MB_2U(SCH_1):GND   I147 @S9S_MB_2U_LIB.S9S_MB_2U(SCH_1):PAGE98
    37    GND @S9S_MB_2U_LIB.S9S_MB_2U(SCH_1):GND   I147 @S9S_MB_2U_LIB.S9S_MB_2U(SCH_1):PAGE98
    39    GND @S9S_MB_2U_LIB.S9S_MB_2U(SCH_1):GND   I147 @S9S_MB_2U_LIB.S9S_MB_2U(SCH_1):PAGE98
    41    GND @S9S_MB_2U_LIB.S9S_MB_2U(SCH_1):GND   I147 @S9S_MB_2U_LIB.S9S_MB_2U(SCH_1):PAGE98
    43    GND @S9S_MB_2U_LIB.S9S_MB_2U(SCH_1):GND   I147 @S9S_MB_2U_LIB.S9S_MB_2U(SCH_1):PAGE98
    46    GND @S9S_MB_2U_LIB.S9S_MB_2U(SCH_1):GND   I147 @S9S_MB_2U_LIB.S9S_MB_2U(SCH_1):PAGE98
    48    GND @S9S_MB_2U_LIB.S9S_MB_2U(SCH_1):GND   I147 @S9S_MB_2U_LIB.S9S_MB_2U(SCH_1):PAGE98
    50    GND @S9S_MB_2U_LIB.S9S_MB_2U(SCH_1):GND   I147 @S9S_MB_2U_LIB.S9S_MB_2U(SCH_1):PAGE98
    52    GND @S9S_MB_2U_LIB.S9S_MB_2U(SCH_1):GND   I147 @S9S_MB_2U_LIB.S9S_MB_2U(SCH_1):PAGE98
    54    GND @S9S_MB_2U_LIB.S9S_MB_2U(SCH_1):GND   I147 @S9S_MB_2U_LIB.S9S_MB_2U(SCH_1):PAGE98
    57    GND @S9S_MB_2U_LIB.S9S_MB_2U(SCH_1):GND   I147 @S9S_MB_2U_LIB.S9S_MB_2U(SCH_1):PAGE98
    59    GND @S9S_MB_2U_LIB.S9S_MB_2U(SCH_1):GND   I147 @S9S_MB_2U_LIB.S9S_MB_2U(SCH_1):PAGE98
    61    GND @S9S_MB_2U_LIB.S9S_MB_2U(SCH_1):GND   I147 @S9S_MB_2U_LIB.S9S_MB_2U(SCH_1):PAGE98
    63    GND @S9S_MB_2U_LIB.S9S_MB_2U(SCH_1):GND   I147 @S9S_MB_2U_LIB.S9S_MB_2U(SCH_1):PAGE98
    65    GND @S9S_MB_2U_LIB.S9S_MB_2U(SCH_1):GND   I147 @S9S_MB_2U_LIB.S9S_MB_2U(SCH_1):PAGE98
    67    GND @S9S_MB_2U_LIB.S9S_MB_2U(SCH_1):GND   I147 @S9S_MB_2U_LIB.S9S_MB_2U(SCH_1):PAGE98
    69    GND @S9S_MB_2U_LIB.S9S_MB_2U(SCH_1):GND   I147 @S9S_MB_2U_LIB.S9S_MB_2U(SCH_1):PAGE98
    71    GND @S9S_MB_2U_LIB.S9S_MB_2U(SCH_1):GND   I147 @S9S_MB_2U_LIB.S9S_MB_2U(SCH_1):PAGE98
    73    GND @S9S_MB_2U_LIB.S9S_MB_2U(SCH_1):GND   I147 @S9S_MB_2U_LIB.S9S_MB_2U(SCH_1):PAGE98
    75    GND @S9S_MB_2U_LIB.S9S_MB_2U(SCH_1):GND   I147 @S9S_MB_2U_LIB.S9S_MB_2U(SCH_1):PAGE98
    77    GND @S9S_MB_2U_LIB.S9S_MB_2U(SCH_1):GND   I147 @S9S_MB_2U_LIB.S9S_MB_2U(SCH_1):PAGE98
    79    GND @S9S_MB_2U_LIB.S9S_MB_2U(SCH_1):GND   I147 @S9S_MB_2U_LIB.S9S_MB_2U(SCH_1):PAGE98
    81    GND @S9S_MB_2U_LIB.S9S_MB_2U(SCH_1):GND   I147 @S9S_MB_2U_LIB.S9S_MB_2U(SCH_1):PAGE98
    83    GND @S9S_MB_2U_LIB.S9S_MB_2U(SCH_1):GND   I147 @S9S_MB_2U_LIB.S9S_MB_2U(SCH_1):PAGE98
    85    GND @S9S_MB_2U_LIB.S9S_MB_2U(SCH_1):GND   I147 @S9S_MB_2U_LIB.S9S_MB_2U(SCH_1):PAGE98
    88    GND @S9S_MB_2U_LIB.S9S_MB_2U(SCH_1):GND   I147 @S9S_MB_2U_LIB.S9S_MB_2U(SCH_1):PAGE98
    90    GND @S9S_MB_2U_LIB.S9S_MB_2U(SCH_1):GND   I147 @S9S_MB_2U_LIB.S9S_MB_2U(SCH_1):PAGE98
    92    GND @S9S_MB_2U_LIB.S9S_MB_2U(SCH_1):GND   I147 @S9S_MB_2U_LIB.S9S_MB_2U(SCH_1):PAGE98
    95    GND @S9S_MB_2U_LIB.S9S_MB_2U(SCH_1):GND   I147 @S9S_MB_2U_LIB.S9S_MB_2U(SCH_1):PAGE98
    97    GND @S9S_MB_2U_LIB.S9S_MB_2U(SCH_1):GND   I147 @S9S_MB_2U_LIB.S9S_MB_2U(SCH_1):PAGE98
    99    GND @S9S_MB_2U_LIB.S9S_MB_2U(SCH_1):GND   I147 @S9S_MB_2U_LIB.S9S_MB_2U(SCH_1):PAGE98
   101    GND @S9S_MB_2U_LIB.S9S_MB_2U(SCH_1):GND   I147 @S9S_MB_2U_LIB.S9S_MB_2U(SCH_1):PAGE98
   103    GND @S9S_MB_2U_LIB.S9S_MB_2U(SCH_1):GND   I147 @S9S_MB_2U_LIB.S9S_MB_2U(SCH_1):PAGE98
   106    GND @S9S_MB_2U_LIB.S9S_MB_2U(SCH_1):GND   I147 @S9S_MB_2U_LIB.S9S_MB_2U(SCH_1):PAGE98
   108    GND @S9S_MB_2U_LIB.S9S_MB_2U(SCH_1):GND   I147 @S9S_MB_2U_LIB.S9S_MB_2U(SCH_1):PAGE98
   110    GND @S9S_MB_2U_LIB.S9S_MB_2U(SCH_1):GND   I147 @S9S_MB_2U_LIB.S9S_MB_2U(SCH_1):PAGE98
   112    GND @S9S_MB_2U_LIB.S9S_MB_2U(SCH_1):GND   I147 @S9S_MB_2U_LIB.S9S_MB_2U(SCH_1):PAGE98
   114    GND @S9S_MB_2U_LIB.S9S_MB_2U(SCH_1):GND   I147 @S9S_MB_2U_LIB.S9S_MB_2U(SCH_1):PAGE98
   117    GND @S9S_MB_2U_LIB.S9S_MB_2U(SCH_1):GND   I147 @S9S_MB_2U_LIB.S9S_MB_2U(SCH_1):PAGE98
   119    GND @S9S_MB_2U_LIB.S9S_MB_2U(SCH_1):GND   I147 @S9S_MB_2U_LIB.S9S_MB_2U(SCH_1):PAGE98
   121    GND @S9S_MB_2U_LIB.S9S_MB_2U(SCH_1):GND   I147 @S9S_MB_2U_LIB.S9S_MB_2U(SCH_1):PAGE98
   123    GND @S9S_MB_2U_LIB.S9S_MB_2U(SCH_1):GND   I147 @S9S_MB_2U_LIB.S9S_MB_2U(SCH_1):PAGE98
   125    GND @S9S_MB_2U_LIB.S9S_MB_2U(SCH_1):GND   I147 @S9S_MB_2U_LIB.S9S_MB_2U(SCH_1):PAGE98
   128    GND @S9S_MB_2U_LIB.S9S_MB_2U(SCH_1):GND   I147 @S9S_MB_2U_LIB.S9S_MB_2U(SCH_1):PAGE98
   130    GND @S9S_MB_2U_LIB.S9S_MB_2U(SCH_1):GND   I147 @S9S_MB_2U_LIB.S9S_MB_2U(SCH_1):PAGE98
   134    GND @S9S_MB_2U_LIB.S9S_MB_2U(SCH_1):GND   I147 @S9S_MB_2U_LIB.S9S_MB_2U(SCH_1):PAGE98
   143    GND @S9S_MB_2U_LIB.S9S_MB_2U(SCH_1):GND   I147 @S9S_MB_2U_LIB.S9S_MB_2U(SCH_1):PAGE98
   151    GND @S9S_MB_2U_LIB.S9S_MB_2U(SCH_1):GND   I147 @S9S_MB_2U_LIB.S9S_MB_2U(SCH_1):PAGE98
   153    GND @S9S_MB_2U_LIB.S9S_MB_2U(SCH_1):GND   I147 @S9S_MB_2U_LIB.S9S_MB_2U(SCH_1):PAGE98
   155    GND @S9S_MB_2U_LIB.S9S_MB_2U(SCH_1):GND   I147 @S9S_MB_2U_LIB.S9S_MB_2U(SCH_1):PAGE98
   158    GND @S9S_MB_2U_LIB.S9S_MB_2U(SCH_1):GND   I147 @S9S_MB_2U_LIB.S9S_MB_2U(SCH_1):PAGE98
   160    GND @S9S_MB_2U_LIB.S9S_MB_2U(SCH_1):GND   I147 @S9S_MB_2U_LIB.S9S_MB_2U(SCH_1):PAGE98
   162    GND @S9S_MB_2U_LIB.S9S_MB_2U(SCH_1):GND   I147 @S9S_MB_2U_LIB.S9S_MB_2U(SCH_1):PAGE98
   164    GND @S9S_MB_2U_LIB.S9S_MB_2U(SCH_1):GND   I147 @S9S_MB_2U_LIB.S9S_MB_2U(SCH_1):PAGE98
   166    GND @S9S_MB_2U_LIB.S9S_MB_2U(SCH_1):GND   I147 @S9S_MB_2U_LIB.S9S_MB_2U(SCH_1):PAGE98
   169    GND @S9S_MB_2U_LIB.S9S_MB_2U(SCH_1):GND   I147 @S9S_MB_2U_LIB.S9S_MB_2U(SCH_1):PAGE98
   171    GND @S9S_MB_2U_LIB.S9S_MB_2U(SCH_1):GND   I147 @S9S_MB_2U_LIB.S9S_MB_2U(SCH_1):PAGE98
   173    GND @S9S_MB_2U_LIB.S9S_MB_2U(SCH_1):GND   I147 @S9S_MB_2U_LIB.S9S_MB_2U(SCH_1):PAGE98
   175    GND @S9S_MB_2U_LIB.S9S_MB_2U(SCH_1):GND   I147 @S9S_MB_2U_LIB.S9S_MB_2U(SCH_1):PAGE98
   177    GND @S9S_MB_2U_LIB.S9S_MB_2U(SCH_1):GND   I147 @S9S_MB_2U_LIB.S9S_MB_2U(SCH_1):PAGE98
   180    GND @S9S_MB_2U_LIB.S9S_MB_2U(SCH_1):GND   I147 @S9S_MB_2U_LIB.S9S_MB_2U(SCH_1):PAGE98
   182    GND @S9S_MB_2U_LIB.S9S_MB_2U(SCH_1):GND   I147 @S9S_MB_2U_LIB.S9S_MB_2U(SCH_1):PAGE98
   184    GND @S9S_MB_2U_LIB.S9S_MB_2U(SCH_1):GND   I147 @S9S_MB_2U_LIB.S9S_MB_2U(SCH_1):PAGE98
   186    GND @S9S_MB_2U_LIB.S9S_MB_2U(SCH_1):GND   I147 @S9S_MB_2U_LIB.S9S_MB_2U(SCH_1):PAGE98
   188    GND @S9S_MB_2U_LIB.S9S_MB_2U(SCH_1):GND   I147 @S9S_MB_2U_LIB.S9S_MB_2U(SCH_1):PAGE98
   191    GND @S9S_MB_2U_LIB.S9S_MB_2U(SCH_1):GND   I147 @S9S_MB_2U_LIB.S9S_MB_2U(SCH_1):PAGE98
   193    GND @S9S_MB_2U_LIB.S9S_MB_2U(SCH_1):GND   I147 @S9S_MB_2U_LIB.S9S_MB_2U(SCH_1):PAGE98
   195    GND @S9S_MB_2U_LIB.S9S_MB_2U(SCH_1):GND   I147 @S9S_MB_2U_LIB.S9S_MB_2U(SCH_1):PAGE98
   197    GND @S9S_MB_2U_LIB.S9S_MB_2U(SCH_1):GND   I147 @S9S_MB_2U_LIB.S9S_MB_2U(SCH_1):PAGE98
   199    GND @S9S_MB_2U_LIB.S9S_MB_2U(SCH_1):GND   I147 @S9S_MB_2U_LIB.S9S_MB_2U(SCH_1):PAGE98
   202    GND @S9S_MB_2U_LIB.S9S_MB_2U(SCH_1):GND   I147 @S9S_MB_2U_LIB.S9S_MB_2U(SCH_1):PAGE98
   204    GND @S9S_MB_2U_LIB.S9S_MB_2U(SCH_1):GND   I147 @S9S_MB_2U_LIB.S9S_MB_2U(SCH_1):PAGE98
   206    GND @S9S_MB_2U_LIB.S9S_MB_2U(SCH_1):GND   I147 @S9S_MB_2U_LIB.S9S_MB_2U(SCH_1):PAGE98
   208    GND @S9S_MB_2U_LIB.S9S_MB_2U(SCH_1):GND   I147 @S9S_MB_2U_LIB.S9S_MB_2U(SCH_1):PAGE98
   210    GND @S9S_MB_2U_LIB.S9S_MB_2U(SCH_1):GND   I147 @S9S_MB_2U_LIB.S9S_MB_2U(SCH_1):PAGE98
   212    GND @S9S_MB_2U_LIB.S9S_MB_2U(SCH_1):GND   I147 @S9S_MB_2U_LIB.S9S_MB_2U(SCH_1):PAGE98
   214    GND @S9S_MB_2U_LIB.S9S_MB_2U(SCH_1):GND   I147 @S9S_MB_2U_LIB.S9S_MB_2U(SCH_1):PAGE98
   216    GND @S9S_MB_2U_LIB.S9S_MB_2U(SCH_1):GND   I147 @S9S_MB_2U_LIB.S9S_MB_2U(SCH_1):PAGE98
   219    GND @S9S_MB_2U_LIB.S9S_MB_2U(SCH_1):GND   I147 @S9S_MB_2U_LIB.S9S_MB_2U(SCH_1):PAGE98
   222    GND @S9S_MB_2U_LIB.S9S_MB_2U(SCH_1):GND   I147 @S9S_MB_2U_LIB.S9S_MB_2U(SCH_1):PAGE98
   224    GND @S9S_MB_2U_LIB.S9S_MB_2U(SCH_1):GND   I147 @S9S_MB_2U_LIB.S9S_MB_2U(SCH_1):PAGE98
   226    GND @S9S_MB_2U_LIB.S9S_MB_2U(SCH_1):GND   I147 @S9S_MB_2U_LIB.S9S_MB_2U(SCH_1):PAGE98
   228    GND @S9S_MB_2U_LIB.S9S_MB_2U(SCH_1):GND   I147 @S9S_MB_2U_LIB.S9S_MB_2U(SCH_1):PAGE98
   233    GND @S9S_MB_2U_LIB.S9S_MB_2U(SCH_1):GND   I147 @S9S_MB_2U_LIB.S9S_MB_2U(SCH_1):PAGE98
   237    GND @S9S_MB_2U_LIB.S9S_MB_2U(SCH_1):GND   I147 @S9S_MB_2U_LIB.S9S_MB_2U(SCH_1):PAGE98
   242    GND @S9S_MB_2U_LIB.S9S_MB_2U(SCH_1):GND   I147 @S9S_MB_2U_LIB.S9S_MB_2U(SCH_1):PAGE98
   244    GND @S9S_MB_2U_LIB.S9S_MB_2U(SCH_1):GND   I147 @S9S_MB_2U_LIB.S9S_MB_2U(SCH_1):PAGE98
   246    GND @S9S_MB_2U_LIB.S9S_MB_2U(SCH_1):GND   I147 @S9S_MB_2U_LIB.S9S_MB_2U(SCH_1):PAGE98
   248    GND @S9S_MB_2U_LIB.S9S_MB_2U(SCH_1):GND   I147 @S9S_MB_2U_LIB.S9S_MB_2U(SCH_1):PAGE98
   251    GND @S9S_MB_2U_LIB.S9S_MB_2U(SCH_1):GND   I147 @S9S_MB_2U_LIB.S9S_MB_2U(SCH_1):PAGE98
   253    GND @S9S_MB_2U_LIB.S9S_MB_2U(SCH_1):GND   I147 @S9S_MB_2U_LIB.S9S_MB_2U(SCH_1):PAGE98
   255    GND @S9S_MB_2U_LIB.S9S_MB_2U(SCH_1):GND   I147 @S9S_MB_2U_LIB.S9S_MB_2U(SCH_1):PAGE98
   257    GND @S9S_MB_2U_LIB.S9S_MB_2U(SCH_1):GND   I147 @S9S_MB_2U_LIB.S9S_MB_2U(SCH_1):PAGE98
   259    GND @S9S_MB_2U_LIB.S9S_MB_2U(SCH_1):GND   I147 @S9S_MB_2U_LIB.S9S_MB_2U(SCH_1):PAGE98
   262    GND @S9S_MB_2U_LIB.S9S_MB_2U(SCH_1):GND   I147 @S9S_MB_2U_LIB.S9S_MB_2U(SCH_1):PAGE98
   264    GND @S9S_MB_2U_LIB.S9S_MB_2U(SCH_1):GND   I147 @S9S_MB_2U_LIB.S9S_MB_2U(SCH_1):PAGE98
   266    GND @S9S_MB_2U_LIB.S9S_MB_2U(SCH_1):GND   I147 @S9S_MB_2U_LIB.S9S_MB_2U(SCH_1):PAGE98
   268    GND @S9S_MB_2U_LIB.S9S_MB_2U(SCH_1):GND   I147 @S9S_MB_2U_LIB.S9S_MB_2U(SCH_1):PAGE98
   270    GND @S9S_MB_2U_LIB.S9S_MB_2U(SCH_1):GND   I147 @S9S_MB_2U_LIB.S9S_MB_2U(SCH_1):PAGE98
   273    GND @S9S_MB_2U_LIB.S9S_MB_2U(SCH_1):GND   I147 @S9S_MB_2U_LIB.S9S_MB_2U(SCH_1):PAGE98
   275    GND @S9S_MB_2U_LIB.S9S_MB_2U(SCH_1):GND   I147 @S9S_MB_2U_LIB.S9S_MB_2U(SCH_1):PAGE98
   277    GND @S9S_MB_2U_LIB.S9S_MB_2U(SCH_1):GND   I147 @S9S_MB_2U_LIB.S9S_MB_2U(SCH_1):PAGE98
   279    GND @S9S_MB_2U_LIB.S9S_MB_2U(SCH_1):GND   I147 @S9S_MB_2U_LIB.S9S_MB_2U(SCH_1):PAGE98
   281    GND @S9S_MB_2U_LIB.S9S_MB_2U(SCH_1):GND   I147 @S9S_MB_2U_LIB.S9S_MB_2U(SCH_1):PAGE98
   284    GND @S9S_MB_2U_LIB.S9S_MB_2U(SCH_1):GND   I147 @S9S_MB_2U_LIB.S9S_MB_2U(SCH_1):PAGE98
   286    GND @S9S_MB_2U_LIB.S9S_MB_2U(SCH_1):GND   I147 @S9S_MB_2U_LIB.S9S_MB_2U(SCH_1):PAGE98
   288    GND @S9S_MB_2U_LIB.S9S_MB_2U(SCH_1):GND   I147 @S9S_MB_2U_LIB.S9S_MB_2U(SCH_1):PAGE98
     1 P12V_S3_AUX_CPU1_NVDIMM @S9S_MB_2U_LIB.S9S_MB_2U(SCH_1):P12V_S3_AUX_CPU1_NVDIMM   I147 @S9S_MB_2U_LIB.S9S_MB_2U(SCH_1):PAGE98
   145 P12V_S3_AUX_CPU1_NVDIMM @S9S_MB_2U_LIB.S9S_MB_2U(SCH_1):P12V_S3_AUX_CPU1_NVDIMM   I147 @S9S_MB_2U_LIB.S9S_MB_2U(SCH_1):PAGE98
   146 P12V_S3_AUX_CPU1_NVDIMM @S9S_MB_2U_LIB.S9S_MB_2U(SCH_1):P12V_S3_AUX_CPU1_NVDIMM   I147 @S9S_MB_2U_LIB.S9S_MB_2U(SCH_1):PAGE98
   230    GND @S9S_MB_2U_LIB.S9S_MB_2U(SCH_1):GND   I147 @S9S_MB_2U_LIB.S9S_MB_2U(SCH_1):PAGE98
   235    GND @S9S_MB_2U_LIB.S9S_MB_2U(SCH_1):GND   I147 @S9S_MB_2U_LIB.S9S_MB_2U(SCH_1):PAGE98
   240    GND @S9S_MB_2U_LIB.S9S_MB_2U(SCH_1):GND   I147 @S9S_MB_2U_LIB.S9S_MB_2U(SCH_1):PAGE98
   132    GND @S9S_MB_2U_LIB.S9S_MB_2U(SCH_1):GND   I147 @S9S_MB_2U_LIB.S9S_MB_2U(SCH_1):PAGE98
   136    GND @S9S_MB_2U_LIB.S9S_MB_2U(SCH_1):GND   I147 @S9S_MB_2U_LIB.S9S_MB_2U(SCH_1):PAGE98
   139    GND @S9S_MB_2U_LIB.S9S_MB_2U(SCH_1):GND   I147 @S9S_MB_2U_LIB.S9S_MB_2U(SCH_1):PAGE98
   141    GND @S9S_MB_2U_LIB.S9S_MB_2U(SCH_1):GND   I147 @S9S_MB_2U_LIB.S9S_MB_2U(SCH_1):PAGE98
    G1    GND @S9S_MB_2U_LIB.S9S_MB_2U(SCH_1):GND   I147 @S9S_MB_2U_LIB.S9S_MB_2U(SCH_1):PAGE98
    G2    GND @S9S_MB_2U_LIB.S9S_MB_2U(SCH_1):GND   I147 @S9S_MB_2U_LIB.S9S_MB_2U(SCH_1):PAGE98
    G3    GND @S9S_MB_2U_LIB.S9S_MB_2U(SCH_1):GND   I147 @S9S_MB_2U_LIB.S9S_MB_2U(SCH_1):PAGE98

 J18 SCONN288_ADR50017P087CC-SCONN2A
     3 P3V3_AUX @S9S_MB_2U_LIB.S9S_MB_2U(SCH_1):P3V3_AUX    I24 @S9S_MB_2U_LIB.S9S_MB_2U(SCH_1):PAGE99
     2 TP_CHA_CPU1_DIMM2_FRU_0 @S9S_MB_2U_LIB.S9S_MB_2U(SCH_1):TP_CHA_CPU1_DIMM2_FRU_0    I24 @S9S_MB_2U_LIB.S9S_MB_2U(SCH_1):PAGE99
   144 TP_CHA_CPU1_DIMM2_FRU_1 @S9S_MB_2U_LIB.S9S_MB_2U(SCH_1):TP_CHA_CPU1_DIMM2_FRU_1    I24 @S9S_MB_2U_LIB.S9S_MB_2U(SCH_1):PAGE99
   149 TP_CHA_CPU1_DIMM2_FRU_2 @S9S_MB_2U_LIB.S9S_MB_2U(SCH_1):TP_CHA_CPU1_DIMM2_FRU_2    I24 @S9S_MB_2U_LIB.S9S_MB_2U(SCH_1):PAGE99
   150 TP_CHA_CPU1_DIMM2_FRU_3 @S9S_MB_2U_LIB.S9S_MB_2U(SCH_1):TP_CHA_CPU1_DIMM2_FRU_3    I24 @S9S_MB_2U_LIB.S9S_MB_2U(SCH_1):PAGE99
   220 TP_CHA_CPU1_DIMM2_FRU_4 @S9S_MB_2U_LIB.S9S_MB_2U(SCH_1):TP_CHA_CPU1_DIMM2_FRU_4    I24 @S9S_MB_2U_LIB.S9S_MB_2U(SCH_1):PAGE99
   231 TP_CHA_CPU1_DIMM2_FRU_5 @S9S_MB_2U_LIB.S9S_MB_2U(SCH_1):TP_CHA_CPU1_DIMM2_FRU_5    I24 @S9S_MB_2U_LIB.S9S_MB_2U(SCH_1):PAGE99
   232 TP_CHA_CPU1_DIMM2_FRU_6 @S9S_MB_2U_LIB.S9S_MB_2U(SCH_1):TP_CHA_CPU1_DIMM2_FRU_6    I24 @S9S_MB_2U_LIB.S9S_MB_2U(SCH_1):PAGE99
   207 RST_M_AB_CPU1_FPGA_N @S9S_MB_2U_LIB.S9S_MB_2U(SCH_1):RST_M_AB_CPU1_FPGA_N    I24 @S9S_MB_2U_LIB.S9S_MB_2U(SCH_1):PAGE99
   147 PWRGD_CHA_CPU1_DIMM2 @S9S_MB_2U_LIB.S9S_MB_2U(SCH_1):PWRGD_CHA_CPU1_DIMM2    I24 @S9S_MB_2U_LIB.S9S_MB_2U(SCH_1):PAGE99
   227 M_A_CPU1_SB_PAR @S9S_MB_2U_LIB.S9S_MB_2U(SCH_1):M_A_CPU1_SB_PAR    I24 @S9S_MB_2U_LIB.S9S_MB_2U(SCH_1):PAGE99
    74 M_A_CPU1_SA_PAR @S9S_MB_2U_LIB.S9S_MB_2U(SCH_1):M_A_CPU1_SA_PAR    I24 @S9S_MB_2U_LIB.S9S_MB_2U(SCH_1):PAGE99
    87 M_A_CPU1_SB_RSP<1> @S9S_MB_2U_LIB.S9S_MB_2U(SCH_1):M_A_CPU1_SB_RSP(1)    I24 @S9S_MB_2U_LIB.S9S_MB_2U(SCH_1):PAGE99
    86 M_A_CPU1_SA_RSP<1> @S9S_MB_2U_LIB.S9S_MB_2U(SCH_1):M_A_CPU1_SA_RSP(1)    I24 @S9S_MB_2U_LIB.S9S_MB_2U(SCH_1):PAGE99
     5 I3C_SPD_DDRABCD_CPU1_LVC1_SDA @S9S_MB_2U_LIB.S9S_MB_2U(SCH_1):I3C_SPD_DDRABCD_CPU1_LVC1_SDA    I24 @S9S_MB_2U_LIB.S9S_MB_2U(SCH_1):PAGE99
     4 I3C_SPD_DDRABCD_CPU1_LVC1_SCL_1 @S9S_MB_2U_LIB.S9S_MB_2U(SCH_1):I3C_SPD_DDRABCD_CPU1_LVC1_SCL_R2    I24 @S9S_MB_2U_LIB.S9S_MB_2U(SCH_1):PAGE99
   148 PD_CHA_CPU1_DIMM2_SAA @S9S_MB_2U_LIB.S9S_MB_2U(SCH_1):PD_CHA_CPU1_DIMM2_SAA    I24 @S9S_MB_2U_LIB.S9S_MB_2U(SCH_1):PAGE99
   100 M_A_CPU1_SB_DQ<0> @S9S_MB_2U_LIB.S9S_MB_2U(SCH_1):M_A_CPU1_SB_DQ(0)    I24 @S9S_MB_2U_LIB.S9S_MB_2U(SCH_1):PAGE99
   102 M_A_CPU1_SB_DQ<1> @S9S_MB_2U_LIB.S9S_MB_2U(SCH_1):M_A_CPU1_SB_DQ(1)    I24 @S9S_MB_2U_LIB.S9S_MB_2U(SCH_1):PAGE99
   245 M_A_CPU1_SB_DQ<2> @S9S_MB_2U_LIB.S9S_MB_2U(SCH_1):M_A_CPU1_SB_DQ(2)    I24 @S9S_MB_2U_LIB.S9S_MB_2U(SCH_1):PAGE99
   247 M_A_CPU1_SB_DQ<3> @S9S_MB_2U_LIB.S9S_MB_2U(SCH_1):M_A_CPU1_SB_DQ(3)    I24 @S9S_MB_2U_LIB.S9S_MB_2U(SCH_1):PAGE99
   107 M_A_CPU1_SB_DQ<4> @S9S_MB_2U_LIB.S9S_MB_2U(SCH_1):M_A_CPU1_SB_DQ(4)    I24 @S9S_MB_2U_LIB.S9S_MB_2U(SCH_1):PAGE99
   109 M_A_CPU1_SB_DQ<5> @S9S_MB_2U_LIB.S9S_MB_2U(SCH_1):M_A_CPU1_SB_DQ(5)    I24 @S9S_MB_2U_LIB.S9S_MB_2U(SCH_1):PAGE99
   252 M_A_CPU1_SB_DQ<6> @S9S_MB_2U_LIB.S9S_MB_2U(SCH_1):M_A_CPU1_SB_DQ(6)    I24 @S9S_MB_2U_LIB.S9S_MB_2U(SCH_1):PAGE99
   254 M_A_CPU1_SB_DQ<7> @S9S_MB_2U_LIB.S9S_MB_2U(SCH_1):M_A_CPU1_SB_DQ(7)    I24 @S9S_MB_2U_LIB.S9S_MB_2U(SCH_1):PAGE99
   111 M_A_CPU1_SB_DQ<8> @S9S_MB_2U_LIB.S9S_MB_2U(SCH_1):M_A_CPU1_SB_DQ(8)    I24 @S9S_MB_2U_LIB.S9S_MB_2U(SCH_1):PAGE99
   113 M_A_CPU1_SB_DQ<9> @S9S_MB_2U_LIB.S9S_MB_2U(SCH_1):M_A_CPU1_SB_DQ(9)    I24 @S9S_MB_2U_LIB.S9S_MB_2U(SCH_1):PAGE99
   256 M_A_CPU1_SB_DQ<10> @S9S_MB_2U_LIB.S9S_MB_2U(SCH_1):M_A_CPU1_SB_DQ(10)    I24 @S9S_MB_2U_LIB.S9S_MB_2U(SCH_1):PAGE99
   258 M_A_CPU1_SB_DQ<11> @S9S_MB_2U_LIB.S9S_MB_2U(SCH_1):M_A_CPU1_SB_DQ(11)    I24 @S9S_MB_2U_LIB.S9S_MB_2U(SCH_1):PAGE99
   118 M_A_CPU1_SB_DQ<12> @S9S_MB_2U_LIB.S9S_MB_2U(SCH_1):M_A_CPU1_SB_DQ(12)    I24 @S9S_MB_2U_LIB.S9S_MB_2U(SCH_1):PAGE99
   120 M_A_CPU1_SB_DQ<13> @S9S_MB_2U_LIB.S9S_MB_2U(SCH_1):M_A_CPU1_SB_DQ(13)    I24 @S9S_MB_2U_LIB.S9S_MB_2U(SCH_1):PAGE99
   263 M_A_CPU1_SB_DQ<14> @S9S_MB_2U_LIB.S9S_MB_2U(SCH_1):M_A_CPU1_SB_DQ(14)    I24 @S9S_MB_2U_LIB.S9S_MB_2U(SCH_1):PAGE99
   265 M_A_CPU1_SB_DQ<15> @S9S_MB_2U_LIB.S9S_MB_2U(SCH_1):M_A_CPU1_SB_DQ(15)    I24 @S9S_MB_2U_LIB.S9S_MB_2U(SCH_1):PAGE99
   122 M_A_CPU1_SB_DQ<16> @S9S_MB_2U_LIB.S9S_MB_2U(SCH_1):M_A_CPU1_SB_DQ(16)    I24 @S9S_MB_2U_LIB.S9S_MB_2U(SCH_1):PAGE99
   124 M_A_CPU1_SB_DQ<17> @S9S_MB_2U_LIB.S9S_MB_2U(SCH_1):M_A_CPU1_SB_DQ(17)    I24 @S9S_MB_2U_LIB.S9S_MB_2U(SCH_1):PAGE99
   267 M_A_CPU1_SB_DQ<18> @S9S_MB_2U_LIB.S9S_MB_2U(SCH_1):M_A_CPU1_SB_DQ(18)    I24 @S9S_MB_2U_LIB.S9S_MB_2U(SCH_1):PAGE99
   269 M_A_CPU1_SB_DQ<19> @S9S_MB_2U_LIB.S9S_MB_2U(SCH_1):M_A_CPU1_SB_DQ(19)    I24 @S9S_MB_2U_LIB.S9S_MB_2U(SCH_1):PAGE99
   129 M_A_CPU1_SB_DQ<20> @S9S_MB_2U_LIB.S9S_MB_2U(SCH_1):M_A_CPU1_SB_DQ(20)    I24 @S9S_MB_2U_LIB.S9S_MB_2U(SCH_1):PAGE99
   131 M_A_CPU1_SB_DQ<21> @S9S_MB_2U_LIB.S9S_MB_2U(SCH_1):M_A_CPU1_SB_DQ(21)    I24 @S9S_MB_2U_LIB.S9S_MB_2U(SCH_1):PAGE99
   274 M_A_CPU1_SB_DQ<22> @S9S_MB_2U_LIB.S9S_MB_2U(SCH_1):M_A_CPU1_SB_DQ(22)    I24 @S9S_MB_2U_LIB.S9S_MB_2U(SCH_1):PAGE99
   276 M_A_CPU1_SB_DQ<23> @S9S_MB_2U_LIB.S9S_MB_2U(SCH_1):M_A_CPU1_SB_DQ(23)    I24 @S9S_MB_2U_LIB.S9S_MB_2U(SCH_1):PAGE99
   133 M_A_CPU1_SB_DQ<24> @S9S_MB_2U_LIB.S9S_MB_2U(SCH_1):M_A_CPU1_SB_DQ(24)    I24 @S9S_MB_2U_LIB.S9S_MB_2U(SCH_1):PAGE99
   135 M_A_CPU1_SB_DQ<25> @S9S_MB_2U_LIB.S9S_MB_2U(SCH_1):M_A_CPU1_SB_DQ(25)    I24 @S9S_MB_2U_LIB.S9S_MB_2U(SCH_1):PAGE99
   278 M_A_CPU1_SB_DQ<26> @S9S_MB_2U_LIB.S9S_MB_2U(SCH_1):M_A_CPU1_SB_DQ(26)    I24 @S9S_MB_2U_LIB.S9S_MB_2U(SCH_1):PAGE99
   280 M_A_CPU1_SB_DQ<27> @S9S_MB_2U_LIB.S9S_MB_2U(SCH_1):M_A_CPU1_SB_DQ(27)    I24 @S9S_MB_2U_LIB.S9S_MB_2U(SCH_1):PAGE99
   140 M_A_CPU1_SB_DQ<28> @S9S_MB_2U_LIB.S9S_MB_2U(SCH_1):M_A_CPU1_SB_DQ(28)    I24 @S9S_MB_2U_LIB.S9S_MB_2U(SCH_1):PAGE99
   142 M_A_CPU1_SB_DQ<29> @S9S_MB_2U_LIB.S9S_MB_2U(SCH_1):M_A_CPU1_SB_DQ(29)    I24 @S9S_MB_2U_LIB.S9S_MB_2U(SCH_1):PAGE99
   285 M_A_CPU1_SB_DQ<30> @S9S_MB_2U_LIB.S9S_MB_2U(SCH_1):M_A_CPU1_SB_DQ(30)    I24 @S9S_MB_2U_LIB.S9S_MB_2U(SCH_1):PAGE99
   287 M_A_CPU1_SB_DQ<31> @S9S_MB_2U_LIB.S9S_MB_2U(SCH_1):M_A_CPU1_SB_DQ(31)    I24 @S9S_MB_2U_LIB.S9S_MB_2U(SCH_1):PAGE99
     7 M_A_CPU1_SA_DQ<0> @S9S_MB_2U_LIB.S9S_MB_2U(SCH_1):M_A_CPU1_SA_DQ(0)    I24 @S9S_MB_2U_LIB.S9S_MB_2U(SCH_1):PAGE99
     9 M_A_CPU1_SA_DQ<1> @S9S_MB_2U_LIB.S9S_MB_2U(SCH_1):M_A_CPU1_SA_DQ(1)    I24 @S9S_MB_2U_LIB.S9S_MB_2U(SCH_1):PAGE99
   152 M_A_CPU1_SA_DQ<2> @S9S_MB_2U_LIB.S9S_MB_2U(SCH_1):M_A_CPU1_SA_DQ(2)    I24 @S9S_MB_2U_LIB.S9S_MB_2U(SCH_1):PAGE99
   154 M_A_CPU1_SA_DQ<3> @S9S_MB_2U_LIB.S9S_MB_2U(SCH_1):M_A_CPU1_SA_DQ(3)    I24 @S9S_MB_2U_LIB.S9S_MB_2U(SCH_1):PAGE99
    14 M_A_CPU1_SA_DQ<4> @S9S_MB_2U_LIB.S9S_MB_2U(SCH_1):M_A_CPU1_SA_DQ(4)    I24 @S9S_MB_2U_LIB.S9S_MB_2U(SCH_1):PAGE99
    16 M_A_CPU1_SA_DQ<5> @S9S_MB_2U_LIB.S9S_MB_2U(SCH_1):M_A_CPU1_SA_DQ(5)    I24 @S9S_MB_2U_LIB.S9S_MB_2U(SCH_1):PAGE99
   159 M_A_CPU1_SA_DQ<6> @S9S_MB_2U_LIB.S9S_MB_2U(SCH_1):M_A_CPU1_SA_DQ(6)    I24 @S9S_MB_2U_LIB.S9S_MB_2U(SCH_1):PAGE99
   161 M_A_CPU1_SA_DQ<7> @S9S_MB_2U_LIB.S9S_MB_2U(SCH_1):M_A_CPU1_SA_DQ(7)    I24 @S9S_MB_2U_LIB.S9S_MB_2U(SCH_1):PAGE99
    18 M_A_CPU1_SA_DQ<8> @S9S_MB_2U_LIB.S9S_MB_2U(SCH_1):M_A_CPU1_SA_DQ(8)    I24 @S9S_MB_2U_LIB.S9S_MB_2U(SCH_1):PAGE99
    20 M_A_CPU1_SA_DQ<9> @S9S_MB_2U_LIB.S9S_MB_2U(SCH_1):M_A_CPU1_SA_DQ(9)    I24 @S9S_MB_2U_LIB.S9S_MB_2U(SCH_1):PAGE99
   163 M_A_CPU1_SA_DQ<10> @S9S_MB_2U_LIB.S9S_MB_2U(SCH_1):M_A_CPU1_SA_DQ(10)    I24 @S9S_MB_2U_LIB.S9S_MB_2U(SCH_1):PAGE99
   165 M_A_CPU1_SA_DQ<11> @S9S_MB_2U_LIB.S9S_MB_2U(SCH_1):M_A_CPU1_SA_DQ(11)    I24 @S9S_MB_2U_LIB.S9S_MB_2U(SCH_1):PAGE99
    25 M_A_CPU1_SA_DQ<12> @S9S_MB_2U_LIB.S9S_MB_2U(SCH_1):M_A_CPU1_SA_DQ(12)    I24 @S9S_MB_2U_LIB.S9S_MB_2U(SCH_1):PAGE99
    27 M_A_CPU1_SA_DQ<13> @S9S_MB_2U_LIB.S9S_MB_2U(SCH_1):M_A_CPU1_SA_DQ(13)    I24 @S9S_MB_2U_LIB.S9S_MB_2U(SCH_1):PAGE99
   170 M_A_CPU1_SA_DQ<14> @S9S_MB_2U_LIB.S9S_MB_2U(SCH_1):M_A_CPU1_SA_DQ(14)    I24 @S9S_MB_2U_LIB.S9S_MB_2U(SCH_1):PAGE99
   172 M_A_CPU1_SA_DQ<15> @S9S_MB_2U_LIB.S9S_MB_2U(SCH_1):M_A_CPU1_SA_DQ(15)    I24 @S9S_MB_2U_LIB.S9S_MB_2U(SCH_1):PAGE99
    29 M_A_CPU1_SA_DQ<16> @S9S_MB_2U_LIB.S9S_MB_2U(SCH_1):M_A_CPU1_SA_DQ(16)    I24 @S9S_MB_2U_LIB.S9S_MB_2U(SCH_1):PAGE99
    31 M_A_CPU1_SA_DQ<17> @S9S_MB_2U_LIB.S9S_MB_2U(SCH_1):M_A_CPU1_SA_DQ(17)    I24 @S9S_MB_2U_LIB.S9S_MB_2U(SCH_1):PAGE99
   174 M_A_CPU1_SA_DQ<18> @S9S_MB_2U_LIB.S9S_MB_2U(SCH_1):M_A_CPU1_SA_DQ(18)    I24 @S9S_MB_2U_LIB.S9S_MB_2U(SCH_1):PAGE99
   176 M_A_CPU1_SA_DQ<19> @S9S_MB_2U_LIB.S9S_MB_2U(SCH_1):M_A_CPU1_SA_DQ(19)    I24 @S9S_MB_2U_LIB.S9S_MB_2U(SCH_1):PAGE99
    36 M_A_CPU1_SA_DQ<20> @S9S_MB_2U_LIB.S9S_MB_2U(SCH_1):M_A_CPU1_SA_DQ(20)    I24 @S9S_MB_2U_LIB.S9S_MB_2U(SCH_1):PAGE99
    38 M_A_CPU1_SA_DQ<21> @S9S_MB_2U_LIB.S9S_MB_2U(SCH_1):M_A_CPU1_SA_DQ(21)    I24 @S9S_MB_2U_LIB.S9S_MB_2U(SCH_1):PAGE99
   181 M_A_CPU1_SA_DQ<22> @S9S_MB_2U_LIB.S9S_MB_2U(SCH_1):M_A_CPU1_SA_DQ(22)    I24 @S9S_MB_2U_LIB.S9S_MB_2U(SCH_1):PAGE99
   183 M_A_CPU1_SA_DQ<23> @S9S_MB_2U_LIB.S9S_MB_2U(SCH_1):M_A_CPU1_SA_DQ(23)    I24 @S9S_MB_2U_LIB.S9S_MB_2U(SCH_1):PAGE99
    40 M_A_CPU1_SA_DQ<24> @S9S_MB_2U_LIB.S9S_MB_2U(SCH_1):M_A_CPU1_SA_DQ(24)    I24 @S9S_MB_2U_LIB.S9S_MB_2U(SCH_1):PAGE99
    42 M_A_CPU1_SA_DQ<25> @S9S_MB_2U_LIB.S9S_MB_2U(SCH_1):M_A_CPU1_SA_DQ(25)    I24 @S9S_MB_2U_LIB.S9S_MB_2U(SCH_1):PAGE99
   185 M_A_CPU1_SA_DQ<26> @S9S_MB_2U_LIB.S9S_MB_2U(SCH_1):M_A_CPU1_SA_DQ(26)    I24 @S9S_MB_2U_LIB.S9S_MB_2U(SCH_1):PAGE99
   187 M_A_CPU1_SA_DQ<27> @S9S_MB_2U_LIB.S9S_MB_2U(SCH_1):M_A_CPU1_SA_DQ(27)    I24 @S9S_MB_2U_LIB.S9S_MB_2U(SCH_1):PAGE99
    47 M_A_CPU1_SA_DQ<28> @S9S_MB_2U_LIB.S9S_MB_2U(SCH_1):M_A_CPU1_SA_DQ(28)    I24 @S9S_MB_2U_LIB.S9S_MB_2U(SCH_1):PAGE99
    49 M_A_CPU1_SA_DQ<29> @S9S_MB_2U_LIB.S9S_MB_2U(SCH_1):M_A_CPU1_SA_DQ(29)    I24 @S9S_MB_2U_LIB.S9S_MB_2U(SCH_1):PAGE99
   192 M_A_CPU1_SA_DQ<30> @S9S_MB_2U_LIB.S9S_MB_2U(SCH_1):M_A_CPU1_SA_DQ(30)    I24 @S9S_MB_2U_LIB.S9S_MB_2U(SCH_1):PAGE99
   229 M_A_CPU1_SB_CS_N<3> @S9S_MB_2U_LIB.S9S_MB_2U(SCH_1):M_A_CPU1_SB_CS_N(3)    I24 @S9S_MB_2U_LIB.S9S_MB_2U(SCH_1):PAGE99
   209 M_A_CPU1_SA_CS_N<3> @S9S_MB_2U_LIB.S9S_MB_2U(SCH_1):M_A_CPU1_SA_CS_N(3)    I24 @S9S_MB_2U_LIB.S9S_MB_2U(SCH_1):PAGE99
    84 M_A_CPU1_SB_CS_N<2> @S9S_MB_2U_LIB.S9S_MB_2U(SCH_1):M_A_CPU1_SB_CS_N(2)    I24 @S9S_MB_2U_LIB.S9S_MB_2U(SCH_1):PAGE99
    64 M_A_CPU1_SA_CS_N<2> @S9S_MB_2U_LIB.S9S_MB_2U(SCH_1):M_A_CPU1_SA_CS_N(2)    I24 @S9S_MB_2U_LIB.S9S_MB_2U(SCH_1):PAGE99
   217 M_A_CPU1_CLK_DP<1> @S9S_MB_2U_LIB.S9S_MB_2U(SCH_1):M_A_CPU1_CLK_DP(1)    I24 @S9S_MB_2U_LIB.S9S_MB_2U(SCH_1):PAGE99
   218 M_A_CPU1_CLK_DN<1> @S9S_MB_2U_LIB.S9S_MB_2U(SCH_1):M_A_CPU1_CLK_DN(1)    I24 @S9S_MB_2U_LIB.S9S_MB_2U(SCH_1):PAGE99
    96 M_A_CPU1_SB_CB<0> @S9S_MB_2U_LIB.S9S_MB_2U(SCH_1):M_A_CPU1_SB_CB(0)    I24 @S9S_MB_2U_LIB.S9S_MB_2U(SCH_1):PAGE99
    98 M_A_CPU1_SB_CB<1> @S9S_MB_2U_LIB.S9S_MB_2U(SCH_1):M_A_CPU1_SB_CB(1)    I24 @S9S_MB_2U_LIB.S9S_MB_2U(SCH_1):PAGE99
   241 M_A_CPU1_SB_CB<2> @S9S_MB_2U_LIB.S9S_MB_2U(SCH_1):M_A_CPU1_SB_CB(2)    I24 @S9S_MB_2U_LIB.S9S_MB_2U(SCH_1):PAGE99
   243 M_A_CPU1_SB_CB<3> @S9S_MB_2U_LIB.S9S_MB_2U(SCH_1):M_A_CPU1_SB_CB(3)    I24 @S9S_MB_2U_LIB.S9S_MB_2U(SCH_1):PAGE99
    89 M_A_CPU1_SB_CB<4> @S9S_MB_2U_LIB.S9S_MB_2U(SCH_1):M_A_CPU1_SB_CB(4)    I24 @S9S_MB_2U_LIB.S9S_MB_2U(SCH_1):PAGE99
    91 M_A_CPU1_SB_CB<5> @S9S_MB_2U_LIB.S9S_MB_2U(SCH_1):M_A_CPU1_SB_CB(5)    I24 @S9S_MB_2U_LIB.S9S_MB_2U(SCH_1):PAGE99
   234 M_A_CPU1_SB_CB<6> @S9S_MB_2U_LIB.S9S_MB_2U(SCH_1):M_A_CPU1_SB_CB(6)    I24 @S9S_MB_2U_LIB.S9S_MB_2U(SCH_1):PAGE99
    51 M_A_CPU1_SA_CB<0> @S9S_MB_2U_LIB.S9S_MB_2U(SCH_1):M_A_CPU1_SA_CB(0)    I24 @S9S_MB_2U_LIB.S9S_MB_2U(SCH_1):PAGE99
   196 M_A_CPU1_SA_CB<2> @S9S_MB_2U_LIB.S9S_MB_2U(SCH_1):M_A_CPU1_SA_CB(2)    I24 @S9S_MB_2U_LIB.S9S_MB_2U(SCH_1):PAGE99
   198 M_A_CPU1_SA_CB<3> @S9S_MB_2U_LIB.S9S_MB_2U(SCH_1):M_A_CPU1_SA_CB(3)    I24 @S9S_MB_2U_LIB.S9S_MB_2U(SCH_1):PAGE99
    60 M_A_CPU1_SA_CB<5> @S9S_MB_2U_LIB.S9S_MB_2U(SCH_1):M_A_CPU1_SA_CB(5)    I24 @S9S_MB_2U_LIB.S9S_MB_2U(SCH_1):PAGE99
   203 M_A_CPU1_SA_CB<6> @S9S_MB_2U_LIB.S9S_MB_2U(SCH_1):M_A_CPU1_SA_CB(6)    I24 @S9S_MB_2U_LIB.S9S_MB_2U(SCH_1):PAGE99
    82 M_A_CPU1_SB_CA<6> @S9S_MB_2U_LIB.S9S_MB_2U(SCH_1):M_A_CPU1_SB_CA(6)    I24 @S9S_MB_2U_LIB.S9S_MB_2U(SCH_1):PAGE99
    72 M_A_CPU1_SA_CA<6> @S9S_MB_2U_LIB.S9S_MB_2U(SCH_1):M_A_CPU1_SA_CA(6)    I24 @S9S_MB_2U_LIB.S9S_MB_2U(SCH_1):PAGE99
   225 M_A_CPU1_SB_CA<5> @S9S_MB_2U_LIB.S9S_MB_2U(SCH_1):M_A_CPU1_SB_CA(5)    I24 @S9S_MB_2U_LIB.S9S_MB_2U(SCH_1):PAGE99
   215 M_A_CPU1_SA_CA<5> @S9S_MB_2U_LIB.S9S_MB_2U(SCH_1):M_A_CPU1_SA_CA(5)    I24 @S9S_MB_2U_LIB.S9S_MB_2U(SCH_1):PAGE99
    80 M_A_CPU1_SB_CA<4> @S9S_MB_2U_LIB.S9S_MB_2U(SCH_1):M_A_CPU1_SB_CA(4)    I24 @S9S_MB_2U_LIB.S9S_MB_2U(SCH_1):PAGE99
    70 M_A_CPU1_SA_CA<4> @S9S_MB_2U_LIB.S9S_MB_2U(SCH_1):M_A_CPU1_SA_CA(4)    I24 @S9S_MB_2U_LIB.S9S_MB_2U(SCH_1):PAGE99
   223 M_A_CPU1_SB_CA<3> @S9S_MB_2U_LIB.S9S_MB_2U(SCH_1):M_A_CPU1_SB_CA(3)    I24 @S9S_MB_2U_LIB.S9S_MB_2U(SCH_1):PAGE99
   213 M_A_CPU1_SA_CA<3> @S9S_MB_2U_LIB.S9S_MB_2U(SCH_1):M_A_CPU1_SA_CA(3)    I24 @S9S_MB_2U_LIB.S9S_MB_2U(SCH_1):PAGE99
    78 M_A_CPU1_SB_CA<2> @S9S_MB_2U_LIB.S9S_MB_2U(SCH_1):M_A_CPU1_SB_CA(2)    I24 @S9S_MB_2U_LIB.S9S_MB_2U(SCH_1):PAGE99
    68 M_A_CPU1_SA_CA<2> @S9S_MB_2U_LIB.S9S_MB_2U(SCH_1):M_A_CPU1_SA_CA(2)    I24 @S9S_MB_2U_LIB.S9S_MB_2U(SCH_1):PAGE99
   221 M_A_CPU1_SB_CA<1> @S9S_MB_2U_LIB.S9S_MB_2U(SCH_1):M_A_CPU1_SB_CA(1)    I24 @S9S_MB_2U_LIB.S9S_MB_2U(SCH_1):PAGE99
   211 M_A_CPU1_SA_CA<1> @S9S_MB_2U_LIB.S9S_MB_2U(SCH_1):M_A_CPU1_SA_CA(1)    I24 @S9S_MB_2U_LIB.S9S_MB_2U(SCH_1):PAGE99
    76 M_A_CPU1_SB_CA<0> @S9S_MB_2U_LIB.S9S_MB_2U(SCH_1):M_A_CPU1_SB_CA(0)    I24 @S9S_MB_2U_LIB.S9S_MB_2U(SCH_1):PAGE99
    66 M_A_CPU1_SA_CA<0> @S9S_MB_2U_LIB.S9S_MB_2U(SCH_1):M_A_CPU1_SA_CA(0)    I24 @S9S_MB_2U_LIB.S9S_MB_2U(SCH_1):PAGE99
    62 M_A_CPU1_ALERT_N @S9S_MB_2U_LIB.S9S_MB_2U(SCH_1):M_A_CPU1_ALERT_N    I24 @S9S_MB_2U_LIB.S9S_MB_2U(SCH_1):PAGE99
   236 M_A_CPU1_SB_CB<7> @S9S_MB_2U_LIB.S9S_MB_2U(SCH_1):M_A_CPU1_SB_CB(7)    I24 @S9S_MB_2U_LIB.S9S_MB_2U(SCH_1):PAGE99
    53 M_A_CPU1_SA_CB<1> @S9S_MB_2U_LIB.S9S_MB_2U(SCH_1):M_A_CPU1_SA_CB(1)    I24 @S9S_MB_2U_LIB.S9S_MB_2U(SCH_1):PAGE99
    58 M_A_CPU1_SA_CB<4> @S9S_MB_2U_LIB.S9S_MB_2U(SCH_1):M_A_CPU1_SA_CB(4)    I24 @S9S_MB_2U_LIB.S9S_MB_2U(SCH_1):PAGE99
   205 M_A_CPU1_SA_CB<7> @S9S_MB_2U_LIB.S9S_MB_2U(SCH_1):M_A_CPU1_SA_CB(7)    I24 @S9S_MB_2U_LIB.S9S_MB_2U(SCH_1):PAGE99
   194 M_A_CPU1_SA_DQ<31> @S9S_MB_2U_LIB.S9S_MB_2U(SCH_1):M_A_CPU1_SA_DQ(31)    I24 @S9S_MB_2U_LIB.S9S_MB_2U(SCH_1):PAGE99
    93 M_A_CPU1_SB_DQS_DP<9> @S9S_MB_2U_LIB.S9S_MB_2U(SCH_1):M_A_CPU1_SB_DQS_DP(9)   I178 @S9S_MB_2U_LIB.S9S_MB_2U(SCH_1):PAGE99
    94 M_A_CPU1_SB_DQS_DN<9> @S9S_MB_2U_LIB.S9S_MB_2U(SCH_1):M_A_CPU1_SB_DQS_DN(9)   I178 @S9S_MB_2U_LIB.S9S_MB_2U(SCH_1):PAGE99
   201 M_A_CPU1_SA_DQS_DP<9> @S9S_MB_2U_LIB.S9S_MB_2U(SCH_1):M_A_CPU1_SA_DQS_DP(9)   I178 @S9S_MB_2U_LIB.S9S_MB_2U(SCH_1):PAGE99
   200 M_A_CPU1_SA_DQS_DN<9> @S9S_MB_2U_LIB.S9S_MB_2U(SCH_1):M_A_CPU1_SA_DQS_DN(9)   I178 @S9S_MB_2U_LIB.S9S_MB_2U(SCH_1):PAGE99
   190 M_A_CPU1_SA_DQS_DP<8> @S9S_MB_2U_LIB.S9S_MB_2U(SCH_1):M_A_CPU1_SA_DQS_DP(8)   I178 @S9S_MB_2U_LIB.S9S_MB_2U(SCH_1):PAGE99
   189 M_A_CPU1_SA_DQS_DN<8> @S9S_MB_2U_LIB.S9S_MB_2U(SCH_1):M_A_CPU1_SA_DQS_DN(8)   I178 @S9S_MB_2U_LIB.S9S_MB_2U(SCH_1):PAGE99
   271 M_A_CPU1_SB_DQS_DN<7> @S9S_MB_2U_LIB.S9S_MB_2U(SCH_1):M_A_CPU1_SB_DQS_DN(7)   I178 @S9S_MB_2U_LIB.S9S_MB_2U(SCH_1):PAGE99
   179 M_A_CPU1_SA_DQS_DP<7> @S9S_MB_2U_LIB.S9S_MB_2U(SCH_1):M_A_CPU1_SA_DQS_DP(7)   I178 @S9S_MB_2U_LIB.S9S_MB_2U(SCH_1):PAGE99
   261 M_A_CPU1_SB_DQS_DP<6> @S9S_MB_2U_LIB.S9S_MB_2U(SCH_1):M_A_CPU1_SB_DQS_DP(6)   I178 @S9S_MB_2U_LIB.S9S_MB_2U(SCH_1):PAGE99
   260 M_A_CPU1_SB_DQS_DN<6> @S9S_MB_2U_LIB.S9S_MB_2U(SCH_1):M_A_CPU1_SB_DQS_DN(6)   I178 @S9S_MB_2U_LIB.S9S_MB_2U(SCH_1):PAGE99
   167 M_A_CPU1_SA_DQS_DN<6> @S9S_MB_2U_LIB.S9S_MB_2U(SCH_1):M_A_CPU1_SA_DQS_DN(6)   I178 @S9S_MB_2U_LIB.S9S_MB_2U(SCH_1):PAGE99
   250 M_A_CPU1_SB_DQS_DP<5> @S9S_MB_2U_LIB.S9S_MB_2U(SCH_1):M_A_CPU1_SB_DQS_DP(5)   I178 @S9S_MB_2U_LIB.S9S_MB_2U(SCH_1):PAGE99
   249 M_A_CPU1_SB_DQS_DN<5> @S9S_MB_2U_LIB.S9S_MB_2U(SCH_1):M_A_CPU1_SB_DQS_DN(5)   I178 @S9S_MB_2U_LIB.S9S_MB_2U(SCH_1):PAGE99
   157 M_A_CPU1_SA_DQS_DP<5> @S9S_MB_2U_LIB.S9S_MB_2U(SCH_1):M_A_CPU1_SA_DQS_DP(5)   I178 @S9S_MB_2U_LIB.S9S_MB_2U(SCH_1):PAGE99
   156 M_A_CPU1_SA_DQS_DN<5> @S9S_MB_2U_LIB.S9S_MB_2U(SCH_1):M_A_CPU1_SA_DQS_DN(5)   I178 @S9S_MB_2U_LIB.S9S_MB_2U(SCH_1):PAGE99
   239 M_A_CPU1_SB_DQS_DP<4> @S9S_MB_2U_LIB.S9S_MB_2U(SCH_1):M_A_CPU1_SB_DQS_DP(4)   I178 @S9S_MB_2U_LIB.S9S_MB_2U(SCH_1):PAGE99
   238 M_A_CPU1_SB_DQS_DN<4> @S9S_MB_2U_LIB.S9S_MB_2U(SCH_1):M_A_CPU1_SB_DQS_DN(4)   I178 @S9S_MB_2U_LIB.S9S_MB_2U(SCH_1):PAGE99
    55 M_A_CPU1_SA_DQS_DP<4> @S9S_MB_2U_LIB.S9S_MB_2U(SCH_1):M_A_CPU1_SA_DQS_DP(4)   I178 @S9S_MB_2U_LIB.S9S_MB_2U(SCH_1):PAGE99
    56 M_A_CPU1_SA_DQS_DN<4> @S9S_MB_2U_LIB.S9S_MB_2U(SCH_1):M_A_CPU1_SA_DQS_DN(4)   I178 @S9S_MB_2U_LIB.S9S_MB_2U(SCH_1):PAGE99
   137 M_A_CPU1_SB_DQS_DP<3> @S9S_MB_2U_LIB.S9S_MB_2U(SCH_1):M_A_CPU1_SB_DQS_DP(3)   I178 @S9S_MB_2U_LIB.S9S_MB_2U(SCH_1):PAGE99
   138 M_A_CPU1_SB_DQS_DN<3> @S9S_MB_2U_LIB.S9S_MB_2U(SCH_1):M_A_CPU1_SB_DQS_DN(3)   I178 @S9S_MB_2U_LIB.S9S_MB_2U(SCH_1):PAGE99
    44 M_A_CPU1_SA_DQS_DP<3> @S9S_MB_2U_LIB.S9S_MB_2U(SCH_1):M_A_CPU1_SA_DQS_DP(3)   I178 @S9S_MB_2U_LIB.S9S_MB_2U(SCH_1):PAGE99
    45 M_A_CPU1_SA_DQS_DN<3> @S9S_MB_2U_LIB.S9S_MB_2U(SCH_1):M_A_CPU1_SA_DQS_DN(3)   I178 @S9S_MB_2U_LIB.S9S_MB_2U(SCH_1):PAGE99
   126 M_A_CPU1_SB_DQS_DP<2> @S9S_MB_2U_LIB.S9S_MB_2U(SCH_1):M_A_CPU1_SB_DQS_DP(2)   I178 @S9S_MB_2U_LIB.S9S_MB_2U(SCH_1):PAGE99
   127 M_A_CPU1_SB_DQS_DN<2> @S9S_MB_2U_LIB.S9S_MB_2U(SCH_1):M_A_CPU1_SB_DQS_DN(2)   I178 @S9S_MB_2U_LIB.S9S_MB_2U(SCH_1):PAGE99
    33 M_A_CPU1_SA_DQS_DP<2> @S9S_MB_2U_LIB.S9S_MB_2U(SCH_1):M_A_CPU1_SA_DQS_DP(2)   I178 @S9S_MB_2U_LIB.S9S_MB_2U(SCH_1):PAGE99
    34 M_A_CPU1_SA_DQS_DN<2> @S9S_MB_2U_LIB.S9S_MB_2U(SCH_1):M_A_CPU1_SA_DQS_DN(2)   I178 @S9S_MB_2U_LIB.S9S_MB_2U(SCH_1):PAGE99
   115 M_A_CPU1_SB_DQS_DP<1> @S9S_MB_2U_LIB.S9S_MB_2U(SCH_1):M_A_CPU1_SB_DQS_DP(1)   I178 @S9S_MB_2U_LIB.S9S_MB_2U(SCH_1):PAGE99
   116 M_A_CPU1_SB_DQS_DN<1> @S9S_MB_2U_LIB.S9S_MB_2U(SCH_1):M_A_CPU1_SB_DQS_DN(1)   I178 @S9S_MB_2U_LIB.S9S_MB_2U(SCH_1):PAGE99
    22 M_A_CPU1_SA_DQS_DP<1> @S9S_MB_2U_LIB.S9S_MB_2U(SCH_1):M_A_CPU1_SA_DQS_DP(1)   I178 @S9S_MB_2U_LIB.S9S_MB_2U(SCH_1):PAGE99
    23 M_A_CPU1_SA_DQS_DN<1> @S9S_MB_2U_LIB.S9S_MB_2U(SCH_1):M_A_CPU1_SA_DQS_DN(1)   I178 @S9S_MB_2U_LIB.S9S_MB_2U(SCH_1):PAGE99
   104 M_A_CPU1_SB_DQS_DP<0> @S9S_MB_2U_LIB.S9S_MB_2U(SCH_1):M_A_CPU1_SB_DQS_DP(0)   I178 @S9S_MB_2U_LIB.S9S_MB_2U(SCH_1):PAGE99
   105 M_A_CPU1_SB_DQS_DN<0> @S9S_MB_2U_LIB.S9S_MB_2U(SCH_1):M_A_CPU1_SB_DQS_DN(0)   I178 @S9S_MB_2U_LIB.S9S_MB_2U(SCH_1):PAGE99
    11 M_A_CPU1_SA_DQS_DP<0> @S9S_MB_2U_LIB.S9S_MB_2U(SCH_1):M_A_CPU1_SA_DQS_DP(0)   I178 @S9S_MB_2U_LIB.S9S_MB_2U(SCH_1):PAGE99
    12 M_A_CPU1_SA_DQS_DN<0> @S9S_MB_2U_LIB.S9S_MB_2U(SCH_1):M_A_CPU1_SA_DQS_DN(0)   I178 @S9S_MB_2U_LIB.S9S_MB_2U(SCH_1):PAGE99
   272 M_A_CPU1_SB_DQS_DP<7> @S9S_MB_2U_LIB.S9S_MB_2U(SCH_1):M_A_CPU1_SB_DQS_DP(7)   I178 @S9S_MB_2U_LIB.S9S_MB_2U(SCH_1):PAGE99
   282 M_A_CPU1_SB_DQS_DN<8> @S9S_MB_2U_LIB.S9S_MB_2U(SCH_1):M_A_CPU1_SB_DQS_DN(8)   I178 @S9S_MB_2U_LIB.S9S_MB_2U(SCH_1):PAGE99
   283 M_A_CPU1_SB_DQS_DP<8> @S9S_MB_2U_LIB.S9S_MB_2U(SCH_1):M_A_CPU1_SB_DQS_DP(8)   I178 @S9S_MB_2U_LIB.S9S_MB_2U(SCH_1):PAGE99
   168 M_A_CPU1_SA_DQS_DP<6> @S9S_MB_2U_LIB.S9S_MB_2U(SCH_1):M_A_CPU1_SA_DQS_DP(6)   I178 @S9S_MB_2U_LIB.S9S_MB_2U(SCH_1):PAGE99
   178 M_A_CPU1_SA_DQS_DN<7> @S9S_MB_2U_LIB.S9S_MB_2U(SCH_1):M_A_CPU1_SA_DQS_DN(7)   I178 @S9S_MB_2U_LIB.S9S_MB_2U(SCH_1):PAGE99
     6    GND @S9S_MB_2U_LIB.S9S_MB_2U(SCH_1):GND   I175 @S9S_MB_2U_LIB.S9S_MB_2U(SCH_1):PAGE99
     8    GND @S9S_MB_2U_LIB.S9S_MB_2U(SCH_1):GND   I175 @S9S_MB_2U_LIB.S9S_MB_2U(SCH_1):PAGE99
    10    GND @S9S_MB_2U_LIB.S9S_MB_2U(SCH_1):GND   I175 @S9S_MB_2U_LIB.S9S_MB_2U(SCH_1):PAGE99
    13    GND @S9S_MB_2U_LIB.S9S_MB_2U(SCH_1):GND   I175 @S9S_MB_2U_LIB.S9S_MB_2U(SCH_1):PAGE99
    15    GND @S9S_MB_2U_LIB.S9S_MB_2U(SCH_1):GND   I175 @S9S_MB_2U_LIB.S9S_MB_2U(SCH_1):PAGE99
    17    GND @S9S_MB_2U_LIB.S9S_MB_2U(SCH_1):GND   I175 @S9S_MB_2U_LIB.S9S_MB_2U(SCH_1):PAGE99
    19    GND @S9S_MB_2U_LIB.S9S_MB_2U(SCH_1):GND   I175 @S9S_MB_2U_LIB.S9S_MB_2U(SCH_1):PAGE99
    21    GND @S9S_MB_2U_LIB.S9S_MB_2U(SCH_1):GND   I175 @S9S_MB_2U_LIB.S9S_MB_2U(SCH_1):PAGE99
    24    GND @S9S_MB_2U_LIB.S9S_MB_2U(SCH_1):GND   I175 @S9S_MB_2U_LIB.S9S_MB_2U(SCH_1):PAGE99
    26    GND @S9S_MB_2U_LIB.S9S_MB_2U(SCH_1):GND   I175 @S9S_MB_2U_LIB.S9S_MB_2U(SCH_1):PAGE99
    28    GND @S9S_MB_2U_LIB.S9S_MB_2U(SCH_1):GND   I175 @S9S_MB_2U_LIB.S9S_MB_2U(SCH_1):PAGE99
    30    GND @S9S_MB_2U_LIB.S9S_MB_2U(SCH_1):GND   I175 @S9S_MB_2U_LIB.S9S_MB_2U(SCH_1):PAGE99
    32    GND @S9S_MB_2U_LIB.S9S_MB_2U(SCH_1):GND   I175 @S9S_MB_2U_LIB.S9S_MB_2U(SCH_1):PAGE99
    35    GND @S9S_MB_2U_LIB.S9S_MB_2U(SCH_1):GND   I175 @S9S_MB_2U_LIB.S9S_MB_2U(SCH_1):PAGE99
    37    GND @S9S_MB_2U_LIB.S9S_MB_2U(SCH_1):GND   I175 @S9S_MB_2U_LIB.S9S_MB_2U(SCH_1):PAGE99
    39    GND @S9S_MB_2U_LIB.S9S_MB_2U(SCH_1):GND   I175 @S9S_MB_2U_LIB.S9S_MB_2U(SCH_1):PAGE99
    41    GND @S9S_MB_2U_LIB.S9S_MB_2U(SCH_1):GND   I175 @S9S_MB_2U_LIB.S9S_MB_2U(SCH_1):PAGE99
    43    GND @S9S_MB_2U_LIB.S9S_MB_2U(SCH_1):GND   I175 @S9S_MB_2U_LIB.S9S_MB_2U(SCH_1):PAGE99
    46    GND @S9S_MB_2U_LIB.S9S_MB_2U(SCH_1):GND   I175 @S9S_MB_2U_LIB.S9S_MB_2U(SCH_1):PAGE99
    48    GND @S9S_MB_2U_LIB.S9S_MB_2U(SCH_1):GND   I175 @S9S_MB_2U_LIB.S9S_MB_2U(SCH_1):PAGE99
    50    GND @S9S_MB_2U_LIB.S9S_MB_2U(SCH_1):GND   I175 @S9S_MB_2U_LIB.S9S_MB_2U(SCH_1):PAGE99
    52    GND @S9S_MB_2U_LIB.S9S_MB_2U(SCH_1):GND   I175 @S9S_MB_2U_LIB.S9S_MB_2U(SCH_1):PAGE99
    54    GND @S9S_MB_2U_LIB.S9S_MB_2U(SCH_1):GND   I175 @S9S_MB_2U_LIB.S9S_MB_2U(SCH_1):PAGE99
    57    GND @S9S_MB_2U_LIB.S9S_MB_2U(SCH_1):GND   I175 @S9S_MB_2U_LIB.S9S_MB_2U(SCH_1):PAGE99
    59    GND @S9S_MB_2U_LIB.S9S_MB_2U(SCH_1):GND   I175 @S9S_MB_2U_LIB.S9S_MB_2U(SCH_1):PAGE99
    61    GND @S9S_MB_2U_LIB.S9S_MB_2U(SCH_1):GND   I175 @S9S_MB_2U_LIB.S9S_MB_2U(SCH_1):PAGE99
    63    GND @S9S_MB_2U_LIB.S9S_MB_2U(SCH_1):GND   I175 @S9S_MB_2U_LIB.S9S_MB_2U(SCH_1):PAGE99
    65    GND @S9S_MB_2U_LIB.S9S_MB_2U(SCH_1):GND   I175 @S9S_MB_2U_LIB.S9S_MB_2U(SCH_1):PAGE99
    67    GND @S9S_MB_2U_LIB.S9S_MB_2U(SCH_1):GND   I175 @S9S_MB_2U_LIB.S9S_MB_2U(SCH_1):PAGE99
    69    GND @S9S_MB_2U_LIB.S9S_MB_2U(SCH_1):GND   I175 @S9S_MB_2U_LIB.S9S_MB_2U(SCH_1):PAGE99
    71    GND @S9S_MB_2U_LIB.S9S_MB_2U(SCH_1):GND   I175 @S9S_MB_2U_LIB.S9S_MB_2U(SCH_1):PAGE99
    73    GND @S9S_MB_2U_LIB.S9S_MB_2U(SCH_1):GND   I175 @S9S_MB_2U_LIB.S9S_MB_2U(SCH_1):PAGE99
    75    GND @S9S_MB_2U_LIB.S9S_MB_2U(SCH_1):GND   I175 @S9S_MB_2U_LIB.S9S_MB_2U(SCH_1):PAGE99
    77    GND @S9S_MB_2U_LIB.S9S_MB_2U(SCH_1):GND   I175 @S9S_MB_2U_LIB.S9S_MB_2U(SCH_1):PAGE99
    79    GND @S9S_MB_2U_LIB.S9S_MB_2U(SCH_1):GND   I175 @S9S_MB_2U_LIB.S9S_MB_2U(SCH_1):PAGE99
    81    GND @S9S_MB_2U_LIB.S9S_MB_2U(SCH_1):GND   I175 @S9S_MB_2U_LIB.S9S_MB_2U(SCH_1):PAGE99
    83    GND @S9S_MB_2U_LIB.S9S_MB_2U(SCH_1):GND   I175 @S9S_MB_2U_LIB.S9S_MB_2U(SCH_1):PAGE99
    85    GND @S9S_MB_2U_LIB.S9S_MB_2U(SCH_1):GND   I175 @S9S_MB_2U_LIB.S9S_MB_2U(SCH_1):PAGE99
    88    GND @S9S_MB_2U_LIB.S9S_MB_2U(SCH_1):GND   I175 @S9S_MB_2U_LIB.S9S_MB_2U(SCH_1):PAGE99
    90    GND @S9S_MB_2U_LIB.S9S_MB_2U(SCH_1):GND   I175 @S9S_MB_2U_LIB.S9S_MB_2U(SCH_1):PAGE99
    92    GND @S9S_MB_2U_LIB.S9S_MB_2U(SCH_1):GND   I175 @S9S_MB_2U_LIB.S9S_MB_2U(SCH_1):PAGE99
    95    GND @S9S_MB_2U_LIB.S9S_MB_2U(SCH_1):GND   I175 @S9S_MB_2U_LIB.S9S_MB_2U(SCH_1):PAGE99
    97    GND @S9S_MB_2U_LIB.S9S_MB_2U(SCH_1):GND   I175 @S9S_MB_2U_LIB.S9S_MB_2U(SCH_1):PAGE99
    99    GND @S9S_MB_2U_LIB.S9S_MB_2U(SCH_1):GND   I175 @S9S_MB_2U_LIB.S9S_MB_2U(SCH_1):PAGE99
   101    GND @S9S_MB_2U_LIB.S9S_MB_2U(SCH_1):GND   I175 @S9S_MB_2U_LIB.S9S_MB_2U(SCH_1):PAGE99
   103    GND @S9S_MB_2U_LIB.S9S_MB_2U(SCH_1):GND   I175 @S9S_MB_2U_LIB.S9S_MB_2U(SCH_1):PAGE99
   106    GND @S9S_MB_2U_LIB.S9S_MB_2U(SCH_1):GND   I175 @S9S_MB_2U_LIB.S9S_MB_2U(SCH_1):PAGE99
   108    GND @S9S_MB_2U_LIB.S9S_MB_2U(SCH_1):GND   I175 @S9S_MB_2U_LIB.S9S_MB_2U(SCH_1):PAGE99
   110    GND @S9S_MB_2U_LIB.S9S_MB_2U(SCH_1):GND   I175 @S9S_MB_2U_LIB.S9S_MB_2U(SCH_1):PAGE99
   112    GND @S9S_MB_2U_LIB.S9S_MB_2U(SCH_1):GND   I175 @S9S_MB_2U_LIB.S9S_MB_2U(SCH_1):PAGE99
   114    GND @S9S_MB_2U_LIB.S9S_MB_2U(SCH_1):GND   I175 @S9S_MB_2U_LIB.S9S_MB_2U(SCH_1):PAGE99
   117    GND @S9S_MB_2U_LIB.S9S_MB_2U(SCH_1):GND   I175 @S9S_MB_2U_LIB.S9S_MB_2U(SCH_1):PAGE99
   119    GND @S9S_MB_2U_LIB.S9S_MB_2U(SCH_1):GND   I175 @S9S_MB_2U_LIB.S9S_MB_2U(SCH_1):PAGE99
   121    GND @S9S_MB_2U_LIB.S9S_MB_2U(SCH_1):GND   I175 @S9S_MB_2U_LIB.S9S_MB_2U(SCH_1):PAGE99
   123    GND @S9S_MB_2U_LIB.S9S_MB_2U(SCH_1):GND   I175 @S9S_MB_2U_LIB.S9S_MB_2U(SCH_1):PAGE99
   125    GND @S9S_MB_2U_LIB.S9S_MB_2U(SCH_1):GND   I175 @S9S_MB_2U_LIB.S9S_MB_2U(SCH_1):PAGE99
   128    GND @S9S_MB_2U_LIB.S9S_MB_2U(SCH_1):GND   I175 @S9S_MB_2U_LIB.S9S_MB_2U(SCH_1):PAGE99
   130    GND @S9S_MB_2U_LIB.S9S_MB_2U(SCH_1):GND   I175 @S9S_MB_2U_LIB.S9S_MB_2U(SCH_1):PAGE99
   134    GND @S9S_MB_2U_LIB.S9S_MB_2U(SCH_1):GND   I175 @S9S_MB_2U_LIB.S9S_MB_2U(SCH_1):PAGE99
   143    GND @S9S_MB_2U_LIB.S9S_MB_2U(SCH_1):GND   I175 @S9S_MB_2U_LIB.S9S_MB_2U(SCH_1):PAGE99
   151    GND @S9S_MB_2U_LIB.S9S_MB_2U(SCH_1):GND   I175 @S9S_MB_2U_LIB.S9S_MB_2U(SCH_1):PAGE99
   153    GND @S9S_MB_2U_LIB.S9S_MB_2U(SCH_1):GND   I175 @S9S_MB_2U_LIB.S9S_MB_2U(SCH_1):PAGE99
   155    GND @S9S_MB_2U_LIB.S9S_MB_2U(SCH_1):GND   I175 @S9S_MB_2U_LIB.S9S_MB_2U(SCH_1):PAGE99
   158    GND @S9S_MB_2U_LIB.S9S_MB_2U(SCH_1):GND   I175 @S9S_MB_2U_LIB.S9S_MB_2U(SCH_1):PAGE99
   160    GND @S9S_MB_2U_LIB.S9S_MB_2U(SCH_1):GND   I175 @S9S_MB_2U_LIB.S9S_MB_2U(SCH_1):PAGE99
   162    GND @S9S_MB_2U_LIB.S9S_MB_2U(SCH_1):GND   I175 @S9S_MB_2U_LIB.S9S_MB_2U(SCH_1):PAGE99
   164    GND @S9S_MB_2U_LIB.S9S_MB_2U(SCH_1):GND   I175 @S9S_MB_2U_LIB.S9S_MB_2U(SCH_1):PAGE99
   166    GND @S9S_MB_2U_LIB.S9S_MB_2U(SCH_1):GND   I175 @S9S_MB_2U_LIB.S9S_MB_2U(SCH_1):PAGE99
   169    GND @S9S_MB_2U_LIB.S9S_MB_2U(SCH_1):GND   I175 @S9S_MB_2U_LIB.S9S_MB_2U(SCH_1):PAGE99
   171    GND @S9S_MB_2U_LIB.S9S_MB_2U(SCH_1):GND   I175 @S9S_MB_2U_LIB.S9S_MB_2U(SCH_1):PAGE99
   173    GND @S9S_MB_2U_LIB.S9S_MB_2U(SCH_1):GND   I175 @S9S_MB_2U_LIB.S9S_MB_2U(SCH_1):PAGE99
   175    GND @S9S_MB_2U_LIB.S9S_MB_2U(SCH_1):GND   I175 @S9S_MB_2U_LIB.S9S_MB_2U(SCH_1):PAGE99
   177    GND @S9S_MB_2U_LIB.S9S_MB_2U(SCH_1):GND   I175 @S9S_MB_2U_LIB.S9S_MB_2U(SCH_1):PAGE99
   180    GND @S9S_MB_2U_LIB.S9S_MB_2U(SCH_1):GND   I175 @S9S_MB_2U_LIB.S9S_MB_2U(SCH_1):PAGE99
   182    GND @S9S_MB_2U_LIB.S9S_MB_2U(SCH_1):GND   I175 @S9S_MB_2U_LIB.S9S_MB_2U(SCH_1):PAGE99
   184    GND @S9S_MB_2U_LIB.S9S_MB_2U(SCH_1):GND   I175 @S9S_MB_2U_LIB.S9S_MB_2U(SCH_1):PAGE99
   186    GND @S9S_MB_2U_LIB.S9S_MB_2U(SCH_1):GND   I175 @S9S_MB_2U_LIB.S9S_MB_2U(SCH_1):PAGE99
   188    GND @S9S_MB_2U_LIB.S9S_MB_2U(SCH_1):GND   I175 @S9S_MB_2U_LIB.S9S_MB_2U(SCH_1):PAGE99
   191    GND @S9S_MB_2U_LIB.S9S_MB_2U(SCH_1):GND   I175 @S9S_MB_2U_LIB.S9S_MB_2U(SCH_1):PAGE99
   193    GND @S9S_MB_2U_LIB.S9S_MB_2U(SCH_1):GND   I175 @S9S_MB_2U_LIB.S9S_MB_2U(SCH_1):PAGE99
   195    GND @S9S_MB_2U_LIB.S9S_MB_2U(SCH_1):GND   I175 @S9S_MB_2U_LIB.S9S_MB_2U(SCH_1):PAGE99
   197    GND @S9S_MB_2U_LIB.S9S_MB_2U(SCH_1):GND   I175 @S9S_MB_2U_LIB.S9S_MB_2U(SCH_1):PAGE99
   199    GND @S9S_MB_2U_LIB.S9S_MB_2U(SCH_1):GND   I175 @S9S_MB_2U_LIB.S9S_MB_2U(SCH_1):PAGE99
   202    GND @S9S_MB_2U_LIB.S9S_MB_2U(SCH_1):GND   I175 @S9S_MB_2U_LIB.S9S_MB_2U(SCH_1):PAGE99
   204    GND @S9S_MB_2U_LIB.S9S_MB_2U(SCH_1):GND   I175 @S9S_MB_2U_LIB.S9S_MB_2U(SCH_1):PAGE99
   206    GND @S9S_MB_2U_LIB.S9S_MB_2U(SCH_1):GND   I175 @S9S_MB_2U_LIB.S9S_MB_2U(SCH_1):PAGE99
   208    GND @S9S_MB_2U_LIB.S9S_MB_2U(SCH_1):GND   I175 @S9S_MB_2U_LIB.S9S_MB_2U(SCH_1):PAGE99
   210    GND @S9S_MB_2U_LIB.S9S_MB_2U(SCH_1):GND   I175 @S9S_MB_2U_LIB.S9S_MB_2U(SCH_1):PAGE99
   212    GND @S9S_MB_2U_LIB.S9S_MB_2U(SCH_1):GND   I175 @S9S_MB_2U_LIB.S9S_MB_2U(SCH_1):PAGE99
   214    GND @S9S_MB_2U_LIB.S9S_MB_2U(SCH_1):GND   I175 @S9S_MB_2U_LIB.S9S_MB_2U(SCH_1):PAGE99
   216    GND @S9S_MB_2U_LIB.S9S_MB_2U(SCH_1):GND   I175 @S9S_MB_2U_LIB.S9S_MB_2U(SCH_1):PAGE99
   219    GND @S9S_MB_2U_LIB.S9S_MB_2U(SCH_1):GND   I175 @S9S_MB_2U_LIB.S9S_MB_2U(SCH_1):PAGE99
   222    GND @S9S_MB_2U_LIB.S9S_MB_2U(SCH_1):GND   I175 @S9S_MB_2U_LIB.S9S_MB_2U(SCH_1):PAGE99
   224    GND @S9S_MB_2U_LIB.S9S_MB_2U(SCH_1):GND   I175 @S9S_MB_2U_LIB.S9S_MB_2U(SCH_1):PAGE99
   226    GND @S9S_MB_2U_LIB.S9S_MB_2U(SCH_1):GND   I175 @S9S_MB_2U_LIB.S9S_MB_2U(SCH_1):PAGE99
   228    GND @S9S_MB_2U_LIB.S9S_MB_2U(SCH_1):GND   I175 @S9S_MB_2U_LIB.S9S_MB_2U(SCH_1):PAGE99
   233    GND @S9S_MB_2U_LIB.S9S_MB_2U(SCH_1):GND   I175 @S9S_MB_2U_LIB.S9S_MB_2U(SCH_1):PAGE99
   237    GND @S9S_MB_2U_LIB.S9S_MB_2U(SCH_1):GND   I175 @S9S_MB_2U_LIB.S9S_MB_2U(SCH_1):PAGE99
   242    GND @S9S_MB_2U_LIB.S9S_MB_2U(SCH_1):GND   I175 @S9S_MB_2U_LIB.S9S_MB_2U(SCH_1):PAGE99
   244    GND @S9S_MB_2U_LIB.S9S_MB_2U(SCH_1):GND   I175 @S9S_MB_2U_LIB.S9S_MB_2U(SCH_1):PAGE99
   246    GND @S9S_MB_2U_LIB.S9S_MB_2U(SCH_1):GND   I175 @S9S_MB_2U_LIB.S9S_MB_2U(SCH_1):PAGE99
   248    GND @S9S_MB_2U_LIB.S9S_MB_2U(SCH_1):GND   I175 @S9S_MB_2U_LIB.S9S_MB_2U(SCH_1):PAGE99
   251    GND @S9S_MB_2U_LIB.S9S_MB_2U(SCH_1):GND   I175 @S9S_MB_2U_LIB.S9S_MB_2U(SCH_1):PAGE99
   253    GND @S9S_MB_2U_LIB.S9S_MB_2U(SCH_1):GND   I175 @S9S_MB_2U_LIB.S9S_MB_2U(SCH_1):PAGE99
   255    GND @S9S_MB_2U_LIB.S9S_MB_2U(SCH_1):GND   I175 @S9S_MB_2U_LIB.S9S_MB_2U(SCH_1):PAGE99
   257    GND @S9S_MB_2U_LIB.S9S_MB_2U(SCH_1):GND   I175 @S9S_MB_2U_LIB.S9S_MB_2U(SCH_1):PAGE99
   259    GND @S9S_MB_2U_LIB.S9S_MB_2U(SCH_1):GND   I175 @S9S_MB_2U_LIB.S9S_MB_2U(SCH_1):PAGE99
   262    GND @S9S_MB_2U_LIB.S9S_MB_2U(SCH_1):GND   I175 @S9S_MB_2U_LIB.S9S_MB_2U(SCH_1):PAGE99
   264    GND @S9S_MB_2U_LIB.S9S_MB_2U(SCH_1):GND   I175 @S9S_MB_2U_LIB.S9S_MB_2U(SCH_1):PAGE99
   266    GND @S9S_MB_2U_LIB.S9S_MB_2U(SCH_1):GND   I175 @S9S_MB_2U_LIB.S9S_MB_2U(SCH_1):PAGE99
   268    GND @S9S_MB_2U_LIB.S9S_MB_2U(SCH_1):GND   I175 @S9S_MB_2U_LIB.S9S_MB_2U(SCH_1):PAGE99
   270    GND @S9S_MB_2U_LIB.S9S_MB_2U(SCH_1):GND   I175 @S9S_MB_2U_LIB.S9S_MB_2U(SCH_1):PAGE99
   273    GND @S9S_MB_2U_LIB.S9S_MB_2U(SCH_1):GND   I175 @S9S_MB_2U_LIB.S9S_MB_2U(SCH_1):PAGE99
   275    GND @S9S_MB_2U_LIB.S9S_MB_2U(SCH_1):GND   I175 @S9S_MB_2U_LIB.S9S_MB_2U(SCH_1):PAGE99
   277    GND @S9S_MB_2U_LIB.S9S_MB_2U(SCH_1):GND   I175 @S9S_MB_2U_LIB.S9S_MB_2U(SCH_1):PAGE99
   279    GND @S9S_MB_2U_LIB.S9S_MB_2U(SCH_1):GND   I175 @S9S_MB_2U_LIB.S9S_MB_2U(SCH_1):PAGE99
   281    GND @S9S_MB_2U_LIB.S9S_MB_2U(SCH_1):GND   I175 @S9S_MB_2U_LIB.S9S_MB_2U(SCH_1):PAGE99
   284    GND @S9S_MB_2U_LIB.S9S_MB_2U(SCH_1):GND   I175 @S9S_MB_2U_LIB.S9S_MB_2U(SCH_1):PAGE99
   286    GND @S9S_MB_2U_LIB.S9S_MB_2U(SCH_1):GND   I175 @S9S_MB_2U_LIB.S9S_MB_2U(SCH_1):PAGE99
   288    GND @S9S_MB_2U_LIB.S9S_MB_2U(SCH_1):GND   I175 @S9S_MB_2U_LIB.S9S_MB_2U(SCH_1):PAGE99
     1 P12V_S3_AUX_CPU1_NVDIMM @S9S_MB_2U_LIB.S9S_MB_2U(SCH_1):P12V_S3_AUX_CPU1_NVDIMM   I175 @S9S_MB_2U_LIB.S9S_MB_2U(SCH_1):PAGE99
   145 P12V_S3_AUX_CPU1_NVDIMM @S9S_MB_2U_LIB.S9S_MB_2U(SCH_1):P12V_S3_AUX_CPU1_NVDIMM   I175 @S9S_MB_2U_LIB.S9S_MB_2U(SCH_1):PAGE99
   146 P12V_S3_AUX_CPU1_NVDIMM @S9S_MB_2U_LIB.S9S_MB_2U(SCH_1):P12V_S3_AUX_CPU1_NVDIMM   I175 @S9S_MB_2U_LIB.S9S_MB_2U(SCH_1):PAGE99
   230    GND @S9S_MB_2U_LIB.S9S_MB_2U(SCH_1):GND   I175 @S9S_MB_2U_LIB.S9S_MB_2U(SCH_1):PAGE99
   235    GND @S9S_MB_2U_LIB.S9S_MB_2U(SCH_1):GND   I175 @S9S_MB_2U_LIB.S9S_MB_2U(SCH_1):PAGE99
   240    GND @S9S_MB_2U_LIB.S9S_MB_2U(SCH_1):GND   I175 @S9S_MB_2U_LIB.S9S_MB_2U(SCH_1):PAGE99
   132    GND @S9S_MB_2U_LIB.S9S_MB_2U(SCH_1):GND   I175 @S9S_MB_2U_LIB.S9S_MB_2U(SCH_1):PAGE99
   136    GND @S9S_MB_2U_LIB.S9S_MB_2U(SCH_1):GND   I175 @S9S_MB_2U_LIB.S9S_MB_2U(SCH_1):PAGE99
   139    GND @S9S_MB_2U_LIB.S9S_MB_2U(SCH_1):GND   I175 @S9S_MB_2U_LIB.S9S_MB_2U(SCH_1):PAGE99
   141    GND @S9S_MB_2U_LIB.S9S_MB_2U(SCH_1):GND   I175 @S9S_MB_2U_LIB.S9S_MB_2U(SCH_1):PAGE99
    G1    GND @S9S_MB_2U_LIB.S9S_MB_2U(SCH_1):GND   I175 @S9S_MB_2U_LIB.S9S_MB_2U(SCH_1):PAGE99
    G2    GND @S9S_MB_2U_LIB.S9S_MB_2U(SCH_1):GND   I175 @S9S_MB_2U_LIB.S9S_MB_2U(SCH_1):PAGE99
    G3    GND @S9S_MB_2U_LIB.S9S_MB_2U(SCH_1):GND   I175 @S9S_MB_2U_LIB.S9S_MB_2U(SCH_1):PAGE99

 J19 SCONN288_ADR50017P130CC-SCONN2A
     3 P3V3_AUX @S9S_MB_2U_LIB.S9S_MB_2U(SCH_1):P3V3_AUX    I25 @S9S_MB_2U_LIB.S9S_MB_2U(SCH_1):PAGE100
     2 TP_CHB_CPU1_DIMM1_FRU_0 @S9S_MB_2U_LIB.S9S_MB_2U(SCH_1):TP_CHB_CPU1_DIMM1_FRU_0    I25 @S9S_MB_2U_LIB.S9S_MB_2U(SCH_1):PAGE100
   144 TP_CHB_CPU1_DIMM1_FRU_1 @S9S_MB_2U_LIB.S9S_MB_2U(SCH_1):TP_CHB_CPU1_DIMM1_FRU_1    I25 @S9S_MB_2U_LIB.S9S_MB_2U(SCH_1):PAGE100
   149 TP_CHB_CPU1_DIMM1_FRU_2 @S9S_MB_2U_LIB.S9S_MB_2U(SCH_1):TP_CHB_CPU1_DIMM1_FRU_2    I25 @S9S_MB_2U_LIB.S9S_MB_2U(SCH_1):PAGE100
   150 TP_CHB_CPU1_DIMM1_FRU_3 @S9S_MB_2U_LIB.S9S_MB_2U(SCH_1):TP_CHB_CPU1_DIMM1_FRU_3    I25 @S9S_MB_2U_LIB.S9S_MB_2U(SCH_1):PAGE100
   220 TP_CHB_CPU1_DIMM1_FRU_4 @S9S_MB_2U_LIB.S9S_MB_2U(SCH_1):TP_CHB_CPU1_DIMM1_FRU_4    I25 @S9S_MB_2U_LIB.S9S_MB_2U(SCH_1):PAGE100
   231 TP_CHB_CPU1_DIMM1_FRU_5 @S9S_MB_2U_LIB.S9S_MB_2U(SCH_1):TP_CHB_CPU1_DIMM1_FRU_5    I25 @S9S_MB_2U_LIB.S9S_MB_2U(SCH_1):PAGE100
   232 TP_CHB_CPU1_DIMM1_FRU_6 @S9S_MB_2U_LIB.S9S_MB_2U(SCH_1):TP_CHB_CPU1_DIMM1_FRU_6    I25 @S9S_MB_2U_LIB.S9S_MB_2U(SCH_1):PAGE100
   207 RST_M_AB_CPU1_FPGA_N @S9S_MB_2U_LIB.S9S_MB_2U(SCH_1):RST_M_AB_CPU1_FPGA_N    I25 @S9S_MB_2U_LIB.S9S_MB_2U(SCH_1):PAGE100
   147 PWRGD_CHB_CPU1_DIMM1 @S9S_MB_2U_LIB.S9S_MB_2U(SCH_1):PWRGD_CHB_CPU1_DIMM1    I25 @S9S_MB_2U_LIB.S9S_MB_2U(SCH_1):PAGE100
   227 M_B_CPU1_SB_PAR @S9S_MB_2U_LIB.S9S_MB_2U(SCH_1):M_B_CPU1_SB_PAR    I25 @S9S_MB_2U_LIB.S9S_MB_2U(SCH_1):PAGE100
    74 M_B_CPU1_SA_PAR @S9S_MB_2U_LIB.S9S_MB_2U(SCH_1):M_B_CPU1_SA_PAR    I25 @S9S_MB_2U_LIB.S9S_MB_2U(SCH_1):PAGE100
    87 M_B_CPU1_SB_RSP<0> @S9S_MB_2U_LIB.S9S_MB_2U(SCH_1):M_B_CPU1_SB_RSP(0)    I25 @S9S_MB_2U_LIB.S9S_MB_2U(SCH_1):PAGE100
    86 M_B_CPU1_SA_RSP<0> @S9S_MB_2U_LIB.S9S_MB_2U(SCH_1):M_B_CPU1_SA_RSP(0)    I25 @S9S_MB_2U_LIB.S9S_MB_2U(SCH_1):PAGE100
     5 I3C_SPD_DDRABCD_CPU1_LVC1_SDA @S9S_MB_2U_LIB.S9S_MB_2U(SCH_1):I3C_SPD_DDRABCD_CPU1_LVC1_SDA    I25 @S9S_MB_2U_LIB.S9S_MB_2U(SCH_1):PAGE100
     4 I3C_SPD_DDRABCD_CPU1_LVC1_SCL_2 @S9S_MB_2U_LIB.S9S_MB_2U(SCH_1):I3C_SPD_DDRABCD_CPU1_LVC1_SCL_R3    I25 @S9S_MB_2U_LIB.S9S_MB_2U(SCH_1):PAGE100
   148 PD_CHB_CPU1_DIMM1_SAA @S9S_MB_2U_LIB.S9S_MB_2U(SCH_1):PD_CHB_CPU1_DIMM1_SAA    I25 @S9S_MB_2U_LIB.S9S_MB_2U(SCH_1):PAGE100
   100 M_B_CPU1_SB_DQ<0> @S9S_MB_2U_LIB.S9S_MB_2U(SCH_1):M_B_CPU1_SB_DQ(0)    I25 @S9S_MB_2U_LIB.S9S_MB_2U(SCH_1):PAGE100
   102 M_B_CPU1_SB_DQ<1> @S9S_MB_2U_LIB.S9S_MB_2U(SCH_1):M_B_CPU1_SB_DQ(1)    I25 @S9S_MB_2U_LIB.S9S_MB_2U(SCH_1):PAGE100
   245 M_B_CPU1_SB_DQ<2> @S9S_MB_2U_LIB.S9S_MB_2U(SCH_1):M_B_CPU1_SB_DQ(2)    I25 @S9S_MB_2U_LIB.S9S_MB_2U(SCH_1):PAGE100
   247 M_B_CPU1_SB_DQ<3> @S9S_MB_2U_LIB.S9S_MB_2U(SCH_1):M_B_CPU1_SB_DQ(3)    I25 @S9S_MB_2U_LIB.S9S_MB_2U(SCH_1):PAGE100
   107 M_B_CPU1_SB_DQ<4> @S9S_MB_2U_LIB.S9S_MB_2U(SCH_1):M_B_CPU1_SB_DQ(4)    I25 @S9S_MB_2U_LIB.S9S_MB_2U(SCH_1):PAGE100
   109 M_B_CPU1_SB_DQ<5> @S9S_MB_2U_LIB.S9S_MB_2U(SCH_1):M_B_CPU1_SB_DQ(5)    I25 @S9S_MB_2U_LIB.S9S_MB_2U(SCH_1):PAGE100
   252 M_B_CPU1_SB_DQ<6> @S9S_MB_2U_LIB.S9S_MB_2U(SCH_1):M_B_CPU1_SB_DQ(6)    I25 @S9S_MB_2U_LIB.S9S_MB_2U(SCH_1):PAGE100
   254 M_B_CPU1_SB_DQ<7> @S9S_MB_2U_LIB.S9S_MB_2U(SCH_1):M_B_CPU1_SB_DQ(7)    I25 @S9S_MB_2U_LIB.S9S_MB_2U(SCH_1):PAGE100
   111 M_B_CPU1_SB_DQ<8> @S9S_MB_2U_LIB.S9S_MB_2U(SCH_1):M_B_CPU1_SB_DQ(8)    I25 @S9S_MB_2U_LIB.S9S_MB_2U(SCH_1):PAGE100
   113 M_B_CPU1_SB_DQ<9> @S9S_MB_2U_LIB.S9S_MB_2U(SCH_1):M_B_CPU1_SB_DQ(9)    I25 @S9S_MB_2U_LIB.S9S_MB_2U(SCH_1):PAGE100
   256 M_B_CPU1_SB_DQ<10> @S9S_MB_2U_LIB.S9S_MB_2U(SCH_1):M_B_CPU1_SB_DQ(10)    I25 @S9S_MB_2U_LIB.S9S_MB_2U(SCH_1):PAGE100
   258 M_B_CPU1_SB_DQ<11> @S9S_MB_2U_LIB.S9S_MB_2U(SCH_1):M_B_CPU1_SB_DQ(11)    I25 @S9S_MB_2U_LIB.S9S_MB_2U(SCH_1):PAGE100
   118 M_B_CPU1_SB_DQ<12> @S9S_MB_2U_LIB.S9S_MB_2U(SCH_1):M_B_CPU1_SB_DQ(12)    I25 @S9S_MB_2U_LIB.S9S_MB_2U(SCH_1):PAGE100
   120 M_B_CPU1_SB_DQ<13> @S9S_MB_2U_LIB.S9S_MB_2U(SCH_1):M_B_CPU1_SB_DQ(13)    I25 @S9S_MB_2U_LIB.S9S_MB_2U(SCH_1):PAGE100
   263 M_B_CPU1_SB_DQ<14> @S9S_MB_2U_LIB.S9S_MB_2U(SCH_1):M_B_CPU1_SB_DQ(14)    I25 @S9S_MB_2U_LIB.S9S_MB_2U(SCH_1):PAGE100
   265 M_B_CPU1_SB_DQ<15> @S9S_MB_2U_LIB.S9S_MB_2U(SCH_1):M_B_CPU1_SB_DQ(15)    I25 @S9S_MB_2U_LIB.S9S_MB_2U(SCH_1):PAGE100
   122 M_B_CPU1_SB_DQ<16> @S9S_MB_2U_LIB.S9S_MB_2U(SCH_1):M_B_CPU1_SB_DQ(16)    I25 @S9S_MB_2U_LIB.S9S_MB_2U(SCH_1):PAGE100
   124 M_B_CPU1_SB_DQ<17> @S9S_MB_2U_LIB.S9S_MB_2U(SCH_1):M_B_CPU1_SB_DQ(17)    I25 @S9S_MB_2U_LIB.S9S_MB_2U(SCH_1):PAGE100
   267 M_B_CPU1_SB_DQ<18> @S9S_MB_2U_LIB.S9S_MB_2U(SCH_1):M_B_CPU1_SB_DQ(18)    I25 @S9S_MB_2U_LIB.S9S_MB_2U(SCH_1):PAGE100
   269 M_B_CPU1_SB_DQ<19> @S9S_MB_2U_LIB.S9S_MB_2U(SCH_1):M_B_CPU1_SB_DQ(19)    I25 @S9S_MB_2U_LIB.S9S_MB_2U(SCH_1):PAGE100
   129 M_B_CPU1_SB_DQ<20> @S9S_MB_2U_LIB.S9S_MB_2U(SCH_1):M_B_CPU1_SB_DQ(20)    I25 @S9S_MB_2U_LIB.S9S_MB_2U(SCH_1):PAGE100
   131 M_B_CPU1_SB_DQ<21> @S9S_MB_2U_LIB.S9S_MB_2U(SCH_1):M_B_CPU1_SB_DQ(21)    I25 @S9S_MB_2U_LIB.S9S_MB_2U(SCH_1):PAGE100
   274 M_B_CPU1_SB_DQ<22> @S9S_MB_2U_LIB.S9S_MB_2U(SCH_1):M_B_CPU1_SB_DQ(22)    I25 @S9S_MB_2U_LIB.S9S_MB_2U(SCH_1):PAGE100
   276 M_B_CPU1_SB_DQ<23> @S9S_MB_2U_LIB.S9S_MB_2U(SCH_1):M_B_CPU1_SB_DQ(23)    I25 @S9S_MB_2U_LIB.S9S_MB_2U(SCH_1):PAGE100
   133 M_B_CPU1_SB_DQ<24> @S9S_MB_2U_LIB.S9S_MB_2U(SCH_1):M_B_CPU1_SB_DQ(24)    I25 @S9S_MB_2U_LIB.S9S_MB_2U(SCH_1):PAGE100
   135 M_B_CPU1_SB_DQ<25> @S9S_MB_2U_LIB.S9S_MB_2U(SCH_1):M_B_CPU1_SB_DQ(25)    I25 @S9S_MB_2U_LIB.S9S_MB_2U(SCH_1):PAGE100
   278 M_B_CPU1_SB_DQ<26> @S9S_MB_2U_LIB.S9S_MB_2U(SCH_1):M_B_CPU1_SB_DQ(26)    I25 @S9S_MB_2U_LIB.S9S_MB_2U(SCH_1):PAGE100
   280 M_B_CPU1_SB_DQ<27> @S9S_MB_2U_LIB.S9S_MB_2U(SCH_1):M_B_CPU1_SB_DQ(27)    I25 @S9S_MB_2U_LIB.S9S_MB_2U(SCH_1):PAGE100
   140 M_B_CPU1_SB_DQ<28> @S9S_MB_2U_LIB.S9S_MB_2U(SCH_1):M_B_CPU1_SB_DQ(28)    I25 @S9S_MB_2U_LIB.S9S_MB_2U(SCH_1):PAGE100
   142 M_B_CPU1_SB_DQ<29> @S9S_MB_2U_LIB.S9S_MB_2U(SCH_1):M_B_CPU1_SB_DQ(29)    I25 @S9S_MB_2U_LIB.S9S_MB_2U(SCH_1):PAGE100
   285 M_B_CPU1_SB_DQ<30> @S9S_MB_2U_LIB.S9S_MB_2U(SCH_1):M_B_CPU1_SB_DQ(30)    I25 @S9S_MB_2U_LIB.S9S_MB_2U(SCH_1):PAGE100
   287 M_B_CPU1_SB_DQ<31> @S9S_MB_2U_LIB.S9S_MB_2U(SCH_1):M_B_CPU1_SB_DQ(31)    I25 @S9S_MB_2U_LIB.S9S_MB_2U(SCH_1):PAGE100
     7 M_B_CPU1_SA_DQ<0> @S9S_MB_2U_LIB.S9S_MB_2U(SCH_1):M_B_CPU1_SA_DQ(0)    I25 @S9S_MB_2U_LIB.S9S_MB_2U(SCH_1):PAGE100
     9 M_B_CPU1_SA_DQ<1> @S9S_MB_2U_LIB.S9S_MB_2U(SCH_1):M_B_CPU1_SA_DQ(1)    I25 @S9S_MB_2U_LIB.S9S_MB_2U(SCH_1):PAGE100
   152 M_B_CPU1_SA_DQ<2> @S9S_MB_2U_LIB.S9S_MB_2U(SCH_1):M_B_CPU1_SA_DQ(2)    I25 @S9S_MB_2U_LIB.S9S_MB_2U(SCH_1):PAGE100
   154 M_B_CPU1_SA_DQ<3> @S9S_MB_2U_LIB.S9S_MB_2U(SCH_1):M_B_CPU1_SA_DQ(3)    I25 @S9S_MB_2U_LIB.S9S_MB_2U(SCH_1):PAGE100
    14 M_B_CPU1_SA_DQ<4> @S9S_MB_2U_LIB.S9S_MB_2U(SCH_1):M_B_CPU1_SA_DQ(4)    I25 @S9S_MB_2U_LIB.S9S_MB_2U(SCH_1):PAGE100
    16 M_B_CPU1_SA_DQ<5> @S9S_MB_2U_LIB.S9S_MB_2U(SCH_1):M_B_CPU1_SA_DQ(5)    I25 @S9S_MB_2U_LIB.S9S_MB_2U(SCH_1):PAGE100
   159 M_B_CPU1_SA_DQ<6> @S9S_MB_2U_LIB.S9S_MB_2U(SCH_1):M_B_CPU1_SA_DQ(6)    I25 @S9S_MB_2U_LIB.S9S_MB_2U(SCH_1):PAGE100
   161 M_B_CPU1_SA_DQ<7> @S9S_MB_2U_LIB.S9S_MB_2U(SCH_1):M_B_CPU1_SA_DQ(7)    I25 @S9S_MB_2U_LIB.S9S_MB_2U(SCH_1):PAGE100
    18 M_B_CPU1_SA_DQ<8> @S9S_MB_2U_LIB.S9S_MB_2U(SCH_1):M_B_CPU1_SA_DQ(8)    I25 @S9S_MB_2U_LIB.S9S_MB_2U(SCH_1):PAGE100
    20 M_B_CPU1_SA_DQ<9> @S9S_MB_2U_LIB.S9S_MB_2U(SCH_1):M_B_CPU1_SA_DQ(9)    I25 @S9S_MB_2U_LIB.S9S_MB_2U(SCH_1):PAGE100
   163 M_B_CPU1_SA_DQ<10> @S9S_MB_2U_LIB.S9S_MB_2U(SCH_1):M_B_CPU1_SA_DQ(10)    I25 @S9S_MB_2U_LIB.S9S_MB_2U(SCH_1):PAGE100
   165 M_B_CPU1_SA_DQ<11> @S9S_MB_2U_LIB.S9S_MB_2U(SCH_1):M_B_CPU1_SA_DQ(11)    I25 @S9S_MB_2U_LIB.S9S_MB_2U(SCH_1):PAGE100
    25 M_B_CPU1_SA_DQ<12> @S9S_MB_2U_LIB.S9S_MB_2U(SCH_1):M_B_CPU1_SA_DQ(12)    I25 @S9S_MB_2U_LIB.S9S_MB_2U(SCH_1):PAGE100
    27 M_B_CPU1_SA_DQ<13> @S9S_MB_2U_LIB.S9S_MB_2U(SCH_1):M_B_CPU1_SA_DQ(13)    I25 @S9S_MB_2U_LIB.S9S_MB_2U(SCH_1):PAGE100
   170 M_B_CPU1_SA_DQ<14> @S9S_MB_2U_LIB.S9S_MB_2U(SCH_1):M_B_CPU1_SA_DQ(14)    I25 @S9S_MB_2U_LIB.S9S_MB_2U(SCH_1):PAGE100
   172 M_B_CPU1_SA_DQ<15> @S9S_MB_2U_LIB.S9S_MB_2U(SCH_1):M_B_CPU1_SA_DQ(15)    I25 @S9S_MB_2U_LIB.S9S_MB_2U(SCH_1):PAGE100
    29 M_B_CPU1_SA_DQ<16> @S9S_MB_2U_LIB.S9S_MB_2U(SCH_1):M_B_CPU1_SA_DQ(16)    I25 @S9S_MB_2U_LIB.S9S_MB_2U(SCH_1):PAGE100
    31 M_B_CPU1_SA_DQ<17> @S9S_MB_2U_LIB.S9S_MB_2U(SCH_1):M_B_CPU1_SA_DQ(17)    I25 @S9S_MB_2U_LIB.S9S_MB_2U(SCH_1):PAGE100
   174 M_B_CPU1_SA_DQ<18> @S9S_MB_2U_LIB.S9S_MB_2U(SCH_1):M_B_CPU1_SA_DQ(18)    I25 @S9S_MB_2U_LIB.S9S_MB_2U(SCH_1):PAGE100
   176 M_B_CPU1_SA_DQ<19> @S9S_MB_2U_LIB.S9S_MB_2U(SCH_1):M_B_CPU1_SA_DQ(19)    I25 @S9S_MB_2U_LIB.S9S_MB_2U(SCH_1):PAGE100
    36 M_B_CPU1_SA_DQ<20> @S9S_MB_2U_LIB.S9S_MB_2U(SCH_1):M_B_CPU1_SA_DQ(20)    I25 @S9S_MB_2U_LIB.S9S_MB_2U(SCH_1):PAGE100
    38 M_B_CPU1_SA_DQ<21> @S9S_MB_2U_LIB.S9S_MB_2U(SCH_1):M_B_CPU1_SA_DQ(21)    I25 @S9S_MB_2U_LIB.S9S_MB_2U(SCH_1):PAGE100
   181 M_B_CPU1_SA_DQ<22> @S9S_MB_2U_LIB.S9S_MB_2U(SCH_1):M_B_CPU1_SA_DQ(22)    I25 @S9S_MB_2U_LIB.S9S_MB_2U(SCH_1):PAGE100
   183 M_B_CPU1_SA_DQ<23> @S9S_MB_2U_LIB.S9S_MB_2U(SCH_1):M_B_CPU1_SA_DQ(23)    I25 @S9S_MB_2U_LIB.S9S_MB_2U(SCH_1):PAGE100
    40 M_B_CPU1_SA_DQ<24> @S9S_MB_2U_LIB.S9S_MB_2U(SCH_1):M_B_CPU1_SA_DQ(24)    I25 @S9S_MB_2U_LIB.S9S_MB_2U(SCH_1):PAGE100
    42 M_B_CPU1_SA_DQ<25> @S9S_MB_2U_LIB.S9S_MB_2U(SCH_1):M_B_CPU1_SA_DQ(25)    I25 @S9S_MB_2U_LIB.S9S_MB_2U(SCH_1):PAGE100
   185 M_B_CPU1_SA_DQ<26> @S9S_MB_2U_LIB.S9S_MB_2U(SCH_1):M_B_CPU1_SA_DQ(26)    I25 @S9S_MB_2U_LIB.S9S_MB_2U(SCH_1):PAGE100
   187 M_B_CPU1_SA_DQ<27> @S9S_MB_2U_LIB.S9S_MB_2U(SCH_1):M_B_CPU1_SA_DQ(27)    I25 @S9S_MB_2U_LIB.S9S_MB_2U(SCH_1):PAGE100
    47 M_B_CPU1_SA_DQ<28> @S9S_MB_2U_LIB.S9S_MB_2U(SCH_1):M_B_CPU1_SA_DQ(28)    I25 @S9S_MB_2U_LIB.S9S_MB_2U(SCH_1):PAGE100
    49 M_B_CPU1_SA_DQ<29> @S9S_MB_2U_LIB.S9S_MB_2U(SCH_1):M_B_CPU1_SA_DQ(29)    I25 @S9S_MB_2U_LIB.S9S_MB_2U(SCH_1):PAGE100
   192 M_B_CPU1_SA_DQ<30> @S9S_MB_2U_LIB.S9S_MB_2U(SCH_1):M_B_CPU1_SA_DQ(30)    I25 @S9S_MB_2U_LIB.S9S_MB_2U(SCH_1):PAGE100
   229 M_B_CPU1_SB_CS_N<1> @S9S_MB_2U_LIB.S9S_MB_2U(SCH_1):M_B_CPU1_SB_CS_N(1)    I25 @S9S_MB_2U_LIB.S9S_MB_2U(SCH_1):PAGE100
   209 M_B_CPU1_SA_CS_N<1> @S9S_MB_2U_LIB.S9S_MB_2U(SCH_1):M_B_CPU1_SA_CS_N(1)    I25 @S9S_MB_2U_LIB.S9S_MB_2U(SCH_1):PAGE100
    84 M_B_CPU1_SB_CS_N<0> @S9S_MB_2U_LIB.S9S_MB_2U(SCH_1):M_B_CPU1_SB_CS_N(0)    I25 @S9S_MB_2U_LIB.S9S_MB_2U(SCH_1):PAGE100
    64 M_B_CPU1_SA_CS_N<0> @S9S_MB_2U_LIB.S9S_MB_2U(SCH_1):M_B_CPU1_SA_CS_N(0)    I25 @S9S_MB_2U_LIB.S9S_MB_2U(SCH_1):PAGE100
   217 M_B_CPU1_CLK_DP<0> @S9S_MB_2U_LIB.S9S_MB_2U(SCH_1):M_B_CPU1_CLK_DP(0)    I25 @S9S_MB_2U_LIB.S9S_MB_2U(SCH_1):PAGE100
   218 M_B_CPU1_CLK_DN<0> @S9S_MB_2U_LIB.S9S_MB_2U(SCH_1):M_B_CPU1_CLK_DN(0)    I25 @S9S_MB_2U_LIB.S9S_MB_2U(SCH_1):PAGE100
    96 M_B_CPU1_SB_CB<0> @S9S_MB_2U_LIB.S9S_MB_2U(SCH_1):M_B_CPU1_SB_CB(0)    I25 @S9S_MB_2U_LIB.S9S_MB_2U(SCH_1):PAGE100
    98 M_B_CPU1_SB_CB<1> @S9S_MB_2U_LIB.S9S_MB_2U(SCH_1):M_B_CPU1_SB_CB(1)    I25 @S9S_MB_2U_LIB.S9S_MB_2U(SCH_1):PAGE100
   241 M_B_CPU1_SB_CB<2> @S9S_MB_2U_LIB.S9S_MB_2U(SCH_1):M_B_CPU1_SB_CB(2)    I25 @S9S_MB_2U_LIB.S9S_MB_2U(SCH_1):PAGE100
   243 M_B_CPU1_SB_CB<3> @S9S_MB_2U_LIB.S9S_MB_2U(SCH_1):M_B_CPU1_SB_CB(3)    I25 @S9S_MB_2U_LIB.S9S_MB_2U(SCH_1):PAGE100
    89 M_B_CPU1_SB_CB<4> @S9S_MB_2U_LIB.S9S_MB_2U(SCH_1):M_B_CPU1_SB_CB(4)    I25 @S9S_MB_2U_LIB.S9S_MB_2U(SCH_1):PAGE100
    91 M_B_CPU1_SB_CB<5> @S9S_MB_2U_LIB.S9S_MB_2U(SCH_1):M_B_CPU1_SB_CB(5)    I25 @S9S_MB_2U_LIB.S9S_MB_2U(SCH_1):PAGE100
   234 M_B_CPU1_SB_CB<6> @S9S_MB_2U_LIB.S9S_MB_2U(SCH_1):M_B_CPU1_SB_CB(6)    I25 @S9S_MB_2U_LIB.S9S_MB_2U(SCH_1):PAGE100
    51 M_B_CPU1_SA_CB<0> @S9S_MB_2U_LIB.S9S_MB_2U(SCH_1):M_B_CPU1_SA_CB(0)    I25 @S9S_MB_2U_LIB.S9S_MB_2U(SCH_1):PAGE100
   196 M_B_CPU1_SA_CB<2> @S9S_MB_2U_LIB.S9S_MB_2U(SCH_1):M_B_CPU1_SA_CB(2)    I25 @S9S_MB_2U_LIB.S9S_MB_2U(SCH_1):PAGE100
   198 M_B_CPU1_SA_CB<3> @S9S_MB_2U_LIB.S9S_MB_2U(SCH_1):M_B_CPU1_SA_CB(3)    I25 @S9S_MB_2U_LIB.S9S_MB_2U(SCH_1):PAGE100
    60 M_B_CPU1_SA_CB<5> @S9S_MB_2U_LIB.S9S_MB_2U(SCH_1):M_B_CPU1_SA_CB(5)    I25 @S9S_MB_2U_LIB.S9S_MB_2U(SCH_1):PAGE100
   203 M_B_CPU1_SA_CB<6> @S9S_MB_2U_LIB.S9S_MB_2U(SCH_1):M_B_CPU1_SA_CB(6)    I25 @S9S_MB_2U_LIB.S9S_MB_2U(SCH_1):PAGE100
    82 M_B_CPU1_SB_CA<6> @S9S_MB_2U_LIB.S9S_MB_2U(SCH_1):M_B_CPU1_SB_CA(6)    I25 @S9S_MB_2U_LIB.S9S_MB_2U(SCH_1):PAGE100
    72 M_B_CPU1_SA_CA<6> @S9S_MB_2U_LIB.S9S_MB_2U(SCH_1):M_B_CPU1_SA_CA(6)    I25 @S9S_MB_2U_LIB.S9S_MB_2U(SCH_1):PAGE100
   225 M_B_CPU1_SB_CA<5> @S9S_MB_2U_LIB.S9S_MB_2U(SCH_1):M_B_CPU1_SB_CA(5)    I25 @S9S_MB_2U_LIB.S9S_MB_2U(SCH_1):PAGE100
   215 M_B_CPU1_SA_CA<5> @S9S_MB_2U_LIB.S9S_MB_2U(SCH_1):M_B_CPU1_SA_CA(5)    I25 @S9S_MB_2U_LIB.S9S_MB_2U(SCH_1):PAGE100
    80 M_B_CPU1_SB_CA<4> @S9S_MB_2U_LIB.S9S_MB_2U(SCH_1):M_B_CPU1_SB_CA(4)    I25 @S9S_MB_2U_LIB.S9S_MB_2U(SCH_1):PAGE100
    70 M_B_CPU1_SA_CA<4> @S9S_MB_2U_LIB.S9S_MB_2U(SCH_1):M_B_CPU1_SA_CA(4)    I25 @S9S_MB_2U_LIB.S9S_MB_2U(SCH_1):PAGE100
   223 M_B_CPU1_SB_CA<3> @S9S_MB_2U_LIB.S9S_MB_2U(SCH_1):M_B_CPU1_SB_CA(3)    I25 @S9S_MB_2U_LIB.S9S_MB_2U(SCH_1):PAGE100
   213 M_B_CPU1_SA_CA<3> @S9S_MB_2U_LIB.S9S_MB_2U(SCH_1):M_B_CPU1_SA_CA(3)    I25 @S9S_MB_2U_LIB.S9S_MB_2U(SCH_1):PAGE100
    78 M_B_CPU1_SB_CA<2> @S9S_MB_2U_LIB.S9S_MB_2U(SCH_1):M_B_CPU1_SB_CA(2)    I25 @S9S_MB_2U_LIB.S9S_MB_2U(SCH_1):PAGE100
    68 M_B_CPU1_SA_CA<2> @S9S_MB_2U_LIB.S9S_MB_2U(SCH_1):M_B_CPU1_SA_CA(2)    I25 @S9S_MB_2U_LIB.S9S_MB_2U(SCH_1):PAGE100
   221 M_B_CPU1_SB_CA<1> @S9S_MB_2U_LIB.S9S_MB_2U(SCH_1):M_B_CPU1_SB_CA(1)    I25 @S9S_MB_2U_LIB.S9S_MB_2U(SCH_1):PAGE100
   211 M_B_CPU1_SA_CA<1> @S9S_MB_2U_LIB.S9S_MB_2U(SCH_1):M_B_CPU1_SA_CA(1)    I25 @S9S_MB_2U_LIB.S9S_MB_2U(SCH_1):PAGE100
    76 M_B_CPU1_SB_CA<0> @S9S_MB_2U_LIB.S9S_MB_2U(SCH_1):M_B_CPU1_SB_CA(0)    I25 @S9S_MB_2U_LIB.S9S_MB_2U(SCH_1):PAGE100
    66 M_B_CPU1_SA_CA<0> @S9S_MB_2U_LIB.S9S_MB_2U(SCH_1):M_B_CPU1_SA_CA(0)    I25 @S9S_MB_2U_LIB.S9S_MB_2U(SCH_1):PAGE100
    62 M_B_CPU1_ALERT_N @S9S_MB_2U_LIB.S9S_MB_2U(SCH_1):M_B_CPU1_ALERT_N    I25 @S9S_MB_2U_LIB.S9S_MB_2U(SCH_1):PAGE100
   236 M_B_CPU1_SB_CB<7> @S9S_MB_2U_LIB.S9S_MB_2U(SCH_1):M_B_CPU1_SB_CB(7)    I25 @S9S_MB_2U_LIB.S9S_MB_2U(SCH_1):PAGE100
    53 M_B_CPU1_SA_CB<1> @S9S_MB_2U_LIB.S9S_MB_2U(SCH_1):M_B_CPU1_SA_CB(1)    I25 @S9S_MB_2U_LIB.S9S_MB_2U(SCH_1):PAGE100
    58 M_B_CPU1_SA_CB<4> @S9S_MB_2U_LIB.S9S_MB_2U(SCH_1):M_B_CPU1_SA_CB(4)    I25 @S9S_MB_2U_LIB.S9S_MB_2U(SCH_1):PAGE100
   205 M_B_CPU1_SA_CB<7> @S9S_MB_2U_LIB.S9S_MB_2U(SCH_1):M_B_CPU1_SA_CB(7)    I25 @S9S_MB_2U_LIB.S9S_MB_2U(SCH_1):PAGE100
   194 M_B_CPU1_SA_DQ<31> @S9S_MB_2U_LIB.S9S_MB_2U(SCH_1):M_B_CPU1_SA_DQ(31)    I25 @S9S_MB_2U_LIB.S9S_MB_2U(SCH_1):PAGE100
    93 M_B_CPU1_SB_DQS_DP<9> @S9S_MB_2U_LIB.S9S_MB_2U(SCH_1):M_B_CPU1_SB_DQS_DP(9)   I178 @S9S_MB_2U_LIB.S9S_MB_2U(SCH_1):PAGE100
    94 M_B_CPU1_SB_DQS_DN<9> @S9S_MB_2U_LIB.S9S_MB_2U(SCH_1):M_B_CPU1_SB_DQS_DN(9)   I178 @S9S_MB_2U_LIB.S9S_MB_2U(SCH_1):PAGE100
   201 M_B_CPU1_SA_DQS_DP<9> @S9S_MB_2U_LIB.S9S_MB_2U(SCH_1):M_B_CPU1_SA_DQS_DP(9)   I178 @S9S_MB_2U_LIB.S9S_MB_2U(SCH_1):PAGE100
   200 M_B_CPU1_SA_DQS_DN<9> @S9S_MB_2U_LIB.S9S_MB_2U(SCH_1):M_B_CPU1_SA_DQS_DN(9)   I178 @S9S_MB_2U_LIB.S9S_MB_2U(SCH_1):PAGE100
   190 M_B_CPU1_SA_DQS_DP<8> @S9S_MB_2U_LIB.S9S_MB_2U(SCH_1):M_B_CPU1_SA_DQS_DP(8)   I178 @S9S_MB_2U_LIB.S9S_MB_2U(SCH_1):PAGE100
   189 M_B_CPU1_SA_DQS_DN<8> @S9S_MB_2U_LIB.S9S_MB_2U(SCH_1):M_B_CPU1_SA_DQS_DN(8)   I178 @S9S_MB_2U_LIB.S9S_MB_2U(SCH_1):PAGE100
   271 M_B_CPU1_SB_DQS_DN<7> @S9S_MB_2U_LIB.S9S_MB_2U(SCH_1):M_B_CPU1_SB_DQS_DN(7)   I178 @S9S_MB_2U_LIB.S9S_MB_2U(SCH_1):PAGE100
   179 M_B_CPU1_SA_DQS_DP<7> @S9S_MB_2U_LIB.S9S_MB_2U(SCH_1):M_B_CPU1_SA_DQS_DP(7)   I178 @S9S_MB_2U_LIB.S9S_MB_2U(SCH_1):PAGE100
   261 M_B_CPU1_SB_DQS_DP<6> @S9S_MB_2U_LIB.S9S_MB_2U(SCH_1):M_B_CPU1_SB_DQS_DP(6)   I178 @S9S_MB_2U_LIB.S9S_MB_2U(SCH_1):PAGE100
   260 M_B_CPU1_SB_DQS_DN<6> @S9S_MB_2U_LIB.S9S_MB_2U(SCH_1):M_B_CPU1_SB_DQS_DN(6)   I178 @S9S_MB_2U_LIB.S9S_MB_2U(SCH_1):PAGE100
   167 M_B_CPU1_SA_DQS_DN<6> @S9S_MB_2U_LIB.S9S_MB_2U(SCH_1):M_B_CPU1_SA_DQS_DN(6)   I178 @S9S_MB_2U_LIB.S9S_MB_2U(SCH_1):PAGE100
   250 M_B_CPU1_SB_DQS_DP<5> @S9S_MB_2U_LIB.S9S_MB_2U(SCH_1):M_B_CPU1_SB_DQS_DP(5)   I178 @S9S_MB_2U_LIB.S9S_MB_2U(SCH_1):PAGE100
   249 M_B_CPU1_SB_DQS_DN<5> @S9S_MB_2U_LIB.S9S_MB_2U(SCH_1):M_B_CPU1_SB_DQS_DN(5)   I178 @S9S_MB_2U_LIB.S9S_MB_2U(SCH_1):PAGE100
   157 M_B_CPU1_SA_DQS_DP<5> @S9S_MB_2U_LIB.S9S_MB_2U(SCH_1):M_B_CPU1_SA_DQS_DP(5)   I178 @S9S_MB_2U_LIB.S9S_MB_2U(SCH_1):PAGE100
   156 M_B_CPU1_SA_DQS_DN<5> @S9S_MB_2U_LIB.S9S_MB_2U(SCH_1):M_B_CPU1_SA_DQS_DN(5)   I178 @S9S_MB_2U_LIB.S9S_MB_2U(SCH_1):PAGE100
   239 M_B_CPU1_SB_DQS_DP<4> @S9S_MB_2U_LIB.S9S_MB_2U(SCH_1):M_B_CPU1_SB_DQS_DP(4)   I178 @S9S_MB_2U_LIB.S9S_MB_2U(SCH_1):PAGE100
   238 M_B_CPU1_SB_DQS_DN<4> @S9S_MB_2U_LIB.S9S_MB_2U(SCH_1):M_B_CPU1_SB_DQS_DN(4)   I178 @S9S_MB_2U_LIB.S9S_MB_2U(SCH_1):PAGE100
    55 M_B_CPU1_SA_DQS_DP<4> @S9S_MB_2U_LIB.S9S_MB_2U(SCH_1):M_B_CPU1_SA_DQS_DP(4)   I178 @S9S_MB_2U_LIB.S9S_MB_2U(SCH_1):PAGE100
    56 M_B_CPU1_SA_DQS_DN<4> @S9S_MB_2U_LIB.S9S_MB_2U(SCH_1):M_B_CPU1_SA_DQS_DN(4)   I178 @S9S_MB_2U_LIB.S9S_MB_2U(SCH_1):PAGE100
   137 M_B_CPU1_SB_DQS_DP<3> @S9S_MB_2U_LIB.S9S_MB_2U(SCH_1):M_B_CPU1_SB_DQS_DP(3)   I178 @S9S_MB_2U_LIB.S9S_MB_2U(SCH_1):PAGE100
   138 M_B_CPU1_SB_DQS_DN<3> @S9S_MB_2U_LIB.S9S_MB_2U(SCH_1):M_B_CPU1_SB_DQS_DN(3)   I178 @S9S_MB_2U_LIB.S9S_MB_2U(SCH_1):PAGE100
    44 M_B_CPU1_SA_DQS_DP<3> @S9S_MB_2U_LIB.S9S_MB_2U(SCH_1):M_B_CPU1_SA_DQS_DP(3)   I178 @S9S_MB_2U_LIB.S9S_MB_2U(SCH_1):PAGE100
    45 M_B_CPU1_SA_DQS_DN<3> @S9S_MB_2U_LIB.S9S_MB_2U(SCH_1):M_B_CPU1_SA_DQS_DN(3)   I178 @S9S_MB_2U_LIB.S9S_MB_2U(SCH_1):PAGE100
   126 M_B_CPU1_SB_DQS_DP<2> @S9S_MB_2U_LIB.S9S_MB_2U(SCH_1):M_B_CPU1_SB_DQS_DP(2)   I178 @S9S_MB_2U_LIB.S9S_MB_2U(SCH_1):PAGE100
   127 M_B_CPU1_SB_DQS_DN<2> @S9S_MB_2U_LIB.S9S_MB_2U(SCH_1):M_B_CPU1_SB_DQS_DN(2)   I178 @S9S_MB_2U_LIB.S9S_MB_2U(SCH_1):PAGE100
    33 M_B_CPU1_SA_DQS_DP<2> @S9S_MB_2U_LIB.S9S_MB_2U(SCH_1):M_B_CPU1_SA_DQS_DP(2)   I178 @S9S_MB_2U_LIB.S9S_MB_2U(SCH_1):PAGE100
    34 M_B_CPU1_SA_DQS_DN<2> @S9S_MB_2U_LIB.S9S_MB_2U(SCH_1):M_B_CPU1_SA_DQS_DN(2)   I178 @S9S_MB_2U_LIB.S9S_MB_2U(SCH_1):PAGE100
   115 M_B_CPU1_SB_DQS_DP<1> @S9S_MB_2U_LIB.S9S_MB_2U(SCH_1):M_B_CPU1_SB_DQS_DP(1)   I178 @S9S_MB_2U_LIB.S9S_MB_2U(SCH_1):PAGE100
   116 M_B_CPU1_SB_DQS_DN<1> @S9S_MB_2U_LIB.S9S_MB_2U(SCH_1):M_B_CPU1_SB_DQS_DN(1)   I178 @S9S_MB_2U_LIB.S9S_MB_2U(SCH_1):PAGE100
    22 M_B_CPU1_SA_DQS_DP<1> @S9S_MB_2U_LIB.S9S_MB_2U(SCH_1):M_B_CPU1_SA_DQS_DP(1)   I178 @S9S_MB_2U_LIB.S9S_MB_2U(SCH_1):PAGE100
    23 M_B_CPU1_SA_DQS_DN<1> @S9S_MB_2U_LIB.S9S_MB_2U(SCH_1):M_B_CPU1_SA_DQS_DN(1)   I178 @S9S_MB_2U_LIB.S9S_MB_2U(SCH_1):PAGE100
   104 M_B_CPU1_SB_DQS_DP<0> @S9S_MB_2U_LIB.S9S_MB_2U(SCH_1):M_B_CPU1_SB_DQS_DP(0)   I178 @S9S_MB_2U_LIB.S9S_MB_2U(SCH_1):PAGE100
   105 M_B_CPU1_SB_DQS_DN<0> @S9S_MB_2U_LIB.S9S_MB_2U(SCH_1):M_B_CPU1_SB_DQS_DN(0)   I178 @S9S_MB_2U_LIB.S9S_MB_2U(SCH_1):PAGE100
    11 M_B_CPU1_SA_DQS_DP<0> @S9S_MB_2U_LIB.S9S_MB_2U(SCH_1):M_B_CPU1_SA_DQS_DP(0)   I178 @S9S_MB_2U_LIB.S9S_MB_2U(SCH_1):PAGE100
    12 M_B_CPU1_SA_DQS_DN<0> @S9S_MB_2U_LIB.S9S_MB_2U(SCH_1):M_B_CPU1_SA_DQS_DN(0)   I178 @S9S_MB_2U_LIB.S9S_MB_2U(SCH_1):PAGE100
   272 M_B_CPU1_SB_DQS_DP<7> @S9S_MB_2U_LIB.S9S_MB_2U(SCH_1):M_B_CPU1_SB_DQS_DP(7)   I178 @S9S_MB_2U_LIB.S9S_MB_2U(SCH_1):PAGE100
   282 M_B_CPU1_SB_DQS_DN<8> @S9S_MB_2U_LIB.S9S_MB_2U(SCH_1):M_B_CPU1_SB_DQS_DN(8)   I178 @S9S_MB_2U_LIB.S9S_MB_2U(SCH_1):PAGE100
   283 M_B_CPU1_SB_DQS_DP<8> @S9S_MB_2U_LIB.S9S_MB_2U(SCH_1):M_B_CPU1_SB_DQS_DP(8)   I178 @S9S_MB_2U_LIB.S9S_MB_2U(SCH_1):PAGE100
   168 M_B_CPU1_SA_DQS_DP<6> @S9S_MB_2U_LIB.S9S_MB_2U(SCH_1):M_B_CPU1_SA_DQS_DP(6)   I178 @S9S_MB_2U_LIB.S9S_MB_2U(SCH_1):PAGE100
   178 M_B_CPU1_SA_DQS_DN<7> @S9S_MB_2U_LIB.S9S_MB_2U(SCH_1):M_B_CPU1_SA_DQS_DN(7)   I178 @S9S_MB_2U_LIB.S9S_MB_2U(SCH_1):PAGE100
     6    GND @S9S_MB_2U_LIB.S9S_MB_2U(SCH_1):GND   I175 @S9S_MB_2U_LIB.S9S_MB_2U(SCH_1):PAGE100
     8    GND @S9S_MB_2U_LIB.S9S_MB_2U(SCH_1):GND   I175 @S9S_MB_2U_LIB.S9S_MB_2U(SCH_1):PAGE100
    10    GND @S9S_MB_2U_LIB.S9S_MB_2U(SCH_1):GND   I175 @S9S_MB_2U_LIB.S9S_MB_2U(SCH_1):PAGE100
    13    GND @S9S_MB_2U_LIB.S9S_MB_2U(SCH_1):GND   I175 @S9S_MB_2U_LIB.S9S_MB_2U(SCH_1):PAGE100
    15    GND @S9S_MB_2U_LIB.S9S_MB_2U(SCH_1):GND   I175 @S9S_MB_2U_LIB.S9S_MB_2U(SCH_1):PAGE100
    17    GND @S9S_MB_2U_LIB.S9S_MB_2U(SCH_1):GND   I175 @S9S_MB_2U_LIB.S9S_MB_2U(SCH_1):PAGE100
    19    GND @S9S_MB_2U_LIB.S9S_MB_2U(SCH_1):GND   I175 @S9S_MB_2U_LIB.S9S_MB_2U(SCH_1):PAGE100
    21    GND @S9S_MB_2U_LIB.S9S_MB_2U(SCH_1):GND   I175 @S9S_MB_2U_LIB.S9S_MB_2U(SCH_1):PAGE100
    24    GND @S9S_MB_2U_LIB.S9S_MB_2U(SCH_1):GND   I175 @S9S_MB_2U_LIB.S9S_MB_2U(SCH_1):PAGE100
    26    GND @S9S_MB_2U_LIB.S9S_MB_2U(SCH_1):GND   I175 @S9S_MB_2U_LIB.S9S_MB_2U(SCH_1):PAGE100
    28    GND @S9S_MB_2U_LIB.S9S_MB_2U(SCH_1):GND   I175 @S9S_MB_2U_LIB.S9S_MB_2U(SCH_1):PAGE100
    30    GND @S9S_MB_2U_LIB.S9S_MB_2U(SCH_1):GND   I175 @S9S_MB_2U_LIB.S9S_MB_2U(SCH_1):PAGE100
    32    GND @S9S_MB_2U_LIB.S9S_MB_2U(SCH_1):GND   I175 @S9S_MB_2U_LIB.S9S_MB_2U(SCH_1):PAGE100
    35    GND @S9S_MB_2U_LIB.S9S_MB_2U(SCH_1):GND   I175 @S9S_MB_2U_LIB.S9S_MB_2U(SCH_1):PAGE100
    37    GND @S9S_MB_2U_LIB.S9S_MB_2U(SCH_1):GND   I175 @S9S_MB_2U_LIB.S9S_MB_2U(SCH_1):PAGE100
    39    GND @S9S_MB_2U_LIB.S9S_MB_2U(SCH_1):GND   I175 @S9S_MB_2U_LIB.S9S_MB_2U(SCH_1):PAGE100
    41    GND @S9S_MB_2U_LIB.S9S_MB_2U(SCH_1):GND   I175 @S9S_MB_2U_LIB.S9S_MB_2U(SCH_1):PAGE100
    43    GND @S9S_MB_2U_LIB.S9S_MB_2U(SCH_1):GND   I175 @S9S_MB_2U_LIB.S9S_MB_2U(SCH_1):PAGE100
    46    GND @S9S_MB_2U_LIB.S9S_MB_2U(SCH_1):GND   I175 @S9S_MB_2U_LIB.S9S_MB_2U(SCH_1):PAGE100
    48    GND @S9S_MB_2U_LIB.S9S_MB_2U(SCH_1):GND   I175 @S9S_MB_2U_LIB.S9S_MB_2U(SCH_1):PAGE100
    50    GND @S9S_MB_2U_LIB.S9S_MB_2U(SCH_1):GND   I175 @S9S_MB_2U_LIB.S9S_MB_2U(SCH_1):PAGE100
    52    GND @S9S_MB_2U_LIB.S9S_MB_2U(SCH_1):GND   I175 @S9S_MB_2U_LIB.S9S_MB_2U(SCH_1):PAGE100
    54    GND @S9S_MB_2U_LIB.S9S_MB_2U(SCH_1):GND   I175 @S9S_MB_2U_LIB.S9S_MB_2U(SCH_1):PAGE100
    57    GND @S9S_MB_2U_LIB.S9S_MB_2U(SCH_1):GND   I175 @S9S_MB_2U_LIB.S9S_MB_2U(SCH_1):PAGE100
    59    GND @S9S_MB_2U_LIB.S9S_MB_2U(SCH_1):GND   I175 @S9S_MB_2U_LIB.S9S_MB_2U(SCH_1):PAGE100
    61    GND @S9S_MB_2U_LIB.S9S_MB_2U(SCH_1):GND   I175 @S9S_MB_2U_LIB.S9S_MB_2U(SCH_1):PAGE100
    63    GND @S9S_MB_2U_LIB.S9S_MB_2U(SCH_1):GND   I175 @S9S_MB_2U_LIB.S9S_MB_2U(SCH_1):PAGE100
    65    GND @S9S_MB_2U_LIB.S9S_MB_2U(SCH_1):GND   I175 @S9S_MB_2U_LIB.S9S_MB_2U(SCH_1):PAGE100
    67    GND @S9S_MB_2U_LIB.S9S_MB_2U(SCH_1):GND   I175 @S9S_MB_2U_LIB.S9S_MB_2U(SCH_1):PAGE100
    69    GND @S9S_MB_2U_LIB.S9S_MB_2U(SCH_1):GND   I175 @S9S_MB_2U_LIB.S9S_MB_2U(SCH_1):PAGE100
    71    GND @S9S_MB_2U_LIB.S9S_MB_2U(SCH_1):GND   I175 @S9S_MB_2U_LIB.S9S_MB_2U(SCH_1):PAGE100
    73    GND @S9S_MB_2U_LIB.S9S_MB_2U(SCH_1):GND   I175 @S9S_MB_2U_LIB.S9S_MB_2U(SCH_1):PAGE100
    75    GND @S9S_MB_2U_LIB.S9S_MB_2U(SCH_1):GND   I175 @S9S_MB_2U_LIB.S9S_MB_2U(SCH_1):PAGE100
    77    GND @S9S_MB_2U_LIB.S9S_MB_2U(SCH_1):GND   I175 @S9S_MB_2U_LIB.S9S_MB_2U(SCH_1):PAGE100
    79    GND @S9S_MB_2U_LIB.S9S_MB_2U(SCH_1):GND   I175 @S9S_MB_2U_LIB.S9S_MB_2U(SCH_1):PAGE100
    81    GND @S9S_MB_2U_LIB.S9S_MB_2U(SCH_1):GND   I175 @S9S_MB_2U_LIB.S9S_MB_2U(SCH_1):PAGE100
    83    GND @S9S_MB_2U_LIB.S9S_MB_2U(SCH_1):GND   I175 @S9S_MB_2U_LIB.S9S_MB_2U(SCH_1):PAGE100
    85    GND @S9S_MB_2U_LIB.S9S_MB_2U(SCH_1):GND   I175 @S9S_MB_2U_LIB.S9S_MB_2U(SCH_1):PAGE100
    88    GND @S9S_MB_2U_LIB.S9S_MB_2U(SCH_1):GND   I175 @S9S_MB_2U_LIB.S9S_MB_2U(SCH_1):PAGE100
    90    GND @S9S_MB_2U_LIB.S9S_MB_2U(SCH_1):GND   I175 @S9S_MB_2U_LIB.S9S_MB_2U(SCH_1):PAGE100
    92    GND @S9S_MB_2U_LIB.S9S_MB_2U(SCH_1):GND   I175 @S9S_MB_2U_LIB.S9S_MB_2U(SCH_1):PAGE100
    95    GND @S9S_MB_2U_LIB.S9S_MB_2U(SCH_1):GND   I175 @S9S_MB_2U_LIB.S9S_MB_2U(SCH_1):PAGE100
    97    GND @S9S_MB_2U_LIB.S9S_MB_2U(SCH_1):GND   I175 @S9S_MB_2U_LIB.S9S_MB_2U(SCH_1):PAGE100
    99    GND @S9S_MB_2U_LIB.S9S_MB_2U(SCH_1):GND   I175 @S9S_MB_2U_LIB.S9S_MB_2U(SCH_1):PAGE100
   101    GND @S9S_MB_2U_LIB.S9S_MB_2U(SCH_1):GND   I175 @S9S_MB_2U_LIB.S9S_MB_2U(SCH_1):PAGE100
   103    GND @S9S_MB_2U_LIB.S9S_MB_2U(SCH_1):GND   I175 @S9S_MB_2U_LIB.S9S_MB_2U(SCH_1):PAGE100
   106    GND @S9S_MB_2U_LIB.S9S_MB_2U(SCH_1):GND   I175 @S9S_MB_2U_LIB.S9S_MB_2U(SCH_1):PAGE100
   108    GND @S9S_MB_2U_LIB.S9S_MB_2U(SCH_1):GND   I175 @S9S_MB_2U_LIB.S9S_MB_2U(SCH_1):PAGE100
   110    GND @S9S_MB_2U_LIB.S9S_MB_2U(SCH_1):GND   I175 @S9S_MB_2U_LIB.S9S_MB_2U(SCH_1):PAGE100
   112    GND @S9S_MB_2U_LIB.S9S_MB_2U(SCH_1):GND   I175 @S9S_MB_2U_LIB.S9S_MB_2U(SCH_1):PAGE100
   114    GND @S9S_MB_2U_LIB.S9S_MB_2U(SCH_1):GND   I175 @S9S_MB_2U_LIB.S9S_MB_2U(SCH_1):PAGE100
   117    GND @S9S_MB_2U_LIB.S9S_MB_2U(SCH_1):GND   I175 @S9S_MB_2U_LIB.S9S_MB_2U(SCH_1):PAGE100
   119    GND @S9S_MB_2U_LIB.S9S_MB_2U(SCH_1):GND   I175 @S9S_MB_2U_LIB.S9S_MB_2U(SCH_1):PAGE100
   121    GND @S9S_MB_2U_LIB.S9S_MB_2U(SCH_1):GND   I175 @S9S_MB_2U_LIB.S9S_MB_2U(SCH_1):PAGE100
   123    GND @S9S_MB_2U_LIB.S9S_MB_2U(SCH_1):GND   I175 @S9S_MB_2U_LIB.S9S_MB_2U(SCH_1):PAGE100
   125    GND @S9S_MB_2U_LIB.S9S_MB_2U(SCH_1):GND   I175 @S9S_MB_2U_LIB.S9S_MB_2U(SCH_1):PAGE100
   128    GND @S9S_MB_2U_LIB.S9S_MB_2U(SCH_1):GND   I175 @S9S_MB_2U_LIB.S9S_MB_2U(SCH_1):PAGE100
   130    GND @S9S_MB_2U_LIB.S9S_MB_2U(SCH_1):GND   I175 @S9S_MB_2U_LIB.S9S_MB_2U(SCH_1):PAGE100
   134    GND @S9S_MB_2U_LIB.S9S_MB_2U(SCH_1):GND   I175 @S9S_MB_2U_LIB.S9S_MB_2U(SCH_1):PAGE100
   143    GND @S9S_MB_2U_LIB.S9S_MB_2U(SCH_1):GND   I175 @S9S_MB_2U_LIB.S9S_MB_2U(SCH_1):PAGE100
   151    GND @S9S_MB_2U_LIB.S9S_MB_2U(SCH_1):GND   I175 @S9S_MB_2U_LIB.S9S_MB_2U(SCH_1):PAGE100
   153    GND @S9S_MB_2U_LIB.S9S_MB_2U(SCH_1):GND   I175 @S9S_MB_2U_LIB.S9S_MB_2U(SCH_1):PAGE100
   155    GND @S9S_MB_2U_LIB.S9S_MB_2U(SCH_1):GND   I175 @S9S_MB_2U_LIB.S9S_MB_2U(SCH_1):PAGE100
   158    GND @S9S_MB_2U_LIB.S9S_MB_2U(SCH_1):GND   I175 @S9S_MB_2U_LIB.S9S_MB_2U(SCH_1):PAGE100
   160    GND @S9S_MB_2U_LIB.S9S_MB_2U(SCH_1):GND   I175 @S9S_MB_2U_LIB.S9S_MB_2U(SCH_1):PAGE100
   162    GND @S9S_MB_2U_LIB.S9S_MB_2U(SCH_1):GND   I175 @S9S_MB_2U_LIB.S9S_MB_2U(SCH_1):PAGE100
   164    GND @S9S_MB_2U_LIB.S9S_MB_2U(SCH_1):GND   I175 @S9S_MB_2U_LIB.S9S_MB_2U(SCH_1):PAGE100
   166    GND @S9S_MB_2U_LIB.S9S_MB_2U(SCH_1):GND   I175 @S9S_MB_2U_LIB.S9S_MB_2U(SCH_1):PAGE100
   169    GND @S9S_MB_2U_LIB.S9S_MB_2U(SCH_1):GND   I175 @S9S_MB_2U_LIB.S9S_MB_2U(SCH_1):PAGE100
   171    GND @S9S_MB_2U_LIB.S9S_MB_2U(SCH_1):GND   I175 @S9S_MB_2U_LIB.S9S_MB_2U(SCH_1):PAGE100
   173    GND @S9S_MB_2U_LIB.S9S_MB_2U(SCH_1):GND   I175 @S9S_MB_2U_LIB.S9S_MB_2U(SCH_1):PAGE100
   175    GND @S9S_MB_2U_LIB.S9S_MB_2U(SCH_1):GND   I175 @S9S_MB_2U_LIB.S9S_MB_2U(SCH_1):PAGE100
   177    GND @S9S_MB_2U_LIB.S9S_MB_2U(SCH_1):GND   I175 @S9S_MB_2U_LIB.S9S_MB_2U(SCH_1):PAGE100
   180    GND @S9S_MB_2U_LIB.S9S_MB_2U(SCH_1):GND   I175 @S9S_MB_2U_LIB.S9S_MB_2U(SCH_1):PAGE100
   182    GND @S9S_MB_2U_LIB.S9S_MB_2U(SCH_1):GND   I175 @S9S_MB_2U_LIB.S9S_MB_2U(SCH_1):PAGE100
   184    GND @S9S_MB_2U_LIB.S9S_MB_2U(SCH_1):GND   I175 @S9S_MB_2U_LIB.S9S_MB_2U(SCH_1):PAGE100
   186    GND @S9S_MB_2U_LIB.S9S_MB_2U(SCH_1):GND   I175 @S9S_MB_2U_LIB.S9S_MB_2U(SCH_1):PAGE100
   188    GND @S9S_MB_2U_LIB.S9S_MB_2U(SCH_1):GND   I175 @S9S_MB_2U_LIB.S9S_MB_2U(SCH_1):PAGE100
   191    GND @S9S_MB_2U_LIB.S9S_MB_2U(SCH_1):GND   I175 @S9S_MB_2U_LIB.S9S_MB_2U(SCH_1):PAGE100
   193    GND @S9S_MB_2U_LIB.S9S_MB_2U(SCH_1):GND   I175 @S9S_MB_2U_LIB.S9S_MB_2U(SCH_1):PAGE100
   195    GND @S9S_MB_2U_LIB.S9S_MB_2U(SCH_1):GND   I175 @S9S_MB_2U_LIB.S9S_MB_2U(SCH_1):PAGE100
   197    GND @S9S_MB_2U_LIB.S9S_MB_2U(SCH_1):GND   I175 @S9S_MB_2U_LIB.S9S_MB_2U(SCH_1):PAGE100
   199    GND @S9S_MB_2U_LIB.S9S_MB_2U(SCH_1):GND   I175 @S9S_MB_2U_LIB.S9S_MB_2U(SCH_1):PAGE100
   202    GND @S9S_MB_2U_LIB.S9S_MB_2U(SCH_1):GND   I175 @S9S_MB_2U_LIB.S9S_MB_2U(SCH_1):PAGE100
   204    GND @S9S_MB_2U_LIB.S9S_MB_2U(SCH_1):GND   I175 @S9S_MB_2U_LIB.S9S_MB_2U(SCH_1):PAGE100
   206    GND @S9S_MB_2U_LIB.S9S_MB_2U(SCH_1):GND   I175 @S9S_MB_2U_LIB.S9S_MB_2U(SCH_1):PAGE100
   208    GND @S9S_MB_2U_LIB.S9S_MB_2U(SCH_1):GND   I175 @S9S_MB_2U_LIB.S9S_MB_2U(SCH_1):PAGE100
   210    GND @S9S_MB_2U_LIB.S9S_MB_2U(SCH_1):GND   I175 @S9S_MB_2U_LIB.S9S_MB_2U(SCH_1):PAGE100
   212    GND @S9S_MB_2U_LIB.S9S_MB_2U(SCH_1):GND   I175 @S9S_MB_2U_LIB.S9S_MB_2U(SCH_1):PAGE100
   214    GND @S9S_MB_2U_LIB.S9S_MB_2U(SCH_1):GND   I175 @S9S_MB_2U_LIB.S9S_MB_2U(SCH_1):PAGE100
   216    GND @S9S_MB_2U_LIB.S9S_MB_2U(SCH_1):GND   I175 @S9S_MB_2U_LIB.S9S_MB_2U(SCH_1):PAGE100
   219    GND @S9S_MB_2U_LIB.S9S_MB_2U(SCH_1):GND   I175 @S9S_MB_2U_LIB.S9S_MB_2U(SCH_1):PAGE100
   222    GND @S9S_MB_2U_LIB.S9S_MB_2U(SCH_1):GND   I175 @S9S_MB_2U_LIB.S9S_MB_2U(SCH_1):PAGE100
   224    GND @S9S_MB_2U_LIB.S9S_MB_2U(SCH_1):GND   I175 @S9S_MB_2U_LIB.S9S_MB_2U(SCH_1):PAGE100
   226    GND @S9S_MB_2U_LIB.S9S_MB_2U(SCH_1):GND   I175 @S9S_MB_2U_LIB.S9S_MB_2U(SCH_1):PAGE100
   228    GND @S9S_MB_2U_LIB.S9S_MB_2U(SCH_1):GND   I175 @S9S_MB_2U_LIB.S9S_MB_2U(SCH_1):PAGE100
   233    GND @S9S_MB_2U_LIB.S9S_MB_2U(SCH_1):GND   I175 @S9S_MB_2U_LIB.S9S_MB_2U(SCH_1):PAGE100
   237    GND @S9S_MB_2U_LIB.S9S_MB_2U(SCH_1):GND   I175 @S9S_MB_2U_LIB.S9S_MB_2U(SCH_1):PAGE100
   242    GND @S9S_MB_2U_LIB.S9S_MB_2U(SCH_1):GND   I175 @S9S_MB_2U_LIB.S9S_MB_2U(SCH_1):PAGE100
   244    GND @S9S_MB_2U_LIB.S9S_MB_2U(SCH_1):GND   I175 @S9S_MB_2U_LIB.S9S_MB_2U(SCH_1):PAGE100
   246    GND @S9S_MB_2U_LIB.S9S_MB_2U(SCH_1):GND   I175 @S9S_MB_2U_LIB.S9S_MB_2U(SCH_1):PAGE100
   248    GND @S9S_MB_2U_LIB.S9S_MB_2U(SCH_1):GND   I175 @S9S_MB_2U_LIB.S9S_MB_2U(SCH_1):PAGE100
   251    GND @S9S_MB_2U_LIB.S9S_MB_2U(SCH_1):GND   I175 @S9S_MB_2U_LIB.S9S_MB_2U(SCH_1):PAGE100
   253    GND @S9S_MB_2U_LIB.S9S_MB_2U(SCH_1):GND   I175 @S9S_MB_2U_LIB.S9S_MB_2U(SCH_1):PAGE100
   255    GND @S9S_MB_2U_LIB.S9S_MB_2U(SCH_1):GND   I175 @S9S_MB_2U_LIB.S9S_MB_2U(SCH_1):PAGE100
   257    GND @S9S_MB_2U_LIB.S9S_MB_2U(SCH_1):GND   I175 @S9S_MB_2U_LIB.S9S_MB_2U(SCH_1):PAGE100
   259    GND @S9S_MB_2U_LIB.S9S_MB_2U(SCH_1):GND   I175 @S9S_MB_2U_LIB.S9S_MB_2U(SCH_1):PAGE100
   262    GND @S9S_MB_2U_LIB.S9S_MB_2U(SCH_1):GND   I175 @S9S_MB_2U_LIB.S9S_MB_2U(SCH_1):PAGE100
   264    GND @S9S_MB_2U_LIB.S9S_MB_2U(SCH_1):GND   I175 @S9S_MB_2U_LIB.S9S_MB_2U(SCH_1):PAGE100
   266    GND @S9S_MB_2U_LIB.S9S_MB_2U(SCH_1):GND   I175 @S9S_MB_2U_LIB.S9S_MB_2U(SCH_1):PAGE100
   268    GND @S9S_MB_2U_LIB.S9S_MB_2U(SCH_1):GND   I175 @S9S_MB_2U_LIB.S9S_MB_2U(SCH_1):PAGE100
   270    GND @S9S_MB_2U_LIB.S9S_MB_2U(SCH_1):GND   I175 @S9S_MB_2U_LIB.S9S_MB_2U(SCH_1):PAGE100
   273    GND @S9S_MB_2U_LIB.S9S_MB_2U(SCH_1):GND   I175 @S9S_MB_2U_LIB.S9S_MB_2U(SCH_1):PAGE100
   275    GND @S9S_MB_2U_LIB.S9S_MB_2U(SCH_1):GND   I175 @S9S_MB_2U_LIB.S9S_MB_2U(SCH_1):PAGE100
   277    GND @S9S_MB_2U_LIB.S9S_MB_2U(SCH_1):GND   I175 @S9S_MB_2U_LIB.S9S_MB_2U(SCH_1):PAGE100
   279    GND @S9S_MB_2U_LIB.S9S_MB_2U(SCH_1):GND   I175 @S9S_MB_2U_LIB.S9S_MB_2U(SCH_1):PAGE100
   281    GND @S9S_MB_2U_LIB.S9S_MB_2U(SCH_1):GND   I175 @S9S_MB_2U_LIB.S9S_MB_2U(SCH_1):PAGE100
   284    GND @S9S_MB_2U_LIB.S9S_MB_2U(SCH_1):GND   I175 @S9S_MB_2U_LIB.S9S_MB_2U(SCH_1):PAGE100
   286    GND @S9S_MB_2U_LIB.S9S_MB_2U(SCH_1):GND   I175 @S9S_MB_2U_LIB.S9S_MB_2U(SCH_1):PAGE100
   288    GND @S9S_MB_2U_LIB.S9S_MB_2U(SCH_1):GND   I175 @S9S_MB_2U_LIB.S9S_MB_2U(SCH_1):PAGE100
     1 P12V_S3_AUX_CPU1_NVDIMM @S9S_MB_2U_LIB.S9S_MB_2U(SCH_1):P12V_S3_AUX_CPU1_NVDIMM   I175 @S9S_MB_2U_LIB.S9S_MB_2U(SCH_1):PAGE100
   145 P12V_S3_AUX_CPU1_NVDIMM @S9S_MB_2U_LIB.S9S_MB_2U(SCH_1):P12V_S3_AUX_CPU1_NVDIMM   I175 @S9S_MB_2U_LIB.S9S_MB_2U(SCH_1):PAGE100
   146 P12V_S3_AUX_CPU1_NVDIMM @S9S_MB_2U_LIB.S9S_MB_2U(SCH_1):P12V_S3_AUX_CPU1_NVDIMM   I175 @S9S_MB_2U_LIB.S9S_MB_2U(SCH_1):PAGE100
   230    GND @S9S_MB_2U_LIB.S9S_MB_2U(SCH_1):GND   I175 @S9S_MB_2U_LIB.S9S_MB_2U(SCH_1):PAGE100
   235    GND @S9S_MB_2U_LIB.S9S_MB_2U(SCH_1):GND   I175 @S9S_MB_2U_LIB.S9S_MB_2U(SCH_1):PAGE100
   240    GND @S9S_MB_2U_LIB.S9S_MB_2U(SCH_1):GND   I175 @S9S_MB_2U_LIB.S9S_MB_2U(SCH_1):PAGE100
   132    GND @S9S_MB_2U_LIB.S9S_MB_2U(SCH_1):GND   I175 @S9S_MB_2U_LIB.S9S_MB_2U(SCH_1):PAGE100
   136    GND @S9S_MB_2U_LIB.S9S_MB_2U(SCH_1):GND   I175 @S9S_MB_2U_LIB.S9S_MB_2U(SCH_1):PAGE100
   139    GND @S9S_MB_2U_LIB.S9S_MB_2U(SCH_1):GND   I175 @S9S_MB_2U_LIB.S9S_MB_2U(SCH_1):PAGE100
   141    GND @S9S_MB_2U_LIB.S9S_MB_2U(SCH_1):GND   I175 @S9S_MB_2U_LIB.S9S_MB_2U(SCH_1):PAGE100
    G1    GND @S9S_MB_2U_LIB.S9S_MB_2U(SCH_1):GND   I175 @S9S_MB_2U_LIB.S9S_MB_2U(SCH_1):PAGE100
    G2    GND @S9S_MB_2U_LIB.S9S_MB_2U(SCH_1):GND   I175 @S9S_MB_2U_LIB.S9S_MB_2U(SCH_1):PAGE100
    G3    GND @S9S_MB_2U_LIB.S9S_MB_2U(SCH_1):GND   I175 @S9S_MB_2U_LIB.S9S_MB_2U(SCH_1):PAGE100

 J20 SCONN288_ADR50017P087CC-SCONN2A
     3 P3V3_AUX @S9S_MB_2U_LIB.S9S_MB_2U(SCH_1):P3V3_AUX    I47 @S9S_MB_2U_LIB.S9S_MB_2U(SCH_1):PAGE101
     2 TP_CHB_CPU1_DIMM2_FRU_0 @S9S_MB_2U_LIB.S9S_MB_2U(SCH_1):TP_CHB_CPU1_DIMM2_FRU_0    I47 @S9S_MB_2U_LIB.S9S_MB_2U(SCH_1):PAGE101
   144 TP_CHB_CPU1_DIMM2_FRU_1 @S9S_MB_2U_LIB.S9S_MB_2U(SCH_1):TP_CHB_CPU1_DIMM2_FRU_1    I47 @S9S_MB_2U_LIB.S9S_MB_2U(SCH_1):PAGE101
   149 TP_CHB_CPU1_DIMM2_FRU_2 @S9S_MB_2U_LIB.S9S_MB_2U(SCH_1):TP_CHB_CPU1_DIMM2_FRU_2    I47 @S9S_MB_2U_LIB.S9S_MB_2U(SCH_1):PAGE101
   150 TP_CHB_CPU1_DIMM2_FRU_3 @S9S_MB_2U_LIB.S9S_MB_2U(SCH_1):TP_CHB_CPU1_DIMM2_FRU_3    I47 @S9S_MB_2U_LIB.S9S_MB_2U(SCH_1):PAGE101
   220 TP_CHB_CPU1_DIMM2_FRU_4 @S9S_MB_2U_LIB.S9S_MB_2U(SCH_1):TP_CHB_CPU1_DIMM2_FRU_4    I47 @S9S_MB_2U_LIB.S9S_MB_2U(SCH_1):PAGE101
   231 TP_CHB_CPU1_DIMM2_FRU_5 @S9S_MB_2U_LIB.S9S_MB_2U(SCH_1):TP_CHB_CPU1_DIMM2_FRU_5    I47 @S9S_MB_2U_LIB.S9S_MB_2U(SCH_1):PAGE101
   232 TP_CHB_CPU1_DIMM2_FRU_6 @S9S_MB_2U_LIB.S9S_MB_2U(SCH_1):TP_CHB_CPU1_DIMM2_FRU_6    I47 @S9S_MB_2U_LIB.S9S_MB_2U(SCH_1):PAGE101
   207 RST_M_AB_CPU1_FPGA_N @S9S_MB_2U_LIB.S9S_MB_2U(SCH_1):RST_M_AB_CPU1_FPGA_N    I47 @S9S_MB_2U_LIB.S9S_MB_2U(SCH_1):PAGE101
   147 PWRGD_CHB_CPU1_DIMM2 @S9S_MB_2U_LIB.S9S_MB_2U(SCH_1):PWRGD_CHB_CPU1_DIMM2    I47 @S9S_MB_2U_LIB.S9S_MB_2U(SCH_1):PAGE101
   227 M_B_CPU1_SB_PAR @S9S_MB_2U_LIB.S9S_MB_2U(SCH_1):M_B_CPU1_SB_PAR    I47 @S9S_MB_2U_LIB.S9S_MB_2U(SCH_1):PAGE101
    74 M_B_CPU1_SA_PAR @S9S_MB_2U_LIB.S9S_MB_2U(SCH_1):M_B_CPU1_SA_PAR    I47 @S9S_MB_2U_LIB.S9S_MB_2U(SCH_1):PAGE101
    87 M_B_CPU1_SB_RSP<1> @S9S_MB_2U_LIB.S9S_MB_2U(SCH_1):M_B_CPU1_SB_RSP(1)    I47 @S9S_MB_2U_LIB.S9S_MB_2U(SCH_1):PAGE101
    86 M_B_CPU1_SA_RSP<1> @S9S_MB_2U_LIB.S9S_MB_2U(SCH_1):M_B_CPU1_SA_RSP(1)    I47 @S9S_MB_2U_LIB.S9S_MB_2U(SCH_1):PAGE101
     5 I3C_SPD_DDRABCD_CPU1_LVC1_SDA @S9S_MB_2U_LIB.S9S_MB_2U(SCH_1):I3C_SPD_DDRABCD_CPU1_LVC1_SDA    I47 @S9S_MB_2U_LIB.S9S_MB_2U(SCH_1):PAGE101
     4 I3C_SPD_DDRABCD_CPU1_LVC1_SCL_3 @S9S_MB_2U_LIB.S9S_MB_2U(SCH_1):I3C_SPD_DDRABCD_CPU1_LVC1_SCL_R4    I47 @S9S_MB_2U_LIB.S9S_MB_2U(SCH_1):PAGE101
   148 PD_CHB_CPU1_DIMM2_SAA @S9S_MB_2U_LIB.S9S_MB_2U(SCH_1):PD_CHB_CPU1_DIMM2_SAA    I47 @S9S_MB_2U_LIB.S9S_MB_2U(SCH_1):PAGE101
   100 M_B_CPU1_SB_DQ<0> @S9S_MB_2U_LIB.S9S_MB_2U(SCH_1):M_B_CPU1_SB_DQ(0)    I47 @S9S_MB_2U_LIB.S9S_MB_2U(SCH_1):PAGE101
   102 M_B_CPU1_SB_DQ<1> @S9S_MB_2U_LIB.S9S_MB_2U(SCH_1):M_B_CPU1_SB_DQ(1)    I47 @S9S_MB_2U_LIB.S9S_MB_2U(SCH_1):PAGE101
   245 M_B_CPU1_SB_DQ<2> @S9S_MB_2U_LIB.S9S_MB_2U(SCH_1):M_B_CPU1_SB_DQ(2)    I47 @S9S_MB_2U_LIB.S9S_MB_2U(SCH_1):PAGE101
   247 M_B_CPU1_SB_DQ<3> @S9S_MB_2U_LIB.S9S_MB_2U(SCH_1):M_B_CPU1_SB_DQ(3)    I47 @S9S_MB_2U_LIB.S9S_MB_2U(SCH_1):PAGE101
   107 M_B_CPU1_SB_DQ<4> @S9S_MB_2U_LIB.S9S_MB_2U(SCH_1):M_B_CPU1_SB_DQ(4)    I47 @S9S_MB_2U_LIB.S9S_MB_2U(SCH_1):PAGE101
   109 M_B_CPU1_SB_DQ<5> @S9S_MB_2U_LIB.S9S_MB_2U(SCH_1):M_B_CPU1_SB_DQ(5)    I47 @S9S_MB_2U_LIB.S9S_MB_2U(SCH_1):PAGE101
   252 M_B_CPU1_SB_DQ<6> @S9S_MB_2U_LIB.S9S_MB_2U(SCH_1):M_B_CPU1_SB_DQ(6)    I47 @S9S_MB_2U_LIB.S9S_MB_2U(SCH_1):PAGE101
   254 M_B_CPU1_SB_DQ<7> @S9S_MB_2U_LIB.S9S_MB_2U(SCH_1):M_B_CPU1_SB_DQ(7)    I47 @S9S_MB_2U_LIB.S9S_MB_2U(SCH_1):PAGE101
   111 M_B_CPU1_SB_DQ<8> @S9S_MB_2U_LIB.S9S_MB_2U(SCH_1):M_B_CPU1_SB_DQ(8)    I47 @S9S_MB_2U_LIB.S9S_MB_2U(SCH_1):PAGE101
   113 M_B_CPU1_SB_DQ<9> @S9S_MB_2U_LIB.S9S_MB_2U(SCH_1):M_B_CPU1_SB_DQ(9)    I47 @S9S_MB_2U_LIB.S9S_MB_2U(SCH_1):PAGE101
   256 M_B_CPU1_SB_DQ<10> @S9S_MB_2U_LIB.S9S_MB_2U(SCH_1):M_B_CPU1_SB_DQ(10)    I47 @S9S_MB_2U_LIB.S9S_MB_2U(SCH_1):PAGE101
   258 M_B_CPU1_SB_DQ<11> @S9S_MB_2U_LIB.S9S_MB_2U(SCH_1):M_B_CPU1_SB_DQ(11)    I47 @S9S_MB_2U_LIB.S9S_MB_2U(SCH_1):PAGE101
   118 M_B_CPU1_SB_DQ<12> @S9S_MB_2U_LIB.S9S_MB_2U(SCH_1):M_B_CPU1_SB_DQ(12)    I47 @S9S_MB_2U_LIB.S9S_MB_2U(SCH_1):PAGE101
   120 M_B_CPU1_SB_DQ<13> @S9S_MB_2U_LIB.S9S_MB_2U(SCH_1):M_B_CPU1_SB_DQ(13)    I47 @S9S_MB_2U_LIB.S9S_MB_2U(SCH_1):PAGE101
   263 M_B_CPU1_SB_DQ<14> @S9S_MB_2U_LIB.S9S_MB_2U(SCH_1):M_B_CPU1_SB_DQ(14)    I47 @S9S_MB_2U_LIB.S9S_MB_2U(SCH_1):PAGE101
   265 M_B_CPU1_SB_DQ<15> @S9S_MB_2U_LIB.S9S_MB_2U(SCH_1):M_B_CPU1_SB_DQ(15)    I47 @S9S_MB_2U_LIB.S9S_MB_2U(SCH_1):PAGE101
   122 M_B_CPU1_SB_DQ<16> @S9S_MB_2U_LIB.S9S_MB_2U(SCH_1):M_B_CPU1_SB_DQ(16)    I47 @S9S_MB_2U_LIB.S9S_MB_2U(SCH_1):PAGE101
   124 M_B_CPU1_SB_DQ<17> @S9S_MB_2U_LIB.S9S_MB_2U(SCH_1):M_B_CPU1_SB_DQ(17)    I47 @S9S_MB_2U_LIB.S9S_MB_2U(SCH_1):PAGE101
   267 M_B_CPU1_SB_DQ<18> @S9S_MB_2U_LIB.S9S_MB_2U(SCH_1):M_B_CPU1_SB_DQ(18)    I47 @S9S_MB_2U_LIB.S9S_MB_2U(SCH_1):PAGE101
   269 M_B_CPU1_SB_DQ<19> @S9S_MB_2U_LIB.S9S_MB_2U(SCH_1):M_B_CPU1_SB_DQ(19)    I47 @S9S_MB_2U_LIB.S9S_MB_2U(SCH_1):PAGE101
   129 M_B_CPU1_SB_DQ<20> @S9S_MB_2U_LIB.S9S_MB_2U(SCH_1):M_B_CPU1_SB_DQ(20)    I47 @S9S_MB_2U_LIB.S9S_MB_2U(SCH_1):PAGE101
   131 M_B_CPU1_SB_DQ<21> @S9S_MB_2U_LIB.S9S_MB_2U(SCH_1):M_B_CPU1_SB_DQ(21)    I47 @S9S_MB_2U_LIB.S9S_MB_2U(SCH_1):PAGE101
   274 M_B_CPU1_SB_DQ<22> @S9S_MB_2U_LIB.S9S_MB_2U(SCH_1):M_B_CPU1_SB_DQ(22)    I47 @S9S_MB_2U_LIB.S9S_MB_2U(SCH_1):PAGE101
   276 M_B_CPU1_SB_DQ<23> @S9S_MB_2U_LIB.S9S_MB_2U(SCH_1):M_B_CPU1_SB_DQ(23)    I47 @S9S_MB_2U_LIB.S9S_MB_2U(SCH_1):PAGE101
   133 M_B_CPU1_SB_DQ<24> @S9S_MB_2U_LIB.S9S_MB_2U(SCH_1):M_B_CPU1_SB_DQ(24)    I47 @S9S_MB_2U_LIB.S9S_MB_2U(SCH_1):PAGE101
   135 M_B_CPU1_SB_DQ<25> @S9S_MB_2U_LIB.S9S_MB_2U(SCH_1):M_B_CPU1_SB_DQ(25)    I47 @S9S_MB_2U_LIB.S9S_MB_2U(SCH_1):PAGE101
   278 M_B_CPU1_SB_DQ<26> @S9S_MB_2U_LIB.S9S_MB_2U(SCH_1):M_B_CPU1_SB_DQ(26)    I47 @S9S_MB_2U_LIB.S9S_MB_2U(SCH_1):PAGE101
   280 M_B_CPU1_SB_DQ<27> @S9S_MB_2U_LIB.S9S_MB_2U(SCH_1):M_B_CPU1_SB_DQ(27)    I47 @S9S_MB_2U_LIB.S9S_MB_2U(SCH_1):PAGE101
   140 M_B_CPU1_SB_DQ<28> @S9S_MB_2U_LIB.S9S_MB_2U(SCH_1):M_B_CPU1_SB_DQ(28)    I47 @S9S_MB_2U_LIB.S9S_MB_2U(SCH_1):PAGE101
   142 M_B_CPU1_SB_DQ<29> @S9S_MB_2U_LIB.S9S_MB_2U(SCH_1):M_B_CPU1_SB_DQ(29)    I47 @S9S_MB_2U_LIB.S9S_MB_2U(SCH_1):PAGE101
   285 M_B_CPU1_SB_DQ<30> @S9S_MB_2U_LIB.S9S_MB_2U(SCH_1):M_B_CPU1_SB_DQ(30)    I47 @S9S_MB_2U_LIB.S9S_MB_2U(SCH_1):PAGE101
   287 M_B_CPU1_SB_DQ<31> @S9S_MB_2U_LIB.S9S_MB_2U(SCH_1):M_B_CPU1_SB_DQ(31)    I47 @S9S_MB_2U_LIB.S9S_MB_2U(SCH_1):PAGE101
     7 M_B_CPU1_SA_DQ<0> @S9S_MB_2U_LIB.S9S_MB_2U(SCH_1):M_B_CPU1_SA_DQ(0)    I47 @S9S_MB_2U_LIB.S9S_MB_2U(SCH_1):PAGE101
     9 M_B_CPU1_SA_DQ<1> @S9S_MB_2U_LIB.S9S_MB_2U(SCH_1):M_B_CPU1_SA_DQ(1)    I47 @S9S_MB_2U_LIB.S9S_MB_2U(SCH_1):PAGE101
   152 M_B_CPU1_SA_DQ<2> @S9S_MB_2U_LIB.S9S_MB_2U(SCH_1):M_B_CPU1_SA_DQ(2)    I47 @S9S_MB_2U_LIB.S9S_MB_2U(SCH_1):PAGE101
   154 M_B_CPU1_SA_DQ<3> @S9S_MB_2U_LIB.S9S_MB_2U(SCH_1):M_B_CPU1_SA_DQ(3)    I47 @S9S_MB_2U_LIB.S9S_MB_2U(SCH_1):PAGE101
    14 M_B_CPU1_SA_DQ<4> @S9S_MB_2U_LIB.S9S_MB_2U(SCH_1):M_B_CPU1_SA_DQ(4)    I47 @S9S_MB_2U_LIB.S9S_MB_2U(SCH_1):PAGE101
    16 M_B_CPU1_SA_DQ<5> @S9S_MB_2U_LIB.S9S_MB_2U(SCH_1):M_B_CPU1_SA_DQ(5)    I47 @S9S_MB_2U_LIB.S9S_MB_2U(SCH_1):PAGE101
   159 M_B_CPU1_SA_DQ<6> @S9S_MB_2U_LIB.S9S_MB_2U(SCH_1):M_B_CPU1_SA_DQ(6)    I47 @S9S_MB_2U_LIB.S9S_MB_2U(SCH_1):PAGE101
   161 M_B_CPU1_SA_DQ<7> @S9S_MB_2U_LIB.S9S_MB_2U(SCH_1):M_B_CPU1_SA_DQ(7)    I47 @S9S_MB_2U_LIB.S9S_MB_2U(SCH_1):PAGE101
    18 M_B_CPU1_SA_DQ<8> @S9S_MB_2U_LIB.S9S_MB_2U(SCH_1):M_B_CPU1_SA_DQ(8)    I47 @S9S_MB_2U_LIB.S9S_MB_2U(SCH_1):PAGE101
    20 M_B_CPU1_SA_DQ<9> @S9S_MB_2U_LIB.S9S_MB_2U(SCH_1):M_B_CPU1_SA_DQ(9)    I47 @S9S_MB_2U_LIB.S9S_MB_2U(SCH_1):PAGE101
   163 M_B_CPU1_SA_DQ<10> @S9S_MB_2U_LIB.S9S_MB_2U(SCH_1):M_B_CPU1_SA_DQ(10)    I47 @S9S_MB_2U_LIB.S9S_MB_2U(SCH_1):PAGE101
   165 M_B_CPU1_SA_DQ<11> @S9S_MB_2U_LIB.S9S_MB_2U(SCH_1):M_B_CPU1_SA_DQ(11)    I47 @S9S_MB_2U_LIB.S9S_MB_2U(SCH_1):PAGE101
    25 M_B_CPU1_SA_DQ<12> @S9S_MB_2U_LIB.S9S_MB_2U(SCH_1):M_B_CPU1_SA_DQ(12)    I47 @S9S_MB_2U_LIB.S9S_MB_2U(SCH_1):PAGE101
    27 M_B_CPU1_SA_DQ<13> @S9S_MB_2U_LIB.S9S_MB_2U(SCH_1):M_B_CPU1_SA_DQ(13)    I47 @S9S_MB_2U_LIB.S9S_MB_2U(SCH_1):PAGE101
   170 M_B_CPU1_SA_DQ<14> @S9S_MB_2U_LIB.S9S_MB_2U(SCH_1):M_B_CPU1_SA_DQ(14)    I47 @S9S_MB_2U_LIB.S9S_MB_2U(SCH_1):PAGE101
   172 M_B_CPU1_SA_DQ<15> @S9S_MB_2U_LIB.S9S_MB_2U(SCH_1):M_B_CPU1_SA_DQ(15)    I47 @S9S_MB_2U_LIB.S9S_MB_2U(SCH_1):PAGE101
    29 M_B_CPU1_SA_DQ<16> @S9S_MB_2U_LIB.S9S_MB_2U(SCH_1):M_B_CPU1_SA_DQ(16)    I47 @S9S_MB_2U_LIB.S9S_MB_2U(SCH_1):PAGE101
    31 M_B_CPU1_SA_DQ<17> @S9S_MB_2U_LIB.S9S_MB_2U(SCH_1):M_B_CPU1_SA_DQ(17)    I47 @S9S_MB_2U_LIB.S9S_MB_2U(SCH_1):PAGE101
   174 M_B_CPU1_SA_DQ<18> @S9S_MB_2U_LIB.S9S_MB_2U(SCH_1):M_B_CPU1_SA_DQ(18)    I47 @S9S_MB_2U_LIB.S9S_MB_2U(SCH_1):PAGE101
   176 M_B_CPU1_SA_DQ<19> @S9S_MB_2U_LIB.S9S_MB_2U(SCH_1):M_B_CPU1_SA_DQ(19)    I47 @S9S_MB_2U_LIB.S9S_MB_2U(SCH_1):PAGE101
    36 M_B_CPU1_SA_DQ<20> @S9S_MB_2U_LIB.S9S_MB_2U(SCH_1):M_B_CPU1_SA_DQ(20)    I47 @S9S_MB_2U_LIB.S9S_MB_2U(SCH_1):PAGE101
    38 M_B_CPU1_SA_DQ<21> @S9S_MB_2U_LIB.S9S_MB_2U(SCH_1):M_B_CPU1_SA_DQ(21)    I47 @S9S_MB_2U_LIB.S9S_MB_2U(SCH_1):PAGE101
   181 M_B_CPU1_SA_DQ<22> @S9S_MB_2U_LIB.S9S_MB_2U(SCH_1):M_B_CPU1_SA_DQ(22)    I47 @S9S_MB_2U_LIB.S9S_MB_2U(SCH_1):PAGE101
   183 M_B_CPU1_SA_DQ<23> @S9S_MB_2U_LIB.S9S_MB_2U(SCH_1):M_B_CPU1_SA_DQ(23)    I47 @S9S_MB_2U_LIB.S9S_MB_2U(SCH_1):PAGE101
    40 M_B_CPU1_SA_DQ<24> @S9S_MB_2U_LIB.S9S_MB_2U(SCH_1):M_B_CPU1_SA_DQ(24)    I47 @S9S_MB_2U_LIB.S9S_MB_2U(SCH_1):PAGE101
    42 M_B_CPU1_SA_DQ<25> @S9S_MB_2U_LIB.S9S_MB_2U(SCH_1):M_B_CPU1_SA_DQ(25)    I47 @S9S_MB_2U_LIB.S9S_MB_2U(SCH_1):PAGE101
   185 M_B_CPU1_SA_DQ<26> @S9S_MB_2U_LIB.S9S_MB_2U(SCH_1):M_B_CPU1_SA_DQ(26)    I47 @S9S_MB_2U_LIB.S9S_MB_2U(SCH_1):PAGE101
   187 M_B_CPU1_SA_DQ<27> @S9S_MB_2U_LIB.S9S_MB_2U(SCH_1):M_B_CPU1_SA_DQ(27)    I47 @S9S_MB_2U_LIB.S9S_MB_2U(SCH_1):PAGE101
    47 M_B_CPU1_SA_DQ<28> @S9S_MB_2U_LIB.S9S_MB_2U(SCH_1):M_B_CPU1_SA_DQ(28)    I47 @S9S_MB_2U_LIB.S9S_MB_2U(SCH_1):PAGE101
    49 M_B_CPU1_SA_DQ<29> @S9S_MB_2U_LIB.S9S_MB_2U(SCH_1):M_B_CPU1_SA_DQ(29)    I47 @S9S_MB_2U_LIB.S9S_MB_2U(SCH_1):PAGE101
   192 M_B_CPU1_SA_DQ<30> @S9S_MB_2U_LIB.S9S_MB_2U(SCH_1):M_B_CPU1_SA_DQ(30)    I47 @S9S_MB_2U_LIB.S9S_MB_2U(SCH_1):PAGE101
   229 M_B_CPU1_SB_CS_N<3> @S9S_MB_2U_LIB.S9S_MB_2U(SCH_1):M_B_CPU1_SB_CS_N(3)    I47 @S9S_MB_2U_LIB.S9S_MB_2U(SCH_1):PAGE101
   209 M_B_CPU1_SA_CS_N<3> @S9S_MB_2U_LIB.S9S_MB_2U(SCH_1):M_B_CPU1_SA_CS_N(3)    I47 @S9S_MB_2U_LIB.S9S_MB_2U(SCH_1):PAGE101
    84 M_B_CPU1_SB_CS_N<2> @S9S_MB_2U_LIB.S9S_MB_2U(SCH_1):M_B_CPU1_SB_CS_N(2)    I47 @S9S_MB_2U_LIB.S9S_MB_2U(SCH_1):PAGE101
    64 M_B_CPU1_SA_CS_N<2> @S9S_MB_2U_LIB.S9S_MB_2U(SCH_1):M_B_CPU1_SA_CS_N(2)    I47 @S9S_MB_2U_LIB.S9S_MB_2U(SCH_1):PAGE101
   217 M_B_CPU1_CLK_DP<1> @S9S_MB_2U_LIB.S9S_MB_2U(SCH_1):M_B_CPU1_CLK_DP(1)    I47 @S9S_MB_2U_LIB.S9S_MB_2U(SCH_1):PAGE101
   218 M_B_CPU1_CLK_DN<1> @S9S_MB_2U_LIB.S9S_MB_2U(SCH_1):M_B_CPU1_CLK_DN(1)    I47 @S9S_MB_2U_LIB.S9S_MB_2U(SCH_1):PAGE101
    96 M_B_CPU1_SB_CB<0> @S9S_MB_2U_LIB.S9S_MB_2U(SCH_1):M_B_CPU1_SB_CB(0)    I47 @S9S_MB_2U_LIB.S9S_MB_2U(SCH_1):PAGE101
    98 M_B_CPU1_SB_CB<1> @S9S_MB_2U_LIB.S9S_MB_2U(SCH_1):M_B_CPU1_SB_CB(1)    I47 @S9S_MB_2U_LIB.S9S_MB_2U(SCH_1):PAGE101
   241 M_B_CPU1_SB_CB<2> @S9S_MB_2U_LIB.S9S_MB_2U(SCH_1):M_B_CPU1_SB_CB(2)    I47 @S9S_MB_2U_LIB.S9S_MB_2U(SCH_1):PAGE101
   243 M_B_CPU1_SB_CB<3> @S9S_MB_2U_LIB.S9S_MB_2U(SCH_1):M_B_CPU1_SB_CB(3)    I47 @S9S_MB_2U_LIB.S9S_MB_2U(SCH_1):PAGE101
    89 M_B_CPU1_SB_CB<4> @S9S_MB_2U_LIB.S9S_MB_2U(SCH_1):M_B_CPU1_SB_CB(4)    I47 @S9S_MB_2U_LIB.S9S_MB_2U(SCH_1):PAGE101
    91 M_B_CPU1_SB_CB<5> @S9S_MB_2U_LIB.S9S_MB_2U(SCH_1):M_B_CPU1_SB_CB(5)    I47 @S9S_MB_2U_LIB.S9S_MB_2U(SCH_1):PAGE101
   234 M_B_CPU1_SB_CB<6> @S9S_MB_2U_LIB.S9S_MB_2U(SCH_1):M_B_CPU1_SB_CB(6)    I47 @S9S_MB_2U_LIB.S9S_MB_2U(SCH_1):PAGE101
    51 M_B_CPU1_SA_CB<0> @S9S_MB_2U_LIB.S9S_MB_2U(SCH_1):M_B_CPU1_SA_CB(0)    I47 @S9S_MB_2U_LIB.S9S_MB_2U(SCH_1):PAGE101
   196 M_B_CPU1_SA_CB<2> @S9S_MB_2U_LIB.S9S_MB_2U(SCH_1):M_B_CPU1_SA_CB(2)    I47 @S9S_MB_2U_LIB.S9S_MB_2U(SCH_1):PAGE101
   198 M_B_CPU1_SA_CB<3> @S9S_MB_2U_LIB.S9S_MB_2U(SCH_1):M_B_CPU1_SA_CB(3)    I47 @S9S_MB_2U_LIB.S9S_MB_2U(SCH_1):PAGE101
    60 M_B_CPU1_SA_CB<5> @S9S_MB_2U_LIB.S9S_MB_2U(SCH_1):M_B_CPU1_SA_CB(5)    I47 @S9S_MB_2U_LIB.S9S_MB_2U(SCH_1):PAGE101
   203 M_B_CPU1_SA_CB<6> @S9S_MB_2U_LIB.S9S_MB_2U(SCH_1):M_B_CPU1_SA_CB(6)    I47 @S9S_MB_2U_LIB.S9S_MB_2U(SCH_1):PAGE101
    82 M_B_CPU1_SB_CA<6> @S9S_MB_2U_LIB.S9S_MB_2U(SCH_1):M_B_CPU1_SB_CA(6)    I47 @S9S_MB_2U_LIB.S9S_MB_2U(SCH_1):PAGE101
    72 M_B_CPU1_SA_CA<6> @S9S_MB_2U_LIB.S9S_MB_2U(SCH_1):M_B_CPU1_SA_CA(6)    I47 @S9S_MB_2U_LIB.S9S_MB_2U(SCH_1):PAGE101
   225 M_B_CPU1_SB_CA<5> @S9S_MB_2U_LIB.S9S_MB_2U(SCH_1):M_B_CPU1_SB_CA(5)    I47 @S9S_MB_2U_LIB.S9S_MB_2U(SCH_1):PAGE101
   215 M_B_CPU1_SA_CA<5> @S9S_MB_2U_LIB.S9S_MB_2U(SCH_1):M_B_CPU1_SA_CA(5)    I47 @S9S_MB_2U_LIB.S9S_MB_2U(SCH_1):PAGE101
    80 M_B_CPU1_SB_CA<4> @S9S_MB_2U_LIB.S9S_MB_2U(SCH_1):M_B_CPU1_SB_CA(4)    I47 @S9S_MB_2U_LIB.S9S_MB_2U(SCH_1):PAGE101
    70 M_B_CPU1_SA_CA<4> @S9S_MB_2U_LIB.S9S_MB_2U(SCH_1):M_B_CPU1_SA_CA(4)    I47 @S9S_MB_2U_LIB.S9S_MB_2U(SCH_1):PAGE101
   223 M_B_CPU1_SB_CA<3> @S9S_MB_2U_LIB.S9S_MB_2U(SCH_1):M_B_CPU1_SB_CA(3)    I47 @S9S_MB_2U_LIB.S9S_MB_2U(SCH_1):PAGE101
   213 M_B_CPU1_SA_CA<3> @S9S_MB_2U_LIB.S9S_MB_2U(SCH_1):M_B_CPU1_SA_CA(3)    I47 @S9S_MB_2U_LIB.S9S_MB_2U(SCH_1):PAGE101
    78 M_B_CPU1_SB_CA<2> @S9S_MB_2U_LIB.S9S_MB_2U(SCH_1):M_B_CPU1_SB_CA(2)    I47 @S9S_MB_2U_LIB.S9S_MB_2U(SCH_1):PAGE101
    68 M_B_CPU1_SA_CA<2> @S9S_MB_2U_LIB.S9S_MB_2U(SCH_1):M_B_CPU1_SA_CA(2)    I47 @S9S_MB_2U_LIB.S9S_MB_2U(SCH_1):PAGE101
   221 M_B_CPU1_SB_CA<1> @S9S_MB_2U_LIB.S9S_MB_2U(SCH_1):M_B_CPU1_SB_CA(1)    I47 @S9S_MB_2U_LIB.S9S_MB_2U(SCH_1):PAGE101
   211 M_B_CPU1_SA_CA<1> @S9S_MB_2U_LIB.S9S_MB_2U(SCH_1):M_B_CPU1_SA_CA(1)    I47 @S9S_MB_2U_LIB.S9S_MB_2U(SCH_1):PAGE101
    76 M_B_CPU1_SB_CA<0> @S9S_MB_2U_LIB.S9S_MB_2U(SCH_1):M_B_CPU1_SB_CA(0)    I47 @S9S_MB_2U_LIB.S9S_MB_2U(SCH_1):PAGE101
    66 M_B_CPU1_SA_CA<0> @S9S_MB_2U_LIB.S9S_MB_2U(SCH_1):M_B_CPU1_SA_CA(0)    I47 @S9S_MB_2U_LIB.S9S_MB_2U(SCH_1):PAGE101
    62 M_B_CPU1_ALERT_N @S9S_MB_2U_LIB.S9S_MB_2U(SCH_1):M_B_CPU1_ALERT_N    I47 @S9S_MB_2U_LIB.S9S_MB_2U(SCH_1):PAGE101
   236 M_B_CPU1_SB_CB<7> @S9S_MB_2U_LIB.S9S_MB_2U(SCH_1):M_B_CPU1_SB_CB(7)    I47 @S9S_MB_2U_LIB.S9S_MB_2U(SCH_1):PAGE101
    53 M_B_CPU1_SA_CB<1> @S9S_MB_2U_LIB.S9S_MB_2U(SCH_1):M_B_CPU1_SA_CB(1)    I47 @S9S_MB_2U_LIB.S9S_MB_2U(SCH_1):PAGE101
    58 M_B_CPU1_SA_CB<4> @S9S_MB_2U_LIB.S9S_MB_2U(SCH_1):M_B_CPU1_SA_CB(4)    I47 @S9S_MB_2U_LIB.S9S_MB_2U(SCH_1):PAGE101
   205 M_B_CPU1_SA_CB<7> @S9S_MB_2U_LIB.S9S_MB_2U(SCH_1):M_B_CPU1_SA_CB(7)    I47 @S9S_MB_2U_LIB.S9S_MB_2U(SCH_1):PAGE101
   194 M_B_CPU1_SA_DQ<31> @S9S_MB_2U_LIB.S9S_MB_2U(SCH_1):M_B_CPU1_SA_DQ(31)    I47 @S9S_MB_2U_LIB.S9S_MB_2U(SCH_1):PAGE101
    93 M_B_CPU1_SB_DQS_DP<9> @S9S_MB_2U_LIB.S9S_MB_2U(SCH_1):M_B_CPU1_SB_DQS_DP(9)   I178 @S9S_MB_2U_LIB.S9S_MB_2U(SCH_1):PAGE101
    94 M_B_CPU1_SB_DQS_DN<9> @S9S_MB_2U_LIB.S9S_MB_2U(SCH_1):M_B_CPU1_SB_DQS_DN(9)   I178 @S9S_MB_2U_LIB.S9S_MB_2U(SCH_1):PAGE101
   201 M_B_CPU1_SA_DQS_DP<9> @S9S_MB_2U_LIB.S9S_MB_2U(SCH_1):M_B_CPU1_SA_DQS_DP(9)   I178 @S9S_MB_2U_LIB.S9S_MB_2U(SCH_1):PAGE101
   200 M_B_CPU1_SA_DQS_DN<9> @S9S_MB_2U_LIB.S9S_MB_2U(SCH_1):M_B_CPU1_SA_DQS_DN(9)   I178 @S9S_MB_2U_LIB.S9S_MB_2U(SCH_1):PAGE101
   190 M_B_CPU1_SA_DQS_DP<8> @S9S_MB_2U_LIB.S9S_MB_2U(SCH_1):M_B_CPU1_SA_DQS_DP(8)   I178 @S9S_MB_2U_LIB.S9S_MB_2U(SCH_1):PAGE101
   189 M_B_CPU1_SA_DQS_DN<8> @S9S_MB_2U_LIB.S9S_MB_2U(SCH_1):M_B_CPU1_SA_DQS_DN(8)   I178 @S9S_MB_2U_LIB.S9S_MB_2U(SCH_1):PAGE101
   271 M_B_CPU1_SB_DQS_DN<7> @S9S_MB_2U_LIB.S9S_MB_2U(SCH_1):M_B_CPU1_SB_DQS_DN(7)   I178 @S9S_MB_2U_LIB.S9S_MB_2U(SCH_1):PAGE101
   179 M_B_CPU1_SA_DQS_DP<7> @S9S_MB_2U_LIB.S9S_MB_2U(SCH_1):M_B_CPU1_SA_DQS_DP(7)   I178 @S9S_MB_2U_LIB.S9S_MB_2U(SCH_1):PAGE101
   261 M_B_CPU1_SB_DQS_DP<6> @S9S_MB_2U_LIB.S9S_MB_2U(SCH_1):M_B_CPU1_SB_DQS_DP(6)   I178 @S9S_MB_2U_LIB.S9S_MB_2U(SCH_1):PAGE101
   260 M_B_CPU1_SB_DQS_DN<6> @S9S_MB_2U_LIB.S9S_MB_2U(SCH_1):M_B_CPU1_SB_DQS_DN(6)   I178 @S9S_MB_2U_LIB.S9S_MB_2U(SCH_1):PAGE101
   167 M_B_CPU1_SA_DQS_DN<6> @S9S_MB_2U_LIB.S9S_MB_2U(SCH_1):M_B_CPU1_SA_DQS_DN(6)   I178 @S9S_MB_2U_LIB.S9S_MB_2U(SCH_1):PAGE101
   250 M_B_CPU1_SB_DQS_DP<5> @S9S_MB_2U_LIB.S9S_MB_2U(SCH_1):M_B_CPU1_SB_DQS_DP(5)   I178 @S9S_MB_2U_LIB.S9S_MB_2U(SCH_1):PAGE101
   249 M_B_CPU1_SB_DQS_DN<5> @S9S_MB_2U_LIB.S9S_MB_2U(SCH_1):M_B_CPU1_SB_DQS_DN(5)   I178 @S9S_MB_2U_LIB.S9S_MB_2U(SCH_1):PAGE101
   157 M_B_CPU1_SA_DQS_DP<5> @S9S_MB_2U_LIB.S9S_MB_2U(SCH_1):M_B_CPU1_SA_DQS_DP(5)   I178 @S9S_MB_2U_LIB.S9S_MB_2U(SCH_1):PAGE101
   156 M_B_CPU1_SA_DQS_DN<5> @S9S_MB_2U_LIB.S9S_MB_2U(SCH_1):M_B_CPU1_SA_DQS_DN(5)   I178 @S9S_MB_2U_LIB.S9S_MB_2U(SCH_1):PAGE101
   239 M_B_CPU1_SB_DQS_DP<4> @S9S_MB_2U_LIB.S9S_MB_2U(SCH_1):M_B_CPU1_SB_DQS_DP(4)   I178 @S9S_MB_2U_LIB.S9S_MB_2U(SCH_1):PAGE101
   238 M_B_CPU1_SB_DQS_DN<4> @S9S_MB_2U_LIB.S9S_MB_2U(SCH_1):M_B_CPU1_SB_DQS_DN(4)   I178 @S9S_MB_2U_LIB.S9S_MB_2U(SCH_1):PAGE101
    55 M_B_CPU1_SA_DQS_DP<4> @S9S_MB_2U_LIB.S9S_MB_2U(SCH_1):M_B_CPU1_SA_DQS_DP(4)   I178 @S9S_MB_2U_LIB.S9S_MB_2U(SCH_1):PAGE101
    56 M_B_CPU1_SA_DQS_DN<4> @S9S_MB_2U_LIB.S9S_MB_2U(SCH_1):M_B_CPU1_SA_DQS_DN(4)   I178 @S9S_MB_2U_LIB.S9S_MB_2U(SCH_1):PAGE101
   137 M_B_CPU1_SB_DQS_DP<3> @S9S_MB_2U_LIB.S9S_MB_2U(SCH_1):M_B_CPU1_SB_DQS_DP(3)   I178 @S9S_MB_2U_LIB.S9S_MB_2U(SCH_1):PAGE101
   138 M_B_CPU1_SB_DQS_DN<3> @S9S_MB_2U_LIB.S9S_MB_2U(SCH_1):M_B_CPU1_SB_DQS_DN(3)   I178 @S9S_MB_2U_LIB.S9S_MB_2U(SCH_1):PAGE101
    44 M_B_CPU1_SA_DQS_DP<3> @S9S_MB_2U_LIB.S9S_MB_2U(SCH_1):M_B_CPU1_SA_DQS_DP(3)   I178 @S9S_MB_2U_LIB.S9S_MB_2U(SCH_1):PAGE101
    45 M_B_CPU1_SA_DQS_DN<3> @S9S_MB_2U_LIB.S9S_MB_2U(SCH_1):M_B_CPU1_SA_DQS_DN(3)   I178 @S9S_MB_2U_LIB.S9S_MB_2U(SCH_1):PAGE101
   126 M_B_CPU1_SB_DQS_DP<2> @S9S_MB_2U_LIB.S9S_MB_2U(SCH_1):M_B_CPU1_SB_DQS_DP(2)   I178 @S9S_MB_2U_LIB.S9S_MB_2U(SCH_1):PAGE101
   127 M_B_CPU1_SB_DQS_DN<2> @S9S_MB_2U_LIB.S9S_MB_2U(SCH_1):M_B_CPU1_SB_DQS_DN(2)   I178 @S9S_MB_2U_LIB.S9S_MB_2U(SCH_1):PAGE101
    33 M_B_CPU1_SA_DQS_DP<2> @S9S_MB_2U_LIB.S9S_MB_2U(SCH_1):M_B_CPU1_SA_DQS_DP(2)   I178 @S9S_MB_2U_LIB.S9S_MB_2U(SCH_1):PAGE101
    34 M_B_CPU1_SA_DQS_DN<2> @S9S_MB_2U_LIB.S9S_MB_2U(SCH_1):M_B_CPU1_SA_DQS_DN(2)   I178 @S9S_MB_2U_LIB.S9S_MB_2U(SCH_1):PAGE101
   115 M_B_CPU1_SB_DQS_DP<1> @S9S_MB_2U_LIB.S9S_MB_2U(SCH_1):M_B_CPU1_SB_DQS_DP(1)   I178 @S9S_MB_2U_LIB.S9S_MB_2U(SCH_1):PAGE101
   116 M_B_CPU1_SB_DQS_DN<1> @S9S_MB_2U_LIB.S9S_MB_2U(SCH_1):M_B_CPU1_SB_DQS_DN(1)   I178 @S9S_MB_2U_LIB.S9S_MB_2U(SCH_1):PAGE101
    22 M_B_CPU1_SA_DQS_DP<1> @S9S_MB_2U_LIB.S9S_MB_2U(SCH_1):M_B_CPU1_SA_DQS_DP(1)   I178 @S9S_MB_2U_LIB.S9S_MB_2U(SCH_1):PAGE101
    23 M_B_CPU1_SA_DQS_DN<1> @S9S_MB_2U_LIB.S9S_MB_2U(SCH_1):M_B_CPU1_SA_DQS_DN(1)   I178 @S9S_MB_2U_LIB.S9S_MB_2U(SCH_1):PAGE101
   104 M_B_CPU1_SB_DQS_DP<0> @S9S_MB_2U_LIB.S9S_MB_2U(SCH_1):M_B_CPU1_SB_DQS_DP(0)   I178 @S9S_MB_2U_LIB.S9S_MB_2U(SCH_1):PAGE101
   105 M_B_CPU1_SB_DQS_DN<0> @S9S_MB_2U_LIB.S9S_MB_2U(SCH_1):M_B_CPU1_SB_DQS_DN(0)   I178 @S9S_MB_2U_LIB.S9S_MB_2U(SCH_1):PAGE101
    11 M_B_CPU1_SA_DQS_DP<0> @S9S_MB_2U_LIB.S9S_MB_2U(SCH_1):M_B_CPU1_SA_DQS_DP(0)   I178 @S9S_MB_2U_LIB.S9S_MB_2U(SCH_1):PAGE101
    12 M_B_CPU1_SA_DQS_DN<0> @S9S_MB_2U_LIB.S9S_MB_2U(SCH_1):M_B_CPU1_SA_DQS_DN(0)   I178 @S9S_MB_2U_LIB.S9S_MB_2U(SCH_1):PAGE101
   272 M_B_CPU1_SB_DQS_DP<7> @S9S_MB_2U_LIB.S9S_MB_2U(SCH_1):M_B_CPU1_SB_DQS_DP(7)   I178 @S9S_MB_2U_LIB.S9S_MB_2U(SCH_1):PAGE101
   282 M_B_CPU1_SB_DQS_DN<8> @S9S_MB_2U_LIB.S9S_MB_2U(SCH_1):M_B_CPU1_SB_DQS_DN(8)   I178 @S9S_MB_2U_LIB.S9S_MB_2U(SCH_1):PAGE101
   283 M_B_CPU1_SB_DQS_DP<8> @S9S_MB_2U_LIB.S9S_MB_2U(SCH_1):M_B_CPU1_SB_DQS_DP(8)   I178 @S9S_MB_2U_LIB.S9S_MB_2U(SCH_1):PAGE101
   168 M_B_CPU1_SA_DQS_DP<6> @S9S_MB_2U_LIB.S9S_MB_2U(SCH_1):M_B_CPU1_SA_DQS_DP(6)   I178 @S9S_MB_2U_LIB.S9S_MB_2U(SCH_1):PAGE101
   178 M_B_CPU1_SA_DQS_DN<7> @S9S_MB_2U_LIB.S9S_MB_2U(SCH_1):M_B_CPU1_SA_DQS_DN(7)   I178 @S9S_MB_2U_LIB.S9S_MB_2U(SCH_1):PAGE101
     6    GND @S9S_MB_2U_LIB.S9S_MB_2U(SCH_1):GND   I176 @S9S_MB_2U_LIB.S9S_MB_2U(SCH_1):PAGE101
     8    GND @S9S_MB_2U_LIB.S9S_MB_2U(SCH_1):GND   I176 @S9S_MB_2U_LIB.S9S_MB_2U(SCH_1):PAGE101
    10    GND @S9S_MB_2U_LIB.S9S_MB_2U(SCH_1):GND   I176 @S9S_MB_2U_LIB.S9S_MB_2U(SCH_1):PAGE101
    13    GND @S9S_MB_2U_LIB.S9S_MB_2U(SCH_1):GND   I176 @S9S_MB_2U_LIB.S9S_MB_2U(SCH_1):PAGE101
    15    GND @S9S_MB_2U_LIB.S9S_MB_2U(SCH_1):GND   I176 @S9S_MB_2U_LIB.S9S_MB_2U(SCH_1):PAGE101
    17    GND @S9S_MB_2U_LIB.S9S_MB_2U(SCH_1):GND   I176 @S9S_MB_2U_LIB.S9S_MB_2U(SCH_1):PAGE101
    19    GND @S9S_MB_2U_LIB.S9S_MB_2U(SCH_1):GND   I176 @S9S_MB_2U_LIB.S9S_MB_2U(SCH_1):PAGE101
    21    GND @S9S_MB_2U_LIB.S9S_MB_2U(SCH_1):GND   I176 @S9S_MB_2U_LIB.S9S_MB_2U(SCH_1):PAGE101
    24    GND @S9S_MB_2U_LIB.S9S_MB_2U(SCH_1):GND   I176 @S9S_MB_2U_LIB.S9S_MB_2U(SCH_1):PAGE101
    26    GND @S9S_MB_2U_LIB.S9S_MB_2U(SCH_1):GND   I176 @S9S_MB_2U_LIB.S9S_MB_2U(SCH_1):PAGE101
    28    GND @S9S_MB_2U_LIB.S9S_MB_2U(SCH_1):GND   I176 @S9S_MB_2U_LIB.S9S_MB_2U(SCH_1):PAGE101
    30    GND @S9S_MB_2U_LIB.S9S_MB_2U(SCH_1):GND   I176 @S9S_MB_2U_LIB.S9S_MB_2U(SCH_1):PAGE101
    32    GND @S9S_MB_2U_LIB.S9S_MB_2U(SCH_1):GND   I176 @S9S_MB_2U_LIB.S9S_MB_2U(SCH_1):PAGE101
    35    GND @S9S_MB_2U_LIB.S9S_MB_2U(SCH_1):GND   I176 @S9S_MB_2U_LIB.S9S_MB_2U(SCH_1):PAGE101
    37    GND @S9S_MB_2U_LIB.S9S_MB_2U(SCH_1):GND   I176 @S9S_MB_2U_LIB.S9S_MB_2U(SCH_1):PAGE101
    39    GND @S9S_MB_2U_LIB.S9S_MB_2U(SCH_1):GND   I176 @S9S_MB_2U_LIB.S9S_MB_2U(SCH_1):PAGE101
    41    GND @S9S_MB_2U_LIB.S9S_MB_2U(SCH_1):GND   I176 @S9S_MB_2U_LIB.S9S_MB_2U(SCH_1):PAGE101
    43    GND @S9S_MB_2U_LIB.S9S_MB_2U(SCH_1):GND   I176 @S9S_MB_2U_LIB.S9S_MB_2U(SCH_1):PAGE101
    46    GND @S9S_MB_2U_LIB.S9S_MB_2U(SCH_1):GND   I176 @S9S_MB_2U_LIB.S9S_MB_2U(SCH_1):PAGE101
    48    GND @S9S_MB_2U_LIB.S9S_MB_2U(SCH_1):GND   I176 @S9S_MB_2U_LIB.S9S_MB_2U(SCH_1):PAGE101
    50    GND @S9S_MB_2U_LIB.S9S_MB_2U(SCH_1):GND   I176 @S9S_MB_2U_LIB.S9S_MB_2U(SCH_1):PAGE101
    52    GND @S9S_MB_2U_LIB.S9S_MB_2U(SCH_1):GND   I176 @S9S_MB_2U_LIB.S9S_MB_2U(SCH_1):PAGE101
    54    GND @S9S_MB_2U_LIB.S9S_MB_2U(SCH_1):GND   I176 @S9S_MB_2U_LIB.S9S_MB_2U(SCH_1):PAGE101
    57    GND @S9S_MB_2U_LIB.S9S_MB_2U(SCH_1):GND   I176 @S9S_MB_2U_LIB.S9S_MB_2U(SCH_1):PAGE101
    59    GND @S9S_MB_2U_LIB.S9S_MB_2U(SCH_1):GND   I176 @S9S_MB_2U_LIB.S9S_MB_2U(SCH_1):PAGE101
    61    GND @S9S_MB_2U_LIB.S9S_MB_2U(SCH_1):GND   I176 @S9S_MB_2U_LIB.S9S_MB_2U(SCH_1):PAGE101
    63    GND @S9S_MB_2U_LIB.S9S_MB_2U(SCH_1):GND   I176 @S9S_MB_2U_LIB.S9S_MB_2U(SCH_1):PAGE101
    65    GND @S9S_MB_2U_LIB.S9S_MB_2U(SCH_1):GND   I176 @S9S_MB_2U_LIB.S9S_MB_2U(SCH_1):PAGE101
    67    GND @S9S_MB_2U_LIB.S9S_MB_2U(SCH_1):GND   I176 @S9S_MB_2U_LIB.S9S_MB_2U(SCH_1):PAGE101
    69    GND @S9S_MB_2U_LIB.S9S_MB_2U(SCH_1):GND   I176 @S9S_MB_2U_LIB.S9S_MB_2U(SCH_1):PAGE101
    71    GND @S9S_MB_2U_LIB.S9S_MB_2U(SCH_1):GND   I176 @S9S_MB_2U_LIB.S9S_MB_2U(SCH_1):PAGE101
    73    GND @S9S_MB_2U_LIB.S9S_MB_2U(SCH_1):GND   I176 @S9S_MB_2U_LIB.S9S_MB_2U(SCH_1):PAGE101
    75    GND @S9S_MB_2U_LIB.S9S_MB_2U(SCH_1):GND   I176 @S9S_MB_2U_LIB.S9S_MB_2U(SCH_1):PAGE101
    77    GND @S9S_MB_2U_LIB.S9S_MB_2U(SCH_1):GND   I176 @S9S_MB_2U_LIB.S9S_MB_2U(SCH_1):PAGE101
    79    GND @S9S_MB_2U_LIB.S9S_MB_2U(SCH_1):GND   I176 @S9S_MB_2U_LIB.S9S_MB_2U(SCH_1):PAGE101
    81    GND @S9S_MB_2U_LIB.S9S_MB_2U(SCH_1):GND   I176 @S9S_MB_2U_LIB.S9S_MB_2U(SCH_1):PAGE101
    83    GND @S9S_MB_2U_LIB.S9S_MB_2U(SCH_1):GND   I176 @S9S_MB_2U_LIB.S9S_MB_2U(SCH_1):PAGE101
    85    GND @S9S_MB_2U_LIB.S9S_MB_2U(SCH_1):GND   I176 @S9S_MB_2U_LIB.S9S_MB_2U(SCH_1):PAGE101
    88    GND @S9S_MB_2U_LIB.S9S_MB_2U(SCH_1):GND   I176 @S9S_MB_2U_LIB.S9S_MB_2U(SCH_1):PAGE101
    90    GND @S9S_MB_2U_LIB.S9S_MB_2U(SCH_1):GND   I176 @S9S_MB_2U_LIB.S9S_MB_2U(SCH_1):PAGE101
    92    GND @S9S_MB_2U_LIB.S9S_MB_2U(SCH_1):GND   I176 @S9S_MB_2U_LIB.S9S_MB_2U(SCH_1):PAGE101
    95    GND @S9S_MB_2U_LIB.S9S_MB_2U(SCH_1):GND   I176 @S9S_MB_2U_LIB.S9S_MB_2U(SCH_1):PAGE101
    97    GND @S9S_MB_2U_LIB.S9S_MB_2U(SCH_1):GND   I176 @S9S_MB_2U_LIB.S9S_MB_2U(SCH_1):PAGE101
    99    GND @S9S_MB_2U_LIB.S9S_MB_2U(SCH_1):GND   I176 @S9S_MB_2U_LIB.S9S_MB_2U(SCH_1):PAGE101
   101    GND @S9S_MB_2U_LIB.S9S_MB_2U(SCH_1):GND   I176 @S9S_MB_2U_LIB.S9S_MB_2U(SCH_1):PAGE101
   103    GND @S9S_MB_2U_LIB.S9S_MB_2U(SCH_1):GND   I176 @S9S_MB_2U_LIB.S9S_MB_2U(SCH_1):PAGE101
   106    GND @S9S_MB_2U_LIB.S9S_MB_2U(SCH_1):GND   I176 @S9S_MB_2U_LIB.S9S_MB_2U(SCH_1):PAGE101
   108    GND @S9S_MB_2U_LIB.S9S_MB_2U(SCH_1):GND   I176 @S9S_MB_2U_LIB.S9S_MB_2U(SCH_1):PAGE101
   110    GND @S9S_MB_2U_LIB.S9S_MB_2U(SCH_1):GND   I176 @S9S_MB_2U_LIB.S9S_MB_2U(SCH_1):PAGE101
   112    GND @S9S_MB_2U_LIB.S9S_MB_2U(SCH_1):GND   I176 @S9S_MB_2U_LIB.S9S_MB_2U(SCH_1):PAGE101
   114    GND @S9S_MB_2U_LIB.S9S_MB_2U(SCH_1):GND   I176 @S9S_MB_2U_LIB.S9S_MB_2U(SCH_1):PAGE101
   117    GND @S9S_MB_2U_LIB.S9S_MB_2U(SCH_1):GND   I176 @S9S_MB_2U_LIB.S9S_MB_2U(SCH_1):PAGE101
   119    GND @S9S_MB_2U_LIB.S9S_MB_2U(SCH_1):GND   I176 @S9S_MB_2U_LIB.S9S_MB_2U(SCH_1):PAGE101
   121    GND @S9S_MB_2U_LIB.S9S_MB_2U(SCH_1):GND   I176 @S9S_MB_2U_LIB.S9S_MB_2U(SCH_1):PAGE101
   123    GND @S9S_MB_2U_LIB.S9S_MB_2U(SCH_1):GND   I176 @S9S_MB_2U_LIB.S9S_MB_2U(SCH_1):PAGE101
   125    GND @S9S_MB_2U_LIB.S9S_MB_2U(SCH_1):GND   I176 @S9S_MB_2U_LIB.S9S_MB_2U(SCH_1):PAGE101
   128    GND @S9S_MB_2U_LIB.S9S_MB_2U(SCH_1):GND   I176 @S9S_MB_2U_LIB.S9S_MB_2U(SCH_1):PAGE101
   130    GND @S9S_MB_2U_LIB.S9S_MB_2U(SCH_1):GND   I176 @S9S_MB_2U_LIB.S9S_MB_2U(SCH_1):PAGE101
   134    GND @S9S_MB_2U_LIB.S9S_MB_2U(SCH_1):GND   I176 @S9S_MB_2U_LIB.S9S_MB_2U(SCH_1):PAGE101
   143    GND @S9S_MB_2U_LIB.S9S_MB_2U(SCH_1):GND   I176 @S9S_MB_2U_LIB.S9S_MB_2U(SCH_1):PAGE101
   151    GND @S9S_MB_2U_LIB.S9S_MB_2U(SCH_1):GND   I176 @S9S_MB_2U_LIB.S9S_MB_2U(SCH_1):PAGE101
   153    GND @S9S_MB_2U_LIB.S9S_MB_2U(SCH_1):GND   I176 @S9S_MB_2U_LIB.S9S_MB_2U(SCH_1):PAGE101
   155    GND @S9S_MB_2U_LIB.S9S_MB_2U(SCH_1):GND   I176 @S9S_MB_2U_LIB.S9S_MB_2U(SCH_1):PAGE101
   158    GND @S9S_MB_2U_LIB.S9S_MB_2U(SCH_1):GND   I176 @S9S_MB_2U_LIB.S9S_MB_2U(SCH_1):PAGE101
   160    GND @S9S_MB_2U_LIB.S9S_MB_2U(SCH_1):GND   I176 @S9S_MB_2U_LIB.S9S_MB_2U(SCH_1):PAGE101
   162    GND @S9S_MB_2U_LIB.S9S_MB_2U(SCH_1):GND   I176 @S9S_MB_2U_LIB.S9S_MB_2U(SCH_1):PAGE101
   164    GND @S9S_MB_2U_LIB.S9S_MB_2U(SCH_1):GND   I176 @S9S_MB_2U_LIB.S9S_MB_2U(SCH_1):PAGE101
   166    GND @S9S_MB_2U_LIB.S9S_MB_2U(SCH_1):GND   I176 @S9S_MB_2U_LIB.S9S_MB_2U(SCH_1):PAGE101
   169    GND @S9S_MB_2U_LIB.S9S_MB_2U(SCH_1):GND   I176 @S9S_MB_2U_LIB.S9S_MB_2U(SCH_1):PAGE101
   171    GND @S9S_MB_2U_LIB.S9S_MB_2U(SCH_1):GND   I176 @S9S_MB_2U_LIB.S9S_MB_2U(SCH_1):PAGE101
   173    GND @S9S_MB_2U_LIB.S9S_MB_2U(SCH_1):GND   I176 @S9S_MB_2U_LIB.S9S_MB_2U(SCH_1):PAGE101
   175    GND @S9S_MB_2U_LIB.S9S_MB_2U(SCH_1):GND   I176 @S9S_MB_2U_LIB.S9S_MB_2U(SCH_1):PAGE101
   177    GND @S9S_MB_2U_LIB.S9S_MB_2U(SCH_1):GND   I176 @S9S_MB_2U_LIB.S9S_MB_2U(SCH_1):PAGE101
   180    GND @S9S_MB_2U_LIB.S9S_MB_2U(SCH_1):GND   I176 @S9S_MB_2U_LIB.S9S_MB_2U(SCH_1):PAGE101
   182    GND @S9S_MB_2U_LIB.S9S_MB_2U(SCH_1):GND   I176 @S9S_MB_2U_LIB.S9S_MB_2U(SCH_1):PAGE101
   184    GND @S9S_MB_2U_LIB.S9S_MB_2U(SCH_1):GND   I176 @S9S_MB_2U_LIB.S9S_MB_2U(SCH_1):PAGE101
   186    GND @S9S_MB_2U_LIB.S9S_MB_2U(SCH_1):GND   I176 @S9S_MB_2U_LIB.S9S_MB_2U(SCH_1):PAGE101
   188    GND @S9S_MB_2U_LIB.S9S_MB_2U(SCH_1):GND   I176 @S9S_MB_2U_LIB.S9S_MB_2U(SCH_1):PAGE101
   191    GND @S9S_MB_2U_LIB.S9S_MB_2U(SCH_1):GND   I176 @S9S_MB_2U_LIB.S9S_MB_2U(SCH_1):PAGE101
   193    GND @S9S_MB_2U_LIB.S9S_MB_2U(SCH_1):GND   I176 @S9S_MB_2U_LIB.S9S_MB_2U(SCH_1):PAGE101
   195    GND @S9S_MB_2U_LIB.S9S_MB_2U(SCH_1):GND   I176 @S9S_MB_2U_LIB.S9S_MB_2U(SCH_1):PAGE101
   197    GND @S9S_MB_2U_LIB.S9S_MB_2U(SCH_1):GND   I176 @S9S_MB_2U_LIB.S9S_MB_2U(SCH_1):PAGE101
   199    GND @S9S_MB_2U_LIB.S9S_MB_2U(SCH_1):GND   I176 @S9S_MB_2U_LIB.S9S_MB_2U(SCH_1):PAGE101
   202    GND @S9S_MB_2U_LIB.S9S_MB_2U(SCH_1):GND   I176 @S9S_MB_2U_LIB.S9S_MB_2U(SCH_1):PAGE101
   204    GND @S9S_MB_2U_LIB.S9S_MB_2U(SCH_1):GND   I176 @S9S_MB_2U_LIB.S9S_MB_2U(SCH_1):PAGE101
   206    GND @S9S_MB_2U_LIB.S9S_MB_2U(SCH_1):GND   I176 @S9S_MB_2U_LIB.S9S_MB_2U(SCH_1):PAGE101
   208    GND @S9S_MB_2U_LIB.S9S_MB_2U(SCH_1):GND   I176 @S9S_MB_2U_LIB.S9S_MB_2U(SCH_1):PAGE101
   210    GND @S9S_MB_2U_LIB.S9S_MB_2U(SCH_1):GND   I176 @S9S_MB_2U_LIB.S9S_MB_2U(SCH_1):PAGE101
   212    GND @S9S_MB_2U_LIB.S9S_MB_2U(SCH_1):GND   I176 @S9S_MB_2U_LIB.S9S_MB_2U(SCH_1):PAGE101
   214    GND @S9S_MB_2U_LIB.S9S_MB_2U(SCH_1):GND   I176 @S9S_MB_2U_LIB.S9S_MB_2U(SCH_1):PAGE101
   216    GND @S9S_MB_2U_LIB.S9S_MB_2U(SCH_1):GND   I176 @S9S_MB_2U_LIB.S9S_MB_2U(SCH_1):PAGE101
   219    GND @S9S_MB_2U_LIB.S9S_MB_2U(SCH_1):GND   I176 @S9S_MB_2U_LIB.S9S_MB_2U(SCH_1):PAGE101
   222    GND @S9S_MB_2U_LIB.S9S_MB_2U(SCH_1):GND   I176 @S9S_MB_2U_LIB.S9S_MB_2U(SCH_1):PAGE101
   224    GND @S9S_MB_2U_LIB.S9S_MB_2U(SCH_1):GND   I176 @S9S_MB_2U_LIB.S9S_MB_2U(SCH_1):PAGE101
   226    GND @S9S_MB_2U_LIB.S9S_MB_2U(SCH_1):GND   I176 @S9S_MB_2U_LIB.S9S_MB_2U(SCH_1):PAGE101
   228    GND @S9S_MB_2U_LIB.S9S_MB_2U(SCH_1):GND   I176 @S9S_MB_2U_LIB.S9S_MB_2U(SCH_1):PAGE101
   233    GND @S9S_MB_2U_LIB.S9S_MB_2U(SCH_1):GND   I176 @S9S_MB_2U_LIB.S9S_MB_2U(SCH_1):PAGE101
   237    GND @S9S_MB_2U_LIB.S9S_MB_2U(SCH_1):GND   I176 @S9S_MB_2U_LIB.S9S_MB_2U(SCH_1):PAGE101
   242    GND @S9S_MB_2U_LIB.S9S_MB_2U(SCH_1):GND   I176 @S9S_MB_2U_LIB.S9S_MB_2U(SCH_1):PAGE101
   244    GND @S9S_MB_2U_LIB.S9S_MB_2U(SCH_1):GND   I176 @S9S_MB_2U_LIB.S9S_MB_2U(SCH_1):PAGE101
   246    GND @S9S_MB_2U_LIB.S9S_MB_2U(SCH_1):GND   I176 @S9S_MB_2U_LIB.S9S_MB_2U(SCH_1):PAGE101
   248    GND @S9S_MB_2U_LIB.S9S_MB_2U(SCH_1):GND   I176 @S9S_MB_2U_LIB.S9S_MB_2U(SCH_1):PAGE101
   251    GND @S9S_MB_2U_LIB.S9S_MB_2U(SCH_1):GND   I176 @S9S_MB_2U_LIB.S9S_MB_2U(SCH_1):PAGE101
   253    GND @S9S_MB_2U_LIB.S9S_MB_2U(SCH_1):GND   I176 @S9S_MB_2U_LIB.S9S_MB_2U(SCH_1):PAGE101
   255    GND @S9S_MB_2U_LIB.S9S_MB_2U(SCH_1):GND   I176 @S9S_MB_2U_LIB.S9S_MB_2U(SCH_1):PAGE101
   257    GND @S9S_MB_2U_LIB.S9S_MB_2U(SCH_1):GND   I176 @S9S_MB_2U_LIB.S9S_MB_2U(SCH_1):PAGE101
   259    GND @S9S_MB_2U_LIB.S9S_MB_2U(SCH_1):GND   I176 @S9S_MB_2U_LIB.S9S_MB_2U(SCH_1):PAGE101
   262    GND @S9S_MB_2U_LIB.S9S_MB_2U(SCH_1):GND   I176 @S9S_MB_2U_LIB.S9S_MB_2U(SCH_1):PAGE101
   264    GND @S9S_MB_2U_LIB.S9S_MB_2U(SCH_1):GND   I176 @S9S_MB_2U_LIB.S9S_MB_2U(SCH_1):PAGE101
   266    GND @S9S_MB_2U_LIB.S9S_MB_2U(SCH_1):GND   I176 @S9S_MB_2U_LIB.S9S_MB_2U(SCH_1):PAGE101
   268    GND @S9S_MB_2U_LIB.S9S_MB_2U(SCH_1):GND   I176 @S9S_MB_2U_LIB.S9S_MB_2U(SCH_1):PAGE101
   270    GND @S9S_MB_2U_LIB.S9S_MB_2U(SCH_1):GND   I176 @S9S_MB_2U_LIB.S9S_MB_2U(SCH_1):PAGE101
   273    GND @S9S_MB_2U_LIB.S9S_MB_2U(SCH_1):GND   I176 @S9S_MB_2U_LIB.S9S_MB_2U(SCH_1):PAGE101
   275    GND @S9S_MB_2U_LIB.S9S_MB_2U(SCH_1):GND   I176 @S9S_MB_2U_LIB.S9S_MB_2U(SCH_1):PAGE101
   277    GND @S9S_MB_2U_LIB.S9S_MB_2U(SCH_1):GND   I176 @S9S_MB_2U_LIB.S9S_MB_2U(SCH_1):PAGE101
   279    GND @S9S_MB_2U_LIB.S9S_MB_2U(SCH_1):GND   I176 @S9S_MB_2U_LIB.S9S_MB_2U(SCH_1):PAGE101
   281    GND @S9S_MB_2U_LIB.S9S_MB_2U(SCH_1):GND   I176 @S9S_MB_2U_LIB.S9S_MB_2U(SCH_1):PAGE101
   284    GND @S9S_MB_2U_LIB.S9S_MB_2U(SCH_1):GND   I176 @S9S_MB_2U_LIB.S9S_MB_2U(SCH_1):PAGE101
   286    GND @S9S_MB_2U_LIB.S9S_MB_2U(SCH_1):GND   I176 @S9S_MB_2U_LIB.S9S_MB_2U(SCH_1):PAGE101
   288    GND @S9S_MB_2U_LIB.S9S_MB_2U(SCH_1):GND   I176 @S9S_MB_2U_LIB.S9S_MB_2U(SCH_1):PAGE101
     1 P12V_S3_AUX_CPU1_NVDIMM @S9S_MB_2U_LIB.S9S_MB_2U(SCH_1):P12V_S3_AUX_CPU1_NVDIMM   I176 @S9S_MB_2U_LIB.S9S_MB_2U(SCH_1):PAGE101
   145 P12V_S3_AUX_CPU1_NVDIMM @S9S_MB_2U_LIB.S9S_MB_2U(SCH_1):P12V_S3_AUX_CPU1_NVDIMM   I176 @S9S_MB_2U_LIB.S9S_MB_2U(SCH_1):PAGE101
   146 P12V_S3_AUX_CPU1_NVDIMM @S9S_MB_2U_LIB.S9S_MB_2U(SCH_1):P12V_S3_AUX_CPU1_NVDIMM   I176 @S9S_MB_2U_LIB.S9S_MB_2U(SCH_1):PAGE101
   230    GND @S9S_MB_2U_LIB.S9S_MB_2U(SCH_1):GND   I176 @S9S_MB_2U_LIB.S9S_MB_2U(SCH_1):PAGE101
   235    GND @S9S_MB_2U_LIB.S9S_MB_2U(SCH_1):GND   I176 @S9S_MB_2U_LIB.S9S_MB_2U(SCH_1):PAGE101
   240    GND @S9S_MB_2U_LIB.S9S_MB_2U(SCH_1):GND   I176 @S9S_MB_2U_LIB.S9S_MB_2U(SCH_1):PAGE101
   132    GND @S9S_MB_2U_LIB.S9S_MB_2U(SCH_1):GND   I176 @S9S_MB_2U_LIB.S9S_MB_2U(SCH_1):PAGE101
   136    GND @S9S_MB_2U_LIB.S9S_MB_2U(SCH_1):GND   I176 @S9S_MB_2U_LIB.S9S_MB_2U(SCH_1):PAGE101
   139    GND @S9S_MB_2U_LIB.S9S_MB_2U(SCH_1):GND   I176 @S9S_MB_2U_LIB.S9S_MB_2U(SCH_1):PAGE101
   141    GND @S9S_MB_2U_LIB.S9S_MB_2U(SCH_1):GND   I176 @S9S_MB_2U_LIB.S9S_MB_2U(SCH_1):PAGE101
    G1    GND @S9S_MB_2U_LIB.S9S_MB_2U(SCH_1):GND   I176 @S9S_MB_2U_LIB.S9S_MB_2U(SCH_1):PAGE101
    G2    GND @S9S_MB_2U_LIB.S9S_MB_2U(SCH_1):GND   I176 @S9S_MB_2U_LIB.S9S_MB_2U(SCH_1):PAGE101
    G3    GND @S9S_MB_2U_LIB.S9S_MB_2U(SCH_1):GND   I176 @S9S_MB_2U_LIB.S9S_MB_2U(SCH_1):PAGE101

 J21 SCONN288_ADR50017P130CC-SCONN2A
     3 P3V3_AUX @S9S_MB_2U_LIB.S9S_MB_2U(SCH_1):P3V3_AUX    I13 @S9S_MB_2U_LIB.S9S_MB_2U(SCH_1):PAGE102
     2 TP_CHC_CPU1_DIMM1_FRU_0 @S9S_MB_2U_LIB.S9S_MB_2U(SCH_1):TP_CHC_CPU1_DIMM1_FRU_0    I13 @S9S_MB_2U_LIB.S9S_MB_2U(SCH_1):PAGE102
   144 TP_CHC_CPU1_DIMM1_FRU_1 @S9S_MB_2U_LIB.S9S_MB_2U(SCH_1):TP_CHC_CPU1_DIMM1_FRU_1    I13 @S9S_MB_2U_LIB.S9S_MB_2U(SCH_1):PAGE102
   149 TP_CHC_CPU1_DIMM1_FRU_2 @S9S_MB_2U_LIB.S9S_MB_2U(SCH_1):TP_CHC_CPU1_DIMM1_FRU_2    I13 @S9S_MB_2U_LIB.S9S_MB_2U(SCH_1):PAGE102
   150 TP_CHC_CPU1_DIMM1_FRU_3 @S9S_MB_2U_LIB.S9S_MB_2U(SCH_1):TP_CHC_CPU1_DIMM1_FRU_3    I13 @S9S_MB_2U_LIB.S9S_MB_2U(SCH_1):PAGE102
   220 TP_CHC_CPU1_DIMM1_FRU_4 @S9S_MB_2U_LIB.S9S_MB_2U(SCH_1):TP_CHC_CPU1_DIMM1_FRU_4    I13 @S9S_MB_2U_LIB.S9S_MB_2U(SCH_1):PAGE102
   231 TP_CHC_CPU1_DIMM1_FRU_5 @S9S_MB_2U_LIB.S9S_MB_2U(SCH_1):TP_CHC_CPU1_DIMM1_FRU_5    I13 @S9S_MB_2U_LIB.S9S_MB_2U(SCH_1):PAGE102
   232 TP_CHC_CPU1_DIMM1_FRU_6 @S9S_MB_2U_LIB.S9S_MB_2U(SCH_1):TP_CHC_CPU1_DIMM1_FRU_6    I13 @S9S_MB_2U_LIB.S9S_MB_2U(SCH_1):PAGE102
   207 RST_M_CD_CPU1_FPGA_N @S9S_MB_2U_LIB.S9S_MB_2U(SCH_1):RST_M_CD_CPU1_FPGA_N    I13 @S9S_MB_2U_LIB.S9S_MB_2U(SCH_1):PAGE102
   147 PWRGD_CHC_CPU1_DIMM1 @S9S_MB_2U_LIB.S9S_MB_2U(SCH_1):PWRGD_CHC_CPU1_DIMM1    I13 @S9S_MB_2U_LIB.S9S_MB_2U(SCH_1):PAGE102
   227 M_C_CPU1_SB_PAR @S9S_MB_2U_LIB.S9S_MB_2U(SCH_1):M_C_CPU1_SB_PAR    I13 @S9S_MB_2U_LIB.S9S_MB_2U(SCH_1):PAGE102
    74 M_C_CPU1_SA_PAR @S9S_MB_2U_LIB.S9S_MB_2U(SCH_1):M_C_CPU1_SA_PAR    I13 @S9S_MB_2U_LIB.S9S_MB_2U(SCH_1):PAGE102
    87 M_C_CPU1_SB_RSP<0> @S9S_MB_2U_LIB.S9S_MB_2U(SCH_1):M_C_CPU1_SB_RSP(0)    I13 @S9S_MB_2U_LIB.S9S_MB_2U(SCH_1):PAGE102
    86 M_C_CPU1_SA_RSP<0> @S9S_MB_2U_LIB.S9S_MB_2U(SCH_1):M_C_CPU1_SA_RSP(0)    I13 @S9S_MB_2U_LIB.S9S_MB_2U(SCH_1):PAGE102
     5 I3C_SPD_DDRABCD_CPU1_LVC1_SDA @S9S_MB_2U_LIB.S9S_MB_2U(SCH_1):I3C_SPD_DDRABCD_CPU1_LVC1_SDA    I13 @S9S_MB_2U_LIB.S9S_MB_2U(SCH_1):PAGE102
     4 I3C_SPD_DDRABCD_CPU1_LVC1_SCL_4 @S9S_MB_2U_LIB.S9S_MB_2U(SCH_1):I3C_SPD_DDRABCD_CPU1_LVC1_SCL_R5    I13 @S9S_MB_2U_LIB.S9S_MB_2U(SCH_1):PAGE102
   148 PD_CHC_CPU1_DIMM1_SAA @S9S_MB_2U_LIB.S9S_MB_2U(SCH_1):PD_CHC_CPU1_DIMM1_SAA    I13 @S9S_MB_2U_LIB.S9S_MB_2U(SCH_1):PAGE102
   100 M_C_CPU1_SB_DQ<0> @S9S_MB_2U_LIB.S9S_MB_2U(SCH_1):M_C_CPU1_SB_DQ(0)    I13 @S9S_MB_2U_LIB.S9S_MB_2U(SCH_1):PAGE102
   102 M_C_CPU1_SB_DQ<1> @S9S_MB_2U_LIB.S9S_MB_2U(SCH_1):M_C_CPU1_SB_DQ(1)    I13 @S9S_MB_2U_LIB.S9S_MB_2U(SCH_1):PAGE102
   245 M_C_CPU1_SB_DQ<2> @S9S_MB_2U_LIB.S9S_MB_2U(SCH_1):M_C_CPU1_SB_DQ(2)    I13 @S9S_MB_2U_LIB.S9S_MB_2U(SCH_1):PAGE102
   247 M_C_CPU1_SB_DQ<3> @S9S_MB_2U_LIB.S9S_MB_2U(SCH_1):M_C_CPU1_SB_DQ(3)    I13 @S9S_MB_2U_LIB.S9S_MB_2U(SCH_1):PAGE102
   107 M_C_CPU1_SB_DQ<4> @S9S_MB_2U_LIB.S9S_MB_2U(SCH_1):M_C_CPU1_SB_DQ(4)    I13 @S9S_MB_2U_LIB.S9S_MB_2U(SCH_1):PAGE102
   109 M_C_CPU1_SB_DQ<5> @S9S_MB_2U_LIB.S9S_MB_2U(SCH_1):M_C_CPU1_SB_DQ(5)    I13 @S9S_MB_2U_LIB.S9S_MB_2U(SCH_1):PAGE102
   252 M_C_CPU1_SB_DQ<6> @S9S_MB_2U_LIB.S9S_MB_2U(SCH_1):M_C_CPU1_SB_DQ(6)    I13 @S9S_MB_2U_LIB.S9S_MB_2U(SCH_1):PAGE102
   254 M_C_CPU1_SB_DQ<7> @S9S_MB_2U_LIB.S9S_MB_2U(SCH_1):M_C_CPU1_SB_DQ(7)    I13 @S9S_MB_2U_LIB.S9S_MB_2U(SCH_1):PAGE102
   111 M_C_CPU1_SB_DQ<8> @S9S_MB_2U_LIB.S9S_MB_2U(SCH_1):M_C_CPU1_SB_DQ(8)    I13 @S9S_MB_2U_LIB.S9S_MB_2U(SCH_1):PAGE102
   113 M_C_CPU1_SB_DQ<9> @S9S_MB_2U_LIB.S9S_MB_2U(SCH_1):M_C_CPU1_SB_DQ(9)    I13 @S9S_MB_2U_LIB.S9S_MB_2U(SCH_1):PAGE102
   256 M_C_CPU1_SB_DQ<10> @S9S_MB_2U_LIB.S9S_MB_2U(SCH_1):M_C_CPU1_SB_DQ(10)    I13 @S9S_MB_2U_LIB.S9S_MB_2U(SCH_1):PAGE102
   258 M_C_CPU1_SB_DQ<11> @S9S_MB_2U_LIB.S9S_MB_2U(SCH_1):M_C_CPU1_SB_DQ(11)    I13 @S9S_MB_2U_LIB.S9S_MB_2U(SCH_1):PAGE102
   118 M_C_CPU1_SB_DQ<12> @S9S_MB_2U_LIB.S9S_MB_2U(SCH_1):M_C_CPU1_SB_DQ(12)    I13 @S9S_MB_2U_LIB.S9S_MB_2U(SCH_1):PAGE102
   120 M_C_CPU1_SB_DQ<13> @S9S_MB_2U_LIB.S9S_MB_2U(SCH_1):M_C_CPU1_SB_DQ(13)    I13 @S9S_MB_2U_LIB.S9S_MB_2U(SCH_1):PAGE102
   263 M_C_CPU1_SB_DQ<14> @S9S_MB_2U_LIB.S9S_MB_2U(SCH_1):M_C_CPU1_SB_DQ(14)    I13 @S9S_MB_2U_LIB.S9S_MB_2U(SCH_1):PAGE102
   265 M_C_CPU1_SB_DQ<15> @S9S_MB_2U_LIB.S9S_MB_2U(SCH_1):M_C_CPU1_SB_DQ(15)    I13 @S9S_MB_2U_LIB.S9S_MB_2U(SCH_1):PAGE102
   122 M_C_CPU1_SB_DQ<16> @S9S_MB_2U_LIB.S9S_MB_2U(SCH_1):M_C_CPU1_SB_DQ(16)    I13 @S9S_MB_2U_LIB.S9S_MB_2U(SCH_1):PAGE102
   124 M_C_CPU1_SB_DQ<17> @S9S_MB_2U_LIB.S9S_MB_2U(SCH_1):M_C_CPU1_SB_DQ(17)    I13 @S9S_MB_2U_LIB.S9S_MB_2U(SCH_1):PAGE102
   267 M_C_CPU1_SB_DQ<18> @S9S_MB_2U_LIB.S9S_MB_2U(SCH_1):M_C_CPU1_SB_DQ(18)    I13 @S9S_MB_2U_LIB.S9S_MB_2U(SCH_1):PAGE102
   269 M_C_CPU1_SB_DQ<19> @S9S_MB_2U_LIB.S9S_MB_2U(SCH_1):M_C_CPU1_SB_DQ(19)    I13 @S9S_MB_2U_LIB.S9S_MB_2U(SCH_1):PAGE102
   129 M_C_CPU1_SB_DQ<20> @S9S_MB_2U_LIB.S9S_MB_2U(SCH_1):M_C_CPU1_SB_DQ(20)    I13 @S9S_MB_2U_LIB.S9S_MB_2U(SCH_1):PAGE102
   131 M_C_CPU1_SB_DQ<21> @S9S_MB_2U_LIB.S9S_MB_2U(SCH_1):M_C_CPU1_SB_DQ(21)    I13 @S9S_MB_2U_LIB.S9S_MB_2U(SCH_1):PAGE102
   274 M_C_CPU1_SB_DQ<22> @S9S_MB_2U_LIB.S9S_MB_2U(SCH_1):M_C_CPU1_SB_DQ(22)    I13 @S9S_MB_2U_LIB.S9S_MB_2U(SCH_1):PAGE102
   276 M_C_CPU1_SB_DQ<23> @S9S_MB_2U_LIB.S9S_MB_2U(SCH_1):M_C_CPU1_SB_DQ(23)    I13 @S9S_MB_2U_LIB.S9S_MB_2U(SCH_1):PAGE102
   133 M_C_CPU1_SB_DQ<24> @S9S_MB_2U_LIB.S9S_MB_2U(SCH_1):M_C_CPU1_SB_DQ(24)    I13 @S9S_MB_2U_LIB.S9S_MB_2U(SCH_1):PAGE102
   135 M_C_CPU1_SB_DQ<25> @S9S_MB_2U_LIB.S9S_MB_2U(SCH_1):M_C_CPU1_SB_DQ(25)    I13 @S9S_MB_2U_LIB.S9S_MB_2U(SCH_1):PAGE102
   278 M_C_CPU1_SB_DQ<26> @S9S_MB_2U_LIB.S9S_MB_2U(SCH_1):M_C_CPU1_SB_DQ(26)    I13 @S9S_MB_2U_LIB.S9S_MB_2U(SCH_1):PAGE102
   280 M_C_CPU1_SB_DQ<27> @S9S_MB_2U_LIB.S9S_MB_2U(SCH_1):M_C_CPU1_SB_DQ(27)    I13 @S9S_MB_2U_LIB.S9S_MB_2U(SCH_1):PAGE102
   140 M_C_CPU1_SB_DQ<28> @S9S_MB_2U_LIB.S9S_MB_2U(SCH_1):M_C_CPU1_SB_DQ(28)    I13 @S9S_MB_2U_LIB.S9S_MB_2U(SCH_1):PAGE102
   142 M_C_CPU1_SB_DQ<29> @S9S_MB_2U_LIB.S9S_MB_2U(SCH_1):M_C_CPU1_SB_DQ(29)    I13 @S9S_MB_2U_LIB.S9S_MB_2U(SCH_1):PAGE102
   285 M_C_CPU1_SB_DQ<30> @S9S_MB_2U_LIB.S9S_MB_2U(SCH_1):M_C_CPU1_SB_DQ(30)    I13 @S9S_MB_2U_LIB.S9S_MB_2U(SCH_1):PAGE102
   287 M_C_CPU1_SB_DQ<31> @S9S_MB_2U_LIB.S9S_MB_2U(SCH_1):M_C_CPU1_SB_DQ(31)    I13 @S9S_MB_2U_LIB.S9S_MB_2U(SCH_1):PAGE102
     7 M_C_CPU1_SA_DQ<0> @S9S_MB_2U_LIB.S9S_MB_2U(SCH_1):M_C_CPU1_SA_DQ(0)    I13 @S9S_MB_2U_LIB.S9S_MB_2U(SCH_1):PAGE102
     9 M_C_CPU1_SA_DQ<1> @S9S_MB_2U_LIB.S9S_MB_2U(SCH_1):M_C_CPU1_SA_DQ(1)    I13 @S9S_MB_2U_LIB.S9S_MB_2U(SCH_1):PAGE102
   152 M_C_CPU1_SA_DQ<2> @S9S_MB_2U_LIB.S9S_MB_2U(SCH_1):M_C_CPU1_SA_DQ(2)    I13 @S9S_MB_2U_LIB.S9S_MB_2U(SCH_1):PAGE102
   154 M_C_CPU1_SA_DQ<3> @S9S_MB_2U_LIB.S9S_MB_2U(SCH_1):M_C_CPU1_SA_DQ(3)    I13 @S9S_MB_2U_LIB.S9S_MB_2U(SCH_1):PAGE102
    14 M_C_CPU1_SA_DQ<4> @S9S_MB_2U_LIB.S9S_MB_2U(SCH_1):M_C_CPU1_SA_DQ(4)    I13 @S9S_MB_2U_LIB.S9S_MB_2U(SCH_1):PAGE102
    16 M_C_CPU1_SA_DQ<5> @S9S_MB_2U_LIB.S9S_MB_2U(SCH_1):M_C_CPU1_SA_DQ(5)    I13 @S9S_MB_2U_LIB.S9S_MB_2U(SCH_1):PAGE102
   159 M_C_CPU1_SA_DQ<6> @S9S_MB_2U_LIB.S9S_MB_2U(SCH_1):M_C_CPU1_SA_DQ(6)    I13 @S9S_MB_2U_LIB.S9S_MB_2U(SCH_1):PAGE102
   161 M_C_CPU1_SA_DQ<7> @S9S_MB_2U_LIB.S9S_MB_2U(SCH_1):M_C_CPU1_SA_DQ(7)    I13 @S9S_MB_2U_LIB.S9S_MB_2U(SCH_1):PAGE102
    18 M_C_CPU1_SA_DQ<8> @S9S_MB_2U_LIB.S9S_MB_2U(SCH_1):M_C_CPU1_SA_DQ(8)    I13 @S9S_MB_2U_LIB.S9S_MB_2U(SCH_1):PAGE102
    20 M_C_CPU1_SA_DQ<9> @S9S_MB_2U_LIB.S9S_MB_2U(SCH_1):M_C_CPU1_SA_DQ(9)    I13 @S9S_MB_2U_LIB.S9S_MB_2U(SCH_1):PAGE102
   163 M_C_CPU1_SA_DQ<10> @S9S_MB_2U_LIB.S9S_MB_2U(SCH_1):M_C_CPU1_SA_DQ(10)    I13 @S9S_MB_2U_LIB.S9S_MB_2U(SCH_1):PAGE102
   165 M_C_CPU1_SA_DQ<11> @S9S_MB_2U_LIB.S9S_MB_2U(SCH_1):M_C_CPU1_SA_DQ(11)    I13 @S9S_MB_2U_LIB.S9S_MB_2U(SCH_1):PAGE102
    25 M_C_CPU1_SA_DQ<12> @S9S_MB_2U_LIB.S9S_MB_2U(SCH_1):M_C_CPU1_SA_DQ(12)    I13 @S9S_MB_2U_LIB.S9S_MB_2U(SCH_1):PAGE102
    27 M_C_CPU1_SA_DQ<13> @S9S_MB_2U_LIB.S9S_MB_2U(SCH_1):M_C_CPU1_SA_DQ(13)    I13 @S9S_MB_2U_LIB.S9S_MB_2U(SCH_1):PAGE102
   170 M_C_CPU1_SA_DQ<14> @S9S_MB_2U_LIB.S9S_MB_2U(SCH_1):M_C_CPU1_SA_DQ(14)    I13 @S9S_MB_2U_LIB.S9S_MB_2U(SCH_1):PAGE102
   172 M_C_CPU1_SA_DQ<15> @S9S_MB_2U_LIB.S9S_MB_2U(SCH_1):M_C_CPU1_SA_DQ(15)    I13 @S9S_MB_2U_LIB.S9S_MB_2U(SCH_1):PAGE102
    29 M_C_CPU1_SA_DQ<16> @S9S_MB_2U_LIB.S9S_MB_2U(SCH_1):M_C_CPU1_SA_DQ(16)    I13 @S9S_MB_2U_LIB.S9S_MB_2U(SCH_1):PAGE102
    31 M_C_CPU1_SA_DQ<17> @S9S_MB_2U_LIB.S9S_MB_2U(SCH_1):M_C_CPU1_SA_DQ(17)    I13 @S9S_MB_2U_LIB.S9S_MB_2U(SCH_1):PAGE102
   174 M_C_CPU1_SA_DQ<18> @S9S_MB_2U_LIB.S9S_MB_2U(SCH_1):M_C_CPU1_SA_DQ(18)    I13 @S9S_MB_2U_LIB.S9S_MB_2U(SCH_1):PAGE102
   176 M_C_CPU1_SA_DQ<19> @S9S_MB_2U_LIB.S9S_MB_2U(SCH_1):M_C_CPU1_SA_DQ(19)    I13 @S9S_MB_2U_LIB.S9S_MB_2U(SCH_1):PAGE102
    36 M_C_CPU1_SA_DQ<20> @S9S_MB_2U_LIB.S9S_MB_2U(SCH_1):M_C_CPU1_SA_DQ(20)    I13 @S9S_MB_2U_LIB.S9S_MB_2U(SCH_1):PAGE102
    38 M_C_CPU1_SA_DQ<21> @S9S_MB_2U_LIB.S9S_MB_2U(SCH_1):M_C_CPU1_SA_DQ(21)    I13 @S9S_MB_2U_LIB.S9S_MB_2U(SCH_1):PAGE102
   181 M_C_CPU1_SA_DQ<22> @S9S_MB_2U_LIB.S9S_MB_2U(SCH_1):M_C_CPU1_SA_DQ(22)    I13 @S9S_MB_2U_LIB.S9S_MB_2U(SCH_1):PAGE102
   183 M_C_CPU1_SA_DQ<23> @S9S_MB_2U_LIB.S9S_MB_2U(SCH_1):M_C_CPU1_SA_DQ(23)    I13 @S9S_MB_2U_LIB.S9S_MB_2U(SCH_1):PAGE102
    40 M_C_CPU1_SA_DQ<24> @S9S_MB_2U_LIB.S9S_MB_2U(SCH_1):M_C_CPU1_SA_DQ(24)    I13 @S9S_MB_2U_LIB.S9S_MB_2U(SCH_1):PAGE102
    42 M_C_CPU1_SA_DQ<25> @S9S_MB_2U_LIB.S9S_MB_2U(SCH_1):M_C_CPU1_SA_DQ(25)    I13 @S9S_MB_2U_LIB.S9S_MB_2U(SCH_1):PAGE102
   185 M_C_CPU1_SA_DQ<26> @S9S_MB_2U_LIB.S9S_MB_2U(SCH_1):M_C_CPU1_SA_DQ(26)    I13 @S9S_MB_2U_LIB.S9S_MB_2U(SCH_1):PAGE102
   187 M_C_CPU1_SA_DQ<27> @S9S_MB_2U_LIB.S9S_MB_2U(SCH_1):M_C_CPU1_SA_DQ(27)    I13 @S9S_MB_2U_LIB.S9S_MB_2U(SCH_1):PAGE102
    47 M_C_CPU1_SA_DQ<28> @S9S_MB_2U_LIB.S9S_MB_2U(SCH_1):M_C_CPU1_SA_DQ(28)    I13 @S9S_MB_2U_LIB.S9S_MB_2U(SCH_1):PAGE102
    49 M_C_CPU1_SA_DQ<29> @S9S_MB_2U_LIB.S9S_MB_2U(SCH_1):M_C_CPU1_SA_DQ(29)    I13 @S9S_MB_2U_LIB.S9S_MB_2U(SCH_1):PAGE102
   192 M_C_CPU1_SA_DQ<30> @S9S_MB_2U_LIB.S9S_MB_2U(SCH_1):M_C_CPU1_SA_DQ(30)    I13 @S9S_MB_2U_LIB.S9S_MB_2U(SCH_1):PAGE102
   229 M_C_CPU1_SB_CS_N<1> @S9S_MB_2U_LIB.S9S_MB_2U(SCH_1):M_C_CPU1_SB_CS_N(1)    I13 @S9S_MB_2U_LIB.S9S_MB_2U(SCH_1):PAGE102
   209 M_C_CPU1_SA_CS_N<1> @S9S_MB_2U_LIB.S9S_MB_2U(SCH_1):M_C_CPU1_SA_CS_N(1)    I13 @S9S_MB_2U_LIB.S9S_MB_2U(SCH_1):PAGE102
    84 M_C_CPU1_SB_CS_N<0> @S9S_MB_2U_LIB.S9S_MB_2U(SCH_1):M_C_CPU1_SB_CS_N(0)    I13 @S9S_MB_2U_LIB.S9S_MB_2U(SCH_1):PAGE102
    64 M_C_CPU1_SA_CS_N<0> @S9S_MB_2U_LIB.S9S_MB_2U(SCH_1):M_C_CPU1_SA_CS_N(0)    I13 @S9S_MB_2U_LIB.S9S_MB_2U(SCH_1):PAGE102
   217 M_C_CPU1_CLK_DP<0> @S9S_MB_2U_LIB.S9S_MB_2U(SCH_1):M_C_CPU1_CLK_DP(0)    I13 @S9S_MB_2U_LIB.S9S_MB_2U(SCH_1):PAGE102
   218 M_C_CPU1_CLK_DN<0> @S9S_MB_2U_LIB.S9S_MB_2U(SCH_1):M_C_CPU1_CLK_DN(0)    I13 @S9S_MB_2U_LIB.S9S_MB_2U(SCH_1):PAGE102
    96 M_C_CPU1_SB_CB<0> @S9S_MB_2U_LIB.S9S_MB_2U(SCH_1):M_C_CPU1_SB_CB(0)    I13 @S9S_MB_2U_LIB.S9S_MB_2U(SCH_1):PAGE102
    98 M_C_CPU1_SB_CB<1> @S9S_MB_2U_LIB.S9S_MB_2U(SCH_1):M_C_CPU1_SB_CB(1)    I13 @S9S_MB_2U_LIB.S9S_MB_2U(SCH_1):PAGE102
   241 M_C_CPU1_SB_CB<2> @S9S_MB_2U_LIB.S9S_MB_2U(SCH_1):M_C_CPU1_SB_CB(2)    I13 @S9S_MB_2U_LIB.S9S_MB_2U(SCH_1):PAGE102
   243 M_C_CPU1_SB_CB<3> @S9S_MB_2U_LIB.S9S_MB_2U(SCH_1):M_C_CPU1_SB_CB(3)    I13 @S9S_MB_2U_LIB.S9S_MB_2U(SCH_1):PAGE102
    89 M_C_CPU1_SB_CB<4> @S9S_MB_2U_LIB.S9S_MB_2U(SCH_1):M_C_CPU1_SB_CB(4)    I13 @S9S_MB_2U_LIB.S9S_MB_2U(SCH_1):PAGE102
    91 M_C_CPU1_SB_CB<5> @S9S_MB_2U_LIB.S9S_MB_2U(SCH_1):M_C_CPU1_SB_CB(5)    I13 @S9S_MB_2U_LIB.S9S_MB_2U(SCH_1):PAGE102
   234 M_C_CPU1_SB_CB<6> @S9S_MB_2U_LIB.S9S_MB_2U(SCH_1):M_C_CPU1_SB_CB(6)    I13 @S9S_MB_2U_LIB.S9S_MB_2U(SCH_1):PAGE102
    51 M_C_CPU1_SA_CB<0> @S9S_MB_2U_LIB.S9S_MB_2U(SCH_1):M_C_CPU1_SA_CB(0)    I13 @S9S_MB_2U_LIB.S9S_MB_2U(SCH_1):PAGE102
   196 M_C_CPU1_SA_CB<2> @S9S_MB_2U_LIB.S9S_MB_2U(SCH_1):M_C_CPU1_SA_CB(2)    I13 @S9S_MB_2U_LIB.S9S_MB_2U(SCH_1):PAGE102
   198 M_C_CPU1_SA_CB<3> @S9S_MB_2U_LIB.S9S_MB_2U(SCH_1):M_C_CPU1_SA_CB(3)    I13 @S9S_MB_2U_LIB.S9S_MB_2U(SCH_1):PAGE102
    60 M_C_CPU1_SA_CB<5> @S9S_MB_2U_LIB.S9S_MB_2U(SCH_1):M_C_CPU1_SA_CB(5)    I13 @S9S_MB_2U_LIB.S9S_MB_2U(SCH_1):PAGE102
   203 M_C_CPU1_SA_CB<6> @S9S_MB_2U_LIB.S9S_MB_2U(SCH_1):M_C_CPU1_SA_CB(6)    I13 @S9S_MB_2U_LIB.S9S_MB_2U(SCH_1):PAGE102
    82 M_C_CPU1_SB_CA<6> @S9S_MB_2U_LIB.S9S_MB_2U(SCH_1):M_C_CPU1_SB_CA(6)    I13 @S9S_MB_2U_LIB.S9S_MB_2U(SCH_1):PAGE102
    72 M_C_CPU1_SA_CA<6> @S9S_MB_2U_LIB.S9S_MB_2U(SCH_1):M_C_CPU1_SA_CA(6)    I13 @S9S_MB_2U_LIB.S9S_MB_2U(SCH_1):PAGE102
   225 M_C_CPU1_SB_CA<5> @S9S_MB_2U_LIB.S9S_MB_2U(SCH_1):M_C_CPU1_SB_CA(5)    I13 @S9S_MB_2U_LIB.S9S_MB_2U(SCH_1):PAGE102
   215 M_C_CPU1_SA_CA<5> @S9S_MB_2U_LIB.S9S_MB_2U(SCH_1):M_C_CPU1_SA_CA(5)    I13 @S9S_MB_2U_LIB.S9S_MB_2U(SCH_1):PAGE102
    80 M_C_CPU1_SB_CA<4> @S9S_MB_2U_LIB.S9S_MB_2U(SCH_1):M_C_CPU1_SB_CA(4)    I13 @S9S_MB_2U_LIB.S9S_MB_2U(SCH_1):PAGE102
    70 M_C_CPU1_SA_CA<4> @S9S_MB_2U_LIB.S9S_MB_2U(SCH_1):M_C_CPU1_SA_CA(4)    I13 @S9S_MB_2U_LIB.S9S_MB_2U(SCH_1):PAGE102
   223 M_C_CPU1_SB_CA<3> @S9S_MB_2U_LIB.S9S_MB_2U(SCH_1):M_C_CPU1_SB_CA(3)    I13 @S9S_MB_2U_LIB.S9S_MB_2U(SCH_1):PAGE102
   213 M_C_CPU1_SA_CA<3> @S9S_MB_2U_LIB.S9S_MB_2U(SCH_1):M_C_CPU1_SA_CA(3)    I13 @S9S_MB_2U_LIB.S9S_MB_2U(SCH_1):PAGE102
    78 M_C_CPU1_SB_CA<2> @S9S_MB_2U_LIB.S9S_MB_2U(SCH_1):M_C_CPU1_SB_CA(2)    I13 @S9S_MB_2U_LIB.S9S_MB_2U(SCH_1):PAGE102
    68 M_C_CPU1_SA_CA<2> @S9S_MB_2U_LIB.S9S_MB_2U(SCH_1):M_C_CPU1_SA_CA(2)    I13 @S9S_MB_2U_LIB.S9S_MB_2U(SCH_1):PAGE102
   221 M_C_CPU1_SB_CA<1> @S9S_MB_2U_LIB.S9S_MB_2U(SCH_1):M_C_CPU1_SB_CA(1)    I13 @S9S_MB_2U_LIB.S9S_MB_2U(SCH_1):PAGE102
   211 M_C_CPU1_SA_CA<1> @S9S_MB_2U_LIB.S9S_MB_2U(SCH_1):M_C_CPU1_SA_CA(1)    I13 @S9S_MB_2U_LIB.S9S_MB_2U(SCH_1):PAGE102
    76 M_C_CPU1_SB_CA<0> @S9S_MB_2U_LIB.S9S_MB_2U(SCH_1):M_C_CPU1_SB_CA(0)    I13 @S9S_MB_2U_LIB.S9S_MB_2U(SCH_1):PAGE102
    66 M_C_CPU1_SA_CA<0> @S9S_MB_2U_LIB.S9S_MB_2U(SCH_1):M_C_CPU1_SA_CA(0)    I13 @S9S_MB_2U_LIB.S9S_MB_2U(SCH_1):PAGE102
    62 M_C_CPU1_ALERT_N @S9S_MB_2U_LIB.S9S_MB_2U(SCH_1):M_C_CPU1_ALERT_N    I13 @S9S_MB_2U_LIB.S9S_MB_2U(SCH_1):PAGE102
   236 M_C_CPU1_SB_CB<7> @S9S_MB_2U_LIB.S9S_MB_2U(SCH_1):M_C_CPU1_SB_CB(7)    I13 @S9S_MB_2U_LIB.S9S_MB_2U(SCH_1):PAGE102
    53 M_C_CPU1_SA_CB<1> @S9S_MB_2U_LIB.S9S_MB_2U(SCH_1):M_C_CPU1_SA_CB(1)    I13 @S9S_MB_2U_LIB.S9S_MB_2U(SCH_1):PAGE102
    58 M_C_CPU1_SA_CB<4> @S9S_MB_2U_LIB.S9S_MB_2U(SCH_1):M_C_CPU1_SA_CB(4)    I13 @S9S_MB_2U_LIB.S9S_MB_2U(SCH_1):PAGE102
   205 M_C_CPU1_SA_CB<7> @S9S_MB_2U_LIB.S9S_MB_2U(SCH_1):M_C_CPU1_SA_CB(7)    I13 @S9S_MB_2U_LIB.S9S_MB_2U(SCH_1):PAGE102
   194 M_C_CPU1_SA_DQ<31> @S9S_MB_2U_LIB.S9S_MB_2U(SCH_1):M_C_CPU1_SA_DQ(31)    I13 @S9S_MB_2U_LIB.S9S_MB_2U(SCH_1):PAGE102
    93 M_C_CPU1_SB_DQS_DP<9> @S9S_MB_2U_LIB.S9S_MB_2U(SCH_1):M_C_CPU1_SB_DQS_DP(9)   I178 @S9S_MB_2U_LIB.S9S_MB_2U(SCH_1):PAGE102
    94 M_C_CPU1_SB_DQS_DN<9> @S9S_MB_2U_LIB.S9S_MB_2U(SCH_1):M_C_CPU1_SB_DQS_DN(9)   I178 @S9S_MB_2U_LIB.S9S_MB_2U(SCH_1):PAGE102
   201 M_C_CPU1_SA_DQS_DP<9> @S9S_MB_2U_LIB.S9S_MB_2U(SCH_1):M_C_CPU1_SA_DQS_DP(9)   I178 @S9S_MB_2U_LIB.S9S_MB_2U(SCH_1):PAGE102
   200 M_C_CPU1_SA_DQS_DN<9> @S9S_MB_2U_LIB.S9S_MB_2U(SCH_1):M_C_CPU1_SA_DQS_DN(9)   I178 @S9S_MB_2U_LIB.S9S_MB_2U(SCH_1):PAGE102
   190 M_C_CPU1_SA_DQS_DP<8> @S9S_MB_2U_LIB.S9S_MB_2U(SCH_1):M_C_CPU1_SA_DQS_DP(8)   I178 @S9S_MB_2U_LIB.S9S_MB_2U(SCH_1):PAGE102
   189 M_C_CPU1_SA_DQS_DN<8> @S9S_MB_2U_LIB.S9S_MB_2U(SCH_1):M_C_CPU1_SA_DQS_DN(8)   I178 @S9S_MB_2U_LIB.S9S_MB_2U(SCH_1):PAGE102
   271 M_C_CPU1_SB_DQS_DN<7> @S9S_MB_2U_LIB.S9S_MB_2U(SCH_1):M_C_CPU1_SB_DQS_DN(7)   I178 @S9S_MB_2U_LIB.S9S_MB_2U(SCH_1):PAGE102
   179 M_C_CPU1_SA_DQS_DP<7> @S9S_MB_2U_LIB.S9S_MB_2U(SCH_1):M_C_CPU1_SA_DQS_DP(7)   I178 @S9S_MB_2U_LIB.S9S_MB_2U(SCH_1):PAGE102
   261 M_C_CPU1_SB_DQS_DP<6> @S9S_MB_2U_LIB.S9S_MB_2U(SCH_1):M_C_CPU1_SB_DQS_DP(6)   I178 @S9S_MB_2U_LIB.S9S_MB_2U(SCH_1):PAGE102
   260 M_C_CPU1_SB_DQS_DN<6> @S9S_MB_2U_LIB.S9S_MB_2U(SCH_1):M_C_CPU1_SB_DQS_DN(6)   I178 @S9S_MB_2U_LIB.S9S_MB_2U(SCH_1):PAGE102
   167 M_C_CPU1_SA_DQS_DN<6> @S9S_MB_2U_LIB.S9S_MB_2U(SCH_1):M_C_CPU1_SA_DQS_DN(6)   I178 @S9S_MB_2U_LIB.S9S_MB_2U(SCH_1):PAGE102
   250 M_C_CPU1_SB_DQS_DP<5> @S9S_MB_2U_LIB.S9S_MB_2U(SCH_1):M_C_CPU1_SB_DQS_DP(5)   I178 @S9S_MB_2U_LIB.S9S_MB_2U(SCH_1):PAGE102
   249 M_C_CPU1_SB_DQS_DN<5> @S9S_MB_2U_LIB.S9S_MB_2U(SCH_1):M_C_CPU1_SB_DQS_DN(5)   I178 @S9S_MB_2U_LIB.S9S_MB_2U(SCH_1):PAGE102
   157 M_C_CPU1_SA_DQS_DP<5> @S9S_MB_2U_LIB.S9S_MB_2U(SCH_1):M_C_CPU1_SA_DQS_DP(5)   I178 @S9S_MB_2U_LIB.S9S_MB_2U(SCH_1):PAGE102
   156 M_C_CPU1_SA_DQS_DN<5> @S9S_MB_2U_LIB.S9S_MB_2U(SCH_1):M_C_CPU1_SA_DQS_DN(5)   I178 @S9S_MB_2U_LIB.S9S_MB_2U(SCH_1):PAGE102
   239 M_C_CPU1_SB_DQS_DP<4> @S9S_MB_2U_LIB.S9S_MB_2U(SCH_1):M_C_CPU1_SB_DQS_DP(4)   I178 @S9S_MB_2U_LIB.S9S_MB_2U(SCH_1):PAGE102
   238 M_C_CPU1_SB_DQS_DN<4> @S9S_MB_2U_LIB.S9S_MB_2U(SCH_1):M_C_CPU1_SB_DQS_DN(4)   I178 @S9S_MB_2U_LIB.S9S_MB_2U(SCH_1):PAGE102
    55 M_C_CPU1_SA_DQS_DP<4> @S9S_MB_2U_LIB.S9S_MB_2U(SCH_1):M_C_CPU1_SA_DQS_DP(4)   I178 @S9S_MB_2U_LIB.S9S_MB_2U(SCH_1):PAGE102
    56 M_C_CPU1_SA_DQS_DN<4> @S9S_MB_2U_LIB.S9S_MB_2U(SCH_1):M_C_CPU1_SA_DQS_DN(4)   I178 @S9S_MB_2U_LIB.S9S_MB_2U(SCH_1):PAGE102
   137 M_C_CPU1_SB_DQS_DP<3> @S9S_MB_2U_LIB.S9S_MB_2U(SCH_1):M_C_CPU1_SB_DQS_DP(3)   I178 @S9S_MB_2U_LIB.S9S_MB_2U(SCH_1):PAGE102
   138 M_C_CPU1_SB_DQS_DN<3> @S9S_MB_2U_LIB.S9S_MB_2U(SCH_1):M_C_CPU1_SB_DQS_DN(3)   I178 @S9S_MB_2U_LIB.S9S_MB_2U(SCH_1):PAGE102
    44 M_C_CPU1_SA_DQS_DP<3> @S9S_MB_2U_LIB.S9S_MB_2U(SCH_1):M_C_CPU1_SA_DQS_DP(3)   I178 @S9S_MB_2U_LIB.S9S_MB_2U(SCH_1):PAGE102
    45 M_C_CPU1_SA_DQS_DN<3> @S9S_MB_2U_LIB.S9S_MB_2U(SCH_1):M_C_CPU1_SA_DQS_DN(3)   I178 @S9S_MB_2U_LIB.S9S_MB_2U(SCH_1):PAGE102
   126 M_C_CPU1_SB_DQS_DP<2> @S9S_MB_2U_LIB.S9S_MB_2U(SCH_1):M_C_CPU1_SB_DQS_DP(2)   I178 @S9S_MB_2U_LIB.S9S_MB_2U(SCH_1):PAGE102
   127 M_C_CPU1_SB_DQS_DN<2> @S9S_MB_2U_LIB.S9S_MB_2U(SCH_1):M_C_CPU1_SB_DQS_DN(2)   I178 @S9S_MB_2U_LIB.S9S_MB_2U(SCH_1):PAGE102
    33 M_C_CPU1_SA_DQS_DP<2> @S9S_MB_2U_LIB.S9S_MB_2U(SCH_1):M_C_CPU1_SA_DQS_DP(2)   I178 @S9S_MB_2U_LIB.S9S_MB_2U(SCH_1):PAGE102
    34 M_C_CPU1_SA_DQS_DN<2> @S9S_MB_2U_LIB.S9S_MB_2U(SCH_1):M_C_CPU1_SA_DQS_DN(2)   I178 @S9S_MB_2U_LIB.S9S_MB_2U(SCH_1):PAGE102
   115 M_C_CPU1_SB_DQS_DP<1> @S9S_MB_2U_LIB.S9S_MB_2U(SCH_1):M_C_CPU1_SB_DQS_DP(1)   I178 @S9S_MB_2U_LIB.S9S_MB_2U(SCH_1):PAGE102
   116 M_C_CPU1_SB_DQS_DN<1> @S9S_MB_2U_LIB.S9S_MB_2U(SCH_1):M_C_CPU1_SB_DQS_DN(1)   I178 @S9S_MB_2U_LIB.S9S_MB_2U(SCH_1):PAGE102
    22 M_C_CPU1_SA_DQS_DP<1> @S9S_MB_2U_LIB.S9S_MB_2U(SCH_1):M_C_CPU1_SA_DQS_DP(1)   I178 @S9S_MB_2U_LIB.S9S_MB_2U(SCH_1):PAGE102
    23 M_C_CPU1_SA_DQS_DN<1> @S9S_MB_2U_LIB.S9S_MB_2U(SCH_1):M_C_CPU1_SA_DQS_DN(1)   I178 @S9S_MB_2U_LIB.S9S_MB_2U(SCH_1):PAGE102
   104 M_C_CPU1_SB_DQS_DP<0> @S9S_MB_2U_LIB.S9S_MB_2U(SCH_1):M_C_CPU1_SB_DQS_DP(0)   I178 @S9S_MB_2U_LIB.S9S_MB_2U(SCH_1):PAGE102
   105 M_C_CPU1_SB_DQS_DN<0> @S9S_MB_2U_LIB.S9S_MB_2U(SCH_1):M_C_CPU1_SB_DQS_DN(0)   I178 @S9S_MB_2U_LIB.S9S_MB_2U(SCH_1):PAGE102
    11 M_C_CPU1_SA_DQS_DP<0> @S9S_MB_2U_LIB.S9S_MB_2U(SCH_1):M_C_CPU1_SA_DQS_DP(0)   I178 @S9S_MB_2U_LIB.S9S_MB_2U(SCH_1):PAGE102
    12 M_C_CPU1_SA_DQS_DN<0> @S9S_MB_2U_LIB.S9S_MB_2U(SCH_1):M_C_CPU1_SA_DQS_DN(0)   I178 @S9S_MB_2U_LIB.S9S_MB_2U(SCH_1):PAGE102
   272 M_C_CPU1_SB_DQS_DP<7> @S9S_MB_2U_LIB.S9S_MB_2U(SCH_1):M_C_CPU1_SB_DQS_DP(7)   I178 @S9S_MB_2U_LIB.S9S_MB_2U(SCH_1):PAGE102
   282 M_C_CPU1_SB_DQS_DN<8> @S9S_MB_2U_LIB.S9S_MB_2U(SCH_1):M_C_CPU1_SB_DQS_DN(8)   I178 @S9S_MB_2U_LIB.S9S_MB_2U(SCH_1):PAGE102
   283 M_C_CPU1_SB_DQS_DP<8> @S9S_MB_2U_LIB.S9S_MB_2U(SCH_1):M_C_CPU1_SB_DQS_DP(8)   I178 @S9S_MB_2U_LIB.S9S_MB_2U(SCH_1):PAGE102
   168 M_C_CPU1_SA_DQS_DP<6> @S9S_MB_2U_LIB.S9S_MB_2U(SCH_1):M_C_CPU1_SA_DQS_DP(6)   I178 @S9S_MB_2U_LIB.S9S_MB_2U(SCH_1):PAGE102
   178 M_C_CPU1_SA_DQS_DN<7> @S9S_MB_2U_LIB.S9S_MB_2U(SCH_1):M_C_CPU1_SA_DQS_DN(7)   I178 @S9S_MB_2U_LIB.S9S_MB_2U(SCH_1):PAGE102
     6    GND @S9S_MB_2U_LIB.S9S_MB_2U(SCH_1):GND   I169 @S9S_MB_2U_LIB.S9S_MB_2U(SCH_1):PAGE102
     8    GND @S9S_MB_2U_LIB.S9S_MB_2U(SCH_1):GND   I169 @S9S_MB_2U_LIB.S9S_MB_2U(SCH_1):PAGE102
    10    GND @S9S_MB_2U_LIB.S9S_MB_2U(SCH_1):GND   I169 @S9S_MB_2U_LIB.S9S_MB_2U(SCH_1):PAGE102
    13    GND @S9S_MB_2U_LIB.S9S_MB_2U(SCH_1):GND   I169 @S9S_MB_2U_LIB.S9S_MB_2U(SCH_1):PAGE102
    15    GND @S9S_MB_2U_LIB.S9S_MB_2U(SCH_1):GND   I169 @S9S_MB_2U_LIB.S9S_MB_2U(SCH_1):PAGE102
    17    GND @S9S_MB_2U_LIB.S9S_MB_2U(SCH_1):GND   I169 @S9S_MB_2U_LIB.S9S_MB_2U(SCH_1):PAGE102
    19    GND @S9S_MB_2U_LIB.S9S_MB_2U(SCH_1):GND   I169 @S9S_MB_2U_LIB.S9S_MB_2U(SCH_1):PAGE102
    21    GND @S9S_MB_2U_LIB.S9S_MB_2U(SCH_1):GND   I169 @S9S_MB_2U_LIB.S9S_MB_2U(SCH_1):PAGE102
    24    GND @S9S_MB_2U_LIB.S9S_MB_2U(SCH_1):GND   I169 @S9S_MB_2U_LIB.S9S_MB_2U(SCH_1):PAGE102
    26    GND @S9S_MB_2U_LIB.S9S_MB_2U(SCH_1):GND   I169 @S9S_MB_2U_LIB.S9S_MB_2U(SCH_1):PAGE102
    28    GND @S9S_MB_2U_LIB.S9S_MB_2U(SCH_1):GND   I169 @S9S_MB_2U_LIB.S9S_MB_2U(SCH_1):PAGE102
    30    GND @S9S_MB_2U_LIB.S9S_MB_2U(SCH_1):GND   I169 @S9S_MB_2U_LIB.S9S_MB_2U(SCH_1):PAGE102
    32    GND @S9S_MB_2U_LIB.S9S_MB_2U(SCH_1):GND   I169 @S9S_MB_2U_LIB.S9S_MB_2U(SCH_1):PAGE102
    35    GND @S9S_MB_2U_LIB.S9S_MB_2U(SCH_1):GND   I169 @S9S_MB_2U_LIB.S9S_MB_2U(SCH_1):PAGE102
    37    GND @S9S_MB_2U_LIB.S9S_MB_2U(SCH_1):GND   I169 @S9S_MB_2U_LIB.S9S_MB_2U(SCH_1):PAGE102
    39    GND @S9S_MB_2U_LIB.S9S_MB_2U(SCH_1):GND   I169 @S9S_MB_2U_LIB.S9S_MB_2U(SCH_1):PAGE102
    41    GND @S9S_MB_2U_LIB.S9S_MB_2U(SCH_1):GND   I169 @S9S_MB_2U_LIB.S9S_MB_2U(SCH_1):PAGE102
    43    GND @S9S_MB_2U_LIB.S9S_MB_2U(SCH_1):GND   I169 @S9S_MB_2U_LIB.S9S_MB_2U(SCH_1):PAGE102
    46    GND @S9S_MB_2U_LIB.S9S_MB_2U(SCH_1):GND   I169 @S9S_MB_2U_LIB.S9S_MB_2U(SCH_1):PAGE102
    48    GND @S9S_MB_2U_LIB.S9S_MB_2U(SCH_1):GND   I169 @S9S_MB_2U_LIB.S9S_MB_2U(SCH_1):PAGE102
    50    GND @S9S_MB_2U_LIB.S9S_MB_2U(SCH_1):GND   I169 @S9S_MB_2U_LIB.S9S_MB_2U(SCH_1):PAGE102
    52    GND @S9S_MB_2U_LIB.S9S_MB_2U(SCH_1):GND   I169 @S9S_MB_2U_LIB.S9S_MB_2U(SCH_1):PAGE102
    54    GND @S9S_MB_2U_LIB.S9S_MB_2U(SCH_1):GND   I169 @S9S_MB_2U_LIB.S9S_MB_2U(SCH_1):PAGE102
    57    GND @S9S_MB_2U_LIB.S9S_MB_2U(SCH_1):GND   I169 @S9S_MB_2U_LIB.S9S_MB_2U(SCH_1):PAGE102
    59    GND @S9S_MB_2U_LIB.S9S_MB_2U(SCH_1):GND   I169 @S9S_MB_2U_LIB.S9S_MB_2U(SCH_1):PAGE102
    61    GND @S9S_MB_2U_LIB.S9S_MB_2U(SCH_1):GND   I169 @S9S_MB_2U_LIB.S9S_MB_2U(SCH_1):PAGE102
    63    GND @S9S_MB_2U_LIB.S9S_MB_2U(SCH_1):GND   I169 @S9S_MB_2U_LIB.S9S_MB_2U(SCH_1):PAGE102
    65    GND @S9S_MB_2U_LIB.S9S_MB_2U(SCH_1):GND   I169 @S9S_MB_2U_LIB.S9S_MB_2U(SCH_1):PAGE102
    67    GND @S9S_MB_2U_LIB.S9S_MB_2U(SCH_1):GND   I169 @S9S_MB_2U_LIB.S9S_MB_2U(SCH_1):PAGE102
    69    GND @S9S_MB_2U_LIB.S9S_MB_2U(SCH_1):GND   I169 @S9S_MB_2U_LIB.S9S_MB_2U(SCH_1):PAGE102
    71    GND @S9S_MB_2U_LIB.S9S_MB_2U(SCH_1):GND   I169 @S9S_MB_2U_LIB.S9S_MB_2U(SCH_1):PAGE102
    73    GND @S9S_MB_2U_LIB.S9S_MB_2U(SCH_1):GND   I169 @S9S_MB_2U_LIB.S9S_MB_2U(SCH_1):PAGE102
    75    GND @S9S_MB_2U_LIB.S9S_MB_2U(SCH_1):GND   I169 @S9S_MB_2U_LIB.S9S_MB_2U(SCH_1):PAGE102
    77    GND @S9S_MB_2U_LIB.S9S_MB_2U(SCH_1):GND   I169 @S9S_MB_2U_LIB.S9S_MB_2U(SCH_1):PAGE102
    79    GND @S9S_MB_2U_LIB.S9S_MB_2U(SCH_1):GND   I169 @S9S_MB_2U_LIB.S9S_MB_2U(SCH_1):PAGE102
    81    GND @S9S_MB_2U_LIB.S9S_MB_2U(SCH_1):GND   I169 @S9S_MB_2U_LIB.S9S_MB_2U(SCH_1):PAGE102
    83    GND @S9S_MB_2U_LIB.S9S_MB_2U(SCH_1):GND   I169 @S9S_MB_2U_LIB.S9S_MB_2U(SCH_1):PAGE102
    85    GND @S9S_MB_2U_LIB.S9S_MB_2U(SCH_1):GND   I169 @S9S_MB_2U_LIB.S9S_MB_2U(SCH_1):PAGE102
    88    GND @S9S_MB_2U_LIB.S9S_MB_2U(SCH_1):GND   I169 @S9S_MB_2U_LIB.S9S_MB_2U(SCH_1):PAGE102
    90    GND @S9S_MB_2U_LIB.S9S_MB_2U(SCH_1):GND   I169 @S9S_MB_2U_LIB.S9S_MB_2U(SCH_1):PAGE102
    92    GND @S9S_MB_2U_LIB.S9S_MB_2U(SCH_1):GND   I169 @S9S_MB_2U_LIB.S9S_MB_2U(SCH_1):PAGE102
    95    GND @S9S_MB_2U_LIB.S9S_MB_2U(SCH_1):GND   I169 @S9S_MB_2U_LIB.S9S_MB_2U(SCH_1):PAGE102
    97    GND @S9S_MB_2U_LIB.S9S_MB_2U(SCH_1):GND   I169 @S9S_MB_2U_LIB.S9S_MB_2U(SCH_1):PAGE102
    99    GND @S9S_MB_2U_LIB.S9S_MB_2U(SCH_1):GND   I169 @S9S_MB_2U_LIB.S9S_MB_2U(SCH_1):PAGE102
   101    GND @S9S_MB_2U_LIB.S9S_MB_2U(SCH_1):GND   I169 @S9S_MB_2U_LIB.S9S_MB_2U(SCH_1):PAGE102
   103    GND @S9S_MB_2U_LIB.S9S_MB_2U(SCH_1):GND   I169 @S9S_MB_2U_LIB.S9S_MB_2U(SCH_1):PAGE102
   106    GND @S9S_MB_2U_LIB.S9S_MB_2U(SCH_1):GND   I169 @S9S_MB_2U_LIB.S9S_MB_2U(SCH_1):PAGE102
   108    GND @S9S_MB_2U_LIB.S9S_MB_2U(SCH_1):GND   I169 @S9S_MB_2U_LIB.S9S_MB_2U(SCH_1):PAGE102
   110    GND @S9S_MB_2U_LIB.S9S_MB_2U(SCH_1):GND   I169 @S9S_MB_2U_LIB.S9S_MB_2U(SCH_1):PAGE102
   112    GND @S9S_MB_2U_LIB.S9S_MB_2U(SCH_1):GND   I169 @S9S_MB_2U_LIB.S9S_MB_2U(SCH_1):PAGE102
   114    GND @S9S_MB_2U_LIB.S9S_MB_2U(SCH_1):GND   I169 @S9S_MB_2U_LIB.S9S_MB_2U(SCH_1):PAGE102
   117    GND @S9S_MB_2U_LIB.S9S_MB_2U(SCH_1):GND   I169 @S9S_MB_2U_LIB.S9S_MB_2U(SCH_1):PAGE102
   119    GND @S9S_MB_2U_LIB.S9S_MB_2U(SCH_1):GND   I169 @S9S_MB_2U_LIB.S9S_MB_2U(SCH_1):PAGE102
   121    GND @S9S_MB_2U_LIB.S9S_MB_2U(SCH_1):GND   I169 @S9S_MB_2U_LIB.S9S_MB_2U(SCH_1):PAGE102
   123    GND @S9S_MB_2U_LIB.S9S_MB_2U(SCH_1):GND   I169 @S9S_MB_2U_LIB.S9S_MB_2U(SCH_1):PAGE102
   125    GND @S9S_MB_2U_LIB.S9S_MB_2U(SCH_1):GND   I169 @S9S_MB_2U_LIB.S9S_MB_2U(SCH_1):PAGE102
   128    GND @S9S_MB_2U_LIB.S9S_MB_2U(SCH_1):GND   I169 @S9S_MB_2U_LIB.S9S_MB_2U(SCH_1):PAGE102
   130    GND @S9S_MB_2U_LIB.S9S_MB_2U(SCH_1):GND   I169 @S9S_MB_2U_LIB.S9S_MB_2U(SCH_1):PAGE102
   134    GND @S9S_MB_2U_LIB.S9S_MB_2U(SCH_1):GND   I169 @S9S_MB_2U_LIB.S9S_MB_2U(SCH_1):PAGE102
   143    GND @S9S_MB_2U_LIB.S9S_MB_2U(SCH_1):GND   I169 @S9S_MB_2U_LIB.S9S_MB_2U(SCH_1):PAGE102
   151    GND @S9S_MB_2U_LIB.S9S_MB_2U(SCH_1):GND   I169 @S9S_MB_2U_LIB.S9S_MB_2U(SCH_1):PAGE102
   153    GND @S9S_MB_2U_LIB.S9S_MB_2U(SCH_1):GND   I169 @S9S_MB_2U_LIB.S9S_MB_2U(SCH_1):PAGE102
   155    GND @S9S_MB_2U_LIB.S9S_MB_2U(SCH_1):GND   I169 @S9S_MB_2U_LIB.S9S_MB_2U(SCH_1):PAGE102
   158    GND @S9S_MB_2U_LIB.S9S_MB_2U(SCH_1):GND   I169 @S9S_MB_2U_LIB.S9S_MB_2U(SCH_1):PAGE102
   160    GND @S9S_MB_2U_LIB.S9S_MB_2U(SCH_1):GND   I169 @S9S_MB_2U_LIB.S9S_MB_2U(SCH_1):PAGE102
   162    GND @S9S_MB_2U_LIB.S9S_MB_2U(SCH_1):GND   I169 @S9S_MB_2U_LIB.S9S_MB_2U(SCH_1):PAGE102
   164    GND @S9S_MB_2U_LIB.S9S_MB_2U(SCH_1):GND   I169 @S9S_MB_2U_LIB.S9S_MB_2U(SCH_1):PAGE102
   166    GND @S9S_MB_2U_LIB.S9S_MB_2U(SCH_1):GND   I169 @S9S_MB_2U_LIB.S9S_MB_2U(SCH_1):PAGE102
   169    GND @S9S_MB_2U_LIB.S9S_MB_2U(SCH_1):GND   I169 @S9S_MB_2U_LIB.S9S_MB_2U(SCH_1):PAGE102
   171    GND @S9S_MB_2U_LIB.S9S_MB_2U(SCH_1):GND   I169 @S9S_MB_2U_LIB.S9S_MB_2U(SCH_1):PAGE102
   173    GND @S9S_MB_2U_LIB.S9S_MB_2U(SCH_1):GND   I169 @S9S_MB_2U_LIB.S9S_MB_2U(SCH_1):PAGE102
   175    GND @S9S_MB_2U_LIB.S9S_MB_2U(SCH_1):GND   I169 @S9S_MB_2U_LIB.S9S_MB_2U(SCH_1):PAGE102
   177    GND @S9S_MB_2U_LIB.S9S_MB_2U(SCH_1):GND   I169 @S9S_MB_2U_LIB.S9S_MB_2U(SCH_1):PAGE102
   180    GND @S9S_MB_2U_LIB.S9S_MB_2U(SCH_1):GND   I169 @S9S_MB_2U_LIB.S9S_MB_2U(SCH_1):PAGE102
   182    GND @S9S_MB_2U_LIB.S9S_MB_2U(SCH_1):GND   I169 @S9S_MB_2U_LIB.S9S_MB_2U(SCH_1):PAGE102
   184    GND @S9S_MB_2U_LIB.S9S_MB_2U(SCH_1):GND   I169 @S9S_MB_2U_LIB.S9S_MB_2U(SCH_1):PAGE102
   186    GND @S9S_MB_2U_LIB.S9S_MB_2U(SCH_1):GND   I169 @S9S_MB_2U_LIB.S9S_MB_2U(SCH_1):PAGE102
   188    GND @S9S_MB_2U_LIB.S9S_MB_2U(SCH_1):GND   I169 @S9S_MB_2U_LIB.S9S_MB_2U(SCH_1):PAGE102
   191    GND @S9S_MB_2U_LIB.S9S_MB_2U(SCH_1):GND   I169 @S9S_MB_2U_LIB.S9S_MB_2U(SCH_1):PAGE102
   193    GND @S9S_MB_2U_LIB.S9S_MB_2U(SCH_1):GND   I169 @S9S_MB_2U_LIB.S9S_MB_2U(SCH_1):PAGE102
   195    GND @S9S_MB_2U_LIB.S9S_MB_2U(SCH_1):GND   I169 @S9S_MB_2U_LIB.S9S_MB_2U(SCH_1):PAGE102
   197    GND @S9S_MB_2U_LIB.S9S_MB_2U(SCH_1):GND   I169 @S9S_MB_2U_LIB.S9S_MB_2U(SCH_1):PAGE102
   199    GND @S9S_MB_2U_LIB.S9S_MB_2U(SCH_1):GND   I169 @S9S_MB_2U_LIB.S9S_MB_2U(SCH_1):PAGE102
   202    GND @S9S_MB_2U_LIB.S9S_MB_2U(SCH_1):GND   I169 @S9S_MB_2U_LIB.S9S_MB_2U(SCH_1):PAGE102
   204    GND @S9S_MB_2U_LIB.S9S_MB_2U(SCH_1):GND   I169 @S9S_MB_2U_LIB.S9S_MB_2U(SCH_1):PAGE102
   206    GND @S9S_MB_2U_LIB.S9S_MB_2U(SCH_1):GND   I169 @S9S_MB_2U_LIB.S9S_MB_2U(SCH_1):PAGE102
   208    GND @S9S_MB_2U_LIB.S9S_MB_2U(SCH_1):GND   I169 @S9S_MB_2U_LIB.S9S_MB_2U(SCH_1):PAGE102
   210    GND @S9S_MB_2U_LIB.S9S_MB_2U(SCH_1):GND   I169 @S9S_MB_2U_LIB.S9S_MB_2U(SCH_1):PAGE102
   212    GND @S9S_MB_2U_LIB.S9S_MB_2U(SCH_1):GND   I169 @S9S_MB_2U_LIB.S9S_MB_2U(SCH_1):PAGE102
   214    GND @S9S_MB_2U_LIB.S9S_MB_2U(SCH_1):GND   I169 @S9S_MB_2U_LIB.S9S_MB_2U(SCH_1):PAGE102
   216    GND @S9S_MB_2U_LIB.S9S_MB_2U(SCH_1):GND   I169 @S9S_MB_2U_LIB.S9S_MB_2U(SCH_1):PAGE102
   219    GND @S9S_MB_2U_LIB.S9S_MB_2U(SCH_1):GND   I169 @S9S_MB_2U_LIB.S9S_MB_2U(SCH_1):PAGE102
   222    GND @S9S_MB_2U_LIB.S9S_MB_2U(SCH_1):GND   I169 @S9S_MB_2U_LIB.S9S_MB_2U(SCH_1):PAGE102
   224    GND @S9S_MB_2U_LIB.S9S_MB_2U(SCH_1):GND   I169 @S9S_MB_2U_LIB.S9S_MB_2U(SCH_1):PAGE102
   226    GND @S9S_MB_2U_LIB.S9S_MB_2U(SCH_1):GND   I169 @S9S_MB_2U_LIB.S9S_MB_2U(SCH_1):PAGE102
   228    GND @S9S_MB_2U_LIB.S9S_MB_2U(SCH_1):GND   I169 @S9S_MB_2U_LIB.S9S_MB_2U(SCH_1):PAGE102
   233    GND @S9S_MB_2U_LIB.S9S_MB_2U(SCH_1):GND   I169 @S9S_MB_2U_LIB.S9S_MB_2U(SCH_1):PAGE102
   237    GND @S9S_MB_2U_LIB.S9S_MB_2U(SCH_1):GND   I169 @S9S_MB_2U_LIB.S9S_MB_2U(SCH_1):PAGE102
   242    GND @S9S_MB_2U_LIB.S9S_MB_2U(SCH_1):GND   I169 @S9S_MB_2U_LIB.S9S_MB_2U(SCH_1):PAGE102
   244    GND @S9S_MB_2U_LIB.S9S_MB_2U(SCH_1):GND   I169 @S9S_MB_2U_LIB.S9S_MB_2U(SCH_1):PAGE102
   246    GND @S9S_MB_2U_LIB.S9S_MB_2U(SCH_1):GND   I169 @S9S_MB_2U_LIB.S9S_MB_2U(SCH_1):PAGE102
   248    GND @S9S_MB_2U_LIB.S9S_MB_2U(SCH_1):GND   I169 @S9S_MB_2U_LIB.S9S_MB_2U(SCH_1):PAGE102
   251    GND @S9S_MB_2U_LIB.S9S_MB_2U(SCH_1):GND   I169 @S9S_MB_2U_LIB.S9S_MB_2U(SCH_1):PAGE102
   253    GND @S9S_MB_2U_LIB.S9S_MB_2U(SCH_1):GND   I169 @S9S_MB_2U_LIB.S9S_MB_2U(SCH_1):PAGE102
   255    GND @S9S_MB_2U_LIB.S9S_MB_2U(SCH_1):GND   I169 @S9S_MB_2U_LIB.S9S_MB_2U(SCH_1):PAGE102
   257    GND @S9S_MB_2U_LIB.S9S_MB_2U(SCH_1):GND   I169 @S9S_MB_2U_LIB.S9S_MB_2U(SCH_1):PAGE102
   259    GND @S9S_MB_2U_LIB.S9S_MB_2U(SCH_1):GND   I169 @S9S_MB_2U_LIB.S9S_MB_2U(SCH_1):PAGE102
   262    GND @S9S_MB_2U_LIB.S9S_MB_2U(SCH_1):GND   I169 @S9S_MB_2U_LIB.S9S_MB_2U(SCH_1):PAGE102
   264    GND @S9S_MB_2U_LIB.S9S_MB_2U(SCH_1):GND   I169 @S9S_MB_2U_LIB.S9S_MB_2U(SCH_1):PAGE102
   266    GND @S9S_MB_2U_LIB.S9S_MB_2U(SCH_1):GND   I169 @S9S_MB_2U_LIB.S9S_MB_2U(SCH_1):PAGE102
   268    GND @S9S_MB_2U_LIB.S9S_MB_2U(SCH_1):GND   I169 @S9S_MB_2U_LIB.S9S_MB_2U(SCH_1):PAGE102
   270    GND @S9S_MB_2U_LIB.S9S_MB_2U(SCH_1):GND   I169 @S9S_MB_2U_LIB.S9S_MB_2U(SCH_1):PAGE102
   273    GND @S9S_MB_2U_LIB.S9S_MB_2U(SCH_1):GND   I169 @S9S_MB_2U_LIB.S9S_MB_2U(SCH_1):PAGE102
   275    GND @S9S_MB_2U_LIB.S9S_MB_2U(SCH_1):GND   I169 @S9S_MB_2U_LIB.S9S_MB_2U(SCH_1):PAGE102
   277    GND @S9S_MB_2U_LIB.S9S_MB_2U(SCH_1):GND   I169 @S9S_MB_2U_LIB.S9S_MB_2U(SCH_1):PAGE102
   279    GND @S9S_MB_2U_LIB.S9S_MB_2U(SCH_1):GND   I169 @S9S_MB_2U_LIB.S9S_MB_2U(SCH_1):PAGE102
   281    GND @S9S_MB_2U_LIB.S9S_MB_2U(SCH_1):GND   I169 @S9S_MB_2U_LIB.S9S_MB_2U(SCH_1):PAGE102
   284    GND @S9S_MB_2U_LIB.S9S_MB_2U(SCH_1):GND   I169 @S9S_MB_2U_LIB.S9S_MB_2U(SCH_1):PAGE102
   286    GND @S9S_MB_2U_LIB.S9S_MB_2U(SCH_1):GND   I169 @S9S_MB_2U_LIB.S9S_MB_2U(SCH_1):PAGE102
   288    GND @S9S_MB_2U_LIB.S9S_MB_2U(SCH_1):GND   I169 @S9S_MB_2U_LIB.S9S_MB_2U(SCH_1):PAGE102
     1 P12V_S3_AUX_CPU1_NVDIMM @S9S_MB_2U_LIB.S9S_MB_2U(SCH_1):P12V_S3_AUX_CPU1_NVDIMM   I169 @S9S_MB_2U_LIB.S9S_MB_2U(SCH_1):PAGE102
   145 P12V_S3_AUX_CPU1_NVDIMM @S9S_MB_2U_LIB.S9S_MB_2U(SCH_1):P12V_S3_AUX_CPU1_NVDIMM   I169 @S9S_MB_2U_LIB.S9S_MB_2U(SCH_1):PAGE102
   146 P12V_S3_AUX_CPU1_NVDIMM @S9S_MB_2U_LIB.S9S_MB_2U(SCH_1):P12V_S3_AUX_CPU1_NVDIMM   I169 @S9S_MB_2U_LIB.S9S_MB_2U(SCH_1):PAGE102
   230    GND @S9S_MB_2U_LIB.S9S_MB_2U(SCH_1):GND   I169 @S9S_MB_2U_LIB.S9S_MB_2U(SCH_1):PAGE102
   235    GND @S9S_MB_2U_LIB.S9S_MB_2U(SCH_1):GND   I169 @S9S_MB_2U_LIB.S9S_MB_2U(SCH_1):PAGE102
   240    GND @S9S_MB_2U_LIB.S9S_MB_2U(SCH_1):GND   I169 @S9S_MB_2U_LIB.S9S_MB_2U(SCH_1):PAGE102
   132    GND @S9S_MB_2U_LIB.S9S_MB_2U(SCH_1):GND   I169 @S9S_MB_2U_LIB.S9S_MB_2U(SCH_1):PAGE102
   136    GND @S9S_MB_2U_LIB.S9S_MB_2U(SCH_1):GND   I169 @S9S_MB_2U_LIB.S9S_MB_2U(SCH_1):PAGE102
   139    GND @S9S_MB_2U_LIB.S9S_MB_2U(SCH_1):GND   I169 @S9S_MB_2U_LIB.S9S_MB_2U(SCH_1):PAGE102
   141    GND @S9S_MB_2U_LIB.S9S_MB_2U(SCH_1):GND   I169 @S9S_MB_2U_LIB.S9S_MB_2U(SCH_1):PAGE102
    G1    GND @S9S_MB_2U_LIB.S9S_MB_2U(SCH_1):GND   I169 @S9S_MB_2U_LIB.S9S_MB_2U(SCH_1):PAGE102
    G2    GND @S9S_MB_2U_LIB.S9S_MB_2U(SCH_1):GND   I169 @S9S_MB_2U_LIB.S9S_MB_2U(SCH_1):PAGE102
    G3    GND @S9S_MB_2U_LIB.S9S_MB_2U(SCH_1):GND   I169 @S9S_MB_2U_LIB.S9S_MB_2U(SCH_1):PAGE102

 J22 SCONN288_ADR50017P087CC-SCONN2A
     3 P3V3_AUX @S9S_MB_2U_LIB.S9S_MB_2U(SCH_1):P3V3_AUX    I51 @S9S_MB_2U_LIB.S9S_MB_2U(SCH_1):PAGE103
     2 TP_CHC_CPU1_DIMM2_FRU_0 @S9S_MB_2U_LIB.S9S_MB_2U(SCH_1):TP_CHC_CPU1_DIMM2_FRU_0    I51 @S9S_MB_2U_LIB.S9S_MB_2U(SCH_1):PAGE103
   144 TP_CHC_CPU1_DIMM2_FRU_1 @S9S_MB_2U_LIB.S9S_MB_2U(SCH_1):TP_CHC_CPU1_DIMM2_FRU_1    I51 @S9S_MB_2U_LIB.S9S_MB_2U(SCH_1):PAGE103
   149 TP_CHC_CPU1_DIMM2_FRU_2 @S9S_MB_2U_LIB.S9S_MB_2U(SCH_1):TP_CHC_CPU1_DIMM2_FRU_2    I51 @S9S_MB_2U_LIB.S9S_MB_2U(SCH_1):PAGE103
   150 TP_CHC_CPU1_DIMM2_FRU_3 @S9S_MB_2U_LIB.S9S_MB_2U(SCH_1):TP_CHC_CPU1_DIMM2_FRU_3    I51 @S9S_MB_2U_LIB.S9S_MB_2U(SCH_1):PAGE103
   220 TP_CHC_CPU1_DIMM2_FRU_4 @S9S_MB_2U_LIB.S9S_MB_2U(SCH_1):TP_CHC_CPU1_DIMM2_FRU_4    I51 @S9S_MB_2U_LIB.S9S_MB_2U(SCH_1):PAGE103
   231 TP_CHC_CPU1_DIMM2_FRU_5 @S9S_MB_2U_LIB.S9S_MB_2U(SCH_1):TP_CHC_CPU1_DIMM2_FRU_5    I51 @S9S_MB_2U_LIB.S9S_MB_2U(SCH_1):PAGE103
   232 TP_CHC_CPU1_DIMM2_FRU_6 @S9S_MB_2U_LIB.S9S_MB_2U(SCH_1):TP_CHC_CPU1_DIMM2_FRU_6    I51 @S9S_MB_2U_LIB.S9S_MB_2U(SCH_1):PAGE103
   207 RST_M_CD_CPU1_FPGA_N @S9S_MB_2U_LIB.S9S_MB_2U(SCH_1):RST_M_CD_CPU1_FPGA_N    I51 @S9S_MB_2U_LIB.S9S_MB_2U(SCH_1):PAGE103
   147 PWRGD_CHC_CPU1_DIMM2 @S9S_MB_2U_LIB.S9S_MB_2U(SCH_1):PWRGD_CHC_CPU1_DIMM2    I51 @S9S_MB_2U_LIB.S9S_MB_2U(SCH_1):PAGE103
   227 M_C_CPU1_SB_PAR @S9S_MB_2U_LIB.S9S_MB_2U(SCH_1):M_C_CPU1_SB_PAR    I51 @S9S_MB_2U_LIB.S9S_MB_2U(SCH_1):PAGE103
    74 M_C_CPU1_SA_PAR @S9S_MB_2U_LIB.S9S_MB_2U(SCH_1):M_C_CPU1_SA_PAR    I51 @S9S_MB_2U_LIB.S9S_MB_2U(SCH_1):PAGE103
    87 M_C_CPU1_SB_RSP<1> @S9S_MB_2U_LIB.S9S_MB_2U(SCH_1):M_C_CPU1_SB_RSP(1)    I51 @S9S_MB_2U_LIB.S9S_MB_2U(SCH_1):PAGE103
    86 M_C_CPU1_SA_RSP<1> @S9S_MB_2U_LIB.S9S_MB_2U(SCH_1):M_C_CPU1_SA_RSP(1)    I51 @S9S_MB_2U_LIB.S9S_MB_2U(SCH_1):PAGE103
     5 I3C_SPD_DDRABCD_CPU1_LVC1_SDA @S9S_MB_2U_LIB.S9S_MB_2U(SCH_1):I3C_SPD_DDRABCD_CPU1_LVC1_SDA    I51 @S9S_MB_2U_LIB.S9S_MB_2U(SCH_1):PAGE103
     4 I3C_SPD_DDRABCD_CPU1_LVC1_SCL_5 @S9S_MB_2U_LIB.S9S_MB_2U(SCH_1):I3C_SPD_DDRABCD_CPU1_LVC1_SCL_R6    I51 @S9S_MB_2U_LIB.S9S_MB_2U(SCH_1):PAGE103
   148 PD_CHC_CPU1_DIMM2_SAA @S9S_MB_2U_LIB.S9S_MB_2U(SCH_1):PD_CHC_CPU1_DIMM2_SAA    I51 @S9S_MB_2U_LIB.S9S_MB_2U(SCH_1):PAGE103
   100 M_C_CPU1_SB_DQ<0> @S9S_MB_2U_LIB.S9S_MB_2U(SCH_1):M_C_CPU1_SB_DQ(0)    I51 @S9S_MB_2U_LIB.S9S_MB_2U(SCH_1):PAGE103
   102 M_C_CPU1_SB_DQ<1> @S9S_MB_2U_LIB.S9S_MB_2U(SCH_1):M_C_CPU1_SB_DQ(1)    I51 @S9S_MB_2U_LIB.S9S_MB_2U(SCH_1):PAGE103
   245 M_C_CPU1_SB_DQ<2> @S9S_MB_2U_LIB.S9S_MB_2U(SCH_1):M_C_CPU1_SB_DQ(2)    I51 @S9S_MB_2U_LIB.S9S_MB_2U(SCH_1):PAGE103
   247 M_C_CPU1_SB_DQ<3> @S9S_MB_2U_LIB.S9S_MB_2U(SCH_1):M_C_CPU1_SB_DQ(3)    I51 @S9S_MB_2U_LIB.S9S_MB_2U(SCH_1):PAGE103
   107 M_C_CPU1_SB_DQ<4> @S9S_MB_2U_LIB.S9S_MB_2U(SCH_1):M_C_CPU1_SB_DQ(4)    I51 @S9S_MB_2U_LIB.S9S_MB_2U(SCH_1):PAGE103
   109 M_C_CPU1_SB_DQ<5> @S9S_MB_2U_LIB.S9S_MB_2U(SCH_1):M_C_CPU1_SB_DQ(5)    I51 @S9S_MB_2U_LIB.S9S_MB_2U(SCH_1):PAGE103
   252 M_C_CPU1_SB_DQ<6> @S9S_MB_2U_LIB.S9S_MB_2U(SCH_1):M_C_CPU1_SB_DQ(6)    I51 @S9S_MB_2U_LIB.S9S_MB_2U(SCH_1):PAGE103
   254 M_C_CPU1_SB_DQ<7> @S9S_MB_2U_LIB.S9S_MB_2U(SCH_1):M_C_CPU1_SB_DQ(7)    I51 @S9S_MB_2U_LIB.S9S_MB_2U(SCH_1):PAGE103
   111 M_C_CPU1_SB_DQ<8> @S9S_MB_2U_LIB.S9S_MB_2U(SCH_1):M_C_CPU1_SB_DQ(8)    I51 @S9S_MB_2U_LIB.S9S_MB_2U(SCH_1):PAGE103
   113 M_C_CPU1_SB_DQ<9> @S9S_MB_2U_LIB.S9S_MB_2U(SCH_1):M_C_CPU1_SB_DQ(9)    I51 @S9S_MB_2U_LIB.S9S_MB_2U(SCH_1):PAGE103
   256 M_C_CPU1_SB_DQ<10> @S9S_MB_2U_LIB.S9S_MB_2U(SCH_1):M_C_CPU1_SB_DQ(10)    I51 @S9S_MB_2U_LIB.S9S_MB_2U(SCH_1):PAGE103
   258 M_C_CPU1_SB_DQ<11> @S9S_MB_2U_LIB.S9S_MB_2U(SCH_1):M_C_CPU1_SB_DQ(11)    I51 @S9S_MB_2U_LIB.S9S_MB_2U(SCH_1):PAGE103
   118 M_C_CPU1_SB_DQ<12> @S9S_MB_2U_LIB.S9S_MB_2U(SCH_1):M_C_CPU1_SB_DQ(12)    I51 @S9S_MB_2U_LIB.S9S_MB_2U(SCH_1):PAGE103
   120 M_C_CPU1_SB_DQ<13> @S9S_MB_2U_LIB.S9S_MB_2U(SCH_1):M_C_CPU1_SB_DQ(13)    I51 @S9S_MB_2U_LIB.S9S_MB_2U(SCH_1):PAGE103
   263 M_C_CPU1_SB_DQ<14> @S9S_MB_2U_LIB.S9S_MB_2U(SCH_1):M_C_CPU1_SB_DQ(14)    I51 @S9S_MB_2U_LIB.S9S_MB_2U(SCH_1):PAGE103
   265 M_C_CPU1_SB_DQ<15> @S9S_MB_2U_LIB.S9S_MB_2U(SCH_1):M_C_CPU1_SB_DQ(15)    I51 @S9S_MB_2U_LIB.S9S_MB_2U(SCH_1):PAGE103
   122 M_C_CPU1_SB_DQ<16> @S9S_MB_2U_LIB.S9S_MB_2U(SCH_1):M_C_CPU1_SB_DQ(16)    I51 @S9S_MB_2U_LIB.S9S_MB_2U(SCH_1):PAGE103
   124 M_C_CPU1_SB_DQ<17> @S9S_MB_2U_LIB.S9S_MB_2U(SCH_1):M_C_CPU1_SB_DQ(17)    I51 @S9S_MB_2U_LIB.S9S_MB_2U(SCH_1):PAGE103
   267 M_C_CPU1_SB_DQ<18> @S9S_MB_2U_LIB.S9S_MB_2U(SCH_1):M_C_CPU1_SB_DQ(18)    I51 @S9S_MB_2U_LIB.S9S_MB_2U(SCH_1):PAGE103
   269 M_C_CPU1_SB_DQ<19> @S9S_MB_2U_LIB.S9S_MB_2U(SCH_1):M_C_CPU1_SB_DQ(19)    I51 @S9S_MB_2U_LIB.S9S_MB_2U(SCH_1):PAGE103
   129 M_C_CPU1_SB_DQ<20> @S9S_MB_2U_LIB.S9S_MB_2U(SCH_1):M_C_CPU1_SB_DQ(20)    I51 @S9S_MB_2U_LIB.S9S_MB_2U(SCH_1):PAGE103
   131 M_C_CPU1_SB_DQ<21> @S9S_MB_2U_LIB.S9S_MB_2U(SCH_1):M_C_CPU1_SB_DQ(21)    I51 @S9S_MB_2U_LIB.S9S_MB_2U(SCH_1):PAGE103
   274 M_C_CPU1_SB_DQ<22> @S9S_MB_2U_LIB.S9S_MB_2U(SCH_1):M_C_CPU1_SB_DQ(22)    I51 @S9S_MB_2U_LIB.S9S_MB_2U(SCH_1):PAGE103
   276 M_C_CPU1_SB_DQ<23> @S9S_MB_2U_LIB.S9S_MB_2U(SCH_1):M_C_CPU1_SB_DQ(23)    I51 @S9S_MB_2U_LIB.S9S_MB_2U(SCH_1):PAGE103
   133 M_C_CPU1_SB_DQ<24> @S9S_MB_2U_LIB.S9S_MB_2U(SCH_1):M_C_CPU1_SB_DQ(24)    I51 @S9S_MB_2U_LIB.S9S_MB_2U(SCH_1):PAGE103
   135 M_C_CPU1_SB_DQ<25> @S9S_MB_2U_LIB.S9S_MB_2U(SCH_1):M_C_CPU1_SB_DQ(25)    I51 @S9S_MB_2U_LIB.S9S_MB_2U(SCH_1):PAGE103
   278 M_C_CPU1_SB_DQ<26> @S9S_MB_2U_LIB.S9S_MB_2U(SCH_1):M_C_CPU1_SB_DQ(26)    I51 @S9S_MB_2U_LIB.S9S_MB_2U(SCH_1):PAGE103
   280 M_C_CPU1_SB_DQ<27> @S9S_MB_2U_LIB.S9S_MB_2U(SCH_1):M_C_CPU1_SB_DQ(27)    I51 @S9S_MB_2U_LIB.S9S_MB_2U(SCH_1):PAGE103
   140 M_C_CPU1_SB_DQ<28> @S9S_MB_2U_LIB.S9S_MB_2U(SCH_1):M_C_CPU1_SB_DQ(28)    I51 @S9S_MB_2U_LIB.S9S_MB_2U(SCH_1):PAGE103
   142 M_C_CPU1_SB_DQ<29> @S9S_MB_2U_LIB.S9S_MB_2U(SCH_1):M_C_CPU1_SB_DQ(29)    I51 @S9S_MB_2U_LIB.S9S_MB_2U(SCH_1):PAGE103
   285 M_C_CPU1_SB_DQ<30> @S9S_MB_2U_LIB.S9S_MB_2U(SCH_1):M_C_CPU1_SB_DQ(30)    I51 @S9S_MB_2U_LIB.S9S_MB_2U(SCH_1):PAGE103
   287 M_C_CPU1_SB_DQ<31> @S9S_MB_2U_LIB.S9S_MB_2U(SCH_1):M_C_CPU1_SB_DQ(31)    I51 @S9S_MB_2U_LIB.S9S_MB_2U(SCH_1):PAGE103
     7 M_C_CPU1_SA_DQ<0> @S9S_MB_2U_LIB.S9S_MB_2U(SCH_1):M_C_CPU1_SA_DQ(0)    I51 @S9S_MB_2U_LIB.S9S_MB_2U(SCH_1):PAGE103
     9 M_C_CPU1_SA_DQ<1> @S9S_MB_2U_LIB.S9S_MB_2U(SCH_1):M_C_CPU1_SA_DQ(1)    I51 @S9S_MB_2U_LIB.S9S_MB_2U(SCH_1):PAGE103
   152 M_C_CPU1_SA_DQ<2> @S9S_MB_2U_LIB.S9S_MB_2U(SCH_1):M_C_CPU1_SA_DQ(2)    I51 @S9S_MB_2U_LIB.S9S_MB_2U(SCH_1):PAGE103
   154 M_C_CPU1_SA_DQ<3> @S9S_MB_2U_LIB.S9S_MB_2U(SCH_1):M_C_CPU1_SA_DQ(3)    I51 @S9S_MB_2U_LIB.S9S_MB_2U(SCH_1):PAGE103
    14 M_C_CPU1_SA_DQ<4> @S9S_MB_2U_LIB.S9S_MB_2U(SCH_1):M_C_CPU1_SA_DQ(4)    I51 @S9S_MB_2U_LIB.S9S_MB_2U(SCH_1):PAGE103
    16 M_C_CPU1_SA_DQ<5> @S9S_MB_2U_LIB.S9S_MB_2U(SCH_1):M_C_CPU1_SA_DQ(5)    I51 @S9S_MB_2U_LIB.S9S_MB_2U(SCH_1):PAGE103
   159 M_C_CPU1_SA_DQ<6> @S9S_MB_2U_LIB.S9S_MB_2U(SCH_1):M_C_CPU1_SA_DQ(6)    I51 @S9S_MB_2U_LIB.S9S_MB_2U(SCH_1):PAGE103
   161 M_C_CPU1_SA_DQ<7> @S9S_MB_2U_LIB.S9S_MB_2U(SCH_1):M_C_CPU1_SA_DQ(7)    I51 @S9S_MB_2U_LIB.S9S_MB_2U(SCH_1):PAGE103
    18 M_C_CPU1_SA_DQ<8> @S9S_MB_2U_LIB.S9S_MB_2U(SCH_1):M_C_CPU1_SA_DQ(8)    I51 @S9S_MB_2U_LIB.S9S_MB_2U(SCH_1):PAGE103
    20 M_C_CPU1_SA_DQ<9> @S9S_MB_2U_LIB.S9S_MB_2U(SCH_1):M_C_CPU1_SA_DQ(9)    I51 @S9S_MB_2U_LIB.S9S_MB_2U(SCH_1):PAGE103
   163 M_C_CPU1_SA_DQ<10> @S9S_MB_2U_LIB.S9S_MB_2U(SCH_1):M_C_CPU1_SA_DQ(10)    I51 @S9S_MB_2U_LIB.S9S_MB_2U(SCH_1):PAGE103
   165 M_C_CPU1_SA_DQ<11> @S9S_MB_2U_LIB.S9S_MB_2U(SCH_1):M_C_CPU1_SA_DQ(11)    I51 @S9S_MB_2U_LIB.S9S_MB_2U(SCH_1):PAGE103
    25 M_C_CPU1_SA_DQ<12> @S9S_MB_2U_LIB.S9S_MB_2U(SCH_1):M_C_CPU1_SA_DQ(12)    I51 @S9S_MB_2U_LIB.S9S_MB_2U(SCH_1):PAGE103
    27 M_C_CPU1_SA_DQ<13> @S9S_MB_2U_LIB.S9S_MB_2U(SCH_1):M_C_CPU1_SA_DQ(13)    I51 @S9S_MB_2U_LIB.S9S_MB_2U(SCH_1):PAGE103
   170 M_C_CPU1_SA_DQ<14> @S9S_MB_2U_LIB.S9S_MB_2U(SCH_1):M_C_CPU1_SA_DQ(14)    I51 @S9S_MB_2U_LIB.S9S_MB_2U(SCH_1):PAGE103
   172 M_C_CPU1_SA_DQ<15> @S9S_MB_2U_LIB.S9S_MB_2U(SCH_1):M_C_CPU1_SA_DQ(15)    I51 @S9S_MB_2U_LIB.S9S_MB_2U(SCH_1):PAGE103
    29 M_C_CPU1_SA_DQ<16> @S9S_MB_2U_LIB.S9S_MB_2U(SCH_1):M_C_CPU1_SA_DQ(16)    I51 @S9S_MB_2U_LIB.S9S_MB_2U(SCH_1):PAGE103
    31 M_C_CPU1_SA_DQ<17> @S9S_MB_2U_LIB.S9S_MB_2U(SCH_1):M_C_CPU1_SA_DQ(17)    I51 @S9S_MB_2U_LIB.S9S_MB_2U(SCH_1):PAGE103
   174 M_C_CPU1_SA_DQ<18> @S9S_MB_2U_LIB.S9S_MB_2U(SCH_1):M_C_CPU1_SA_DQ(18)    I51 @S9S_MB_2U_LIB.S9S_MB_2U(SCH_1):PAGE103
   176 M_C_CPU1_SA_DQ<19> @S9S_MB_2U_LIB.S9S_MB_2U(SCH_1):M_C_CPU1_SA_DQ(19)    I51 @S9S_MB_2U_LIB.S9S_MB_2U(SCH_1):PAGE103
    36 M_C_CPU1_SA_DQ<20> @S9S_MB_2U_LIB.S9S_MB_2U(SCH_1):M_C_CPU1_SA_DQ(20)    I51 @S9S_MB_2U_LIB.S9S_MB_2U(SCH_1):PAGE103
    38 M_C_CPU1_SA_DQ<21> @S9S_MB_2U_LIB.S9S_MB_2U(SCH_1):M_C_CPU1_SA_DQ(21)    I51 @S9S_MB_2U_LIB.S9S_MB_2U(SCH_1):PAGE103
   181 M_C_CPU1_SA_DQ<22> @S9S_MB_2U_LIB.S9S_MB_2U(SCH_1):M_C_CPU1_SA_DQ(22)    I51 @S9S_MB_2U_LIB.S9S_MB_2U(SCH_1):PAGE103
   183 M_C_CPU1_SA_DQ<23> @S9S_MB_2U_LIB.S9S_MB_2U(SCH_1):M_C_CPU1_SA_DQ(23)    I51 @S9S_MB_2U_LIB.S9S_MB_2U(SCH_1):PAGE103
    40 M_C_CPU1_SA_DQ<24> @S9S_MB_2U_LIB.S9S_MB_2U(SCH_1):M_C_CPU1_SA_DQ(24)    I51 @S9S_MB_2U_LIB.S9S_MB_2U(SCH_1):PAGE103
    42 M_C_CPU1_SA_DQ<25> @S9S_MB_2U_LIB.S9S_MB_2U(SCH_1):M_C_CPU1_SA_DQ(25)    I51 @S9S_MB_2U_LIB.S9S_MB_2U(SCH_1):PAGE103
   185 M_C_CPU1_SA_DQ<26> @S9S_MB_2U_LIB.S9S_MB_2U(SCH_1):M_C_CPU1_SA_DQ(26)    I51 @S9S_MB_2U_LIB.S9S_MB_2U(SCH_1):PAGE103
   187 M_C_CPU1_SA_DQ<27> @S9S_MB_2U_LIB.S9S_MB_2U(SCH_1):M_C_CPU1_SA_DQ(27)    I51 @S9S_MB_2U_LIB.S9S_MB_2U(SCH_1):PAGE103
    47 M_C_CPU1_SA_DQ<28> @S9S_MB_2U_LIB.S9S_MB_2U(SCH_1):M_C_CPU1_SA_DQ(28)    I51 @S9S_MB_2U_LIB.S9S_MB_2U(SCH_1):PAGE103
    49 M_C_CPU1_SA_DQ<29> @S9S_MB_2U_LIB.S9S_MB_2U(SCH_1):M_C_CPU1_SA_DQ(29)    I51 @S9S_MB_2U_LIB.S9S_MB_2U(SCH_1):PAGE103
   192 M_C_CPU1_SA_DQ<30> @S9S_MB_2U_LIB.S9S_MB_2U(SCH_1):M_C_CPU1_SA_DQ(30)    I51 @S9S_MB_2U_LIB.S9S_MB_2U(SCH_1):PAGE103
   229 M_C_CPU1_SB_CS_N<3> @S9S_MB_2U_LIB.S9S_MB_2U(SCH_1):M_C_CPU1_SB_CS_N(3)    I51 @S9S_MB_2U_LIB.S9S_MB_2U(SCH_1):PAGE103
   209 M_C_CPU1_SA_CS_N<3> @S9S_MB_2U_LIB.S9S_MB_2U(SCH_1):M_C_CPU1_SA_CS_N(3)    I51 @S9S_MB_2U_LIB.S9S_MB_2U(SCH_1):PAGE103
    84 M_C_CPU1_SB_CS_N<2> @S9S_MB_2U_LIB.S9S_MB_2U(SCH_1):M_C_CPU1_SB_CS_N(2)    I51 @S9S_MB_2U_LIB.S9S_MB_2U(SCH_1):PAGE103
    64 M_C_CPU1_SA_CS_N<2> @S9S_MB_2U_LIB.S9S_MB_2U(SCH_1):M_C_CPU1_SA_CS_N(2)    I51 @S9S_MB_2U_LIB.S9S_MB_2U(SCH_1):PAGE103
   217 M_C_CPU1_CLK_DP<1> @S9S_MB_2U_LIB.S9S_MB_2U(SCH_1):M_C_CPU1_CLK_DP(1)    I51 @S9S_MB_2U_LIB.S9S_MB_2U(SCH_1):PAGE103
   218 M_C_CPU1_CLK_DN<1> @S9S_MB_2U_LIB.S9S_MB_2U(SCH_1):M_C_CPU1_CLK_DN(1)    I51 @S9S_MB_2U_LIB.S9S_MB_2U(SCH_1):PAGE103
    96 M_C_CPU1_SB_CB<0> @S9S_MB_2U_LIB.S9S_MB_2U(SCH_1):M_C_CPU1_SB_CB(0)    I51 @S9S_MB_2U_LIB.S9S_MB_2U(SCH_1):PAGE103
    98 M_C_CPU1_SB_CB<1> @S9S_MB_2U_LIB.S9S_MB_2U(SCH_1):M_C_CPU1_SB_CB(1)    I51 @S9S_MB_2U_LIB.S9S_MB_2U(SCH_1):PAGE103
   241 M_C_CPU1_SB_CB<2> @S9S_MB_2U_LIB.S9S_MB_2U(SCH_1):M_C_CPU1_SB_CB(2)    I51 @S9S_MB_2U_LIB.S9S_MB_2U(SCH_1):PAGE103
   243 M_C_CPU1_SB_CB<3> @S9S_MB_2U_LIB.S9S_MB_2U(SCH_1):M_C_CPU1_SB_CB(3)    I51 @S9S_MB_2U_LIB.S9S_MB_2U(SCH_1):PAGE103
    89 M_C_CPU1_SB_CB<4> @S9S_MB_2U_LIB.S9S_MB_2U(SCH_1):M_C_CPU1_SB_CB(4)    I51 @S9S_MB_2U_LIB.S9S_MB_2U(SCH_1):PAGE103
    91 M_C_CPU1_SB_CB<5> @S9S_MB_2U_LIB.S9S_MB_2U(SCH_1):M_C_CPU1_SB_CB(5)    I51 @S9S_MB_2U_LIB.S9S_MB_2U(SCH_1):PAGE103
   234 M_C_CPU1_SB_CB<6> @S9S_MB_2U_LIB.S9S_MB_2U(SCH_1):M_C_CPU1_SB_CB(6)    I51 @S9S_MB_2U_LIB.S9S_MB_2U(SCH_1):PAGE103
    51 M_C_CPU1_SA_CB<0> @S9S_MB_2U_LIB.S9S_MB_2U(SCH_1):M_C_CPU1_SA_CB(0)    I51 @S9S_MB_2U_LIB.S9S_MB_2U(SCH_1):PAGE103
   196 M_C_CPU1_SA_CB<2> @S9S_MB_2U_LIB.S9S_MB_2U(SCH_1):M_C_CPU1_SA_CB(2)    I51 @S9S_MB_2U_LIB.S9S_MB_2U(SCH_1):PAGE103
   198 M_C_CPU1_SA_CB<3> @S9S_MB_2U_LIB.S9S_MB_2U(SCH_1):M_C_CPU1_SA_CB(3)    I51 @S9S_MB_2U_LIB.S9S_MB_2U(SCH_1):PAGE103
    60 M_C_CPU1_SA_CB<5> @S9S_MB_2U_LIB.S9S_MB_2U(SCH_1):M_C_CPU1_SA_CB(5)    I51 @S9S_MB_2U_LIB.S9S_MB_2U(SCH_1):PAGE103
   203 M_C_CPU1_SA_CB<6> @S9S_MB_2U_LIB.S9S_MB_2U(SCH_1):M_C_CPU1_SA_CB(6)    I51 @S9S_MB_2U_LIB.S9S_MB_2U(SCH_1):PAGE103
    82 M_C_CPU1_SB_CA<6> @S9S_MB_2U_LIB.S9S_MB_2U(SCH_1):M_C_CPU1_SB_CA(6)    I51 @S9S_MB_2U_LIB.S9S_MB_2U(SCH_1):PAGE103
    72 M_C_CPU1_SA_CA<6> @S9S_MB_2U_LIB.S9S_MB_2U(SCH_1):M_C_CPU1_SA_CA(6)    I51 @S9S_MB_2U_LIB.S9S_MB_2U(SCH_1):PAGE103
   225 M_C_CPU1_SB_CA<5> @S9S_MB_2U_LIB.S9S_MB_2U(SCH_1):M_C_CPU1_SB_CA(5)    I51 @S9S_MB_2U_LIB.S9S_MB_2U(SCH_1):PAGE103
   215 M_C_CPU1_SA_CA<5> @S9S_MB_2U_LIB.S9S_MB_2U(SCH_1):M_C_CPU1_SA_CA(5)    I51 @S9S_MB_2U_LIB.S9S_MB_2U(SCH_1):PAGE103
    80 M_C_CPU1_SB_CA<4> @S9S_MB_2U_LIB.S9S_MB_2U(SCH_1):M_C_CPU1_SB_CA(4)    I51 @S9S_MB_2U_LIB.S9S_MB_2U(SCH_1):PAGE103
    70 M_C_CPU1_SA_CA<4> @S9S_MB_2U_LIB.S9S_MB_2U(SCH_1):M_C_CPU1_SA_CA(4)    I51 @S9S_MB_2U_LIB.S9S_MB_2U(SCH_1):PAGE103
   223 M_C_CPU1_SB_CA<3> @S9S_MB_2U_LIB.S9S_MB_2U(SCH_1):M_C_CPU1_SB_CA(3)    I51 @S9S_MB_2U_LIB.S9S_MB_2U(SCH_1):PAGE103
   213 M_C_CPU1_SA_CA<3> @S9S_MB_2U_LIB.S9S_MB_2U(SCH_1):M_C_CPU1_SA_CA(3)    I51 @S9S_MB_2U_LIB.S9S_MB_2U(SCH_1):PAGE103
    78 M_C_CPU1_SB_CA<2> @S9S_MB_2U_LIB.S9S_MB_2U(SCH_1):M_C_CPU1_SB_CA(2)    I51 @S9S_MB_2U_LIB.S9S_MB_2U(SCH_1):PAGE103
    68 M_C_CPU1_SA_CA<2> @S9S_MB_2U_LIB.S9S_MB_2U(SCH_1):M_C_CPU1_SA_CA(2)    I51 @S9S_MB_2U_LIB.S9S_MB_2U(SCH_1):PAGE103
   221 M_C_CPU1_SB_CA<1> @S9S_MB_2U_LIB.S9S_MB_2U(SCH_1):M_C_CPU1_SB_CA(1)    I51 @S9S_MB_2U_LIB.S9S_MB_2U(SCH_1):PAGE103
   211 M_C_CPU1_SA_CA<1> @S9S_MB_2U_LIB.S9S_MB_2U(SCH_1):M_C_CPU1_SA_CA(1)    I51 @S9S_MB_2U_LIB.S9S_MB_2U(SCH_1):PAGE103
    76 M_C_CPU1_SB_CA<0> @S9S_MB_2U_LIB.S9S_MB_2U(SCH_1):M_C_CPU1_SB_CA(0)    I51 @S9S_MB_2U_LIB.S9S_MB_2U(SCH_1):PAGE103
    66 M_C_CPU1_SA_CA<0> @S9S_MB_2U_LIB.S9S_MB_2U(SCH_1):M_C_CPU1_SA_CA(0)    I51 @S9S_MB_2U_LIB.S9S_MB_2U(SCH_1):PAGE103
    62 M_C_CPU1_ALERT_N @S9S_MB_2U_LIB.S9S_MB_2U(SCH_1):M_C_CPU1_ALERT_N    I51 @S9S_MB_2U_LIB.S9S_MB_2U(SCH_1):PAGE103
   236 M_C_CPU1_SB_CB<7> @S9S_MB_2U_LIB.S9S_MB_2U(SCH_1):M_C_CPU1_SB_CB(7)    I51 @S9S_MB_2U_LIB.S9S_MB_2U(SCH_1):PAGE103
    53 M_C_CPU1_SA_CB<1> @S9S_MB_2U_LIB.S9S_MB_2U(SCH_1):M_C_CPU1_SA_CB(1)    I51 @S9S_MB_2U_LIB.S9S_MB_2U(SCH_1):PAGE103
    58 M_C_CPU1_SA_CB<4> @S9S_MB_2U_LIB.S9S_MB_2U(SCH_1):M_C_CPU1_SA_CB(4)    I51 @S9S_MB_2U_LIB.S9S_MB_2U(SCH_1):PAGE103
   205 M_C_CPU1_SA_CB<7> @S9S_MB_2U_LIB.S9S_MB_2U(SCH_1):M_C_CPU1_SA_CB(7)    I51 @S9S_MB_2U_LIB.S9S_MB_2U(SCH_1):PAGE103
   194 M_C_CPU1_SA_DQ<31> @S9S_MB_2U_LIB.S9S_MB_2U(SCH_1):M_C_CPU1_SA_DQ(31)    I51 @S9S_MB_2U_LIB.S9S_MB_2U(SCH_1):PAGE103
    93 M_C_CPU1_SB_DQS_DP<9> @S9S_MB_2U_LIB.S9S_MB_2U(SCH_1):M_C_CPU1_SB_DQS_DP(9)   I178 @S9S_MB_2U_LIB.S9S_MB_2U(SCH_1):PAGE103
    94 M_C_CPU1_SB_DQS_DN<9> @S9S_MB_2U_LIB.S9S_MB_2U(SCH_1):M_C_CPU1_SB_DQS_DN(9)   I178 @S9S_MB_2U_LIB.S9S_MB_2U(SCH_1):PAGE103
   201 M_C_CPU1_SA_DQS_DP<9> @S9S_MB_2U_LIB.S9S_MB_2U(SCH_1):M_C_CPU1_SA_DQS_DP(9)   I178 @S9S_MB_2U_LIB.S9S_MB_2U(SCH_1):PAGE103
   200 M_C_CPU1_SA_DQS_DN<9> @S9S_MB_2U_LIB.S9S_MB_2U(SCH_1):M_C_CPU1_SA_DQS_DN(9)   I178 @S9S_MB_2U_LIB.S9S_MB_2U(SCH_1):PAGE103
   190 M_C_CPU1_SA_DQS_DP<8> @S9S_MB_2U_LIB.S9S_MB_2U(SCH_1):M_C_CPU1_SA_DQS_DP(8)   I178 @S9S_MB_2U_LIB.S9S_MB_2U(SCH_1):PAGE103
   189 M_C_CPU1_SA_DQS_DN<8> @S9S_MB_2U_LIB.S9S_MB_2U(SCH_1):M_C_CPU1_SA_DQS_DN(8)   I178 @S9S_MB_2U_LIB.S9S_MB_2U(SCH_1):PAGE103
   271 M_C_CPU1_SB_DQS_DN<7> @S9S_MB_2U_LIB.S9S_MB_2U(SCH_1):M_C_CPU1_SB_DQS_DN(7)   I178 @S9S_MB_2U_LIB.S9S_MB_2U(SCH_1):PAGE103
   179 M_C_CPU1_SA_DQS_DP<7> @S9S_MB_2U_LIB.S9S_MB_2U(SCH_1):M_C_CPU1_SA_DQS_DP(7)   I178 @S9S_MB_2U_LIB.S9S_MB_2U(SCH_1):PAGE103
   261 M_C_CPU1_SB_DQS_DP<6> @S9S_MB_2U_LIB.S9S_MB_2U(SCH_1):M_C_CPU1_SB_DQS_DP(6)   I178 @S9S_MB_2U_LIB.S9S_MB_2U(SCH_1):PAGE103
   260 M_C_CPU1_SB_DQS_DN<6> @S9S_MB_2U_LIB.S9S_MB_2U(SCH_1):M_C_CPU1_SB_DQS_DN(6)   I178 @S9S_MB_2U_LIB.S9S_MB_2U(SCH_1):PAGE103
   167 M_C_CPU1_SA_DQS_DN<6> @S9S_MB_2U_LIB.S9S_MB_2U(SCH_1):M_C_CPU1_SA_DQS_DN(6)   I178 @S9S_MB_2U_LIB.S9S_MB_2U(SCH_1):PAGE103
   250 M_C_CPU1_SB_DQS_DP<5> @S9S_MB_2U_LIB.S9S_MB_2U(SCH_1):M_C_CPU1_SB_DQS_DP(5)   I178 @S9S_MB_2U_LIB.S9S_MB_2U(SCH_1):PAGE103
   249 M_C_CPU1_SB_DQS_DN<5> @S9S_MB_2U_LIB.S9S_MB_2U(SCH_1):M_C_CPU1_SB_DQS_DN(5)   I178 @S9S_MB_2U_LIB.S9S_MB_2U(SCH_1):PAGE103
   157 M_C_CPU1_SA_DQS_DP<5> @S9S_MB_2U_LIB.S9S_MB_2U(SCH_1):M_C_CPU1_SA_DQS_DP(5)   I178 @S9S_MB_2U_LIB.S9S_MB_2U(SCH_1):PAGE103
   156 M_C_CPU1_SA_DQS_DN<5> @S9S_MB_2U_LIB.S9S_MB_2U(SCH_1):M_C_CPU1_SA_DQS_DN(5)   I178 @S9S_MB_2U_LIB.S9S_MB_2U(SCH_1):PAGE103
   239 M_C_CPU1_SB_DQS_DP<4> @S9S_MB_2U_LIB.S9S_MB_2U(SCH_1):M_C_CPU1_SB_DQS_DP(4)   I178 @S9S_MB_2U_LIB.S9S_MB_2U(SCH_1):PAGE103
   238 M_C_CPU1_SB_DQS_DN<4> @S9S_MB_2U_LIB.S9S_MB_2U(SCH_1):M_C_CPU1_SB_DQS_DN(4)   I178 @S9S_MB_2U_LIB.S9S_MB_2U(SCH_1):PAGE103
    55 M_C_CPU1_SA_DQS_DP<4> @S9S_MB_2U_LIB.S9S_MB_2U(SCH_1):M_C_CPU1_SA_DQS_DP(4)   I178 @S9S_MB_2U_LIB.S9S_MB_2U(SCH_1):PAGE103
    56 M_C_CPU1_SA_DQS_DN<4> @S9S_MB_2U_LIB.S9S_MB_2U(SCH_1):M_C_CPU1_SA_DQS_DN(4)   I178 @S9S_MB_2U_LIB.S9S_MB_2U(SCH_1):PAGE103
   137 M_C_CPU1_SB_DQS_DP<3> @S9S_MB_2U_LIB.S9S_MB_2U(SCH_1):M_C_CPU1_SB_DQS_DP(3)   I178 @S9S_MB_2U_LIB.S9S_MB_2U(SCH_1):PAGE103
   138 M_C_CPU1_SB_DQS_DN<3> @S9S_MB_2U_LIB.S9S_MB_2U(SCH_1):M_C_CPU1_SB_DQS_DN(3)   I178 @S9S_MB_2U_LIB.S9S_MB_2U(SCH_1):PAGE103
    44 M_C_CPU1_SA_DQS_DP<3> @S9S_MB_2U_LIB.S9S_MB_2U(SCH_1):M_C_CPU1_SA_DQS_DP(3)   I178 @S9S_MB_2U_LIB.S9S_MB_2U(SCH_1):PAGE103
    45 M_C_CPU1_SA_DQS_DN<3> @S9S_MB_2U_LIB.S9S_MB_2U(SCH_1):M_C_CPU1_SA_DQS_DN(3)   I178 @S9S_MB_2U_LIB.S9S_MB_2U(SCH_1):PAGE103
   126 M_C_CPU1_SB_DQS_DP<2> @S9S_MB_2U_LIB.S9S_MB_2U(SCH_1):M_C_CPU1_SB_DQS_DP(2)   I178 @S9S_MB_2U_LIB.S9S_MB_2U(SCH_1):PAGE103
   127 M_C_CPU1_SB_DQS_DN<2> @S9S_MB_2U_LIB.S9S_MB_2U(SCH_1):M_C_CPU1_SB_DQS_DN(2)   I178 @S9S_MB_2U_LIB.S9S_MB_2U(SCH_1):PAGE103
    33 M_C_CPU1_SA_DQS_DP<2> @S9S_MB_2U_LIB.S9S_MB_2U(SCH_1):M_C_CPU1_SA_DQS_DP(2)   I178 @S9S_MB_2U_LIB.S9S_MB_2U(SCH_1):PAGE103
    34 M_C_CPU1_SA_DQS_DN<2> @S9S_MB_2U_LIB.S9S_MB_2U(SCH_1):M_C_CPU1_SA_DQS_DN(2)   I178 @S9S_MB_2U_LIB.S9S_MB_2U(SCH_1):PAGE103
   115 M_C_CPU1_SB_DQS_DP<1> @S9S_MB_2U_LIB.S9S_MB_2U(SCH_1):M_C_CPU1_SB_DQS_DP(1)   I178 @S9S_MB_2U_LIB.S9S_MB_2U(SCH_1):PAGE103
   116 M_C_CPU1_SB_DQS_DN<1> @S9S_MB_2U_LIB.S9S_MB_2U(SCH_1):M_C_CPU1_SB_DQS_DN(1)   I178 @S9S_MB_2U_LIB.S9S_MB_2U(SCH_1):PAGE103
    22 M_C_CPU1_SA_DQS_DP<1> @S9S_MB_2U_LIB.S9S_MB_2U(SCH_1):M_C_CPU1_SA_DQS_DP(1)   I178 @S9S_MB_2U_LIB.S9S_MB_2U(SCH_1):PAGE103
    23 M_C_CPU1_SA_DQS_DN<1> @S9S_MB_2U_LIB.S9S_MB_2U(SCH_1):M_C_CPU1_SA_DQS_DN(1)   I178 @S9S_MB_2U_LIB.S9S_MB_2U(SCH_1):PAGE103
   104 M_C_CPU1_SB_DQS_DP<0> @S9S_MB_2U_LIB.S9S_MB_2U(SCH_1):M_C_CPU1_SB_DQS_DP(0)   I178 @S9S_MB_2U_LIB.S9S_MB_2U(SCH_1):PAGE103
   105 M_C_CPU1_SB_DQS_DN<0> @S9S_MB_2U_LIB.S9S_MB_2U(SCH_1):M_C_CPU1_SB_DQS_DN(0)   I178 @S9S_MB_2U_LIB.S9S_MB_2U(SCH_1):PAGE103
    11 M_C_CPU1_SA_DQS_DP<0> @S9S_MB_2U_LIB.S9S_MB_2U(SCH_1):M_C_CPU1_SA_DQS_DP(0)   I178 @S9S_MB_2U_LIB.S9S_MB_2U(SCH_1):PAGE103
    12 M_C_CPU1_SA_DQS_DN<0> @S9S_MB_2U_LIB.S9S_MB_2U(SCH_1):M_C_CPU1_SA_DQS_DN(0)   I178 @S9S_MB_2U_LIB.S9S_MB_2U(SCH_1):PAGE103
   272 M_C_CPU1_SB_DQS_DP<7> @S9S_MB_2U_LIB.S9S_MB_2U(SCH_1):M_C_CPU1_SB_DQS_DP(7)   I178 @S9S_MB_2U_LIB.S9S_MB_2U(SCH_1):PAGE103
   282 M_C_CPU1_SB_DQS_DN<8> @S9S_MB_2U_LIB.S9S_MB_2U(SCH_1):M_C_CPU1_SB_DQS_DN(8)   I178 @S9S_MB_2U_LIB.S9S_MB_2U(SCH_1):PAGE103
   283 M_C_CPU1_SB_DQS_DP<8> @S9S_MB_2U_LIB.S9S_MB_2U(SCH_1):M_C_CPU1_SB_DQS_DP(8)   I178 @S9S_MB_2U_LIB.S9S_MB_2U(SCH_1):PAGE103
   168 M_C_CPU1_SA_DQS_DP<6> @S9S_MB_2U_LIB.S9S_MB_2U(SCH_1):M_C_CPU1_SA_DQS_DP(6)   I178 @S9S_MB_2U_LIB.S9S_MB_2U(SCH_1):PAGE103
   178 M_C_CPU1_SA_DQS_DN<7> @S9S_MB_2U_LIB.S9S_MB_2U(SCH_1):M_C_CPU1_SA_DQS_DN(7)   I178 @S9S_MB_2U_LIB.S9S_MB_2U(SCH_1):PAGE103
     6    GND @S9S_MB_2U_LIB.S9S_MB_2U(SCH_1):GND   I176 @S9S_MB_2U_LIB.S9S_MB_2U(SCH_1):PAGE103
     8    GND @S9S_MB_2U_LIB.S9S_MB_2U(SCH_1):GND   I176 @S9S_MB_2U_LIB.S9S_MB_2U(SCH_1):PAGE103
    10    GND @S9S_MB_2U_LIB.S9S_MB_2U(SCH_1):GND   I176 @S9S_MB_2U_LIB.S9S_MB_2U(SCH_1):PAGE103
    13    GND @S9S_MB_2U_LIB.S9S_MB_2U(SCH_1):GND   I176 @S9S_MB_2U_LIB.S9S_MB_2U(SCH_1):PAGE103
    15    GND @S9S_MB_2U_LIB.S9S_MB_2U(SCH_1):GND   I176 @S9S_MB_2U_LIB.S9S_MB_2U(SCH_1):PAGE103
    17    GND @S9S_MB_2U_LIB.S9S_MB_2U(SCH_1):GND   I176 @S9S_MB_2U_LIB.S9S_MB_2U(SCH_1):PAGE103
    19    GND @S9S_MB_2U_LIB.S9S_MB_2U(SCH_1):GND   I176 @S9S_MB_2U_LIB.S9S_MB_2U(SCH_1):PAGE103
    21    GND @S9S_MB_2U_LIB.S9S_MB_2U(SCH_1):GND   I176 @S9S_MB_2U_LIB.S9S_MB_2U(SCH_1):PAGE103
    24    GND @S9S_MB_2U_LIB.S9S_MB_2U(SCH_1):GND   I176 @S9S_MB_2U_LIB.S9S_MB_2U(SCH_1):PAGE103
    26    GND @S9S_MB_2U_LIB.S9S_MB_2U(SCH_1):GND   I176 @S9S_MB_2U_LIB.S9S_MB_2U(SCH_1):PAGE103
    28    GND @S9S_MB_2U_LIB.S9S_MB_2U(SCH_1):GND   I176 @S9S_MB_2U_LIB.S9S_MB_2U(SCH_1):PAGE103
    30    GND @S9S_MB_2U_LIB.S9S_MB_2U(SCH_1):GND   I176 @S9S_MB_2U_LIB.S9S_MB_2U(SCH_1):PAGE103
    32    GND @S9S_MB_2U_LIB.S9S_MB_2U(SCH_1):GND   I176 @S9S_MB_2U_LIB.S9S_MB_2U(SCH_1):PAGE103
    35    GND @S9S_MB_2U_LIB.S9S_MB_2U(SCH_1):GND   I176 @S9S_MB_2U_LIB.S9S_MB_2U(SCH_1):PAGE103
    37    GND @S9S_MB_2U_LIB.S9S_MB_2U(SCH_1):GND   I176 @S9S_MB_2U_LIB.S9S_MB_2U(SCH_1):PAGE103
    39    GND @S9S_MB_2U_LIB.S9S_MB_2U(SCH_1):GND   I176 @S9S_MB_2U_LIB.S9S_MB_2U(SCH_1):PAGE103
    41    GND @S9S_MB_2U_LIB.S9S_MB_2U(SCH_1):GND   I176 @S9S_MB_2U_LIB.S9S_MB_2U(SCH_1):PAGE103
    43    GND @S9S_MB_2U_LIB.S9S_MB_2U(SCH_1):GND   I176 @S9S_MB_2U_LIB.S9S_MB_2U(SCH_1):PAGE103
    46    GND @S9S_MB_2U_LIB.S9S_MB_2U(SCH_1):GND   I176 @S9S_MB_2U_LIB.S9S_MB_2U(SCH_1):PAGE103
    48    GND @S9S_MB_2U_LIB.S9S_MB_2U(SCH_1):GND   I176 @S9S_MB_2U_LIB.S9S_MB_2U(SCH_1):PAGE103
    50    GND @S9S_MB_2U_LIB.S9S_MB_2U(SCH_1):GND   I176 @S9S_MB_2U_LIB.S9S_MB_2U(SCH_1):PAGE103
    52    GND @S9S_MB_2U_LIB.S9S_MB_2U(SCH_1):GND   I176 @S9S_MB_2U_LIB.S9S_MB_2U(SCH_1):PAGE103
    54    GND @S9S_MB_2U_LIB.S9S_MB_2U(SCH_1):GND   I176 @S9S_MB_2U_LIB.S9S_MB_2U(SCH_1):PAGE103
    57    GND @S9S_MB_2U_LIB.S9S_MB_2U(SCH_1):GND   I176 @S9S_MB_2U_LIB.S9S_MB_2U(SCH_1):PAGE103
    59    GND @S9S_MB_2U_LIB.S9S_MB_2U(SCH_1):GND   I176 @S9S_MB_2U_LIB.S9S_MB_2U(SCH_1):PAGE103
    61    GND @S9S_MB_2U_LIB.S9S_MB_2U(SCH_1):GND   I176 @S9S_MB_2U_LIB.S9S_MB_2U(SCH_1):PAGE103
    63    GND @S9S_MB_2U_LIB.S9S_MB_2U(SCH_1):GND   I176 @S9S_MB_2U_LIB.S9S_MB_2U(SCH_1):PAGE103
    65    GND @S9S_MB_2U_LIB.S9S_MB_2U(SCH_1):GND   I176 @S9S_MB_2U_LIB.S9S_MB_2U(SCH_1):PAGE103
    67    GND @S9S_MB_2U_LIB.S9S_MB_2U(SCH_1):GND   I176 @S9S_MB_2U_LIB.S9S_MB_2U(SCH_1):PAGE103
    69    GND @S9S_MB_2U_LIB.S9S_MB_2U(SCH_1):GND   I176 @S9S_MB_2U_LIB.S9S_MB_2U(SCH_1):PAGE103
    71    GND @S9S_MB_2U_LIB.S9S_MB_2U(SCH_1):GND   I176 @S9S_MB_2U_LIB.S9S_MB_2U(SCH_1):PAGE103
    73    GND @S9S_MB_2U_LIB.S9S_MB_2U(SCH_1):GND   I176 @S9S_MB_2U_LIB.S9S_MB_2U(SCH_1):PAGE103
    75    GND @S9S_MB_2U_LIB.S9S_MB_2U(SCH_1):GND   I176 @S9S_MB_2U_LIB.S9S_MB_2U(SCH_1):PAGE103
    77    GND @S9S_MB_2U_LIB.S9S_MB_2U(SCH_1):GND   I176 @S9S_MB_2U_LIB.S9S_MB_2U(SCH_1):PAGE103
    79    GND @S9S_MB_2U_LIB.S9S_MB_2U(SCH_1):GND   I176 @S9S_MB_2U_LIB.S9S_MB_2U(SCH_1):PAGE103
    81    GND @S9S_MB_2U_LIB.S9S_MB_2U(SCH_1):GND   I176 @S9S_MB_2U_LIB.S9S_MB_2U(SCH_1):PAGE103
    83    GND @S9S_MB_2U_LIB.S9S_MB_2U(SCH_1):GND   I176 @S9S_MB_2U_LIB.S9S_MB_2U(SCH_1):PAGE103
    85    GND @S9S_MB_2U_LIB.S9S_MB_2U(SCH_1):GND   I176 @S9S_MB_2U_LIB.S9S_MB_2U(SCH_1):PAGE103
    88    GND @S9S_MB_2U_LIB.S9S_MB_2U(SCH_1):GND   I176 @S9S_MB_2U_LIB.S9S_MB_2U(SCH_1):PAGE103
    90    GND @S9S_MB_2U_LIB.S9S_MB_2U(SCH_1):GND   I176 @S9S_MB_2U_LIB.S9S_MB_2U(SCH_1):PAGE103
    92    GND @S9S_MB_2U_LIB.S9S_MB_2U(SCH_1):GND   I176 @S9S_MB_2U_LIB.S9S_MB_2U(SCH_1):PAGE103
    95    GND @S9S_MB_2U_LIB.S9S_MB_2U(SCH_1):GND   I176 @S9S_MB_2U_LIB.S9S_MB_2U(SCH_1):PAGE103
    97    GND @S9S_MB_2U_LIB.S9S_MB_2U(SCH_1):GND   I176 @S9S_MB_2U_LIB.S9S_MB_2U(SCH_1):PAGE103
    99    GND @S9S_MB_2U_LIB.S9S_MB_2U(SCH_1):GND   I176 @S9S_MB_2U_LIB.S9S_MB_2U(SCH_1):PAGE103
   101    GND @S9S_MB_2U_LIB.S9S_MB_2U(SCH_1):GND   I176 @S9S_MB_2U_LIB.S9S_MB_2U(SCH_1):PAGE103
   103    GND @S9S_MB_2U_LIB.S9S_MB_2U(SCH_1):GND   I176 @S9S_MB_2U_LIB.S9S_MB_2U(SCH_1):PAGE103
   106    GND @S9S_MB_2U_LIB.S9S_MB_2U(SCH_1):GND   I176 @S9S_MB_2U_LIB.S9S_MB_2U(SCH_1):PAGE103
   108    GND @S9S_MB_2U_LIB.S9S_MB_2U(SCH_1):GND   I176 @S9S_MB_2U_LIB.S9S_MB_2U(SCH_1):PAGE103
   110    GND @S9S_MB_2U_LIB.S9S_MB_2U(SCH_1):GND   I176 @S9S_MB_2U_LIB.S9S_MB_2U(SCH_1):PAGE103
   112    GND @S9S_MB_2U_LIB.S9S_MB_2U(SCH_1):GND   I176 @S9S_MB_2U_LIB.S9S_MB_2U(SCH_1):PAGE103
   114    GND @S9S_MB_2U_LIB.S9S_MB_2U(SCH_1):GND   I176 @S9S_MB_2U_LIB.S9S_MB_2U(SCH_1):PAGE103
   117    GND @S9S_MB_2U_LIB.S9S_MB_2U(SCH_1):GND   I176 @S9S_MB_2U_LIB.S9S_MB_2U(SCH_1):PAGE103
   119    GND @S9S_MB_2U_LIB.S9S_MB_2U(SCH_1):GND   I176 @S9S_MB_2U_LIB.S9S_MB_2U(SCH_1):PAGE103
   121    GND @S9S_MB_2U_LIB.S9S_MB_2U(SCH_1):GND   I176 @S9S_MB_2U_LIB.S9S_MB_2U(SCH_1):PAGE103
   123    GND @S9S_MB_2U_LIB.S9S_MB_2U(SCH_1):GND   I176 @S9S_MB_2U_LIB.S9S_MB_2U(SCH_1):PAGE103
   125    GND @S9S_MB_2U_LIB.S9S_MB_2U(SCH_1):GND   I176 @S9S_MB_2U_LIB.S9S_MB_2U(SCH_1):PAGE103
   128    GND @S9S_MB_2U_LIB.S9S_MB_2U(SCH_1):GND   I176 @S9S_MB_2U_LIB.S9S_MB_2U(SCH_1):PAGE103
   130    GND @S9S_MB_2U_LIB.S9S_MB_2U(SCH_1):GND   I176 @S9S_MB_2U_LIB.S9S_MB_2U(SCH_1):PAGE103
   134    GND @S9S_MB_2U_LIB.S9S_MB_2U(SCH_1):GND   I176 @S9S_MB_2U_LIB.S9S_MB_2U(SCH_1):PAGE103
   143    GND @S9S_MB_2U_LIB.S9S_MB_2U(SCH_1):GND   I176 @S9S_MB_2U_LIB.S9S_MB_2U(SCH_1):PAGE103
   151    GND @S9S_MB_2U_LIB.S9S_MB_2U(SCH_1):GND   I176 @S9S_MB_2U_LIB.S9S_MB_2U(SCH_1):PAGE103
   153    GND @S9S_MB_2U_LIB.S9S_MB_2U(SCH_1):GND   I176 @S9S_MB_2U_LIB.S9S_MB_2U(SCH_1):PAGE103
   155    GND @S9S_MB_2U_LIB.S9S_MB_2U(SCH_1):GND   I176 @S9S_MB_2U_LIB.S9S_MB_2U(SCH_1):PAGE103
   158    GND @S9S_MB_2U_LIB.S9S_MB_2U(SCH_1):GND   I176 @S9S_MB_2U_LIB.S9S_MB_2U(SCH_1):PAGE103
   160    GND @S9S_MB_2U_LIB.S9S_MB_2U(SCH_1):GND   I176 @S9S_MB_2U_LIB.S9S_MB_2U(SCH_1):PAGE103
   162    GND @S9S_MB_2U_LIB.S9S_MB_2U(SCH_1):GND   I176 @S9S_MB_2U_LIB.S9S_MB_2U(SCH_1):PAGE103
   164    GND @S9S_MB_2U_LIB.S9S_MB_2U(SCH_1):GND   I176 @S9S_MB_2U_LIB.S9S_MB_2U(SCH_1):PAGE103
   166    GND @S9S_MB_2U_LIB.S9S_MB_2U(SCH_1):GND   I176 @S9S_MB_2U_LIB.S9S_MB_2U(SCH_1):PAGE103
   169    GND @S9S_MB_2U_LIB.S9S_MB_2U(SCH_1):GND   I176 @S9S_MB_2U_LIB.S9S_MB_2U(SCH_1):PAGE103
   171    GND @S9S_MB_2U_LIB.S9S_MB_2U(SCH_1):GND   I176 @S9S_MB_2U_LIB.S9S_MB_2U(SCH_1):PAGE103
   173    GND @S9S_MB_2U_LIB.S9S_MB_2U(SCH_1):GND   I176 @S9S_MB_2U_LIB.S9S_MB_2U(SCH_1):PAGE103
   175    GND @S9S_MB_2U_LIB.S9S_MB_2U(SCH_1):GND   I176 @S9S_MB_2U_LIB.S9S_MB_2U(SCH_1):PAGE103
   177    GND @S9S_MB_2U_LIB.S9S_MB_2U(SCH_1):GND   I176 @S9S_MB_2U_LIB.S9S_MB_2U(SCH_1):PAGE103
   180    GND @S9S_MB_2U_LIB.S9S_MB_2U(SCH_1):GND   I176 @S9S_MB_2U_LIB.S9S_MB_2U(SCH_1):PAGE103
   182    GND @S9S_MB_2U_LIB.S9S_MB_2U(SCH_1):GND   I176 @S9S_MB_2U_LIB.S9S_MB_2U(SCH_1):PAGE103
   184    GND @S9S_MB_2U_LIB.S9S_MB_2U(SCH_1):GND   I176 @S9S_MB_2U_LIB.S9S_MB_2U(SCH_1):PAGE103
   186    GND @S9S_MB_2U_LIB.S9S_MB_2U(SCH_1):GND   I176 @S9S_MB_2U_LIB.S9S_MB_2U(SCH_1):PAGE103
   188    GND @S9S_MB_2U_LIB.S9S_MB_2U(SCH_1):GND   I176 @S9S_MB_2U_LIB.S9S_MB_2U(SCH_1):PAGE103
   191    GND @S9S_MB_2U_LIB.S9S_MB_2U(SCH_1):GND   I176 @S9S_MB_2U_LIB.S9S_MB_2U(SCH_1):PAGE103
   193    GND @S9S_MB_2U_LIB.S9S_MB_2U(SCH_1):GND   I176 @S9S_MB_2U_LIB.S9S_MB_2U(SCH_1):PAGE103
   195    GND @S9S_MB_2U_LIB.S9S_MB_2U(SCH_1):GND   I176 @S9S_MB_2U_LIB.S9S_MB_2U(SCH_1):PAGE103
   197    GND @S9S_MB_2U_LIB.S9S_MB_2U(SCH_1):GND   I176 @S9S_MB_2U_LIB.S9S_MB_2U(SCH_1):PAGE103
   199    GND @S9S_MB_2U_LIB.S9S_MB_2U(SCH_1):GND   I176 @S9S_MB_2U_LIB.S9S_MB_2U(SCH_1):PAGE103
   202    GND @S9S_MB_2U_LIB.S9S_MB_2U(SCH_1):GND   I176 @S9S_MB_2U_LIB.S9S_MB_2U(SCH_1):PAGE103
   204    GND @S9S_MB_2U_LIB.S9S_MB_2U(SCH_1):GND   I176 @S9S_MB_2U_LIB.S9S_MB_2U(SCH_1):PAGE103
   206    GND @S9S_MB_2U_LIB.S9S_MB_2U(SCH_1):GND   I176 @S9S_MB_2U_LIB.S9S_MB_2U(SCH_1):PAGE103
   208    GND @S9S_MB_2U_LIB.S9S_MB_2U(SCH_1):GND   I176 @S9S_MB_2U_LIB.S9S_MB_2U(SCH_1):PAGE103
   210    GND @S9S_MB_2U_LIB.S9S_MB_2U(SCH_1):GND   I176 @S9S_MB_2U_LIB.S9S_MB_2U(SCH_1):PAGE103
   212    GND @S9S_MB_2U_LIB.S9S_MB_2U(SCH_1):GND   I176 @S9S_MB_2U_LIB.S9S_MB_2U(SCH_1):PAGE103
   214    GND @S9S_MB_2U_LIB.S9S_MB_2U(SCH_1):GND   I176 @S9S_MB_2U_LIB.S9S_MB_2U(SCH_1):PAGE103
   216    GND @S9S_MB_2U_LIB.S9S_MB_2U(SCH_1):GND   I176 @S9S_MB_2U_LIB.S9S_MB_2U(SCH_1):PAGE103
   219    GND @S9S_MB_2U_LIB.S9S_MB_2U(SCH_1):GND   I176 @S9S_MB_2U_LIB.S9S_MB_2U(SCH_1):PAGE103
   222    GND @S9S_MB_2U_LIB.S9S_MB_2U(SCH_1):GND   I176 @S9S_MB_2U_LIB.S9S_MB_2U(SCH_1):PAGE103
   224    GND @S9S_MB_2U_LIB.S9S_MB_2U(SCH_1):GND   I176 @S9S_MB_2U_LIB.S9S_MB_2U(SCH_1):PAGE103
   226    GND @S9S_MB_2U_LIB.S9S_MB_2U(SCH_1):GND   I176 @S9S_MB_2U_LIB.S9S_MB_2U(SCH_1):PAGE103
   228    GND @S9S_MB_2U_LIB.S9S_MB_2U(SCH_1):GND   I176 @S9S_MB_2U_LIB.S9S_MB_2U(SCH_1):PAGE103
   233    GND @S9S_MB_2U_LIB.S9S_MB_2U(SCH_1):GND   I176 @S9S_MB_2U_LIB.S9S_MB_2U(SCH_1):PAGE103
   237    GND @S9S_MB_2U_LIB.S9S_MB_2U(SCH_1):GND   I176 @S9S_MB_2U_LIB.S9S_MB_2U(SCH_1):PAGE103
   242    GND @S9S_MB_2U_LIB.S9S_MB_2U(SCH_1):GND   I176 @S9S_MB_2U_LIB.S9S_MB_2U(SCH_1):PAGE103
   244    GND @S9S_MB_2U_LIB.S9S_MB_2U(SCH_1):GND   I176 @S9S_MB_2U_LIB.S9S_MB_2U(SCH_1):PAGE103
   246    GND @S9S_MB_2U_LIB.S9S_MB_2U(SCH_1):GND   I176 @S9S_MB_2U_LIB.S9S_MB_2U(SCH_1):PAGE103
   248    GND @S9S_MB_2U_LIB.S9S_MB_2U(SCH_1):GND   I176 @S9S_MB_2U_LIB.S9S_MB_2U(SCH_1):PAGE103
   251    GND @S9S_MB_2U_LIB.S9S_MB_2U(SCH_1):GND   I176 @S9S_MB_2U_LIB.S9S_MB_2U(SCH_1):PAGE103
   253    GND @S9S_MB_2U_LIB.S9S_MB_2U(SCH_1):GND   I176 @S9S_MB_2U_LIB.S9S_MB_2U(SCH_1):PAGE103
   255    GND @S9S_MB_2U_LIB.S9S_MB_2U(SCH_1):GND   I176 @S9S_MB_2U_LIB.S9S_MB_2U(SCH_1):PAGE103
   257    GND @S9S_MB_2U_LIB.S9S_MB_2U(SCH_1):GND   I176 @S9S_MB_2U_LIB.S9S_MB_2U(SCH_1):PAGE103
   259    GND @S9S_MB_2U_LIB.S9S_MB_2U(SCH_1):GND   I176 @S9S_MB_2U_LIB.S9S_MB_2U(SCH_1):PAGE103
   262    GND @S9S_MB_2U_LIB.S9S_MB_2U(SCH_1):GND   I176 @S9S_MB_2U_LIB.S9S_MB_2U(SCH_1):PAGE103
   264    GND @S9S_MB_2U_LIB.S9S_MB_2U(SCH_1):GND   I176 @S9S_MB_2U_LIB.S9S_MB_2U(SCH_1):PAGE103
   266    GND @S9S_MB_2U_LIB.S9S_MB_2U(SCH_1):GND   I176 @S9S_MB_2U_LIB.S9S_MB_2U(SCH_1):PAGE103
   268    GND @S9S_MB_2U_LIB.S9S_MB_2U(SCH_1):GND   I176 @S9S_MB_2U_LIB.S9S_MB_2U(SCH_1):PAGE103
   270    GND @S9S_MB_2U_LIB.S9S_MB_2U(SCH_1):GND   I176 @S9S_MB_2U_LIB.S9S_MB_2U(SCH_1):PAGE103
   273    GND @S9S_MB_2U_LIB.S9S_MB_2U(SCH_1):GND   I176 @S9S_MB_2U_LIB.S9S_MB_2U(SCH_1):PAGE103
   275    GND @S9S_MB_2U_LIB.S9S_MB_2U(SCH_1):GND   I176 @S9S_MB_2U_LIB.S9S_MB_2U(SCH_1):PAGE103
   277    GND @S9S_MB_2U_LIB.S9S_MB_2U(SCH_1):GND   I176 @S9S_MB_2U_LIB.S9S_MB_2U(SCH_1):PAGE103
   279    GND @S9S_MB_2U_LIB.S9S_MB_2U(SCH_1):GND   I176 @S9S_MB_2U_LIB.S9S_MB_2U(SCH_1):PAGE103
   281    GND @S9S_MB_2U_LIB.S9S_MB_2U(SCH_1):GND   I176 @S9S_MB_2U_LIB.S9S_MB_2U(SCH_1):PAGE103
   284    GND @S9S_MB_2U_LIB.S9S_MB_2U(SCH_1):GND   I176 @S9S_MB_2U_LIB.S9S_MB_2U(SCH_1):PAGE103
   286    GND @S9S_MB_2U_LIB.S9S_MB_2U(SCH_1):GND   I176 @S9S_MB_2U_LIB.S9S_MB_2U(SCH_1):PAGE103
   288    GND @S9S_MB_2U_LIB.S9S_MB_2U(SCH_1):GND   I176 @S9S_MB_2U_LIB.S9S_MB_2U(SCH_1):PAGE103
     1 P12V_S3_AUX_CPU1_NVDIMM @S9S_MB_2U_LIB.S9S_MB_2U(SCH_1):P12V_S3_AUX_CPU1_NVDIMM   I176 @S9S_MB_2U_LIB.S9S_MB_2U(SCH_1):PAGE103
   145 P12V_S3_AUX_CPU1_NVDIMM @S9S_MB_2U_LIB.S9S_MB_2U(SCH_1):P12V_S3_AUX_CPU1_NVDIMM   I176 @S9S_MB_2U_LIB.S9S_MB_2U(SCH_1):PAGE103
   146 P12V_S3_AUX_CPU1_NVDIMM @S9S_MB_2U_LIB.S9S_MB_2U(SCH_1):P12V_S3_AUX_CPU1_NVDIMM   I176 @S9S_MB_2U_LIB.S9S_MB_2U(SCH_1):PAGE103
   230    GND @S9S_MB_2U_LIB.S9S_MB_2U(SCH_1):GND   I176 @S9S_MB_2U_LIB.S9S_MB_2U(SCH_1):PAGE103
   235    GND @S9S_MB_2U_LIB.S9S_MB_2U(SCH_1):GND   I176 @S9S_MB_2U_LIB.S9S_MB_2U(SCH_1):PAGE103
   240    GND @S9S_MB_2U_LIB.S9S_MB_2U(SCH_1):GND   I176 @S9S_MB_2U_LIB.S9S_MB_2U(SCH_1):PAGE103
   132    GND @S9S_MB_2U_LIB.S9S_MB_2U(SCH_1):GND   I176 @S9S_MB_2U_LIB.S9S_MB_2U(SCH_1):PAGE103
   136    GND @S9S_MB_2U_LIB.S9S_MB_2U(SCH_1):GND   I176 @S9S_MB_2U_LIB.S9S_MB_2U(SCH_1):PAGE103
   139    GND @S9S_MB_2U_LIB.S9S_MB_2U(SCH_1):GND   I176 @S9S_MB_2U_LIB.S9S_MB_2U(SCH_1):PAGE103
   141    GND @S9S_MB_2U_LIB.S9S_MB_2U(SCH_1):GND   I176 @S9S_MB_2U_LIB.S9S_MB_2U(SCH_1):PAGE103
    G1    GND @S9S_MB_2U_LIB.S9S_MB_2U(SCH_1):GND   I176 @S9S_MB_2U_LIB.S9S_MB_2U(SCH_1):PAGE103
    G2    GND @S9S_MB_2U_LIB.S9S_MB_2U(SCH_1):GND   I176 @S9S_MB_2U_LIB.S9S_MB_2U(SCH_1):PAGE103
    G3    GND @S9S_MB_2U_LIB.S9S_MB_2U(SCH_1):GND   I176 @S9S_MB_2U_LIB.S9S_MB_2U(SCH_1):PAGE103

 J23 SCONN288_ADR50017P130CC-SCONN2A
     3 P3V3_AUX @S9S_MB_2U_LIB.S9S_MB_2U(SCH_1):P3V3_AUX    I25 @S9S_MB_2U_LIB.S9S_MB_2U(SCH_1):PAGE104
     2 TP_CHD_CPU1_DIMM1_FRU_0 @S9S_MB_2U_LIB.S9S_MB_2U(SCH_1):TP_CHD_CPU1_DIMM1_FRU_0    I25 @S9S_MB_2U_LIB.S9S_MB_2U(SCH_1):PAGE104
   144 TP_CHD_CPU1_DIMM1_FRU_1 @S9S_MB_2U_LIB.S9S_MB_2U(SCH_1):TP_CHD_CPU1_DIMM1_FRU_1    I25 @S9S_MB_2U_LIB.S9S_MB_2U(SCH_1):PAGE104
   149 TP_CHD_CPU1_DIMM1_FRU_2 @S9S_MB_2U_LIB.S9S_MB_2U(SCH_1):TP_CHD_CPU1_DIMM1_FRU_2    I25 @S9S_MB_2U_LIB.S9S_MB_2U(SCH_1):PAGE104
   150 TP_CHD_CPU1_DIMM1_FRU_3 @S9S_MB_2U_LIB.S9S_MB_2U(SCH_1):TP_CHD_CPU1_DIMM1_FRU_3    I25 @S9S_MB_2U_LIB.S9S_MB_2U(SCH_1):PAGE104
   220 TP_CHD_CPU1_DIMM1_FRU_4 @S9S_MB_2U_LIB.S9S_MB_2U(SCH_1):TP_CHD_CPU1_DIMM1_FRU_4    I25 @S9S_MB_2U_LIB.S9S_MB_2U(SCH_1):PAGE104
   231 TP_CHD_CPU1_DIMM1_FRU_5 @S9S_MB_2U_LIB.S9S_MB_2U(SCH_1):TP_CHD_CPU1_DIMM1_FRU_5    I25 @S9S_MB_2U_LIB.S9S_MB_2U(SCH_1):PAGE104
   232 TP_CHD_CPU1_DIMM1_FRU_6 @S9S_MB_2U_LIB.S9S_MB_2U(SCH_1):TP_CHD_CPU1_DIMM1_FRU_6    I25 @S9S_MB_2U_LIB.S9S_MB_2U(SCH_1):PAGE104
   207 RST_M_CD_CPU1_FPGA_N @S9S_MB_2U_LIB.S9S_MB_2U(SCH_1):RST_M_CD_CPU1_FPGA_N    I25 @S9S_MB_2U_LIB.S9S_MB_2U(SCH_1):PAGE104
   147 PWRGD_CHD_CPU1_DIMM1 @S9S_MB_2U_LIB.S9S_MB_2U(SCH_1):PWRGD_CHD_CPU1_DIMM1    I25 @S9S_MB_2U_LIB.S9S_MB_2U(SCH_1):PAGE104
   227 M_D_CPU1_SB_PAR @S9S_MB_2U_LIB.S9S_MB_2U(SCH_1):M_D_CPU1_SB_PAR    I25 @S9S_MB_2U_LIB.S9S_MB_2U(SCH_1):PAGE104
    74 M_D_CPU1_SA_PAR @S9S_MB_2U_LIB.S9S_MB_2U(SCH_1):M_D_CPU1_SA_PAR    I25 @S9S_MB_2U_LIB.S9S_MB_2U(SCH_1):PAGE104
    87 M_D_CPU1_SB_RSP<0> @S9S_MB_2U_LIB.S9S_MB_2U(SCH_1):M_D_CPU1_SB_RSP(0)    I25 @S9S_MB_2U_LIB.S9S_MB_2U(SCH_1):PAGE104
    86 M_D_CPU1_SA_RSP<0> @S9S_MB_2U_LIB.S9S_MB_2U(SCH_1):M_D_CPU1_SA_RSP(0)    I25 @S9S_MB_2U_LIB.S9S_MB_2U(SCH_1):PAGE104
     5 I3C_SPD_DDRABCD_CPU1_LVC1_SDA @S9S_MB_2U_LIB.S9S_MB_2U(SCH_1):I3C_SPD_DDRABCD_CPU1_LVC1_SDA    I25 @S9S_MB_2U_LIB.S9S_MB_2U(SCH_1):PAGE104
     4 I3C_SPD_DDRABCD_CPU1_LVC1_SCL_6 @S9S_MB_2U_LIB.S9S_MB_2U(SCH_1):I3C_SPD_DDRABCD_CPU1_LVC1_SCL_R7    I25 @S9S_MB_2U_LIB.S9S_MB_2U(SCH_1):PAGE104
   148 PD_CHD_CPU1_DIMM1_SAA @S9S_MB_2U_LIB.S9S_MB_2U(SCH_1):PD_CHD_CPU1_DIMM1_SAA    I25 @S9S_MB_2U_LIB.S9S_MB_2U(SCH_1):PAGE104
   100 M_D_CPU1_SB_DQ<0> @S9S_MB_2U_LIB.S9S_MB_2U(SCH_1):M_D_CPU1_SB_DQ(0)    I25 @S9S_MB_2U_LIB.S9S_MB_2U(SCH_1):PAGE104
   102 M_D_CPU1_SB_DQ<1> @S9S_MB_2U_LIB.S9S_MB_2U(SCH_1):M_D_CPU1_SB_DQ(1)    I25 @S9S_MB_2U_LIB.S9S_MB_2U(SCH_1):PAGE104
   245 M_D_CPU1_SB_DQ<2> @S9S_MB_2U_LIB.S9S_MB_2U(SCH_1):M_D_CPU1_SB_DQ(2)    I25 @S9S_MB_2U_LIB.S9S_MB_2U(SCH_1):PAGE104
   247 M_D_CPU1_SB_DQ<3> @S9S_MB_2U_LIB.S9S_MB_2U(SCH_1):M_D_CPU1_SB_DQ(3)    I25 @S9S_MB_2U_LIB.S9S_MB_2U(SCH_1):PAGE104
   107 M_D_CPU1_SB_DQ<4> @S9S_MB_2U_LIB.S9S_MB_2U(SCH_1):M_D_CPU1_SB_DQ(4)    I25 @S9S_MB_2U_LIB.S9S_MB_2U(SCH_1):PAGE104
   109 M_D_CPU1_SB_DQ<5> @S9S_MB_2U_LIB.S9S_MB_2U(SCH_1):M_D_CPU1_SB_DQ(5)    I25 @S9S_MB_2U_LIB.S9S_MB_2U(SCH_1):PAGE104
   252 M_D_CPU1_SB_DQ<6> @S9S_MB_2U_LIB.S9S_MB_2U(SCH_1):M_D_CPU1_SB_DQ(6)    I25 @S9S_MB_2U_LIB.S9S_MB_2U(SCH_1):PAGE104
   254 M_D_CPU1_SB_DQ<7> @S9S_MB_2U_LIB.S9S_MB_2U(SCH_1):M_D_CPU1_SB_DQ(7)    I25 @S9S_MB_2U_LIB.S9S_MB_2U(SCH_1):PAGE104
   111 M_D_CPU1_SB_DQ<8> @S9S_MB_2U_LIB.S9S_MB_2U(SCH_1):M_D_CPU1_SB_DQ(8)    I25 @S9S_MB_2U_LIB.S9S_MB_2U(SCH_1):PAGE104
   113 M_D_CPU1_SB_DQ<9> @S9S_MB_2U_LIB.S9S_MB_2U(SCH_1):M_D_CPU1_SB_DQ(9)    I25 @S9S_MB_2U_LIB.S9S_MB_2U(SCH_1):PAGE104
   256 M_D_CPU1_SB_DQ<10> @S9S_MB_2U_LIB.S9S_MB_2U(SCH_1):M_D_CPU1_SB_DQ(10)    I25 @S9S_MB_2U_LIB.S9S_MB_2U(SCH_1):PAGE104
   258 M_D_CPU1_SB_DQ<11> @S9S_MB_2U_LIB.S9S_MB_2U(SCH_1):M_D_CPU1_SB_DQ(11)    I25 @S9S_MB_2U_LIB.S9S_MB_2U(SCH_1):PAGE104
   118 M_D_CPU1_SB_DQ<12> @S9S_MB_2U_LIB.S9S_MB_2U(SCH_1):M_D_CPU1_SB_DQ(12)    I25 @S9S_MB_2U_LIB.S9S_MB_2U(SCH_1):PAGE104
   120 M_D_CPU1_SB_DQ<13> @S9S_MB_2U_LIB.S9S_MB_2U(SCH_1):M_D_CPU1_SB_DQ(13)    I25 @S9S_MB_2U_LIB.S9S_MB_2U(SCH_1):PAGE104
   263 M_D_CPU1_SB_DQ<14> @S9S_MB_2U_LIB.S9S_MB_2U(SCH_1):M_D_CPU1_SB_DQ(14)    I25 @S9S_MB_2U_LIB.S9S_MB_2U(SCH_1):PAGE104
   265 M_D_CPU1_SB_DQ<15> @S9S_MB_2U_LIB.S9S_MB_2U(SCH_1):M_D_CPU1_SB_DQ(15)    I25 @S9S_MB_2U_LIB.S9S_MB_2U(SCH_1):PAGE104
   122 M_D_CPU1_SB_DQ<16> @S9S_MB_2U_LIB.S9S_MB_2U(SCH_1):M_D_CPU1_SB_DQ(16)    I25 @S9S_MB_2U_LIB.S9S_MB_2U(SCH_1):PAGE104
   124 M_D_CPU1_SB_DQ<17> @S9S_MB_2U_LIB.S9S_MB_2U(SCH_1):M_D_CPU1_SB_DQ(17)    I25 @S9S_MB_2U_LIB.S9S_MB_2U(SCH_1):PAGE104
   267 M_D_CPU1_SB_DQ<18> @S9S_MB_2U_LIB.S9S_MB_2U(SCH_1):M_D_CPU1_SB_DQ(18)    I25 @S9S_MB_2U_LIB.S9S_MB_2U(SCH_1):PAGE104
   269 M_D_CPU1_SB_DQ<19> @S9S_MB_2U_LIB.S9S_MB_2U(SCH_1):M_D_CPU1_SB_DQ(19)    I25 @S9S_MB_2U_LIB.S9S_MB_2U(SCH_1):PAGE104
   129 M_D_CPU1_SB_DQ<20> @S9S_MB_2U_LIB.S9S_MB_2U(SCH_1):M_D_CPU1_SB_DQ(20)    I25 @S9S_MB_2U_LIB.S9S_MB_2U(SCH_1):PAGE104
   131 M_D_CPU1_SB_DQ<21> @S9S_MB_2U_LIB.S9S_MB_2U(SCH_1):M_D_CPU1_SB_DQ(21)    I25 @S9S_MB_2U_LIB.S9S_MB_2U(SCH_1):PAGE104
   274 M_D_CPU1_SB_DQ<22> @S9S_MB_2U_LIB.S9S_MB_2U(SCH_1):M_D_CPU1_SB_DQ(22)    I25 @S9S_MB_2U_LIB.S9S_MB_2U(SCH_1):PAGE104
   276 M_D_CPU1_SB_DQ<23> @S9S_MB_2U_LIB.S9S_MB_2U(SCH_1):M_D_CPU1_SB_DQ(23)    I25 @S9S_MB_2U_LIB.S9S_MB_2U(SCH_1):PAGE104
   133 M_D_CPU1_SB_DQ<24> @S9S_MB_2U_LIB.S9S_MB_2U(SCH_1):M_D_CPU1_SB_DQ(24)    I25 @S9S_MB_2U_LIB.S9S_MB_2U(SCH_1):PAGE104
   135 M_D_CPU1_SB_DQ<25> @S9S_MB_2U_LIB.S9S_MB_2U(SCH_1):M_D_CPU1_SB_DQ(25)    I25 @S9S_MB_2U_LIB.S9S_MB_2U(SCH_1):PAGE104
   278 M_D_CPU1_SB_DQ<26> @S9S_MB_2U_LIB.S9S_MB_2U(SCH_1):M_D_CPU1_SB_DQ(26)    I25 @S9S_MB_2U_LIB.S9S_MB_2U(SCH_1):PAGE104
   280 M_D_CPU1_SB_DQ<27> @S9S_MB_2U_LIB.S9S_MB_2U(SCH_1):M_D_CPU1_SB_DQ(27)    I25 @S9S_MB_2U_LIB.S9S_MB_2U(SCH_1):PAGE104
   140 M_D_CPU1_SB_DQ<28> @S9S_MB_2U_LIB.S9S_MB_2U(SCH_1):M_D_CPU1_SB_DQ(28)    I25 @S9S_MB_2U_LIB.S9S_MB_2U(SCH_1):PAGE104
   142 M_D_CPU1_SB_DQ<29> @S9S_MB_2U_LIB.S9S_MB_2U(SCH_1):M_D_CPU1_SB_DQ(29)    I25 @S9S_MB_2U_LIB.S9S_MB_2U(SCH_1):PAGE104
   285 M_D_CPU1_SB_DQ<30> @S9S_MB_2U_LIB.S9S_MB_2U(SCH_1):M_D_CPU1_SB_DQ(30)    I25 @S9S_MB_2U_LIB.S9S_MB_2U(SCH_1):PAGE104
   287 M_D_CPU1_SB_DQ<31> @S9S_MB_2U_LIB.S9S_MB_2U(SCH_1):M_D_CPU1_SB_DQ(31)    I25 @S9S_MB_2U_LIB.S9S_MB_2U(SCH_1):PAGE104
     7 M_D_CPU1_SA_DQ<0> @S9S_MB_2U_LIB.S9S_MB_2U(SCH_1):M_D_CPU1_SA_DQ(0)    I25 @S9S_MB_2U_LIB.S9S_MB_2U(SCH_1):PAGE104
     9 M_D_CPU1_SA_DQ<1> @S9S_MB_2U_LIB.S9S_MB_2U(SCH_1):M_D_CPU1_SA_DQ(1)    I25 @S9S_MB_2U_LIB.S9S_MB_2U(SCH_1):PAGE104
   152 M_D_CPU1_SA_DQ<2> @S9S_MB_2U_LIB.S9S_MB_2U(SCH_1):M_D_CPU1_SA_DQ(2)    I25 @S9S_MB_2U_LIB.S9S_MB_2U(SCH_1):PAGE104
   154 M_D_CPU1_SA_DQ<3> @S9S_MB_2U_LIB.S9S_MB_2U(SCH_1):M_D_CPU1_SA_DQ(3)    I25 @S9S_MB_2U_LIB.S9S_MB_2U(SCH_1):PAGE104
    14 M_D_CPU1_SA_DQ<4> @S9S_MB_2U_LIB.S9S_MB_2U(SCH_1):M_D_CPU1_SA_DQ(4)    I25 @S9S_MB_2U_LIB.S9S_MB_2U(SCH_1):PAGE104
    16 M_D_CPU1_SA_DQ<5> @S9S_MB_2U_LIB.S9S_MB_2U(SCH_1):M_D_CPU1_SA_DQ(5)    I25 @S9S_MB_2U_LIB.S9S_MB_2U(SCH_1):PAGE104
   159 M_D_CPU1_SA_DQ<6> @S9S_MB_2U_LIB.S9S_MB_2U(SCH_1):M_D_CPU1_SA_DQ(6)    I25 @S9S_MB_2U_LIB.S9S_MB_2U(SCH_1):PAGE104
   161 M_D_CPU1_SA_DQ<7> @S9S_MB_2U_LIB.S9S_MB_2U(SCH_1):M_D_CPU1_SA_DQ(7)    I25 @S9S_MB_2U_LIB.S9S_MB_2U(SCH_1):PAGE104
    18 M_D_CPU1_SA_DQ<8> @S9S_MB_2U_LIB.S9S_MB_2U(SCH_1):M_D_CPU1_SA_DQ(8)    I25 @S9S_MB_2U_LIB.S9S_MB_2U(SCH_1):PAGE104
    20 M_D_CPU1_SA_DQ<9> @S9S_MB_2U_LIB.S9S_MB_2U(SCH_1):M_D_CPU1_SA_DQ(9)    I25 @S9S_MB_2U_LIB.S9S_MB_2U(SCH_1):PAGE104
   163 M_D_CPU1_SA_DQ<10> @S9S_MB_2U_LIB.S9S_MB_2U(SCH_1):M_D_CPU1_SA_DQ(10)    I25 @S9S_MB_2U_LIB.S9S_MB_2U(SCH_1):PAGE104
   165 M_D_CPU1_SA_DQ<11> @S9S_MB_2U_LIB.S9S_MB_2U(SCH_1):M_D_CPU1_SA_DQ(11)    I25 @S9S_MB_2U_LIB.S9S_MB_2U(SCH_1):PAGE104
    25 M_D_CPU1_SA_DQ<12> @S9S_MB_2U_LIB.S9S_MB_2U(SCH_1):M_D_CPU1_SA_DQ(12)    I25 @S9S_MB_2U_LIB.S9S_MB_2U(SCH_1):PAGE104
    27 M_D_CPU1_SA_DQ<13> @S9S_MB_2U_LIB.S9S_MB_2U(SCH_1):M_D_CPU1_SA_DQ(13)    I25 @S9S_MB_2U_LIB.S9S_MB_2U(SCH_1):PAGE104
   170 M_D_CPU1_SA_DQ<14> @S9S_MB_2U_LIB.S9S_MB_2U(SCH_1):M_D_CPU1_SA_DQ(14)    I25 @S9S_MB_2U_LIB.S9S_MB_2U(SCH_1):PAGE104
   172 M_D_CPU1_SA_DQ<15> @S9S_MB_2U_LIB.S9S_MB_2U(SCH_1):M_D_CPU1_SA_DQ(15)    I25 @S9S_MB_2U_LIB.S9S_MB_2U(SCH_1):PAGE104
    29 M_D_CPU1_SA_DQ<16> @S9S_MB_2U_LIB.S9S_MB_2U(SCH_1):M_D_CPU1_SA_DQ(16)    I25 @S9S_MB_2U_LIB.S9S_MB_2U(SCH_1):PAGE104
    31 M_D_CPU1_SA_DQ<17> @S9S_MB_2U_LIB.S9S_MB_2U(SCH_1):M_D_CPU1_SA_DQ(17)    I25 @S9S_MB_2U_LIB.S9S_MB_2U(SCH_1):PAGE104
   174 M_D_CPU1_SA_DQ<18> @S9S_MB_2U_LIB.S9S_MB_2U(SCH_1):M_D_CPU1_SA_DQ(18)    I25 @S9S_MB_2U_LIB.S9S_MB_2U(SCH_1):PAGE104
   176 M_D_CPU1_SA_DQ<19> @S9S_MB_2U_LIB.S9S_MB_2U(SCH_1):M_D_CPU1_SA_DQ(19)    I25 @S9S_MB_2U_LIB.S9S_MB_2U(SCH_1):PAGE104
    36 M_D_CPU1_SA_DQ<20> @S9S_MB_2U_LIB.S9S_MB_2U(SCH_1):M_D_CPU1_SA_DQ(20)    I25 @S9S_MB_2U_LIB.S9S_MB_2U(SCH_1):PAGE104
    38 M_D_CPU1_SA_DQ<21> @S9S_MB_2U_LIB.S9S_MB_2U(SCH_1):M_D_CPU1_SA_DQ(21)    I25 @S9S_MB_2U_LIB.S9S_MB_2U(SCH_1):PAGE104
   181 M_D_CPU1_SA_DQ<22> @S9S_MB_2U_LIB.S9S_MB_2U(SCH_1):M_D_CPU1_SA_DQ(22)    I25 @S9S_MB_2U_LIB.S9S_MB_2U(SCH_1):PAGE104
   183 M_D_CPU1_SA_DQ<23> @S9S_MB_2U_LIB.S9S_MB_2U(SCH_1):M_D_CPU1_SA_DQ(23)    I25 @S9S_MB_2U_LIB.S9S_MB_2U(SCH_1):PAGE104
    40 M_D_CPU1_SA_DQ<24> @S9S_MB_2U_LIB.S9S_MB_2U(SCH_1):M_D_CPU1_SA_DQ(24)    I25 @S9S_MB_2U_LIB.S9S_MB_2U(SCH_1):PAGE104
    42 M_D_CPU1_SA_DQ<25> @S9S_MB_2U_LIB.S9S_MB_2U(SCH_1):M_D_CPU1_SA_DQ(25)    I25 @S9S_MB_2U_LIB.S9S_MB_2U(SCH_1):PAGE104
   185 M_D_CPU1_SA_DQ<26> @S9S_MB_2U_LIB.S9S_MB_2U(SCH_1):M_D_CPU1_SA_DQ(26)    I25 @S9S_MB_2U_LIB.S9S_MB_2U(SCH_1):PAGE104
   187 M_D_CPU1_SA_DQ<27> @S9S_MB_2U_LIB.S9S_MB_2U(SCH_1):M_D_CPU1_SA_DQ(27)    I25 @S9S_MB_2U_LIB.S9S_MB_2U(SCH_1):PAGE104
    47 M_D_CPU1_SA_DQ<28> @S9S_MB_2U_LIB.S9S_MB_2U(SCH_1):M_D_CPU1_SA_DQ(28)    I25 @S9S_MB_2U_LIB.S9S_MB_2U(SCH_1):PAGE104
    49 M_D_CPU1_SA_DQ<29> @S9S_MB_2U_LIB.S9S_MB_2U(SCH_1):M_D_CPU1_SA_DQ(29)    I25 @S9S_MB_2U_LIB.S9S_MB_2U(SCH_1):PAGE104
   192 M_D_CPU1_SA_DQ<30> @S9S_MB_2U_LIB.S9S_MB_2U(SCH_1):M_D_CPU1_SA_DQ(30)    I25 @S9S_MB_2U_LIB.S9S_MB_2U(SCH_1):PAGE104
   229 M_D_CPU1_SB_CS_N<1> @S9S_MB_2U_LIB.S9S_MB_2U(SCH_1):M_D_CPU1_SB_CS_N(1)    I25 @S9S_MB_2U_LIB.S9S_MB_2U(SCH_1):PAGE104
   209 M_D_CPU1_SA_CS_N<1> @S9S_MB_2U_LIB.S9S_MB_2U(SCH_1):M_D_CPU1_SA_CS_N(1)    I25 @S9S_MB_2U_LIB.S9S_MB_2U(SCH_1):PAGE104
    84 M_D_CPU1_SB_CS_N<0> @S9S_MB_2U_LIB.S9S_MB_2U(SCH_1):M_D_CPU1_SB_CS_N(0)    I25 @S9S_MB_2U_LIB.S9S_MB_2U(SCH_1):PAGE104
    64 M_D_CPU1_SA_CS_N<0> @S9S_MB_2U_LIB.S9S_MB_2U(SCH_1):M_D_CPU1_SA_CS_N(0)    I25 @S9S_MB_2U_LIB.S9S_MB_2U(SCH_1):PAGE104
   217 M_D_CPU1_CLK_DP<0> @S9S_MB_2U_LIB.S9S_MB_2U(SCH_1):M_D_CPU1_CLK_DP(0)    I25 @S9S_MB_2U_LIB.S9S_MB_2U(SCH_1):PAGE104
   218 M_D_CPU1_CLK_DN<0> @S9S_MB_2U_LIB.S9S_MB_2U(SCH_1):M_D_CPU1_CLK_DN(0)    I25 @S9S_MB_2U_LIB.S9S_MB_2U(SCH_1):PAGE104
    96 M_D_CPU1_SB_CB<0> @S9S_MB_2U_LIB.S9S_MB_2U(SCH_1):M_D_CPU1_SB_CB(0)    I25 @S9S_MB_2U_LIB.S9S_MB_2U(SCH_1):PAGE104
    98 M_D_CPU1_SB_CB<1> @S9S_MB_2U_LIB.S9S_MB_2U(SCH_1):M_D_CPU1_SB_CB(1)    I25 @S9S_MB_2U_LIB.S9S_MB_2U(SCH_1):PAGE104
   241 M_D_CPU1_SB_CB<2> @S9S_MB_2U_LIB.S9S_MB_2U(SCH_1):M_D_CPU1_SB_CB(2)    I25 @S9S_MB_2U_LIB.S9S_MB_2U(SCH_1):PAGE104
   243 M_D_CPU1_SB_CB<3> @S9S_MB_2U_LIB.S9S_MB_2U(SCH_1):M_D_CPU1_SB_CB(3)    I25 @S9S_MB_2U_LIB.S9S_MB_2U(SCH_1):PAGE104
    89 M_D_CPU1_SB_CB<4> @S9S_MB_2U_LIB.S9S_MB_2U(SCH_1):M_D_CPU1_SB_CB(4)    I25 @S9S_MB_2U_LIB.S9S_MB_2U(SCH_1):PAGE104
    91 M_D_CPU1_SB_CB<5> @S9S_MB_2U_LIB.S9S_MB_2U(SCH_1):M_D_CPU1_SB_CB(5)    I25 @S9S_MB_2U_LIB.S9S_MB_2U(SCH_1):PAGE104
   234 M_D_CPU1_SB_CB<6> @S9S_MB_2U_LIB.S9S_MB_2U(SCH_1):M_D_CPU1_SB_CB(6)    I25 @S9S_MB_2U_LIB.S9S_MB_2U(SCH_1):PAGE104
    51 M_D_CPU1_SA_CB<0> @S9S_MB_2U_LIB.S9S_MB_2U(SCH_1):M_D_CPU1_SA_CB(0)    I25 @S9S_MB_2U_LIB.S9S_MB_2U(SCH_1):PAGE104
   196 M_D_CPU1_SA_CB<2> @S9S_MB_2U_LIB.S9S_MB_2U(SCH_1):M_D_CPU1_SA_CB(2)    I25 @S9S_MB_2U_LIB.S9S_MB_2U(SCH_1):PAGE104
   198 M_D_CPU1_SA_CB<3> @S9S_MB_2U_LIB.S9S_MB_2U(SCH_1):M_D_CPU1_SA_CB(3)    I25 @S9S_MB_2U_LIB.S9S_MB_2U(SCH_1):PAGE104
    60 M_D_CPU1_SA_CB<5> @S9S_MB_2U_LIB.S9S_MB_2U(SCH_1):M_D_CPU1_SA_CB(5)    I25 @S9S_MB_2U_LIB.S9S_MB_2U(SCH_1):PAGE104
   203 M_D_CPU1_SA_CB<6> @S9S_MB_2U_LIB.S9S_MB_2U(SCH_1):M_D_CPU1_SA_CB(6)    I25 @S9S_MB_2U_LIB.S9S_MB_2U(SCH_1):PAGE104
    82 M_D_CPU1_SB_CA<6> @S9S_MB_2U_LIB.S9S_MB_2U(SCH_1):M_D_CPU1_SB_CA(6)    I25 @S9S_MB_2U_LIB.S9S_MB_2U(SCH_1):PAGE104
    72 M_D_CPU1_SA_CA<6> @S9S_MB_2U_LIB.S9S_MB_2U(SCH_1):M_D_CPU1_SA_CA(6)    I25 @S9S_MB_2U_LIB.S9S_MB_2U(SCH_1):PAGE104
   225 M_D_CPU1_SB_CA<5> @S9S_MB_2U_LIB.S9S_MB_2U(SCH_1):M_D_CPU1_SB_CA(5)    I25 @S9S_MB_2U_LIB.S9S_MB_2U(SCH_1):PAGE104
   215 M_D_CPU1_SA_CA<5> @S9S_MB_2U_LIB.S9S_MB_2U(SCH_1):M_D_CPU1_SA_CA(5)    I25 @S9S_MB_2U_LIB.S9S_MB_2U(SCH_1):PAGE104
    80 M_D_CPU1_SB_CA<4> @S9S_MB_2U_LIB.S9S_MB_2U(SCH_1):M_D_CPU1_SB_CA(4)    I25 @S9S_MB_2U_LIB.S9S_MB_2U(SCH_1):PAGE104
    70 M_D_CPU1_SA_CA<4> @S9S_MB_2U_LIB.S9S_MB_2U(SCH_1):M_D_CPU1_SA_CA(4)    I25 @S9S_MB_2U_LIB.S9S_MB_2U(SCH_1):PAGE104
   223 M_D_CPU1_SB_CA<3> @S9S_MB_2U_LIB.S9S_MB_2U(SCH_1):M_D_CPU1_SB_CA(3)    I25 @S9S_MB_2U_LIB.S9S_MB_2U(SCH_1):PAGE104
   213 M_D_CPU1_SA_CA<3> @S9S_MB_2U_LIB.S9S_MB_2U(SCH_1):M_D_CPU1_SA_CA(3)    I25 @S9S_MB_2U_LIB.S9S_MB_2U(SCH_1):PAGE104
    78 M_D_CPU1_SB_CA<2> @S9S_MB_2U_LIB.S9S_MB_2U(SCH_1):M_D_CPU1_SB_CA(2)    I25 @S9S_MB_2U_LIB.S9S_MB_2U(SCH_1):PAGE104
    68 M_D_CPU1_SA_CA<2> @S9S_MB_2U_LIB.S9S_MB_2U(SCH_1):M_D_CPU1_SA_CA(2)    I25 @S9S_MB_2U_LIB.S9S_MB_2U(SCH_1):PAGE104
   221 M_D_CPU1_SB_CA<1> @S9S_MB_2U_LIB.S9S_MB_2U(SCH_1):M_D_CPU1_SB_CA(1)    I25 @S9S_MB_2U_LIB.S9S_MB_2U(SCH_1):PAGE104
   211 M_D_CPU1_SA_CA<1> @S9S_MB_2U_LIB.S9S_MB_2U(SCH_1):M_D_CPU1_SA_CA(1)    I25 @S9S_MB_2U_LIB.S9S_MB_2U(SCH_1):PAGE104
    76 M_D_CPU1_SB_CA<0> @S9S_MB_2U_LIB.S9S_MB_2U(SCH_1):M_D_CPU1_SB_CA(0)    I25 @S9S_MB_2U_LIB.S9S_MB_2U(SCH_1):PAGE104
    66 M_D_CPU1_SA_CA<0> @S9S_MB_2U_LIB.S9S_MB_2U(SCH_1):M_D_CPU1_SA_CA(0)    I25 @S9S_MB_2U_LIB.S9S_MB_2U(SCH_1):PAGE104
    62 M_D_CPU1_ALERT_N @S9S_MB_2U_LIB.S9S_MB_2U(SCH_1):M_D_CPU1_ALERT_N    I25 @S9S_MB_2U_LIB.S9S_MB_2U(SCH_1):PAGE104
   236 M_D_CPU1_SB_CB<7> @S9S_MB_2U_LIB.S9S_MB_2U(SCH_1):M_D_CPU1_SB_CB(7)    I25 @S9S_MB_2U_LIB.S9S_MB_2U(SCH_1):PAGE104
    53 M_D_CPU1_SA_CB<1> @S9S_MB_2U_LIB.S9S_MB_2U(SCH_1):M_D_CPU1_SA_CB(1)    I25 @S9S_MB_2U_LIB.S9S_MB_2U(SCH_1):PAGE104
    58 M_D_CPU1_SA_CB<4> @S9S_MB_2U_LIB.S9S_MB_2U(SCH_1):M_D_CPU1_SA_CB(4)    I25 @S9S_MB_2U_LIB.S9S_MB_2U(SCH_1):PAGE104
   205 M_D_CPU1_SA_CB<7> @S9S_MB_2U_LIB.S9S_MB_2U(SCH_1):M_D_CPU1_SA_CB(7)    I25 @S9S_MB_2U_LIB.S9S_MB_2U(SCH_1):PAGE104
   194 M_D_CPU1_SA_DQ<31> @S9S_MB_2U_LIB.S9S_MB_2U(SCH_1):M_D_CPU1_SA_DQ(31)    I25 @S9S_MB_2U_LIB.S9S_MB_2U(SCH_1):PAGE104
    93 M_D_CPU1_SB_DQS_DP<9> @S9S_MB_2U_LIB.S9S_MB_2U(SCH_1):M_D_CPU1_SB_DQS_DP(9)   I178 @S9S_MB_2U_LIB.S9S_MB_2U(SCH_1):PAGE104
    94 M_D_CPU1_SB_DQS_DN<9> @S9S_MB_2U_LIB.S9S_MB_2U(SCH_1):M_D_CPU1_SB_DQS_DN(9)   I178 @S9S_MB_2U_LIB.S9S_MB_2U(SCH_1):PAGE104
   201 M_D_CPU1_SA_DQS_DP<9> @S9S_MB_2U_LIB.S9S_MB_2U(SCH_1):M_D_CPU1_SA_DQS_DP(9)   I178 @S9S_MB_2U_LIB.S9S_MB_2U(SCH_1):PAGE104
   200 M_D_CPU1_SA_DQS_DN<9> @S9S_MB_2U_LIB.S9S_MB_2U(SCH_1):M_D_CPU1_SA_DQS_DN(9)   I178 @S9S_MB_2U_LIB.S9S_MB_2U(SCH_1):PAGE104
   190 M_D_CPU1_SA_DQS_DP<8> @S9S_MB_2U_LIB.S9S_MB_2U(SCH_1):M_D_CPU1_SA_DQS_DP(8)   I178 @S9S_MB_2U_LIB.S9S_MB_2U(SCH_1):PAGE104
   189 M_D_CPU1_SA_DQS_DN<8> @S9S_MB_2U_LIB.S9S_MB_2U(SCH_1):M_D_CPU1_SA_DQS_DN(8)   I178 @S9S_MB_2U_LIB.S9S_MB_2U(SCH_1):PAGE104
   271 M_D_CPU1_SB_DQS_DN<7> @S9S_MB_2U_LIB.S9S_MB_2U(SCH_1):M_D_CPU1_SB_DQS_DN(7)   I178 @S9S_MB_2U_LIB.S9S_MB_2U(SCH_1):PAGE104
   179 M_D_CPU1_SA_DQS_DP<7> @S9S_MB_2U_LIB.S9S_MB_2U(SCH_1):M_D_CPU1_SA_DQS_DP(7)   I178 @S9S_MB_2U_LIB.S9S_MB_2U(SCH_1):PAGE104
   261 M_D_CPU1_SB_DQS_DP<6> @S9S_MB_2U_LIB.S9S_MB_2U(SCH_1):M_D_CPU1_SB_DQS_DP(6)   I178 @S9S_MB_2U_LIB.S9S_MB_2U(SCH_1):PAGE104
   260 M_D_CPU1_SB_DQS_DN<6> @S9S_MB_2U_LIB.S9S_MB_2U(SCH_1):M_D_CPU1_SB_DQS_DN(6)   I178 @S9S_MB_2U_LIB.S9S_MB_2U(SCH_1):PAGE104
   167 M_D_CPU1_SA_DQS_DN<6> @S9S_MB_2U_LIB.S9S_MB_2U(SCH_1):M_D_CPU1_SA_DQS_DN(6)   I178 @S9S_MB_2U_LIB.S9S_MB_2U(SCH_1):PAGE104
   250 M_D_CPU1_SB_DQS_DP<5> @S9S_MB_2U_LIB.S9S_MB_2U(SCH_1):M_D_CPU1_SB_DQS_DP(5)   I178 @S9S_MB_2U_LIB.S9S_MB_2U(SCH_1):PAGE104
   249 M_D_CPU1_SB_DQS_DN<5> @S9S_MB_2U_LIB.S9S_MB_2U(SCH_1):M_D_CPU1_SB_DQS_DN(5)   I178 @S9S_MB_2U_LIB.S9S_MB_2U(SCH_1):PAGE104
   157 M_D_CPU1_SA_DQS_DP<5> @S9S_MB_2U_LIB.S9S_MB_2U(SCH_1):M_D_CPU1_SA_DQS_DP(5)   I178 @S9S_MB_2U_LIB.S9S_MB_2U(SCH_1):PAGE104
   156 M_D_CPU1_SA_DQS_DN<5> @S9S_MB_2U_LIB.S9S_MB_2U(SCH_1):M_D_CPU1_SA_DQS_DN(5)   I178 @S9S_MB_2U_LIB.S9S_MB_2U(SCH_1):PAGE104
   239 M_D_CPU1_SB_DQS_DP<4> @S9S_MB_2U_LIB.S9S_MB_2U(SCH_1):M_D_CPU1_SB_DQS_DP(4)   I178 @S9S_MB_2U_LIB.S9S_MB_2U(SCH_1):PAGE104
   238 M_D_CPU1_SB_DQS_DN<4> @S9S_MB_2U_LIB.S9S_MB_2U(SCH_1):M_D_CPU1_SB_DQS_DN(4)   I178 @S9S_MB_2U_LIB.S9S_MB_2U(SCH_1):PAGE104
    55 M_D_CPU1_SA_DQS_DP<4> @S9S_MB_2U_LIB.S9S_MB_2U(SCH_1):M_D_CPU1_SA_DQS_DP(4)   I178 @S9S_MB_2U_LIB.S9S_MB_2U(SCH_1):PAGE104
    56 M_D_CPU1_SA_DQS_DN<4> @S9S_MB_2U_LIB.S9S_MB_2U(SCH_1):M_D_CPU1_SA_DQS_DN(4)   I178 @S9S_MB_2U_LIB.S9S_MB_2U(SCH_1):PAGE104
   137 M_D_CPU1_SB_DQS_DP<3> @S9S_MB_2U_LIB.S9S_MB_2U(SCH_1):M_D_CPU1_SB_DQS_DP(3)   I178 @S9S_MB_2U_LIB.S9S_MB_2U(SCH_1):PAGE104
   138 M_D_CPU1_SB_DQS_DN<3> @S9S_MB_2U_LIB.S9S_MB_2U(SCH_1):M_D_CPU1_SB_DQS_DN(3)   I178 @S9S_MB_2U_LIB.S9S_MB_2U(SCH_1):PAGE104
    44 M_D_CPU1_SA_DQS_DP<3> @S9S_MB_2U_LIB.S9S_MB_2U(SCH_1):M_D_CPU1_SA_DQS_DP(3)   I178 @S9S_MB_2U_LIB.S9S_MB_2U(SCH_1):PAGE104
    45 M_D_CPU1_SA_DQS_DN<3> @S9S_MB_2U_LIB.S9S_MB_2U(SCH_1):M_D_CPU1_SA_DQS_DN(3)   I178 @S9S_MB_2U_LIB.S9S_MB_2U(SCH_1):PAGE104
   126 M_D_CPU1_SB_DQS_DP<2> @S9S_MB_2U_LIB.S9S_MB_2U(SCH_1):M_D_CPU1_SB_DQS_DP(2)   I178 @S9S_MB_2U_LIB.S9S_MB_2U(SCH_1):PAGE104
   127 M_D_CPU1_SB_DQS_DN<2> @S9S_MB_2U_LIB.S9S_MB_2U(SCH_1):M_D_CPU1_SB_DQS_DN(2)   I178 @S9S_MB_2U_LIB.S9S_MB_2U(SCH_1):PAGE104
    33 M_D_CPU1_SA_DQS_DP<2> @S9S_MB_2U_LIB.S9S_MB_2U(SCH_1):M_D_CPU1_SA_DQS_DP(2)   I178 @S9S_MB_2U_LIB.S9S_MB_2U(SCH_1):PAGE104
    34 M_D_CPU1_SA_DQS_DN<2> @S9S_MB_2U_LIB.S9S_MB_2U(SCH_1):M_D_CPU1_SA_DQS_DN(2)   I178 @S9S_MB_2U_LIB.S9S_MB_2U(SCH_1):PAGE104
   115 M_D_CPU1_SB_DQS_DP<1> @S9S_MB_2U_LIB.S9S_MB_2U(SCH_1):M_D_CPU1_SB_DQS_DP(1)   I178 @S9S_MB_2U_LIB.S9S_MB_2U(SCH_1):PAGE104
   116 M_D_CPU1_SB_DQS_DN<1> @S9S_MB_2U_LIB.S9S_MB_2U(SCH_1):M_D_CPU1_SB_DQS_DN(1)   I178 @S9S_MB_2U_LIB.S9S_MB_2U(SCH_1):PAGE104
    22 M_D_CPU1_SA_DQS_DP<1> @S9S_MB_2U_LIB.S9S_MB_2U(SCH_1):M_D_CPU1_SA_DQS_DP(1)   I178 @S9S_MB_2U_LIB.S9S_MB_2U(SCH_1):PAGE104
    23 M_D_CPU1_SA_DQS_DN<1> @S9S_MB_2U_LIB.S9S_MB_2U(SCH_1):M_D_CPU1_SA_DQS_DN(1)   I178 @S9S_MB_2U_LIB.S9S_MB_2U(SCH_1):PAGE104
   104 M_D_CPU1_SB_DQS_DP<0> @S9S_MB_2U_LIB.S9S_MB_2U(SCH_1):M_D_CPU1_SB_DQS_DP(0)   I178 @S9S_MB_2U_LIB.S9S_MB_2U(SCH_1):PAGE104
   105 M_D_CPU1_SB_DQS_DN<0> @S9S_MB_2U_LIB.S9S_MB_2U(SCH_1):M_D_CPU1_SB_DQS_DN(0)   I178 @S9S_MB_2U_LIB.S9S_MB_2U(SCH_1):PAGE104
    11 M_D_CPU1_SA_DQS_DP<0> @S9S_MB_2U_LIB.S9S_MB_2U(SCH_1):M_D_CPU1_SA_DQS_DP(0)   I178 @S9S_MB_2U_LIB.S9S_MB_2U(SCH_1):PAGE104
    12 M_D_CPU1_SA_DQS_DN<0> @S9S_MB_2U_LIB.S9S_MB_2U(SCH_1):M_D_CPU1_SA_DQS_DN(0)   I178 @S9S_MB_2U_LIB.S9S_MB_2U(SCH_1):PAGE104
   272 M_D_CPU1_SB_DQS_DP<7> @S9S_MB_2U_LIB.S9S_MB_2U(SCH_1):M_D_CPU1_SB_DQS_DP(7)   I178 @S9S_MB_2U_LIB.S9S_MB_2U(SCH_1):PAGE104
   282 M_D_CPU1_SB_DQS_DN<8> @S9S_MB_2U_LIB.S9S_MB_2U(SCH_1):M_D_CPU1_SB_DQS_DN(8)   I178 @S9S_MB_2U_LIB.S9S_MB_2U(SCH_1):PAGE104
   283 M_D_CPU1_SB_DQS_DP<8> @S9S_MB_2U_LIB.S9S_MB_2U(SCH_1):M_D_CPU1_SB_DQS_DP(8)   I178 @S9S_MB_2U_LIB.S9S_MB_2U(SCH_1):PAGE104
   168 M_D_CPU1_SA_DQS_DP<6> @S9S_MB_2U_LIB.S9S_MB_2U(SCH_1):M_D_CPU1_SA_DQS_DP(6)   I178 @S9S_MB_2U_LIB.S9S_MB_2U(SCH_1):PAGE104
   178 M_D_CPU1_SA_DQS_DN<7> @S9S_MB_2U_LIB.S9S_MB_2U(SCH_1):M_D_CPU1_SA_DQS_DN(7)   I178 @S9S_MB_2U_LIB.S9S_MB_2U(SCH_1):PAGE104
     6    GND @S9S_MB_2U_LIB.S9S_MB_2U(SCH_1):GND   I175 @S9S_MB_2U_LIB.S9S_MB_2U(SCH_1):PAGE104
     8    GND @S9S_MB_2U_LIB.S9S_MB_2U(SCH_1):GND   I175 @S9S_MB_2U_LIB.S9S_MB_2U(SCH_1):PAGE104
    10    GND @S9S_MB_2U_LIB.S9S_MB_2U(SCH_1):GND   I175 @S9S_MB_2U_LIB.S9S_MB_2U(SCH_1):PAGE104
    13    GND @S9S_MB_2U_LIB.S9S_MB_2U(SCH_1):GND   I175 @S9S_MB_2U_LIB.S9S_MB_2U(SCH_1):PAGE104
    15    GND @S9S_MB_2U_LIB.S9S_MB_2U(SCH_1):GND   I175 @S9S_MB_2U_LIB.S9S_MB_2U(SCH_1):PAGE104
    17    GND @S9S_MB_2U_LIB.S9S_MB_2U(SCH_1):GND   I175 @S9S_MB_2U_LIB.S9S_MB_2U(SCH_1):PAGE104
    19    GND @S9S_MB_2U_LIB.S9S_MB_2U(SCH_1):GND   I175 @S9S_MB_2U_LIB.S9S_MB_2U(SCH_1):PAGE104
    21    GND @S9S_MB_2U_LIB.S9S_MB_2U(SCH_1):GND   I175 @S9S_MB_2U_LIB.S9S_MB_2U(SCH_1):PAGE104
    24    GND @S9S_MB_2U_LIB.S9S_MB_2U(SCH_1):GND   I175 @S9S_MB_2U_LIB.S9S_MB_2U(SCH_1):PAGE104
    26    GND @S9S_MB_2U_LIB.S9S_MB_2U(SCH_1):GND   I175 @S9S_MB_2U_LIB.S9S_MB_2U(SCH_1):PAGE104
    28    GND @S9S_MB_2U_LIB.S9S_MB_2U(SCH_1):GND   I175 @S9S_MB_2U_LIB.S9S_MB_2U(SCH_1):PAGE104
    30    GND @S9S_MB_2U_LIB.S9S_MB_2U(SCH_1):GND   I175 @S9S_MB_2U_LIB.S9S_MB_2U(SCH_1):PAGE104
    32    GND @S9S_MB_2U_LIB.S9S_MB_2U(SCH_1):GND   I175 @S9S_MB_2U_LIB.S9S_MB_2U(SCH_1):PAGE104
    35    GND @S9S_MB_2U_LIB.S9S_MB_2U(SCH_1):GND   I175 @S9S_MB_2U_LIB.S9S_MB_2U(SCH_1):PAGE104
    37    GND @S9S_MB_2U_LIB.S9S_MB_2U(SCH_1):GND   I175 @S9S_MB_2U_LIB.S9S_MB_2U(SCH_1):PAGE104
    39    GND @S9S_MB_2U_LIB.S9S_MB_2U(SCH_1):GND   I175 @S9S_MB_2U_LIB.S9S_MB_2U(SCH_1):PAGE104
    41    GND @S9S_MB_2U_LIB.S9S_MB_2U(SCH_1):GND   I175 @S9S_MB_2U_LIB.S9S_MB_2U(SCH_1):PAGE104
    43    GND @S9S_MB_2U_LIB.S9S_MB_2U(SCH_1):GND   I175 @S9S_MB_2U_LIB.S9S_MB_2U(SCH_1):PAGE104
    46    GND @S9S_MB_2U_LIB.S9S_MB_2U(SCH_1):GND   I175 @S9S_MB_2U_LIB.S9S_MB_2U(SCH_1):PAGE104
    48    GND @S9S_MB_2U_LIB.S9S_MB_2U(SCH_1):GND   I175 @S9S_MB_2U_LIB.S9S_MB_2U(SCH_1):PAGE104
    50    GND @S9S_MB_2U_LIB.S9S_MB_2U(SCH_1):GND   I175 @S9S_MB_2U_LIB.S9S_MB_2U(SCH_1):PAGE104
    52    GND @S9S_MB_2U_LIB.S9S_MB_2U(SCH_1):GND   I175 @S9S_MB_2U_LIB.S9S_MB_2U(SCH_1):PAGE104
    54    GND @S9S_MB_2U_LIB.S9S_MB_2U(SCH_1):GND   I175 @S9S_MB_2U_LIB.S9S_MB_2U(SCH_1):PAGE104
    57    GND @S9S_MB_2U_LIB.S9S_MB_2U(SCH_1):GND   I175 @S9S_MB_2U_LIB.S9S_MB_2U(SCH_1):PAGE104
    59    GND @S9S_MB_2U_LIB.S9S_MB_2U(SCH_1):GND   I175 @S9S_MB_2U_LIB.S9S_MB_2U(SCH_1):PAGE104
    61    GND @S9S_MB_2U_LIB.S9S_MB_2U(SCH_1):GND   I175 @S9S_MB_2U_LIB.S9S_MB_2U(SCH_1):PAGE104
    63    GND @S9S_MB_2U_LIB.S9S_MB_2U(SCH_1):GND   I175 @S9S_MB_2U_LIB.S9S_MB_2U(SCH_1):PAGE104
    65    GND @S9S_MB_2U_LIB.S9S_MB_2U(SCH_1):GND   I175 @S9S_MB_2U_LIB.S9S_MB_2U(SCH_1):PAGE104
    67    GND @S9S_MB_2U_LIB.S9S_MB_2U(SCH_1):GND   I175 @S9S_MB_2U_LIB.S9S_MB_2U(SCH_1):PAGE104
    69    GND @S9S_MB_2U_LIB.S9S_MB_2U(SCH_1):GND   I175 @S9S_MB_2U_LIB.S9S_MB_2U(SCH_1):PAGE104
    71    GND @S9S_MB_2U_LIB.S9S_MB_2U(SCH_1):GND   I175 @S9S_MB_2U_LIB.S9S_MB_2U(SCH_1):PAGE104
    73    GND @S9S_MB_2U_LIB.S9S_MB_2U(SCH_1):GND   I175 @S9S_MB_2U_LIB.S9S_MB_2U(SCH_1):PAGE104
    75    GND @S9S_MB_2U_LIB.S9S_MB_2U(SCH_1):GND   I175 @S9S_MB_2U_LIB.S9S_MB_2U(SCH_1):PAGE104
    77    GND @S9S_MB_2U_LIB.S9S_MB_2U(SCH_1):GND   I175 @S9S_MB_2U_LIB.S9S_MB_2U(SCH_1):PAGE104
    79    GND @S9S_MB_2U_LIB.S9S_MB_2U(SCH_1):GND   I175 @S9S_MB_2U_LIB.S9S_MB_2U(SCH_1):PAGE104
    81    GND @S9S_MB_2U_LIB.S9S_MB_2U(SCH_1):GND   I175 @S9S_MB_2U_LIB.S9S_MB_2U(SCH_1):PAGE104
    83    GND @S9S_MB_2U_LIB.S9S_MB_2U(SCH_1):GND   I175 @S9S_MB_2U_LIB.S9S_MB_2U(SCH_1):PAGE104
    85    GND @S9S_MB_2U_LIB.S9S_MB_2U(SCH_1):GND   I175 @S9S_MB_2U_LIB.S9S_MB_2U(SCH_1):PAGE104
    88    GND @S9S_MB_2U_LIB.S9S_MB_2U(SCH_1):GND   I175 @S9S_MB_2U_LIB.S9S_MB_2U(SCH_1):PAGE104
    90    GND @S9S_MB_2U_LIB.S9S_MB_2U(SCH_1):GND   I175 @S9S_MB_2U_LIB.S9S_MB_2U(SCH_1):PAGE104
    92    GND @S9S_MB_2U_LIB.S9S_MB_2U(SCH_1):GND   I175 @S9S_MB_2U_LIB.S9S_MB_2U(SCH_1):PAGE104
    95    GND @S9S_MB_2U_LIB.S9S_MB_2U(SCH_1):GND   I175 @S9S_MB_2U_LIB.S9S_MB_2U(SCH_1):PAGE104
    97    GND @S9S_MB_2U_LIB.S9S_MB_2U(SCH_1):GND   I175 @S9S_MB_2U_LIB.S9S_MB_2U(SCH_1):PAGE104
    99    GND @S9S_MB_2U_LIB.S9S_MB_2U(SCH_1):GND   I175 @S9S_MB_2U_LIB.S9S_MB_2U(SCH_1):PAGE104
   101    GND @S9S_MB_2U_LIB.S9S_MB_2U(SCH_1):GND   I175 @S9S_MB_2U_LIB.S9S_MB_2U(SCH_1):PAGE104
   103    GND @S9S_MB_2U_LIB.S9S_MB_2U(SCH_1):GND   I175 @S9S_MB_2U_LIB.S9S_MB_2U(SCH_1):PAGE104
   106    GND @S9S_MB_2U_LIB.S9S_MB_2U(SCH_1):GND   I175 @S9S_MB_2U_LIB.S9S_MB_2U(SCH_1):PAGE104
   108    GND @S9S_MB_2U_LIB.S9S_MB_2U(SCH_1):GND   I175 @S9S_MB_2U_LIB.S9S_MB_2U(SCH_1):PAGE104
   110    GND @S9S_MB_2U_LIB.S9S_MB_2U(SCH_1):GND   I175 @S9S_MB_2U_LIB.S9S_MB_2U(SCH_1):PAGE104
   112    GND @S9S_MB_2U_LIB.S9S_MB_2U(SCH_1):GND   I175 @S9S_MB_2U_LIB.S9S_MB_2U(SCH_1):PAGE104
   114    GND @S9S_MB_2U_LIB.S9S_MB_2U(SCH_1):GND   I175 @S9S_MB_2U_LIB.S9S_MB_2U(SCH_1):PAGE104
   117    GND @S9S_MB_2U_LIB.S9S_MB_2U(SCH_1):GND   I175 @S9S_MB_2U_LIB.S9S_MB_2U(SCH_1):PAGE104
   119    GND @S9S_MB_2U_LIB.S9S_MB_2U(SCH_1):GND   I175 @S9S_MB_2U_LIB.S9S_MB_2U(SCH_1):PAGE104
   121    GND @S9S_MB_2U_LIB.S9S_MB_2U(SCH_1):GND   I175 @S9S_MB_2U_LIB.S9S_MB_2U(SCH_1):PAGE104
   123    GND @S9S_MB_2U_LIB.S9S_MB_2U(SCH_1):GND   I175 @S9S_MB_2U_LIB.S9S_MB_2U(SCH_1):PAGE104
   125    GND @S9S_MB_2U_LIB.S9S_MB_2U(SCH_1):GND   I175 @S9S_MB_2U_LIB.S9S_MB_2U(SCH_1):PAGE104
   128    GND @S9S_MB_2U_LIB.S9S_MB_2U(SCH_1):GND   I175 @S9S_MB_2U_LIB.S9S_MB_2U(SCH_1):PAGE104
   130    GND @S9S_MB_2U_LIB.S9S_MB_2U(SCH_1):GND   I175 @S9S_MB_2U_LIB.S9S_MB_2U(SCH_1):PAGE104
   134    GND @S9S_MB_2U_LIB.S9S_MB_2U(SCH_1):GND   I175 @S9S_MB_2U_LIB.S9S_MB_2U(SCH_1):PAGE104
   143    GND @S9S_MB_2U_LIB.S9S_MB_2U(SCH_1):GND   I175 @S9S_MB_2U_LIB.S9S_MB_2U(SCH_1):PAGE104
   151    GND @S9S_MB_2U_LIB.S9S_MB_2U(SCH_1):GND   I175 @S9S_MB_2U_LIB.S9S_MB_2U(SCH_1):PAGE104
   153    GND @S9S_MB_2U_LIB.S9S_MB_2U(SCH_1):GND   I175 @S9S_MB_2U_LIB.S9S_MB_2U(SCH_1):PAGE104
   155    GND @S9S_MB_2U_LIB.S9S_MB_2U(SCH_1):GND   I175 @S9S_MB_2U_LIB.S9S_MB_2U(SCH_1):PAGE104
   158    GND @S9S_MB_2U_LIB.S9S_MB_2U(SCH_1):GND   I175 @S9S_MB_2U_LIB.S9S_MB_2U(SCH_1):PAGE104
   160    GND @S9S_MB_2U_LIB.S9S_MB_2U(SCH_1):GND   I175 @S9S_MB_2U_LIB.S9S_MB_2U(SCH_1):PAGE104
   162    GND @S9S_MB_2U_LIB.S9S_MB_2U(SCH_1):GND   I175 @S9S_MB_2U_LIB.S9S_MB_2U(SCH_1):PAGE104
   164    GND @S9S_MB_2U_LIB.S9S_MB_2U(SCH_1):GND   I175 @S9S_MB_2U_LIB.S9S_MB_2U(SCH_1):PAGE104
   166    GND @S9S_MB_2U_LIB.S9S_MB_2U(SCH_1):GND   I175 @S9S_MB_2U_LIB.S9S_MB_2U(SCH_1):PAGE104
   169    GND @S9S_MB_2U_LIB.S9S_MB_2U(SCH_1):GND   I175 @S9S_MB_2U_LIB.S9S_MB_2U(SCH_1):PAGE104
   171    GND @S9S_MB_2U_LIB.S9S_MB_2U(SCH_1):GND   I175 @S9S_MB_2U_LIB.S9S_MB_2U(SCH_1):PAGE104
   173    GND @S9S_MB_2U_LIB.S9S_MB_2U(SCH_1):GND   I175 @S9S_MB_2U_LIB.S9S_MB_2U(SCH_1):PAGE104
   175    GND @S9S_MB_2U_LIB.S9S_MB_2U(SCH_1):GND   I175 @S9S_MB_2U_LIB.S9S_MB_2U(SCH_1):PAGE104
   177    GND @S9S_MB_2U_LIB.S9S_MB_2U(SCH_1):GND   I175 @S9S_MB_2U_LIB.S9S_MB_2U(SCH_1):PAGE104
   180    GND @S9S_MB_2U_LIB.S9S_MB_2U(SCH_1):GND   I175 @S9S_MB_2U_LIB.S9S_MB_2U(SCH_1):PAGE104
   182    GND @S9S_MB_2U_LIB.S9S_MB_2U(SCH_1):GND   I175 @S9S_MB_2U_LIB.S9S_MB_2U(SCH_1):PAGE104
   184    GND @S9S_MB_2U_LIB.S9S_MB_2U(SCH_1):GND   I175 @S9S_MB_2U_LIB.S9S_MB_2U(SCH_1):PAGE104
   186    GND @S9S_MB_2U_LIB.S9S_MB_2U(SCH_1):GND   I175 @S9S_MB_2U_LIB.S9S_MB_2U(SCH_1):PAGE104
   188    GND @S9S_MB_2U_LIB.S9S_MB_2U(SCH_1):GND   I175 @S9S_MB_2U_LIB.S9S_MB_2U(SCH_1):PAGE104
   191    GND @S9S_MB_2U_LIB.S9S_MB_2U(SCH_1):GND   I175 @S9S_MB_2U_LIB.S9S_MB_2U(SCH_1):PAGE104
   193    GND @S9S_MB_2U_LIB.S9S_MB_2U(SCH_1):GND   I175 @S9S_MB_2U_LIB.S9S_MB_2U(SCH_1):PAGE104
   195    GND @S9S_MB_2U_LIB.S9S_MB_2U(SCH_1):GND   I175 @S9S_MB_2U_LIB.S9S_MB_2U(SCH_1):PAGE104
   197    GND @S9S_MB_2U_LIB.S9S_MB_2U(SCH_1):GND   I175 @S9S_MB_2U_LIB.S9S_MB_2U(SCH_1):PAGE104
   199    GND @S9S_MB_2U_LIB.S9S_MB_2U(SCH_1):GND   I175 @S9S_MB_2U_LIB.S9S_MB_2U(SCH_1):PAGE104
   202    GND @S9S_MB_2U_LIB.S9S_MB_2U(SCH_1):GND   I175 @S9S_MB_2U_LIB.S9S_MB_2U(SCH_1):PAGE104
   204    GND @S9S_MB_2U_LIB.S9S_MB_2U(SCH_1):GND   I175 @S9S_MB_2U_LIB.S9S_MB_2U(SCH_1):PAGE104
   206    GND @S9S_MB_2U_LIB.S9S_MB_2U(SCH_1):GND   I175 @S9S_MB_2U_LIB.S9S_MB_2U(SCH_1):PAGE104
   208    GND @S9S_MB_2U_LIB.S9S_MB_2U(SCH_1):GND   I175 @S9S_MB_2U_LIB.S9S_MB_2U(SCH_1):PAGE104
   210    GND @S9S_MB_2U_LIB.S9S_MB_2U(SCH_1):GND   I175 @S9S_MB_2U_LIB.S9S_MB_2U(SCH_1):PAGE104
   212    GND @S9S_MB_2U_LIB.S9S_MB_2U(SCH_1):GND   I175 @S9S_MB_2U_LIB.S9S_MB_2U(SCH_1):PAGE104
   214    GND @S9S_MB_2U_LIB.S9S_MB_2U(SCH_1):GND   I175 @S9S_MB_2U_LIB.S9S_MB_2U(SCH_1):PAGE104
   216    GND @S9S_MB_2U_LIB.S9S_MB_2U(SCH_1):GND   I175 @S9S_MB_2U_LIB.S9S_MB_2U(SCH_1):PAGE104
   219    GND @S9S_MB_2U_LIB.S9S_MB_2U(SCH_1):GND   I175 @S9S_MB_2U_LIB.S9S_MB_2U(SCH_1):PAGE104
   222    GND @S9S_MB_2U_LIB.S9S_MB_2U(SCH_1):GND   I175 @S9S_MB_2U_LIB.S9S_MB_2U(SCH_1):PAGE104
   224    GND @S9S_MB_2U_LIB.S9S_MB_2U(SCH_1):GND   I175 @S9S_MB_2U_LIB.S9S_MB_2U(SCH_1):PAGE104
   226    GND @S9S_MB_2U_LIB.S9S_MB_2U(SCH_1):GND   I175 @S9S_MB_2U_LIB.S9S_MB_2U(SCH_1):PAGE104
   228    GND @S9S_MB_2U_LIB.S9S_MB_2U(SCH_1):GND   I175 @S9S_MB_2U_LIB.S9S_MB_2U(SCH_1):PAGE104
   233    GND @S9S_MB_2U_LIB.S9S_MB_2U(SCH_1):GND   I175 @S9S_MB_2U_LIB.S9S_MB_2U(SCH_1):PAGE104
   237    GND @S9S_MB_2U_LIB.S9S_MB_2U(SCH_1):GND   I175 @S9S_MB_2U_LIB.S9S_MB_2U(SCH_1):PAGE104
   242    GND @S9S_MB_2U_LIB.S9S_MB_2U(SCH_1):GND   I175 @S9S_MB_2U_LIB.S9S_MB_2U(SCH_1):PAGE104
   244    GND @S9S_MB_2U_LIB.S9S_MB_2U(SCH_1):GND   I175 @S9S_MB_2U_LIB.S9S_MB_2U(SCH_1):PAGE104
   246    GND @S9S_MB_2U_LIB.S9S_MB_2U(SCH_1):GND   I175 @S9S_MB_2U_LIB.S9S_MB_2U(SCH_1):PAGE104
   248    GND @S9S_MB_2U_LIB.S9S_MB_2U(SCH_1):GND   I175 @S9S_MB_2U_LIB.S9S_MB_2U(SCH_1):PAGE104
   251    GND @S9S_MB_2U_LIB.S9S_MB_2U(SCH_1):GND   I175 @S9S_MB_2U_LIB.S9S_MB_2U(SCH_1):PAGE104
   253    GND @S9S_MB_2U_LIB.S9S_MB_2U(SCH_1):GND   I175 @S9S_MB_2U_LIB.S9S_MB_2U(SCH_1):PAGE104
   255    GND @S9S_MB_2U_LIB.S9S_MB_2U(SCH_1):GND   I175 @S9S_MB_2U_LIB.S9S_MB_2U(SCH_1):PAGE104
   257    GND @S9S_MB_2U_LIB.S9S_MB_2U(SCH_1):GND   I175 @S9S_MB_2U_LIB.S9S_MB_2U(SCH_1):PAGE104
   259    GND @S9S_MB_2U_LIB.S9S_MB_2U(SCH_1):GND   I175 @S9S_MB_2U_LIB.S9S_MB_2U(SCH_1):PAGE104
   262    GND @S9S_MB_2U_LIB.S9S_MB_2U(SCH_1):GND   I175 @S9S_MB_2U_LIB.S9S_MB_2U(SCH_1):PAGE104
   264    GND @S9S_MB_2U_LIB.S9S_MB_2U(SCH_1):GND   I175 @S9S_MB_2U_LIB.S9S_MB_2U(SCH_1):PAGE104
   266    GND @S9S_MB_2U_LIB.S9S_MB_2U(SCH_1):GND   I175 @S9S_MB_2U_LIB.S9S_MB_2U(SCH_1):PAGE104
   268    GND @S9S_MB_2U_LIB.S9S_MB_2U(SCH_1):GND   I175 @S9S_MB_2U_LIB.S9S_MB_2U(SCH_1):PAGE104
   270    GND @S9S_MB_2U_LIB.S9S_MB_2U(SCH_1):GND   I175 @S9S_MB_2U_LIB.S9S_MB_2U(SCH_1):PAGE104
   273    GND @S9S_MB_2U_LIB.S9S_MB_2U(SCH_1):GND   I175 @S9S_MB_2U_LIB.S9S_MB_2U(SCH_1):PAGE104
   275    GND @S9S_MB_2U_LIB.S9S_MB_2U(SCH_1):GND   I175 @S9S_MB_2U_LIB.S9S_MB_2U(SCH_1):PAGE104
   277    GND @S9S_MB_2U_LIB.S9S_MB_2U(SCH_1):GND   I175 @S9S_MB_2U_LIB.S9S_MB_2U(SCH_1):PAGE104
   279    GND @S9S_MB_2U_LIB.S9S_MB_2U(SCH_1):GND   I175 @S9S_MB_2U_LIB.S9S_MB_2U(SCH_1):PAGE104
   281    GND @S9S_MB_2U_LIB.S9S_MB_2U(SCH_1):GND   I175 @S9S_MB_2U_LIB.S9S_MB_2U(SCH_1):PAGE104
   284    GND @S9S_MB_2U_LIB.S9S_MB_2U(SCH_1):GND   I175 @S9S_MB_2U_LIB.S9S_MB_2U(SCH_1):PAGE104
   286    GND @S9S_MB_2U_LIB.S9S_MB_2U(SCH_1):GND   I175 @S9S_MB_2U_LIB.S9S_MB_2U(SCH_1):PAGE104
   288    GND @S9S_MB_2U_LIB.S9S_MB_2U(SCH_1):GND   I175 @S9S_MB_2U_LIB.S9S_MB_2U(SCH_1):PAGE104
     1 P12V_S3_AUX_CPU1_NVDIMM @S9S_MB_2U_LIB.S9S_MB_2U(SCH_1):P12V_S3_AUX_CPU1_NVDIMM   I175 @S9S_MB_2U_LIB.S9S_MB_2U(SCH_1):PAGE104
   145 P12V_S3_AUX_CPU1_NVDIMM @S9S_MB_2U_LIB.S9S_MB_2U(SCH_1):P12V_S3_AUX_CPU1_NVDIMM   I175 @S9S_MB_2U_LIB.S9S_MB_2U(SCH_1):PAGE104
   146 P12V_S3_AUX_CPU1_NVDIMM @S9S_MB_2U_LIB.S9S_MB_2U(SCH_1):P12V_S3_AUX_CPU1_NVDIMM   I175 @S9S_MB_2U_LIB.S9S_MB_2U(SCH_1):PAGE104
   230    GND @S9S_MB_2U_LIB.S9S_MB_2U(SCH_1):GND   I175 @S9S_MB_2U_LIB.S9S_MB_2U(SCH_1):PAGE104
   235    GND @S9S_MB_2U_LIB.S9S_MB_2U(SCH_1):GND   I175 @S9S_MB_2U_LIB.S9S_MB_2U(SCH_1):PAGE104
   240    GND @S9S_MB_2U_LIB.S9S_MB_2U(SCH_1):GND   I175 @S9S_MB_2U_LIB.S9S_MB_2U(SCH_1):PAGE104
   132    GND @S9S_MB_2U_LIB.S9S_MB_2U(SCH_1):GND   I175 @S9S_MB_2U_LIB.S9S_MB_2U(SCH_1):PAGE104
   136    GND @S9S_MB_2U_LIB.S9S_MB_2U(SCH_1):GND   I175 @S9S_MB_2U_LIB.S9S_MB_2U(SCH_1):PAGE104
   139    GND @S9S_MB_2U_LIB.S9S_MB_2U(SCH_1):GND   I175 @S9S_MB_2U_LIB.S9S_MB_2U(SCH_1):PAGE104
   141    GND @S9S_MB_2U_LIB.S9S_MB_2U(SCH_1):GND   I175 @S9S_MB_2U_LIB.S9S_MB_2U(SCH_1):PAGE104
    G1    GND @S9S_MB_2U_LIB.S9S_MB_2U(SCH_1):GND   I175 @S9S_MB_2U_LIB.S9S_MB_2U(SCH_1):PAGE104
    G2    GND @S9S_MB_2U_LIB.S9S_MB_2U(SCH_1):GND   I175 @S9S_MB_2U_LIB.S9S_MB_2U(SCH_1):PAGE104
    G3    GND @S9S_MB_2U_LIB.S9S_MB_2U(SCH_1):GND   I175 @S9S_MB_2U_LIB.S9S_MB_2U(SCH_1):PAGE104

 J24 SCONN288_ADR50017P087CC-SCONN2A
     3 P3V3_AUX @S9S_MB_2U_LIB.S9S_MB_2U(SCH_1):P3V3_AUX   I178 @S9S_MB_2U_LIB.S9S_MB_2U(SCH_1):PAGE105
     2 TP_CHD_CPU1_DIMM2_FRU_0 @S9S_MB_2U_LIB.S9S_MB_2U(SCH_1):TP_CHD_CPU1_DIMM2_FRU_0   I178 @S9S_MB_2U_LIB.S9S_MB_2U(SCH_1):PAGE105
   144 TP_CHD_CPU1_DIMM2_FRU_1 @S9S_MB_2U_LIB.S9S_MB_2U(SCH_1):TP_CHD_CPU1_DIMM2_FRU_1   I178 @S9S_MB_2U_LIB.S9S_MB_2U(SCH_1):PAGE105
   149 TP_CHD_CPU1_DIMM2_FRU_2 @S9S_MB_2U_LIB.S9S_MB_2U(SCH_1):TP_CHD_CPU1_DIMM2_FRU_2   I178 @S9S_MB_2U_LIB.S9S_MB_2U(SCH_1):PAGE105
   150 TP_CHD_CPU1_DIMM2_FRU_3 @S9S_MB_2U_LIB.S9S_MB_2U(SCH_1):TP_CHD_CPU1_DIMM2_FRU_3   I178 @S9S_MB_2U_LIB.S9S_MB_2U(SCH_1):PAGE105
   220 TP_CHD_CPU1_DIMM2_FRU_4 @S9S_MB_2U_LIB.S9S_MB_2U(SCH_1):TP_CHD_CPU1_DIMM2_FRU_4   I178 @S9S_MB_2U_LIB.S9S_MB_2U(SCH_1):PAGE105
   231 TP_CHD_CPU1_DIMM2_FRU_5 @S9S_MB_2U_LIB.S9S_MB_2U(SCH_1):TP_CHD_CPU1_DIMM2_FRU_5   I178 @S9S_MB_2U_LIB.S9S_MB_2U(SCH_1):PAGE105
   232 TP_CHD_CPU1_DIMM2_FRU_6 @S9S_MB_2U_LIB.S9S_MB_2U(SCH_1):TP_CHD_CPU1_DIMM2_FRU_6   I178 @S9S_MB_2U_LIB.S9S_MB_2U(SCH_1):PAGE105
   207 RST_M_CD_CPU1_FPGA_N @S9S_MB_2U_LIB.S9S_MB_2U(SCH_1):RST_M_CD_CPU1_FPGA_N   I178 @S9S_MB_2U_LIB.S9S_MB_2U(SCH_1):PAGE105
   147 PWRGD_CHD_CPU1_DIMM2 @S9S_MB_2U_LIB.S9S_MB_2U(SCH_1):PWRGD_CHD_CPU1_DIMM2   I178 @S9S_MB_2U_LIB.S9S_MB_2U(SCH_1):PAGE105
   227 M_D_CPU1_SB_PAR @S9S_MB_2U_LIB.S9S_MB_2U(SCH_1):M_D_CPU1_SB_PAR   I178 @S9S_MB_2U_LIB.S9S_MB_2U(SCH_1):PAGE105
    74 M_D_CPU1_SA_PAR @S9S_MB_2U_LIB.S9S_MB_2U(SCH_1):M_D_CPU1_SA_PAR   I178 @S9S_MB_2U_LIB.S9S_MB_2U(SCH_1):PAGE105
    87 M_D_CPU1_SB_RSP<1> @S9S_MB_2U_LIB.S9S_MB_2U(SCH_1):M_D_CPU1_SB_RSP(1)   I178 @S9S_MB_2U_LIB.S9S_MB_2U(SCH_1):PAGE105
    86 M_D_CPU1_SA_RSP<1> @S9S_MB_2U_LIB.S9S_MB_2U(SCH_1):M_D_CPU1_SA_RSP(1)   I178 @S9S_MB_2U_LIB.S9S_MB_2U(SCH_1):PAGE105
     5 I3C_SPD_DDRABCD_CPU1_LVC1_SDA @S9S_MB_2U_LIB.S9S_MB_2U(SCH_1):I3C_SPD_DDRABCD_CPU1_LVC1_SDA   I178 @S9S_MB_2U_LIB.S9S_MB_2U(SCH_1):PAGE105
     4 I3C_SPD_DDRABCD_CPU1_LVC1_SCL_7 @S9S_MB_2U_LIB.S9S_MB_2U(SCH_1):I3C_SPD_DDRABCD_CPU1_LVC1_SCL_R8   I178 @S9S_MB_2U_LIB.S9S_MB_2U(SCH_1):PAGE105
   148 PD_CHD_CPU1_DIMM2_SAA @S9S_MB_2U_LIB.S9S_MB_2U(SCH_1):PD_CHD_CPU1_DIMM2_SAA   I178 @S9S_MB_2U_LIB.S9S_MB_2U(SCH_1):PAGE105
   100 M_D_CPU1_SB_DQ<0> @S9S_MB_2U_LIB.S9S_MB_2U(SCH_1):M_D_CPU1_SB_DQ(0)   I178 @S9S_MB_2U_LIB.S9S_MB_2U(SCH_1):PAGE105
   102 M_D_CPU1_SB_DQ<1> @S9S_MB_2U_LIB.S9S_MB_2U(SCH_1):M_D_CPU1_SB_DQ(1)   I178 @S9S_MB_2U_LIB.S9S_MB_2U(SCH_1):PAGE105
   245 M_D_CPU1_SB_DQ<2> @S9S_MB_2U_LIB.S9S_MB_2U(SCH_1):M_D_CPU1_SB_DQ(2)   I178 @S9S_MB_2U_LIB.S9S_MB_2U(SCH_1):PAGE105
   247 M_D_CPU1_SB_DQ<3> @S9S_MB_2U_LIB.S9S_MB_2U(SCH_1):M_D_CPU1_SB_DQ(3)   I178 @S9S_MB_2U_LIB.S9S_MB_2U(SCH_1):PAGE105
   107 M_D_CPU1_SB_DQ<4> @S9S_MB_2U_LIB.S9S_MB_2U(SCH_1):M_D_CPU1_SB_DQ(4)   I178 @S9S_MB_2U_LIB.S9S_MB_2U(SCH_1):PAGE105
   109 M_D_CPU1_SB_DQ<5> @S9S_MB_2U_LIB.S9S_MB_2U(SCH_1):M_D_CPU1_SB_DQ(5)   I178 @S9S_MB_2U_LIB.S9S_MB_2U(SCH_1):PAGE105
   252 M_D_CPU1_SB_DQ<6> @S9S_MB_2U_LIB.S9S_MB_2U(SCH_1):M_D_CPU1_SB_DQ(6)   I178 @S9S_MB_2U_LIB.S9S_MB_2U(SCH_1):PAGE105
   254 M_D_CPU1_SB_DQ<7> @S9S_MB_2U_LIB.S9S_MB_2U(SCH_1):M_D_CPU1_SB_DQ(7)   I178 @S9S_MB_2U_LIB.S9S_MB_2U(SCH_1):PAGE105
   111 M_D_CPU1_SB_DQ<8> @S9S_MB_2U_LIB.S9S_MB_2U(SCH_1):M_D_CPU1_SB_DQ(8)   I178 @S9S_MB_2U_LIB.S9S_MB_2U(SCH_1):PAGE105
   113 M_D_CPU1_SB_DQ<9> @S9S_MB_2U_LIB.S9S_MB_2U(SCH_1):M_D_CPU1_SB_DQ(9)   I178 @S9S_MB_2U_LIB.S9S_MB_2U(SCH_1):PAGE105
   256 M_D_CPU1_SB_DQ<10> @S9S_MB_2U_LIB.S9S_MB_2U(SCH_1):M_D_CPU1_SB_DQ(10)   I178 @S9S_MB_2U_LIB.S9S_MB_2U(SCH_1):PAGE105
   258 M_D_CPU1_SB_DQ<11> @S9S_MB_2U_LIB.S9S_MB_2U(SCH_1):M_D_CPU1_SB_DQ(11)   I178 @S9S_MB_2U_LIB.S9S_MB_2U(SCH_1):PAGE105
   118 M_D_CPU1_SB_DQ<12> @S9S_MB_2U_LIB.S9S_MB_2U(SCH_1):M_D_CPU1_SB_DQ(12)   I178 @S9S_MB_2U_LIB.S9S_MB_2U(SCH_1):PAGE105
   120 M_D_CPU1_SB_DQ<13> @S9S_MB_2U_LIB.S9S_MB_2U(SCH_1):M_D_CPU1_SB_DQ(13)   I178 @S9S_MB_2U_LIB.S9S_MB_2U(SCH_1):PAGE105
   263 M_D_CPU1_SB_DQ<14> @S9S_MB_2U_LIB.S9S_MB_2U(SCH_1):M_D_CPU1_SB_DQ(14)   I178 @S9S_MB_2U_LIB.S9S_MB_2U(SCH_1):PAGE105
   265 M_D_CPU1_SB_DQ<15> @S9S_MB_2U_LIB.S9S_MB_2U(SCH_1):M_D_CPU1_SB_DQ(15)   I178 @S9S_MB_2U_LIB.S9S_MB_2U(SCH_1):PAGE105
   122 M_D_CPU1_SB_DQ<16> @S9S_MB_2U_LIB.S9S_MB_2U(SCH_1):M_D_CPU1_SB_DQ(16)   I178 @S9S_MB_2U_LIB.S9S_MB_2U(SCH_1):PAGE105
   124 M_D_CPU1_SB_DQ<17> @S9S_MB_2U_LIB.S9S_MB_2U(SCH_1):M_D_CPU1_SB_DQ(17)   I178 @S9S_MB_2U_LIB.S9S_MB_2U(SCH_1):PAGE105
   267 M_D_CPU1_SB_DQ<18> @S9S_MB_2U_LIB.S9S_MB_2U(SCH_1):M_D_CPU1_SB_DQ(18)   I178 @S9S_MB_2U_LIB.S9S_MB_2U(SCH_1):PAGE105
   269 M_D_CPU1_SB_DQ<19> @S9S_MB_2U_LIB.S9S_MB_2U(SCH_1):M_D_CPU1_SB_DQ(19)   I178 @S9S_MB_2U_LIB.S9S_MB_2U(SCH_1):PAGE105
   129 M_D_CPU1_SB_DQ<20> @S9S_MB_2U_LIB.S9S_MB_2U(SCH_1):M_D_CPU1_SB_DQ(20)   I178 @S9S_MB_2U_LIB.S9S_MB_2U(SCH_1):PAGE105
   131 M_D_CPU1_SB_DQ<21> @S9S_MB_2U_LIB.S9S_MB_2U(SCH_1):M_D_CPU1_SB_DQ(21)   I178 @S9S_MB_2U_LIB.S9S_MB_2U(SCH_1):PAGE105
   274 M_D_CPU1_SB_DQ<22> @S9S_MB_2U_LIB.S9S_MB_2U(SCH_1):M_D_CPU1_SB_DQ(22)   I178 @S9S_MB_2U_LIB.S9S_MB_2U(SCH_1):PAGE105
   276 M_D_CPU1_SB_DQ<23> @S9S_MB_2U_LIB.S9S_MB_2U(SCH_1):M_D_CPU1_SB_DQ(23)   I178 @S9S_MB_2U_LIB.S9S_MB_2U(SCH_1):PAGE105
   133 M_D_CPU1_SB_DQ<24> @S9S_MB_2U_LIB.S9S_MB_2U(SCH_1):M_D_CPU1_SB_DQ(24)   I178 @S9S_MB_2U_LIB.S9S_MB_2U(SCH_1):PAGE105
   135 M_D_CPU1_SB_DQ<25> @S9S_MB_2U_LIB.S9S_MB_2U(SCH_1):M_D_CPU1_SB_DQ(25)   I178 @S9S_MB_2U_LIB.S9S_MB_2U(SCH_1):PAGE105
   278 M_D_CPU1_SB_DQ<26> @S9S_MB_2U_LIB.S9S_MB_2U(SCH_1):M_D_CPU1_SB_DQ(26)   I178 @S9S_MB_2U_LIB.S9S_MB_2U(SCH_1):PAGE105
   280 M_D_CPU1_SB_DQ<27> @S9S_MB_2U_LIB.S9S_MB_2U(SCH_1):M_D_CPU1_SB_DQ(27)   I178 @S9S_MB_2U_LIB.S9S_MB_2U(SCH_1):PAGE105
   140 M_D_CPU1_SB_DQ<28> @S9S_MB_2U_LIB.S9S_MB_2U(SCH_1):M_D_CPU1_SB_DQ(28)   I178 @S9S_MB_2U_LIB.S9S_MB_2U(SCH_1):PAGE105
   142 M_D_CPU1_SB_DQ<29> @S9S_MB_2U_LIB.S9S_MB_2U(SCH_1):M_D_CPU1_SB_DQ(29)   I178 @S9S_MB_2U_LIB.S9S_MB_2U(SCH_1):PAGE105
   285 M_D_CPU1_SB_DQ<30> @S9S_MB_2U_LIB.S9S_MB_2U(SCH_1):M_D_CPU1_SB_DQ(30)   I178 @S9S_MB_2U_LIB.S9S_MB_2U(SCH_1):PAGE105
   287 M_D_CPU1_SB_DQ<31> @S9S_MB_2U_LIB.S9S_MB_2U(SCH_1):M_D_CPU1_SB_DQ(31)   I178 @S9S_MB_2U_LIB.S9S_MB_2U(SCH_1):PAGE105
     7 M_D_CPU1_SA_DQ<0> @S9S_MB_2U_LIB.S9S_MB_2U(SCH_1):M_D_CPU1_SA_DQ(0)   I178 @S9S_MB_2U_LIB.S9S_MB_2U(SCH_1):PAGE105
     9 M_D_CPU1_SA_DQ<1> @S9S_MB_2U_LIB.S9S_MB_2U(SCH_1):M_D_CPU1_SA_DQ(1)   I178 @S9S_MB_2U_LIB.S9S_MB_2U(SCH_1):PAGE105
   152 M_D_CPU1_SA_DQ<2> @S9S_MB_2U_LIB.S9S_MB_2U(SCH_1):M_D_CPU1_SA_DQ(2)   I178 @S9S_MB_2U_LIB.S9S_MB_2U(SCH_1):PAGE105
   154 M_D_CPU1_SA_DQ<3> @S9S_MB_2U_LIB.S9S_MB_2U(SCH_1):M_D_CPU1_SA_DQ(3)   I178 @S9S_MB_2U_LIB.S9S_MB_2U(SCH_1):PAGE105
    14 M_D_CPU1_SA_DQ<4> @S9S_MB_2U_LIB.S9S_MB_2U(SCH_1):M_D_CPU1_SA_DQ(4)   I178 @S9S_MB_2U_LIB.S9S_MB_2U(SCH_1):PAGE105
    16 M_D_CPU1_SA_DQ<5> @S9S_MB_2U_LIB.S9S_MB_2U(SCH_1):M_D_CPU1_SA_DQ(5)   I178 @S9S_MB_2U_LIB.S9S_MB_2U(SCH_1):PAGE105
   159 M_D_CPU1_SA_DQ<6> @S9S_MB_2U_LIB.S9S_MB_2U(SCH_1):M_D_CPU1_SA_DQ(6)   I178 @S9S_MB_2U_LIB.S9S_MB_2U(SCH_1):PAGE105
   161 M_D_CPU1_SA_DQ<7> @S9S_MB_2U_LIB.S9S_MB_2U(SCH_1):M_D_CPU1_SA_DQ(7)   I178 @S9S_MB_2U_LIB.S9S_MB_2U(SCH_1):PAGE105
    18 M_D_CPU1_SA_DQ<8> @S9S_MB_2U_LIB.S9S_MB_2U(SCH_1):M_D_CPU1_SA_DQ(8)   I178 @S9S_MB_2U_LIB.S9S_MB_2U(SCH_1):PAGE105
    20 M_D_CPU1_SA_DQ<9> @S9S_MB_2U_LIB.S9S_MB_2U(SCH_1):M_D_CPU1_SA_DQ(9)   I178 @S9S_MB_2U_LIB.S9S_MB_2U(SCH_1):PAGE105
   163 M_D_CPU1_SA_DQ<10> @S9S_MB_2U_LIB.S9S_MB_2U(SCH_1):M_D_CPU1_SA_DQ(10)   I178 @S9S_MB_2U_LIB.S9S_MB_2U(SCH_1):PAGE105
   165 M_D_CPU1_SA_DQ<11> @S9S_MB_2U_LIB.S9S_MB_2U(SCH_1):M_D_CPU1_SA_DQ(11)   I178 @S9S_MB_2U_LIB.S9S_MB_2U(SCH_1):PAGE105
    25 M_D_CPU1_SA_DQ<12> @S9S_MB_2U_LIB.S9S_MB_2U(SCH_1):M_D_CPU1_SA_DQ(12)   I178 @S9S_MB_2U_LIB.S9S_MB_2U(SCH_1):PAGE105
    27 M_D_CPU1_SA_DQ<13> @S9S_MB_2U_LIB.S9S_MB_2U(SCH_1):M_D_CPU1_SA_DQ(13)   I178 @S9S_MB_2U_LIB.S9S_MB_2U(SCH_1):PAGE105
   170 M_D_CPU1_SA_DQ<14> @S9S_MB_2U_LIB.S9S_MB_2U(SCH_1):M_D_CPU1_SA_DQ(14)   I178 @S9S_MB_2U_LIB.S9S_MB_2U(SCH_1):PAGE105
   172 M_D_CPU1_SA_DQ<15> @S9S_MB_2U_LIB.S9S_MB_2U(SCH_1):M_D_CPU1_SA_DQ(15)   I178 @S9S_MB_2U_LIB.S9S_MB_2U(SCH_1):PAGE105
    29 M_D_CPU1_SA_DQ<16> @S9S_MB_2U_LIB.S9S_MB_2U(SCH_1):M_D_CPU1_SA_DQ(16)   I178 @S9S_MB_2U_LIB.S9S_MB_2U(SCH_1):PAGE105
    31 M_D_CPU1_SA_DQ<17> @S9S_MB_2U_LIB.S9S_MB_2U(SCH_1):M_D_CPU1_SA_DQ(17)   I178 @S9S_MB_2U_LIB.S9S_MB_2U(SCH_1):PAGE105
   174 M_D_CPU1_SA_DQ<18> @S9S_MB_2U_LIB.S9S_MB_2U(SCH_1):M_D_CPU1_SA_DQ(18)   I178 @S9S_MB_2U_LIB.S9S_MB_2U(SCH_1):PAGE105
   176 M_D_CPU1_SA_DQ<19> @S9S_MB_2U_LIB.S9S_MB_2U(SCH_1):M_D_CPU1_SA_DQ(19)   I178 @S9S_MB_2U_LIB.S9S_MB_2U(SCH_1):PAGE105
    36 M_D_CPU1_SA_DQ<20> @S9S_MB_2U_LIB.S9S_MB_2U(SCH_1):M_D_CPU1_SA_DQ(20)   I178 @S9S_MB_2U_LIB.S9S_MB_2U(SCH_1):PAGE105
    38 M_D_CPU1_SA_DQ<21> @S9S_MB_2U_LIB.S9S_MB_2U(SCH_1):M_D_CPU1_SA_DQ(21)   I178 @S9S_MB_2U_LIB.S9S_MB_2U(SCH_1):PAGE105
   181 M_D_CPU1_SA_DQ<22> @S9S_MB_2U_LIB.S9S_MB_2U(SCH_1):M_D_CPU1_SA_DQ(22)   I178 @S9S_MB_2U_LIB.S9S_MB_2U(SCH_1):PAGE105
   183 M_D_CPU1_SA_DQ<23> @S9S_MB_2U_LIB.S9S_MB_2U(SCH_1):M_D_CPU1_SA_DQ(23)   I178 @S9S_MB_2U_LIB.S9S_MB_2U(SCH_1):PAGE105
    40 M_D_CPU1_SA_DQ<24> @S9S_MB_2U_LIB.S9S_MB_2U(SCH_1):M_D_CPU1_SA_DQ(24)   I178 @S9S_MB_2U_LIB.S9S_MB_2U(SCH_1):PAGE105
    42 M_D_CPU1_SA_DQ<25> @S9S_MB_2U_LIB.S9S_MB_2U(SCH_1):M_D_CPU1_SA_DQ(25)   I178 @S9S_MB_2U_LIB.S9S_MB_2U(SCH_1):PAGE105
   185 M_D_CPU1_SA_DQ<26> @S9S_MB_2U_LIB.S9S_MB_2U(SCH_1):M_D_CPU1_SA_DQ(26)   I178 @S9S_MB_2U_LIB.S9S_MB_2U(SCH_1):PAGE105
   187 M_D_CPU1_SA_DQ<27> @S9S_MB_2U_LIB.S9S_MB_2U(SCH_1):M_D_CPU1_SA_DQ(27)   I178 @S9S_MB_2U_LIB.S9S_MB_2U(SCH_1):PAGE105
    47 M_D_CPU1_SA_DQ<28> @S9S_MB_2U_LIB.S9S_MB_2U(SCH_1):M_D_CPU1_SA_DQ(28)   I178 @S9S_MB_2U_LIB.S9S_MB_2U(SCH_1):PAGE105
    49 M_D_CPU1_SA_DQ<29> @S9S_MB_2U_LIB.S9S_MB_2U(SCH_1):M_D_CPU1_SA_DQ(29)   I178 @S9S_MB_2U_LIB.S9S_MB_2U(SCH_1):PAGE105
   192 M_D_CPU1_SA_DQ<30> @S9S_MB_2U_LIB.S9S_MB_2U(SCH_1):M_D_CPU1_SA_DQ(30)   I178 @S9S_MB_2U_LIB.S9S_MB_2U(SCH_1):PAGE105
   229 M_D_CPU1_SB_CS_N<3> @S9S_MB_2U_LIB.S9S_MB_2U(SCH_1):M_D_CPU1_SB_CS_N(3)   I178 @S9S_MB_2U_LIB.S9S_MB_2U(SCH_1):PAGE105
   209 M_D_CPU1_SA_CS_N<3> @S9S_MB_2U_LIB.S9S_MB_2U(SCH_1):M_D_CPU1_SA_CS_N(3)   I178 @S9S_MB_2U_LIB.S9S_MB_2U(SCH_1):PAGE105
    84 M_D_CPU1_SB_CS_N<2> @S9S_MB_2U_LIB.S9S_MB_2U(SCH_1):M_D_CPU1_SB_CS_N(2)   I178 @S9S_MB_2U_LIB.S9S_MB_2U(SCH_1):PAGE105
    64 M_D_CPU1_SA_CS_N<2> @S9S_MB_2U_LIB.S9S_MB_2U(SCH_1):M_D_CPU1_SA_CS_N(2)   I178 @S9S_MB_2U_LIB.S9S_MB_2U(SCH_1):PAGE105
   217 M_D_CPU1_CLK_DP<1> @S9S_MB_2U_LIB.S9S_MB_2U(SCH_1):M_D_CPU1_CLK_DP(1)   I178 @S9S_MB_2U_LIB.S9S_MB_2U(SCH_1):PAGE105
   218 M_D_CPU1_CLK_DN<1> @S9S_MB_2U_LIB.S9S_MB_2U(SCH_1):M_D_CPU1_CLK_DN(1)   I178 @S9S_MB_2U_LIB.S9S_MB_2U(SCH_1):PAGE105
    96 M_D_CPU1_SB_CB<0> @S9S_MB_2U_LIB.S9S_MB_2U(SCH_1):M_D_CPU1_SB_CB(0)   I178 @S9S_MB_2U_LIB.S9S_MB_2U(SCH_1):PAGE105
    98 M_D_CPU1_SB_CB<1> @S9S_MB_2U_LIB.S9S_MB_2U(SCH_1):M_D_CPU1_SB_CB(1)   I178 @S9S_MB_2U_LIB.S9S_MB_2U(SCH_1):PAGE105
   241 M_D_CPU1_SB_CB<2> @S9S_MB_2U_LIB.S9S_MB_2U(SCH_1):M_D_CPU1_SB_CB(2)   I178 @S9S_MB_2U_LIB.S9S_MB_2U(SCH_1):PAGE105
   243 M_D_CPU1_SB_CB<3> @S9S_MB_2U_LIB.S9S_MB_2U(SCH_1):M_D_CPU1_SB_CB(3)   I178 @S9S_MB_2U_LIB.S9S_MB_2U(SCH_1):PAGE105
    89 M_D_CPU1_SB_CB<4> @S9S_MB_2U_LIB.S9S_MB_2U(SCH_1):M_D_CPU1_SB_CB(4)   I178 @S9S_MB_2U_LIB.S9S_MB_2U(SCH_1):PAGE105
    91 M_D_CPU1_SB_CB<5> @S9S_MB_2U_LIB.S9S_MB_2U(SCH_1):M_D_CPU1_SB_CB(5)   I178 @S9S_MB_2U_LIB.S9S_MB_2U(SCH_1):PAGE105
   234 M_D_CPU1_SB_CB<6> @S9S_MB_2U_LIB.S9S_MB_2U(SCH_1):M_D_CPU1_SB_CB(6)   I178 @S9S_MB_2U_LIB.S9S_MB_2U(SCH_1):PAGE105
    51 M_D_CPU1_SA_CB<0> @S9S_MB_2U_LIB.S9S_MB_2U(SCH_1):M_D_CPU1_SA_CB(0)   I178 @S9S_MB_2U_LIB.S9S_MB_2U(SCH_1):PAGE105
   196 M_D_CPU1_SA_CB<2> @S9S_MB_2U_LIB.S9S_MB_2U(SCH_1):M_D_CPU1_SA_CB(2)   I178 @S9S_MB_2U_LIB.S9S_MB_2U(SCH_1):PAGE105
   198 M_D_CPU1_SA_CB<3> @S9S_MB_2U_LIB.S9S_MB_2U(SCH_1):M_D_CPU1_SA_CB(3)   I178 @S9S_MB_2U_LIB.S9S_MB_2U(SCH_1):PAGE105
    60 M_D_CPU1_SA_CB<5> @S9S_MB_2U_LIB.S9S_MB_2U(SCH_1):M_D_CPU1_SA_CB(5)   I178 @S9S_MB_2U_LIB.S9S_MB_2U(SCH_1):PAGE105
   203 M_D_CPU1_SA_CB<6> @S9S_MB_2U_LIB.S9S_MB_2U(SCH_1):M_D_CPU1_SA_CB(6)   I178 @S9S_MB_2U_LIB.S9S_MB_2U(SCH_1):PAGE105
    82 M_D_CPU1_SB_CA<6> @S9S_MB_2U_LIB.S9S_MB_2U(SCH_1):M_D_CPU1_SB_CA(6)   I178 @S9S_MB_2U_LIB.S9S_MB_2U(SCH_1):PAGE105
    72 M_D_CPU1_SA_CA<6> @S9S_MB_2U_LIB.S9S_MB_2U(SCH_1):M_D_CPU1_SA_CA(6)   I178 @S9S_MB_2U_LIB.S9S_MB_2U(SCH_1):PAGE105
   225 M_D_CPU1_SB_CA<5> @S9S_MB_2U_LIB.S9S_MB_2U(SCH_1):M_D_CPU1_SB_CA(5)   I178 @S9S_MB_2U_LIB.S9S_MB_2U(SCH_1):PAGE105
   215 M_D_CPU1_SA_CA<5> @S9S_MB_2U_LIB.S9S_MB_2U(SCH_1):M_D_CPU1_SA_CA(5)   I178 @S9S_MB_2U_LIB.S9S_MB_2U(SCH_1):PAGE105
    80 M_D_CPU1_SB_CA<4> @S9S_MB_2U_LIB.S9S_MB_2U(SCH_1):M_D_CPU1_SB_CA(4)   I178 @S9S_MB_2U_LIB.S9S_MB_2U(SCH_1):PAGE105
    70 M_D_CPU1_SA_CA<4> @S9S_MB_2U_LIB.S9S_MB_2U(SCH_1):M_D_CPU1_SA_CA(4)   I178 @S9S_MB_2U_LIB.S9S_MB_2U(SCH_1):PAGE105
   223 M_D_CPU1_SB_CA<3> @S9S_MB_2U_LIB.S9S_MB_2U(SCH_1):M_D_CPU1_SB_CA(3)   I178 @S9S_MB_2U_LIB.S9S_MB_2U(SCH_1):PAGE105
   213 M_D_CPU1_SA_CA<3> @S9S_MB_2U_LIB.S9S_MB_2U(SCH_1):M_D_CPU1_SA_CA(3)   I178 @S9S_MB_2U_LIB.S9S_MB_2U(SCH_1):PAGE105
    78 M_D_CPU1_SB_CA<2> @S9S_MB_2U_LIB.S9S_MB_2U(SCH_1):M_D_CPU1_SB_CA(2)   I178 @S9S_MB_2U_LIB.S9S_MB_2U(SCH_1):PAGE105
    68 M_D_CPU1_SA_CA<2> @S9S_MB_2U_LIB.S9S_MB_2U(SCH_1):M_D_CPU1_SA_CA(2)   I178 @S9S_MB_2U_LIB.S9S_MB_2U(SCH_1):PAGE105
   221 M_D_CPU1_SB_CA<1> @S9S_MB_2U_LIB.S9S_MB_2U(SCH_1):M_D_CPU1_SB_CA(1)   I178 @S9S_MB_2U_LIB.S9S_MB_2U(SCH_1):PAGE105
   211 M_D_CPU1_SA_CA<1> @S9S_MB_2U_LIB.S9S_MB_2U(SCH_1):M_D_CPU1_SA_CA(1)   I178 @S9S_MB_2U_LIB.S9S_MB_2U(SCH_1):PAGE105
    76 M_D_CPU1_SB_CA<0> @S9S_MB_2U_LIB.S9S_MB_2U(SCH_1):M_D_CPU1_SB_CA(0)   I178 @S9S_MB_2U_LIB.S9S_MB_2U(SCH_1):PAGE105
    66 M_D_CPU1_SA_CA<0> @S9S_MB_2U_LIB.S9S_MB_2U(SCH_1):M_D_CPU1_SA_CA(0)   I178 @S9S_MB_2U_LIB.S9S_MB_2U(SCH_1):PAGE105
    62 M_D_CPU1_ALERT_N @S9S_MB_2U_LIB.S9S_MB_2U(SCH_1):M_D_CPU1_ALERT_N   I178 @S9S_MB_2U_LIB.S9S_MB_2U(SCH_1):PAGE105
   236 M_D_CPU1_SB_CB<7> @S9S_MB_2U_LIB.S9S_MB_2U(SCH_1):M_D_CPU1_SB_CB(7)   I178 @S9S_MB_2U_LIB.S9S_MB_2U(SCH_1):PAGE105
    53 M_D_CPU1_SA_CB<1> @S9S_MB_2U_LIB.S9S_MB_2U(SCH_1):M_D_CPU1_SA_CB(1)   I178 @S9S_MB_2U_LIB.S9S_MB_2U(SCH_1):PAGE105
    58 M_D_CPU1_SA_CB<4> @S9S_MB_2U_LIB.S9S_MB_2U(SCH_1):M_D_CPU1_SA_CB(4)   I178 @S9S_MB_2U_LIB.S9S_MB_2U(SCH_1):PAGE105
   205 M_D_CPU1_SA_CB<7> @S9S_MB_2U_LIB.S9S_MB_2U(SCH_1):M_D_CPU1_SA_CB(7)   I178 @S9S_MB_2U_LIB.S9S_MB_2U(SCH_1):PAGE105
   194 M_D_CPU1_SA_DQ<31> @S9S_MB_2U_LIB.S9S_MB_2U(SCH_1):M_D_CPU1_SA_DQ(31)   I178 @S9S_MB_2U_LIB.S9S_MB_2U(SCH_1):PAGE105
    93 M_D_CPU1_SB_DQS_DP<9> @S9S_MB_2U_LIB.S9S_MB_2U(SCH_1):M_D_CPU1_SB_DQS_DP(9)   I181 @S9S_MB_2U_LIB.S9S_MB_2U(SCH_1):PAGE105
    94 M_D_CPU1_SB_DQS_DN<9> @S9S_MB_2U_LIB.S9S_MB_2U(SCH_1):M_D_CPU1_SB_DQS_DN(9)   I181 @S9S_MB_2U_LIB.S9S_MB_2U(SCH_1):PAGE105
   201 M_D_CPU1_SA_DQS_DP<9> @S9S_MB_2U_LIB.S9S_MB_2U(SCH_1):M_D_CPU1_SA_DQS_DP(9)   I181 @S9S_MB_2U_LIB.S9S_MB_2U(SCH_1):PAGE105
   200 M_D_CPU1_SA_DQS_DN<9> @S9S_MB_2U_LIB.S9S_MB_2U(SCH_1):M_D_CPU1_SA_DQS_DN(9)   I181 @S9S_MB_2U_LIB.S9S_MB_2U(SCH_1):PAGE105
   190 M_D_CPU1_SA_DQS_DP<8> @S9S_MB_2U_LIB.S9S_MB_2U(SCH_1):M_D_CPU1_SA_DQS_DP(8)   I181 @S9S_MB_2U_LIB.S9S_MB_2U(SCH_1):PAGE105
   189 M_D_CPU1_SA_DQS_DN<8> @S9S_MB_2U_LIB.S9S_MB_2U(SCH_1):M_D_CPU1_SA_DQS_DN(8)   I181 @S9S_MB_2U_LIB.S9S_MB_2U(SCH_1):PAGE105
   271 M_D_CPU1_SB_DQS_DN<7> @S9S_MB_2U_LIB.S9S_MB_2U(SCH_1):M_D_CPU1_SB_DQS_DN(7)   I181 @S9S_MB_2U_LIB.S9S_MB_2U(SCH_1):PAGE105
   179 M_D_CPU1_SA_DQS_DP<7> @S9S_MB_2U_LIB.S9S_MB_2U(SCH_1):M_D_CPU1_SA_DQS_DP(7)   I181 @S9S_MB_2U_LIB.S9S_MB_2U(SCH_1):PAGE105
   261 M_D_CPU1_SB_DQS_DP<6> @S9S_MB_2U_LIB.S9S_MB_2U(SCH_1):M_D_CPU1_SB_DQS_DP(6)   I181 @S9S_MB_2U_LIB.S9S_MB_2U(SCH_1):PAGE105
   260 M_D_CPU1_SB_DQS_DN<6> @S9S_MB_2U_LIB.S9S_MB_2U(SCH_1):M_D_CPU1_SB_DQS_DN(6)   I181 @S9S_MB_2U_LIB.S9S_MB_2U(SCH_1):PAGE105
   167 M_D_CPU1_SA_DQS_DN<6> @S9S_MB_2U_LIB.S9S_MB_2U(SCH_1):M_D_CPU1_SA_DQS_DN(6)   I181 @S9S_MB_2U_LIB.S9S_MB_2U(SCH_1):PAGE105
   250 M_D_CPU1_SB_DQS_DP<5> @S9S_MB_2U_LIB.S9S_MB_2U(SCH_1):M_D_CPU1_SB_DQS_DP(5)   I181 @S9S_MB_2U_LIB.S9S_MB_2U(SCH_1):PAGE105
   249 M_D_CPU1_SB_DQS_DN<5> @S9S_MB_2U_LIB.S9S_MB_2U(SCH_1):M_D_CPU1_SB_DQS_DN(5)   I181 @S9S_MB_2U_LIB.S9S_MB_2U(SCH_1):PAGE105
   157 M_D_CPU1_SA_DQS_DP<5> @S9S_MB_2U_LIB.S9S_MB_2U(SCH_1):M_D_CPU1_SA_DQS_DP(5)   I181 @S9S_MB_2U_LIB.S9S_MB_2U(SCH_1):PAGE105
   156 M_D_CPU1_SA_DQS_DN<5> @S9S_MB_2U_LIB.S9S_MB_2U(SCH_1):M_D_CPU1_SA_DQS_DN(5)   I181 @S9S_MB_2U_LIB.S9S_MB_2U(SCH_1):PAGE105
   239 M_D_CPU1_SB_DQS_DP<4> @S9S_MB_2U_LIB.S9S_MB_2U(SCH_1):M_D_CPU1_SB_DQS_DP(4)   I181 @S9S_MB_2U_LIB.S9S_MB_2U(SCH_1):PAGE105
   238 M_D_CPU1_SB_DQS_DN<4> @S9S_MB_2U_LIB.S9S_MB_2U(SCH_1):M_D_CPU1_SB_DQS_DN(4)   I181 @S9S_MB_2U_LIB.S9S_MB_2U(SCH_1):PAGE105
    55 M_D_CPU1_SA_DQS_DP<4> @S9S_MB_2U_LIB.S9S_MB_2U(SCH_1):M_D_CPU1_SA_DQS_DP(4)   I181 @S9S_MB_2U_LIB.S9S_MB_2U(SCH_1):PAGE105
    56 M_D_CPU1_SA_DQS_DN<4> @S9S_MB_2U_LIB.S9S_MB_2U(SCH_1):M_D_CPU1_SA_DQS_DN(4)   I181 @S9S_MB_2U_LIB.S9S_MB_2U(SCH_1):PAGE105
   137 M_D_CPU1_SB_DQS_DP<3> @S9S_MB_2U_LIB.S9S_MB_2U(SCH_1):M_D_CPU1_SB_DQS_DP(3)   I181 @S9S_MB_2U_LIB.S9S_MB_2U(SCH_1):PAGE105
   138 M_D_CPU1_SB_DQS_DN<3> @S9S_MB_2U_LIB.S9S_MB_2U(SCH_1):M_D_CPU1_SB_DQS_DN(3)   I181 @S9S_MB_2U_LIB.S9S_MB_2U(SCH_1):PAGE105
    44 M_D_CPU1_SA_DQS_DP<3> @S9S_MB_2U_LIB.S9S_MB_2U(SCH_1):M_D_CPU1_SA_DQS_DP(3)   I181 @S9S_MB_2U_LIB.S9S_MB_2U(SCH_1):PAGE105
    45 M_D_CPU1_SA_DQS_DN<3> @S9S_MB_2U_LIB.S9S_MB_2U(SCH_1):M_D_CPU1_SA_DQS_DN(3)   I181 @S9S_MB_2U_LIB.S9S_MB_2U(SCH_1):PAGE105
   126 M_D_CPU1_SB_DQS_DP<2> @S9S_MB_2U_LIB.S9S_MB_2U(SCH_1):M_D_CPU1_SB_DQS_DP(2)   I181 @S9S_MB_2U_LIB.S9S_MB_2U(SCH_1):PAGE105
   127 M_D_CPU1_SB_DQS_DN<2> @S9S_MB_2U_LIB.S9S_MB_2U(SCH_1):M_D_CPU1_SB_DQS_DN(2)   I181 @S9S_MB_2U_LIB.S9S_MB_2U(SCH_1):PAGE105
    33 M_D_CPU1_SA_DQS_DP<2> @S9S_MB_2U_LIB.S9S_MB_2U(SCH_1):M_D_CPU1_SA_DQS_DP(2)   I181 @S9S_MB_2U_LIB.S9S_MB_2U(SCH_1):PAGE105
    34 M_D_CPU1_SA_DQS_DN<2> @S9S_MB_2U_LIB.S9S_MB_2U(SCH_1):M_D_CPU1_SA_DQS_DN(2)   I181 @S9S_MB_2U_LIB.S9S_MB_2U(SCH_1):PAGE105
   115 M_D_CPU1_SB_DQS_DP<1> @S9S_MB_2U_LIB.S9S_MB_2U(SCH_1):M_D_CPU1_SB_DQS_DP(1)   I181 @S9S_MB_2U_LIB.S9S_MB_2U(SCH_1):PAGE105
   116 M_D_CPU1_SB_DQS_DN<1> @S9S_MB_2U_LIB.S9S_MB_2U(SCH_1):M_D_CPU1_SB_DQS_DN(1)   I181 @S9S_MB_2U_LIB.S9S_MB_2U(SCH_1):PAGE105
    22 M_D_CPU1_SA_DQS_DP<1> @S9S_MB_2U_LIB.S9S_MB_2U(SCH_1):M_D_CPU1_SA_DQS_DP(1)   I181 @S9S_MB_2U_LIB.S9S_MB_2U(SCH_1):PAGE105
    23 M_D_CPU1_SA_DQS_DN<1> @S9S_MB_2U_LIB.S9S_MB_2U(SCH_1):M_D_CPU1_SA_DQS_DN(1)   I181 @S9S_MB_2U_LIB.S9S_MB_2U(SCH_1):PAGE105
   104 M_D_CPU1_SB_DQS_DP<0> @S9S_MB_2U_LIB.S9S_MB_2U(SCH_1):M_D_CPU1_SB_DQS_DP(0)   I181 @S9S_MB_2U_LIB.S9S_MB_2U(SCH_1):PAGE105
   105 M_D_CPU1_SB_DQS_DN<0> @S9S_MB_2U_LIB.S9S_MB_2U(SCH_1):M_D_CPU1_SB_DQS_DN(0)   I181 @S9S_MB_2U_LIB.S9S_MB_2U(SCH_1):PAGE105
    11 M_D_CPU1_SA_DQS_DP<0> @S9S_MB_2U_LIB.S9S_MB_2U(SCH_1):M_D_CPU1_SA_DQS_DP(0)   I181 @S9S_MB_2U_LIB.S9S_MB_2U(SCH_1):PAGE105
    12 M_D_CPU1_SA_DQS_DN<0> @S9S_MB_2U_LIB.S9S_MB_2U(SCH_1):M_D_CPU1_SA_DQS_DN(0)   I181 @S9S_MB_2U_LIB.S9S_MB_2U(SCH_1):PAGE105
   272 M_D_CPU1_SB_DQS_DP<7> @S9S_MB_2U_LIB.S9S_MB_2U(SCH_1):M_D_CPU1_SB_DQS_DP(7)   I181 @S9S_MB_2U_LIB.S9S_MB_2U(SCH_1):PAGE105
   282 M_D_CPU1_SB_DQS_DN<8> @S9S_MB_2U_LIB.S9S_MB_2U(SCH_1):M_D_CPU1_SB_DQS_DN(8)   I181 @S9S_MB_2U_LIB.S9S_MB_2U(SCH_1):PAGE105
   283 M_D_CPU1_SB_DQS_DP<8> @S9S_MB_2U_LIB.S9S_MB_2U(SCH_1):M_D_CPU1_SB_DQS_DP(8)   I181 @S9S_MB_2U_LIB.S9S_MB_2U(SCH_1):PAGE105
   168 M_D_CPU1_SA_DQS_DP<6> @S9S_MB_2U_LIB.S9S_MB_2U(SCH_1):M_D_CPU1_SA_DQS_DP(6)   I181 @S9S_MB_2U_LIB.S9S_MB_2U(SCH_1):PAGE105
   178 M_D_CPU1_SA_DQS_DN<7> @S9S_MB_2U_LIB.S9S_MB_2U(SCH_1):M_D_CPU1_SA_DQS_DN(7)   I181 @S9S_MB_2U_LIB.S9S_MB_2U(SCH_1):PAGE105
     6    GND @S9S_MB_2U_LIB.S9S_MB_2U(SCH_1):GND   I180 @S9S_MB_2U_LIB.S9S_MB_2U(SCH_1):PAGE105
     8    GND @S9S_MB_2U_LIB.S9S_MB_2U(SCH_1):GND   I180 @S9S_MB_2U_LIB.S9S_MB_2U(SCH_1):PAGE105
    10    GND @S9S_MB_2U_LIB.S9S_MB_2U(SCH_1):GND   I180 @S9S_MB_2U_LIB.S9S_MB_2U(SCH_1):PAGE105
    13    GND @S9S_MB_2U_LIB.S9S_MB_2U(SCH_1):GND   I180 @S9S_MB_2U_LIB.S9S_MB_2U(SCH_1):PAGE105
    15    GND @S9S_MB_2U_LIB.S9S_MB_2U(SCH_1):GND   I180 @S9S_MB_2U_LIB.S9S_MB_2U(SCH_1):PAGE105
    17    GND @S9S_MB_2U_LIB.S9S_MB_2U(SCH_1):GND   I180 @S9S_MB_2U_LIB.S9S_MB_2U(SCH_1):PAGE105
    19    GND @S9S_MB_2U_LIB.S9S_MB_2U(SCH_1):GND   I180 @S9S_MB_2U_LIB.S9S_MB_2U(SCH_1):PAGE105
    21    GND @S9S_MB_2U_LIB.S9S_MB_2U(SCH_1):GND   I180 @S9S_MB_2U_LIB.S9S_MB_2U(SCH_1):PAGE105
    24    GND @S9S_MB_2U_LIB.S9S_MB_2U(SCH_1):GND   I180 @S9S_MB_2U_LIB.S9S_MB_2U(SCH_1):PAGE105
    26    GND @S9S_MB_2U_LIB.S9S_MB_2U(SCH_1):GND   I180 @S9S_MB_2U_LIB.S9S_MB_2U(SCH_1):PAGE105
    28    GND @S9S_MB_2U_LIB.S9S_MB_2U(SCH_1):GND   I180 @S9S_MB_2U_LIB.S9S_MB_2U(SCH_1):PAGE105
    30    GND @S9S_MB_2U_LIB.S9S_MB_2U(SCH_1):GND   I180 @S9S_MB_2U_LIB.S9S_MB_2U(SCH_1):PAGE105
    32    GND @S9S_MB_2U_LIB.S9S_MB_2U(SCH_1):GND   I180 @S9S_MB_2U_LIB.S9S_MB_2U(SCH_1):PAGE105
    35    GND @S9S_MB_2U_LIB.S9S_MB_2U(SCH_1):GND   I180 @S9S_MB_2U_LIB.S9S_MB_2U(SCH_1):PAGE105
    37    GND @S9S_MB_2U_LIB.S9S_MB_2U(SCH_1):GND   I180 @S9S_MB_2U_LIB.S9S_MB_2U(SCH_1):PAGE105
    39    GND @S9S_MB_2U_LIB.S9S_MB_2U(SCH_1):GND   I180 @S9S_MB_2U_LIB.S9S_MB_2U(SCH_1):PAGE105
    41    GND @S9S_MB_2U_LIB.S9S_MB_2U(SCH_1):GND   I180 @S9S_MB_2U_LIB.S9S_MB_2U(SCH_1):PAGE105
    43    GND @S9S_MB_2U_LIB.S9S_MB_2U(SCH_1):GND   I180 @S9S_MB_2U_LIB.S9S_MB_2U(SCH_1):PAGE105
    46    GND @S9S_MB_2U_LIB.S9S_MB_2U(SCH_1):GND   I180 @S9S_MB_2U_LIB.S9S_MB_2U(SCH_1):PAGE105
    48    GND @S9S_MB_2U_LIB.S9S_MB_2U(SCH_1):GND   I180 @S9S_MB_2U_LIB.S9S_MB_2U(SCH_1):PAGE105
    50    GND @S9S_MB_2U_LIB.S9S_MB_2U(SCH_1):GND   I180 @S9S_MB_2U_LIB.S9S_MB_2U(SCH_1):PAGE105
    52    GND @S9S_MB_2U_LIB.S9S_MB_2U(SCH_1):GND   I180 @S9S_MB_2U_LIB.S9S_MB_2U(SCH_1):PAGE105
    54    GND @S9S_MB_2U_LIB.S9S_MB_2U(SCH_1):GND   I180 @S9S_MB_2U_LIB.S9S_MB_2U(SCH_1):PAGE105
    57    GND @S9S_MB_2U_LIB.S9S_MB_2U(SCH_1):GND   I180 @S9S_MB_2U_LIB.S9S_MB_2U(SCH_1):PAGE105
    59    GND @S9S_MB_2U_LIB.S9S_MB_2U(SCH_1):GND   I180 @S9S_MB_2U_LIB.S9S_MB_2U(SCH_1):PAGE105
    61    GND @S9S_MB_2U_LIB.S9S_MB_2U(SCH_1):GND   I180 @S9S_MB_2U_LIB.S9S_MB_2U(SCH_1):PAGE105
    63    GND @S9S_MB_2U_LIB.S9S_MB_2U(SCH_1):GND   I180 @S9S_MB_2U_LIB.S9S_MB_2U(SCH_1):PAGE105
    65    GND @S9S_MB_2U_LIB.S9S_MB_2U(SCH_1):GND   I180 @S9S_MB_2U_LIB.S9S_MB_2U(SCH_1):PAGE105
    67    GND @S9S_MB_2U_LIB.S9S_MB_2U(SCH_1):GND   I180 @S9S_MB_2U_LIB.S9S_MB_2U(SCH_1):PAGE105
    69    GND @S9S_MB_2U_LIB.S9S_MB_2U(SCH_1):GND   I180 @S9S_MB_2U_LIB.S9S_MB_2U(SCH_1):PAGE105
    71    GND @S9S_MB_2U_LIB.S9S_MB_2U(SCH_1):GND   I180 @S9S_MB_2U_LIB.S9S_MB_2U(SCH_1):PAGE105
    73    GND @S9S_MB_2U_LIB.S9S_MB_2U(SCH_1):GND   I180 @S9S_MB_2U_LIB.S9S_MB_2U(SCH_1):PAGE105
    75    GND @S9S_MB_2U_LIB.S9S_MB_2U(SCH_1):GND   I180 @S9S_MB_2U_LIB.S9S_MB_2U(SCH_1):PAGE105
    77    GND @S9S_MB_2U_LIB.S9S_MB_2U(SCH_1):GND   I180 @S9S_MB_2U_LIB.S9S_MB_2U(SCH_1):PAGE105
    79    GND @S9S_MB_2U_LIB.S9S_MB_2U(SCH_1):GND   I180 @S9S_MB_2U_LIB.S9S_MB_2U(SCH_1):PAGE105
    81    GND @S9S_MB_2U_LIB.S9S_MB_2U(SCH_1):GND   I180 @S9S_MB_2U_LIB.S9S_MB_2U(SCH_1):PAGE105
    83    GND @S9S_MB_2U_LIB.S9S_MB_2U(SCH_1):GND   I180 @S9S_MB_2U_LIB.S9S_MB_2U(SCH_1):PAGE105
    85    GND @S9S_MB_2U_LIB.S9S_MB_2U(SCH_1):GND   I180 @S9S_MB_2U_LIB.S9S_MB_2U(SCH_1):PAGE105
    88    GND @S9S_MB_2U_LIB.S9S_MB_2U(SCH_1):GND   I180 @S9S_MB_2U_LIB.S9S_MB_2U(SCH_1):PAGE105
    90    GND @S9S_MB_2U_LIB.S9S_MB_2U(SCH_1):GND   I180 @S9S_MB_2U_LIB.S9S_MB_2U(SCH_1):PAGE105
    92    GND @S9S_MB_2U_LIB.S9S_MB_2U(SCH_1):GND   I180 @S9S_MB_2U_LIB.S9S_MB_2U(SCH_1):PAGE105
    95    GND @S9S_MB_2U_LIB.S9S_MB_2U(SCH_1):GND   I180 @S9S_MB_2U_LIB.S9S_MB_2U(SCH_1):PAGE105
    97    GND @S9S_MB_2U_LIB.S9S_MB_2U(SCH_1):GND   I180 @S9S_MB_2U_LIB.S9S_MB_2U(SCH_1):PAGE105
    99    GND @S9S_MB_2U_LIB.S9S_MB_2U(SCH_1):GND   I180 @S9S_MB_2U_LIB.S9S_MB_2U(SCH_1):PAGE105
   101    GND @S9S_MB_2U_LIB.S9S_MB_2U(SCH_1):GND   I180 @S9S_MB_2U_LIB.S9S_MB_2U(SCH_1):PAGE105
   103    GND @S9S_MB_2U_LIB.S9S_MB_2U(SCH_1):GND   I180 @S9S_MB_2U_LIB.S9S_MB_2U(SCH_1):PAGE105
   106    GND @S9S_MB_2U_LIB.S9S_MB_2U(SCH_1):GND   I180 @S9S_MB_2U_LIB.S9S_MB_2U(SCH_1):PAGE105
   108    GND @S9S_MB_2U_LIB.S9S_MB_2U(SCH_1):GND   I180 @S9S_MB_2U_LIB.S9S_MB_2U(SCH_1):PAGE105
   110    GND @S9S_MB_2U_LIB.S9S_MB_2U(SCH_1):GND   I180 @S9S_MB_2U_LIB.S9S_MB_2U(SCH_1):PAGE105
   112    GND @S9S_MB_2U_LIB.S9S_MB_2U(SCH_1):GND   I180 @S9S_MB_2U_LIB.S9S_MB_2U(SCH_1):PAGE105
   114    GND @S9S_MB_2U_LIB.S9S_MB_2U(SCH_1):GND   I180 @S9S_MB_2U_LIB.S9S_MB_2U(SCH_1):PAGE105
   117    GND @S9S_MB_2U_LIB.S9S_MB_2U(SCH_1):GND   I180 @S9S_MB_2U_LIB.S9S_MB_2U(SCH_1):PAGE105
   119    GND @S9S_MB_2U_LIB.S9S_MB_2U(SCH_1):GND   I180 @S9S_MB_2U_LIB.S9S_MB_2U(SCH_1):PAGE105
   121    GND @S9S_MB_2U_LIB.S9S_MB_2U(SCH_1):GND   I180 @S9S_MB_2U_LIB.S9S_MB_2U(SCH_1):PAGE105
   123    GND @S9S_MB_2U_LIB.S9S_MB_2U(SCH_1):GND   I180 @S9S_MB_2U_LIB.S9S_MB_2U(SCH_1):PAGE105
   125    GND @S9S_MB_2U_LIB.S9S_MB_2U(SCH_1):GND   I180 @S9S_MB_2U_LIB.S9S_MB_2U(SCH_1):PAGE105
   128    GND @S9S_MB_2U_LIB.S9S_MB_2U(SCH_1):GND   I180 @S9S_MB_2U_LIB.S9S_MB_2U(SCH_1):PAGE105
   130    GND @S9S_MB_2U_LIB.S9S_MB_2U(SCH_1):GND   I180 @S9S_MB_2U_LIB.S9S_MB_2U(SCH_1):PAGE105
   134    GND @S9S_MB_2U_LIB.S9S_MB_2U(SCH_1):GND   I180 @S9S_MB_2U_LIB.S9S_MB_2U(SCH_1):PAGE105
   143    GND @S9S_MB_2U_LIB.S9S_MB_2U(SCH_1):GND   I180 @S9S_MB_2U_LIB.S9S_MB_2U(SCH_1):PAGE105
   151    GND @S9S_MB_2U_LIB.S9S_MB_2U(SCH_1):GND   I180 @S9S_MB_2U_LIB.S9S_MB_2U(SCH_1):PAGE105
   153    GND @S9S_MB_2U_LIB.S9S_MB_2U(SCH_1):GND   I180 @S9S_MB_2U_LIB.S9S_MB_2U(SCH_1):PAGE105
   155    GND @S9S_MB_2U_LIB.S9S_MB_2U(SCH_1):GND   I180 @S9S_MB_2U_LIB.S9S_MB_2U(SCH_1):PAGE105
   158    GND @S9S_MB_2U_LIB.S9S_MB_2U(SCH_1):GND   I180 @S9S_MB_2U_LIB.S9S_MB_2U(SCH_1):PAGE105
   160    GND @S9S_MB_2U_LIB.S9S_MB_2U(SCH_1):GND   I180 @S9S_MB_2U_LIB.S9S_MB_2U(SCH_1):PAGE105
   162    GND @S9S_MB_2U_LIB.S9S_MB_2U(SCH_1):GND   I180 @S9S_MB_2U_LIB.S9S_MB_2U(SCH_1):PAGE105
   164    GND @S9S_MB_2U_LIB.S9S_MB_2U(SCH_1):GND   I180 @S9S_MB_2U_LIB.S9S_MB_2U(SCH_1):PAGE105
   166    GND @S9S_MB_2U_LIB.S9S_MB_2U(SCH_1):GND   I180 @S9S_MB_2U_LIB.S9S_MB_2U(SCH_1):PAGE105
   169    GND @S9S_MB_2U_LIB.S9S_MB_2U(SCH_1):GND   I180 @S9S_MB_2U_LIB.S9S_MB_2U(SCH_1):PAGE105
   171    GND @S9S_MB_2U_LIB.S9S_MB_2U(SCH_1):GND   I180 @S9S_MB_2U_LIB.S9S_MB_2U(SCH_1):PAGE105
   173    GND @S9S_MB_2U_LIB.S9S_MB_2U(SCH_1):GND   I180 @S9S_MB_2U_LIB.S9S_MB_2U(SCH_1):PAGE105
   175    GND @S9S_MB_2U_LIB.S9S_MB_2U(SCH_1):GND   I180 @S9S_MB_2U_LIB.S9S_MB_2U(SCH_1):PAGE105
   177    GND @S9S_MB_2U_LIB.S9S_MB_2U(SCH_1):GND   I180 @S9S_MB_2U_LIB.S9S_MB_2U(SCH_1):PAGE105
   180    GND @S9S_MB_2U_LIB.S9S_MB_2U(SCH_1):GND   I180 @S9S_MB_2U_LIB.S9S_MB_2U(SCH_1):PAGE105
   182    GND @S9S_MB_2U_LIB.S9S_MB_2U(SCH_1):GND   I180 @S9S_MB_2U_LIB.S9S_MB_2U(SCH_1):PAGE105
   184    GND @S9S_MB_2U_LIB.S9S_MB_2U(SCH_1):GND   I180 @S9S_MB_2U_LIB.S9S_MB_2U(SCH_1):PAGE105
   186    GND @S9S_MB_2U_LIB.S9S_MB_2U(SCH_1):GND   I180 @S9S_MB_2U_LIB.S9S_MB_2U(SCH_1):PAGE105
   188    GND @S9S_MB_2U_LIB.S9S_MB_2U(SCH_1):GND   I180 @S9S_MB_2U_LIB.S9S_MB_2U(SCH_1):PAGE105
   191    GND @S9S_MB_2U_LIB.S9S_MB_2U(SCH_1):GND   I180 @S9S_MB_2U_LIB.S9S_MB_2U(SCH_1):PAGE105
   193    GND @S9S_MB_2U_LIB.S9S_MB_2U(SCH_1):GND   I180 @S9S_MB_2U_LIB.S9S_MB_2U(SCH_1):PAGE105
   195    GND @S9S_MB_2U_LIB.S9S_MB_2U(SCH_1):GND   I180 @S9S_MB_2U_LIB.S9S_MB_2U(SCH_1):PAGE105
   197    GND @S9S_MB_2U_LIB.S9S_MB_2U(SCH_1):GND   I180 @S9S_MB_2U_LIB.S9S_MB_2U(SCH_1):PAGE105
   199    GND @S9S_MB_2U_LIB.S9S_MB_2U(SCH_1):GND   I180 @S9S_MB_2U_LIB.S9S_MB_2U(SCH_1):PAGE105
   202    GND @S9S_MB_2U_LIB.S9S_MB_2U(SCH_1):GND   I180 @S9S_MB_2U_LIB.S9S_MB_2U(SCH_1):PAGE105
   204    GND @S9S_MB_2U_LIB.S9S_MB_2U(SCH_1):GND   I180 @S9S_MB_2U_LIB.S9S_MB_2U(SCH_1):PAGE105
   206    GND @S9S_MB_2U_LIB.S9S_MB_2U(SCH_1):GND   I180 @S9S_MB_2U_LIB.S9S_MB_2U(SCH_1):PAGE105
   208    GND @S9S_MB_2U_LIB.S9S_MB_2U(SCH_1):GND   I180 @S9S_MB_2U_LIB.S9S_MB_2U(SCH_1):PAGE105
   210    GND @S9S_MB_2U_LIB.S9S_MB_2U(SCH_1):GND   I180 @S9S_MB_2U_LIB.S9S_MB_2U(SCH_1):PAGE105
   212    GND @S9S_MB_2U_LIB.S9S_MB_2U(SCH_1):GND   I180 @S9S_MB_2U_LIB.S9S_MB_2U(SCH_1):PAGE105
   214    GND @S9S_MB_2U_LIB.S9S_MB_2U(SCH_1):GND   I180 @S9S_MB_2U_LIB.S9S_MB_2U(SCH_1):PAGE105
   216    GND @S9S_MB_2U_LIB.S9S_MB_2U(SCH_1):GND   I180 @S9S_MB_2U_LIB.S9S_MB_2U(SCH_1):PAGE105
   219    GND @S9S_MB_2U_LIB.S9S_MB_2U(SCH_1):GND   I180 @S9S_MB_2U_LIB.S9S_MB_2U(SCH_1):PAGE105
   222    GND @S9S_MB_2U_LIB.S9S_MB_2U(SCH_1):GND   I180 @S9S_MB_2U_LIB.S9S_MB_2U(SCH_1):PAGE105
   224    GND @S9S_MB_2U_LIB.S9S_MB_2U(SCH_1):GND   I180 @S9S_MB_2U_LIB.S9S_MB_2U(SCH_1):PAGE105
   226    GND @S9S_MB_2U_LIB.S9S_MB_2U(SCH_1):GND   I180 @S9S_MB_2U_LIB.S9S_MB_2U(SCH_1):PAGE105
   228    GND @S9S_MB_2U_LIB.S9S_MB_2U(SCH_1):GND   I180 @S9S_MB_2U_LIB.S9S_MB_2U(SCH_1):PAGE105
   233    GND @S9S_MB_2U_LIB.S9S_MB_2U(SCH_1):GND   I180 @S9S_MB_2U_LIB.S9S_MB_2U(SCH_1):PAGE105
   237    GND @S9S_MB_2U_LIB.S9S_MB_2U(SCH_1):GND   I180 @S9S_MB_2U_LIB.S9S_MB_2U(SCH_1):PAGE105
   242    GND @S9S_MB_2U_LIB.S9S_MB_2U(SCH_1):GND   I180 @S9S_MB_2U_LIB.S9S_MB_2U(SCH_1):PAGE105
   244    GND @S9S_MB_2U_LIB.S9S_MB_2U(SCH_1):GND   I180 @S9S_MB_2U_LIB.S9S_MB_2U(SCH_1):PAGE105
   246    GND @S9S_MB_2U_LIB.S9S_MB_2U(SCH_1):GND   I180 @S9S_MB_2U_LIB.S9S_MB_2U(SCH_1):PAGE105
   248    GND @S9S_MB_2U_LIB.S9S_MB_2U(SCH_1):GND   I180 @S9S_MB_2U_LIB.S9S_MB_2U(SCH_1):PAGE105
   251    GND @S9S_MB_2U_LIB.S9S_MB_2U(SCH_1):GND   I180 @S9S_MB_2U_LIB.S9S_MB_2U(SCH_1):PAGE105
   253    GND @S9S_MB_2U_LIB.S9S_MB_2U(SCH_1):GND   I180 @S9S_MB_2U_LIB.S9S_MB_2U(SCH_1):PAGE105
   255    GND @S9S_MB_2U_LIB.S9S_MB_2U(SCH_1):GND   I180 @S9S_MB_2U_LIB.S9S_MB_2U(SCH_1):PAGE105
   257    GND @S9S_MB_2U_LIB.S9S_MB_2U(SCH_1):GND   I180 @S9S_MB_2U_LIB.S9S_MB_2U(SCH_1):PAGE105
   259    GND @S9S_MB_2U_LIB.S9S_MB_2U(SCH_1):GND   I180 @S9S_MB_2U_LIB.S9S_MB_2U(SCH_1):PAGE105
   262    GND @S9S_MB_2U_LIB.S9S_MB_2U(SCH_1):GND   I180 @S9S_MB_2U_LIB.S9S_MB_2U(SCH_1):PAGE105
   264    GND @S9S_MB_2U_LIB.S9S_MB_2U(SCH_1):GND   I180 @S9S_MB_2U_LIB.S9S_MB_2U(SCH_1):PAGE105
   266    GND @S9S_MB_2U_LIB.S9S_MB_2U(SCH_1):GND   I180 @S9S_MB_2U_LIB.S9S_MB_2U(SCH_1):PAGE105
   268    GND @S9S_MB_2U_LIB.S9S_MB_2U(SCH_1):GND   I180 @S9S_MB_2U_LIB.S9S_MB_2U(SCH_1):PAGE105
   270    GND @S9S_MB_2U_LIB.S9S_MB_2U(SCH_1):GND   I180 @S9S_MB_2U_LIB.S9S_MB_2U(SCH_1):PAGE105
   273    GND @S9S_MB_2U_LIB.S9S_MB_2U(SCH_1):GND   I180 @S9S_MB_2U_LIB.S9S_MB_2U(SCH_1):PAGE105
   275    GND @S9S_MB_2U_LIB.S9S_MB_2U(SCH_1):GND   I180 @S9S_MB_2U_LIB.S9S_MB_2U(SCH_1):PAGE105
   277    GND @S9S_MB_2U_LIB.S9S_MB_2U(SCH_1):GND   I180 @S9S_MB_2U_LIB.S9S_MB_2U(SCH_1):PAGE105
   279    GND @S9S_MB_2U_LIB.S9S_MB_2U(SCH_1):GND   I180 @S9S_MB_2U_LIB.S9S_MB_2U(SCH_1):PAGE105
   281    GND @S9S_MB_2U_LIB.S9S_MB_2U(SCH_1):GND   I180 @S9S_MB_2U_LIB.S9S_MB_2U(SCH_1):PAGE105
   284    GND @S9S_MB_2U_LIB.S9S_MB_2U(SCH_1):GND   I180 @S9S_MB_2U_LIB.S9S_MB_2U(SCH_1):PAGE105
   286    GND @S9S_MB_2U_LIB.S9S_MB_2U(SCH_1):GND   I180 @S9S_MB_2U_LIB.S9S_MB_2U(SCH_1):PAGE105
   288    GND @S9S_MB_2U_LIB.S9S_MB_2U(SCH_1):GND   I180 @S9S_MB_2U_LIB.S9S_MB_2U(SCH_1):PAGE105
     1 P12V_S3_AUX_CPU1_NVDIMM @S9S_MB_2U_LIB.S9S_MB_2U(SCH_1):P12V_S3_AUX_CPU1_NVDIMM   I180 @S9S_MB_2U_LIB.S9S_MB_2U(SCH_1):PAGE105
   145 P12V_S3_AUX_CPU1_NVDIMM @S9S_MB_2U_LIB.S9S_MB_2U(SCH_1):P12V_S3_AUX_CPU1_NVDIMM   I180 @S9S_MB_2U_LIB.S9S_MB_2U(SCH_1):PAGE105
   146 P12V_S3_AUX_CPU1_NVDIMM @S9S_MB_2U_LIB.S9S_MB_2U(SCH_1):P12V_S3_AUX_CPU1_NVDIMM   I180 @S9S_MB_2U_LIB.S9S_MB_2U(SCH_1):PAGE105
   230    GND @S9S_MB_2U_LIB.S9S_MB_2U(SCH_1):GND   I180 @S9S_MB_2U_LIB.S9S_MB_2U(SCH_1):PAGE105
   235    GND @S9S_MB_2U_LIB.S9S_MB_2U(SCH_1):GND   I180 @S9S_MB_2U_LIB.S9S_MB_2U(SCH_1):PAGE105
   240    GND @S9S_MB_2U_LIB.S9S_MB_2U(SCH_1):GND   I180 @S9S_MB_2U_LIB.S9S_MB_2U(SCH_1):PAGE105
   132    GND @S9S_MB_2U_LIB.S9S_MB_2U(SCH_1):GND   I180 @S9S_MB_2U_LIB.S9S_MB_2U(SCH_1):PAGE105
   136    GND @S9S_MB_2U_LIB.S9S_MB_2U(SCH_1):GND   I180 @S9S_MB_2U_LIB.S9S_MB_2U(SCH_1):PAGE105
   139    GND @S9S_MB_2U_LIB.S9S_MB_2U(SCH_1):GND   I180 @S9S_MB_2U_LIB.S9S_MB_2U(SCH_1):PAGE105
   141    GND @S9S_MB_2U_LIB.S9S_MB_2U(SCH_1):GND   I180 @S9S_MB_2U_LIB.S9S_MB_2U(SCH_1):PAGE105
    G1    GND @S9S_MB_2U_LIB.S9S_MB_2U(SCH_1):GND   I180 @S9S_MB_2U_LIB.S9S_MB_2U(SCH_1):PAGE105
    G2    GND @S9S_MB_2U_LIB.S9S_MB_2U(SCH_1):GND   I180 @S9S_MB_2U_LIB.S9S_MB_2U(SCH_1):PAGE105
    G3    GND @S9S_MB_2U_LIB.S9S_MB_2U(SCH_1):GND   I180 @S9S_MB_2U_LIB.S9S_MB_2U(SCH_1):PAGE105

 J25 SCONN288_ADR50017P130CC-SCONN2A
     3 P3V3_AUX @S9S_MB_2U_LIB.S9S_MB_2U(SCH_1):P3V3_AUX   I180 @S9S_MB_2U_LIB.S9S_MB_2U(SCH_1):PAGE106
     2 TP_CHE_CPU1_DIMM1_FRU_0 @S9S_MB_2U_LIB.S9S_MB_2U(SCH_1):TP_CHE_CPU1_DIMM1_FRU_0   I180 @S9S_MB_2U_LIB.S9S_MB_2U(SCH_1):PAGE106
   144 TP_CHE_CPU1_DIMM1_FRU_1 @S9S_MB_2U_LIB.S9S_MB_2U(SCH_1):TP_CHE_CPU1_DIMM1_FRU_1   I180 @S9S_MB_2U_LIB.S9S_MB_2U(SCH_1):PAGE106
   149 TP_CHE_CPU1_DIMM1_FRU_2 @S9S_MB_2U_LIB.S9S_MB_2U(SCH_1):TP_CHE_CPU1_DIMM1_FRU_2   I180 @S9S_MB_2U_LIB.S9S_MB_2U(SCH_1):PAGE106
   150 TP_CHE_CPU1_DIMM1_FRU_3 @S9S_MB_2U_LIB.S9S_MB_2U(SCH_1):TP_CHE_CPU1_DIMM1_FRU_3   I180 @S9S_MB_2U_LIB.S9S_MB_2U(SCH_1):PAGE106
   220 TP_CHE_CPU1_DIMM1_FRU_4 @S9S_MB_2U_LIB.S9S_MB_2U(SCH_1):TP_CHE_CPU1_DIMM1_FRU_4   I180 @S9S_MB_2U_LIB.S9S_MB_2U(SCH_1):PAGE106
   231 TP_CHE_CPU1_DIMM1_FRU_5 @S9S_MB_2U_LIB.S9S_MB_2U(SCH_1):TP_CHE_CPU1_DIMM1_FRU_5   I180 @S9S_MB_2U_LIB.S9S_MB_2U(SCH_1):PAGE106
   232 TP_CHE_CPU1_DIMM1_FRU_6 @S9S_MB_2U_LIB.S9S_MB_2U(SCH_1):TP_CHE_CPU1_DIMM1_FRU_6   I180 @S9S_MB_2U_LIB.S9S_MB_2U(SCH_1):PAGE106
   207 RST_M_EF_CPU1_FPGA_N @S9S_MB_2U_LIB.S9S_MB_2U(SCH_1):RST_M_EF_CPU1_FPGA_N   I180 @S9S_MB_2U_LIB.S9S_MB_2U(SCH_1):PAGE106
   147 PWRGD_CHE_CPU1_DIMM1 @S9S_MB_2U_LIB.S9S_MB_2U(SCH_1):PWRGD_CHE_CPU1_DIMM1   I180 @S9S_MB_2U_LIB.S9S_MB_2U(SCH_1):PAGE106
   227 M_E_CPU1_SB_PAR @S9S_MB_2U_LIB.S9S_MB_2U(SCH_1):M_E_CPU1_SB_PAR   I180 @S9S_MB_2U_LIB.S9S_MB_2U(SCH_1):PAGE106
    74 M_E_CPU1_SA_PAR @S9S_MB_2U_LIB.S9S_MB_2U(SCH_1):M_E_CPU1_SA_PAR   I180 @S9S_MB_2U_LIB.S9S_MB_2U(SCH_1):PAGE106
    87 M_E_CPU1_SB_RSP<0> @S9S_MB_2U_LIB.S9S_MB_2U(SCH_1):M_E_CPU1_SB_RSP(0)   I180 @S9S_MB_2U_LIB.S9S_MB_2U(SCH_1):PAGE106
    86 M_E_CPU1_SA_RSP<0> @S9S_MB_2U_LIB.S9S_MB_2U(SCH_1):M_E_CPU1_SA_RSP(0)   I180 @S9S_MB_2U_LIB.S9S_MB_2U(SCH_1):PAGE106
     5 I3C_SPD_DDREFGH_CPU1_LVC1_SDA @S9S_MB_2U_LIB.S9S_MB_2U(SCH_1):I3C_SPD_DDREFGH_CPU1_LVC1_SDA   I180 @S9S_MB_2U_LIB.S9S_MB_2U(SCH_1):PAGE106
     4 I3C_SPD_DDREFGH_CPU1_LVC1_SCL_R @S9S_MB_2U_LIB.S9S_MB_2U(SCH_1):I3C_SPD_DDREFGH_CPU1_LVC1_SCL_R1   I180 @S9S_MB_2U_LIB.S9S_MB_2U(SCH_1):PAGE106
   148 PD_CHE_CPU1_DIMM1_SAA @S9S_MB_2U_LIB.S9S_MB_2U(SCH_1):PD_CHE_CPU1_DIMM1_SAA   I180 @S9S_MB_2U_LIB.S9S_MB_2U(SCH_1):PAGE106
   100 M_E_CPU1_SB_DQ<0> @S9S_MB_2U_LIB.S9S_MB_2U(SCH_1):M_E_CPU1_SB_DQ(0)   I180 @S9S_MB_2U_LIB.S9S_MB_2U(SCH_1):PAGE106
   102 M_E_CPU1_SB_DQ<1> @S9S_MB_2U_LIB.S9S_MB_2U(SCH_1):M_E_CPU1_SB_DQ(1)   I180 @S9S_MB_2U_LIB.S9S_MB_2U(SCH_1):PAGE106
   245 M_E_CPU1_SB_DQ<2> @S9S_MB_2U_LIB.S9S_MB_2U(SCH_1):M_E_CPU1_SB_DQ(2)   I180 @S9S_MB_2U_LIB.S9S_MB_2U(SCH_1):PAGE106
   247 M_E_CPU1_SB_DQ<3> @S9S_MB_2U_LIB.S9S_MB_2U(SCH_1):M_E_CPU1_SB_DQ(3)   I180 @S9S_MB_2U_LIB.S9S_MB_2U(SCH_1):PAGE106
   107 M_E_CPU1_SB_DQ<4> @S9S_MB_2U_LIB.S9S_MB_2U(SCH_1):M_E_CPU1_SB_DQ(4)   I180 @S9S_MB_2U_LIB.S9S_MB_2U(SCH_1):PAGE106
   109 M_E_CPU1_SB_DQ<5> @S9S_MB_2U_LIB.S9S_MB_2U(SCH_1):M_E_CPU1_SB_DQ(5)   I180 @S9S_MB_2U_LIB.S9S_MB_2U(SCH_1):PAGE106
   252 M_E_CPU1_SB_DQ<6> @S9S_MB_2U_LIB.S9S_MB_2U(SCH_1):M_E_CPU1_SB_DQ(6)   I180 @S9S_MB_2U_LIB.S9S_MB_2U(SCH_1):PAGE106
   254 M_E_CPU1_SB_DQ<7> @S9S_MB_2U_LIB.S9S_MB_2U(SCH_1):M_E_CPU1_SB_DQ(7)   I180 @S9S_MB_2U_LIB.S9S_MB_2U(SCH_1):PAGE106
   111 M_E_CPU1_SB_DQ<8> @S9S_MB_2U_LIB.S9S_MB_2U(SCH_1):M_E_CPU1_SB_DQ(8)   I180 @S9S_MB_2U_LIB.S9S_MB_2U(SCH_1):PAGE106
   113 M_E_CPU1_SB_DQ<9> @S9S_MB_2U_LIB.S9S_MB_2U(SCH_1):M_E_CPU1_SB_DQ(9)   I180 @S9S_MB_2U_LIB.S9S_MB_2U(SCH_1):PAGE106
   256 M_E_CPU1_SB_DQ<10> @S9S_MB_2U_LIB.S9S_MB_2U(SCH_1):M_E_CPU1_SB_DQ(10)   I180 @S9S_MB_2U_LIB.S9S_MB_2U(SCH_1):PAGE106
   258 M_E_CPU1_SB_DQ<11> @S9S_MB_2U_LIB.S9S_MB_2U(SCH_1):M_E_CPU1_SB_DQ(11)   I180 @S9S_MB_2U_LIB.S9S_MB_2U(SCH_1):PAGE106
   118 M_E_CPU1_SB_DQ<12> @S9S_MB_2U_LIB.S9S_MB_2U(SCH_1):M_E_CPU1_SB_DQ(12)   I180 @S9S_MB_2U_LIB.S9S_MB_2U(SCH_1):PAGE106
   120 M_E_CPU1_SB_DQ<13> @S9S_MB_2U_LIB.S9S_MB_2U(SCH_1):M_E_CPU1_SB_DQ(13)   I180 @S9S_MB_2U_LIB.S9S_MB_2U(SCH_1):PAGE106
   263 M_E_CPU1_SB_DQ<14> @S9S_MB_2U_LIB.S9S_MB_2U(SCH_1):M_E_CPU1_SB_DQ(14)   I180 @S9S_MB_2U_LIB.S9S_MB_2U(SCH_1):PAGE106
   265 M_E_CPU1_SB_DQ<15> @S9S_MB_2U_LIB.S9S_MB_2U(SCH_1):M_E_CPU1_SB_DQ(15)   I180 @S9S_MB_2U_LIB.S9S_MB_2U(SCH_1):PAGE106
   122 M_E_CPU1_SB_DQ<16> @S9S_MB_2U_LIB.S9S_MB_2U(SCH_1):M_E_CPU1_SB_DQ(16)   I180 @S9S_MB_2U_LIB.S9S_MB_2U(SCH_1):PAGE106
   124 M_E_CPU1_SB_DQ<17> @S9S_MB_2U_LIB.S9S_MB_2U(SCH_1):M_E_CPU1_SB_DQ(17)   I180 @S9S_MB_2U_LIB.S9S_MB_2U(SCH_1):PAGE106
   267 M_E_CPU1_SB_DQ<18> @S9S_MB_2U_LIB.S9S_MB_2U(SCH_1):M_E_CPU1_SB_DQ(18)   I180 @S9S_MB_2U_LIB.S9S_MB_2U(SCH_1):PAGE106
   269 M_E_CPU1_SB_DQ<19> @S9S_MB_2U_LIB.S9S_MB_2U(SCH_1):M_E_CPU1_SB_DQ(19)   I180 @S9S_MB_2U_LIB.S9S_MB_2U(SCH_1):PAGE106
   129 M_E_CPU1_SB_DQ<20> @S9S_MB_2U_LIB.S9S_MB_2U(SCH_1):M_E_CPU1_SB_DQ(20)   I180 @S9S_MB_2U_LIB.S9S_MB_2U(SCH_1):PAGE106
   131 M_E_CPU1_SB_DQ<21> @S9S_MB_2U_LIB.S9S_MB_2U(SCH_1):M_E_CPU1_SB_DQ(21)   I180 @S9S_MB_2U_LIB.S9S_MB_2U(SCH_1):PAGE106
   274 M_E_CPU1_SB_DQ<22> @S9S_MB_2U_LIB.S9S_MB_2U(SCH_1):M_E_CPU1_SB_DQ(22)   I180 @S9S_MB_2U_LIB.S9S_MB_2U(SCH_1):PAGE106
   276 M_E_CPU1_SB_DQ<23> @S9S_MB_2U_LIB.S9S_MB_2U(SCH_1):M_E_CPU1_SB_DQ(23)   I180 @S9S_MB_2U_LIB.S9S_MB_2U(SCH_1):PAGE106
   133 M_E_CPU1_SB_DQ<24> @S9S_MB_2U_LIB.S9S_MB_2U(SCH_1):M_E_CPU1_SB_DQ(24)   I180 @S9S_MB_2U_LIB.S9S_MB_2U(SCH_1):PAGE106
   135 M_E_CPU1_SB_DQ<25> @S9S_MB_2U_LIB.S9S_MB_2U(SCH_1):M_E_CPU1_SB_DQ(25)   I180 @S9S_MB_2U_LIB.S9S_MB_2U(SCH_1):PAGE106
   278 M_E_CPU1_SB_DQ<26> @S9S_MB_2U_LIB.S9S_MB_2U(SCH_1):M_E_CPU1_SB_DQ(26)   I180 @S9S_MB_2U_LIB.S9S_MB_2U(SCH_1):PAGE106
   280 M_E_CPU1_SB_DQ<27> @S9S_MB_2U_LIB.S9S_MB_2U(SCH_1):M_E_CPU1_SB_DQ(27)   I180 @S9S_MB_2U_LIB.S9S_MB_2U(SCH_1):PAGE106
   140 M_E_CPU1_SB_DQ<28> @S9S_MB_2U_LIB.S9S_MB_2U(SCH_1):M_E_CPU1_SB_DQ(28)   I180 @S9S_MB_2U_LIB.S9S_MB_2U(SCH_1):PAGE106
   142 M_E_CPU1_SB_DQ<29> @S9S_MB_2U_LIB.S9S_MB_2U(SCH_1):M_E_CPU1_SB_DQ(29)   I180 @S9S_MB_2U_LIB.S9S_MB_2U(SCH_1):PAGE106
   285 M_E_CPU1_SB_DQ<30> @S9S_MB_2U_LIB.S9S_MB_2U(SCH_1):M_E_CPU1_SB_DQ(30)   I180 @S9S_MB_2U_LIB.S9S_MB_2U(SCH_1):PAGE106
   287 M_E_CPU1_SB_DQ<31> @S9S_MB_2U_LIB.S9S_MB_2U(SCH_1):M_E_CPU1_SB_DQ(31)   I180 @S9S_MB_2U_LIB.S9S_MB_2U(SCH_1):PAGE106
     7 M_E_CPU1_SA_DQ<0> @S9S_MB_2U_LIB.S9S_MB_2U(SCH_1):M_E_CPU1_SA_DQ(0)   I180 @S9S_MB_2U_LIB.S9S_MB_2U(SCH_1):PAGE106
     9 M_E_CPU1_SA_DQ<1> @S9S_MB_2U_LIB.S9S_MB_2U(SCH_1):M_E_CPU1_SA_DQ(1)   I180 @S9S_MB_2U_LIB.S9S_MB_2U(SCH_1):PAGE106
   152 M_E_CPU1_SA_DQ<2> @S9S_MB_2U_LIB.S9S_MB_2U(SCH_1):M_E_CPU1_SA_DQ(2)   I180 @S9S_MB_2U_LIB.S9S_MB_2U(SCH_1):PAGE106
   154 M_E_CPU1_SA_DQ<3> @S9S_MB_2U_LIB.S9S_MB_2U(SCH_1):M_E_CPU1_SA_DQ(3)   I180 @S9S_MB_2U_LIB.S9S_MB_2U(SCH_1):PAGE106
    14 M_E_CPU1_SA_DQ<4> @S9S_MB_2U_LIB.S9S_MB_2U(SCH_1):M_E_CPU1_SA_DQ(4)   I180 @S9S_MB_2U_LIB.S9S_MB_2U(SCH_1):PAGE106
    16 M_E_CPU1_SA_DQ<5> @S9S_MB_2U_LIB.S9S_MB_2U(SCH_1):M_E_CPU1_SA_DQ(5)   I180 @S9S_MB_2U_LIB.S9S_MB_2U(SCH_1):PAGE106
   159 M_E_CPU1_SA_DQ<6> @S9S_MB_2U_LIB.S9S_MB_2U(SCH_1):M_E_CPU1_SA_DQ(6)   I180 @S9S_MB_2U_LIB.S9S_MB_2U(SCH_1):PAGE106
   161 M_E_CPU1_SA_DQ<7> @S9S_MB_2U_LIB.S9S_MB_2U(SCH_1):M_E_CPU1_SA_DQ(7)   I180 @S9S_MB_2U_LIB.S9S_MB_2U(SCH_1):PAGE106
    18 M_E_CPU1_SA_DQ<8> @S9S_MB_2U_LIB.S9S_MB_2U(SCH_1):M_E_CPU1_SA_DQ(8)   I180 @S9S_MB_2U_LIB.S9S_MB_2U(SCH_1):PAGE106
    20 M_E_CPU1_SA_DQ<9> @S9S_MB_2U_LIB.S9S_MB_2U(SCH_1):M_E_CPU1_SA_DQ(9)   I180 @S9S_MB_2U_LIB.S9S_MB_2U(SCH_1):PAGE106
   163 M_E_CPU1_SA_DQ<10> @S9S_MB_2U_LIB.S9S_MB_2U(SCH_1):M_E_CPU1_SA_DQ(10)   I180 @S9S_MB_2U_LIB.S9S_MB_2U(SCH_1):PAGE106
   165 M_E_CPU1_SA_DQ<11> @S9S_MB_2U_LIB.S9S_MB_2U(SCH_1):M_E_CPU1_SA_DQ(11)   I180 @S9S_MB_2U_LIB.S9S_MB_2U(SCH_1):PAGE106
    25 M_E_CPU1_SA_DQ<12> @S9S_MB_2U_LIB.S9S_MB_2U(SCH_1):M_E_CPU1_SA_DQ(12)   I180 @S9S_MB_2U_LIB.S9S_MB_2U(SCH_1):PAGE106
    27 M_E_CPU1_SA_DQ<13> @S9S_MB_2U_LIB.S9S_MB_2U(SCH_1):M_E_CPU1_SA_DQ(13)   I180 @S9S_MB_2U_LIB.S9S_MB_2U(SCH_1):PAGE106
   170 M_E_CPU1_SA_DQ<14> @S9S_MB_2U_LIB.S9S_MB_2U(SCH_1):M_E_CPU1_SA_DQ(14)   I180 @S9S_MB_2U_LIB.S9S_MB_2U(SCH_1):PAGE106
   172 M_E_CPU1_SA_DQ<15> @S9S_MB_2U_LIB.S9S_MB_2U(SCH_1):M_E_CPU1_SA_DQ(15)   I180 @S9S_MB_2U_LIB.S9S_MB_2U(SCH_1):PAGE106
    29 M_E_CPU1_SA_DQ<16> @S9S_MB_2U_LIB.S9S_MB_2U(SCH_1):M_E_CPU1_SA_DQ(16)   I180 @S9S_MB_2U_LIB.S9S_MB_2U(SCH_1):PAGE106
    31 M_E_CPU1_SA_DQ<17> @S9S_MB_2U_LIB.S9S_MB_2U(SCH_1):M_E_CPU1_SA_DQ(17)   I180 @S9S_MB_2U_LIB.S9S_MB_2U(SCH_1):PAGE106
   174 M_E_CPU1_SA_DQ<18> @S9S_MB_2U_LIB.S9S_MB_2U(SCH_1):M_E_CPU1_SA_DQ(18)   I180 @S9S_MB_2U_LIB.S9S_MB_2U(SCH_1):PAGE106
   176 M_E_CPU1_SA_DQ<19> @S9S_MB_2U_LIB.S9S_MB_2U(SCH_1):M_E_CPU1_SA_DQ(19)   I180 @S9S_MB_2U_LIB.S9S_MB_2U(SCH_1):PAGE106
    36 M_E_CPU1_SA_DQ<20> @S9S_MB_2U_LIB.S9S_MB_2U(SCH_1):M_E_CPU1_SA_DQ(20)   I180 @S9S_MB_2U_LIB.S9S_MB_2U(SCH_1):PAGE106
    38 M_E_CPU1_SA_DQ<21> @S9S_MB_2U_LIB.S9S_MB_2U(SCH_1):M_E_CPU1_SA_DQ(21)   I180 @S9S_MB_2U_LIB.S9S_MB_2U(SCH_1):PAGE106
   181 M_E_CPU1_SA_DQ<22> @S9S_MB_2U_LIB.S9S_MB_2U(SCH_1):M_E_CPU1_SA_DQ(22)   I180 @S9S_MB_2U_LIB.S9S_MB_2U(SCH_1):PAGE106
   183 M_E_CPU1_SA_DQ<23> @S9S_MB_2U_LIB.S9S_MB_2U(SCH_1):M_E_CPU1_SA_DQ(23)   I180 @S9S_MB_2U_LIB.S9S_MB_2U(SCH_1):PAGE106
    40 M_E_CPU1_SA_DQ<24> @S9S_MB_2U_LIB.S9S_MB_2U(SCH_1):M_E_CPU1_SA_DQ(24)   I180 @S9S_MB_2U_LIB.S9S_MB_2U(SCH_1):PAGE106
    42 M_E_CPU1_SA_DQ<25> @S9S_MB_2U_LIB.S9S_MB_2U(SCH_1):M_E_CPU1_SA_DQ(25)   I180 @S9S_MB_2U_LIB.S9S_MB_2U(SCH_1):PAGE106
   185 M_E_CPU1_SA_DQ<26> @S9S_MB_2U_LIB.S9S_MB_2U(SCH_1):M_E_CPU1_SA_DQ(26)   I180 @S9S_MB_2U_LIB.S9S_MB_2U(SCH_1):PAGE106
   187 M_E_CPU1_SA_DQ<27> @S9S_MB_2U_LIB.S9S_MB_2U(SCH_1):M_E_CPU1_SA_DQ(27)   I180 @S9S_MB_2U_LIB.S9S_MB_2U(SCH_1):PAGE106
    47 M_E_CPU1_SA_DQ<28> @S9S_MB_2U_LIB.S9S_MB_2U(SCH_1):M_E_CPU1_SA_DQ(28)   I180 @S9S_MB_2U_LIB.S9S_MB_2U(SCH_1):PAGE106
    49 M_E_CPU1_SA_DQ<29> @S9S_MB_2U_LIB.S9S_MB_2U(SCH_1):M_E_CPU1_SA_DQ(29)   I180 @S9S_MB_2U_LIB.S9S_MB_2U(SCH_1):PAGE106
   192 M_E_CPU1_SA_DQ<30> @S9S_MB_2U_LIB.S9S_MB_2U(SCH_1):M_E_CPU1_SA_DQ(30)   I180 @S9S_MB_2U_LIB.S9S_MB_2U(SCH_1):PAGE106
   229 M_E_CPU1_SB_CS_N<1> @S9S_MB_2U_LIB.S9S_MB_2U(SCH_1):M_E_CPU1_SB_CS_N(1)   I180 @S9S_MB_2U_LIB.S9S_MB_2U(SCH_1):PAGE106
   209 M_E_CPU1_SA_CS_N<1> @S9S_MB_2U_LIB.S9S_MB_2U(SCH_1):M_E_CPU1_SA_CS_N(1)   I180 @S9S_MB_2U_LIB.S9S_MB_2U(SCH_1):PAGE106
    84 M_E_CPU1_SB_CS_N<0> @S9S_MB_2U_LIB.S9S_MB_2U(SCH_1):M_E_CPU1_SB_CS_N(0)   I180 @S9S_MB_2U_LIB.S9S_MB_2U(SCH_1):PAGE106
    64 M_E_CPU1_SA_CS_N<0> @S9S_MB_2U_LIB.S9S_MB_2U(SCH_1):M_E_CPU1_SA_CS_N(0)   I180 @S9S_MB_2U_LIB.S9S_MB_2U(SCH_1):PAGE106
   217 M_E_CPU1_CLK_DP<0> @S9S_MB_2U_LIB.S9S_MB_2U(SCH_1):M_E_CPU1_CLK_DP(0)   I180 @S9S_MB_2U_LIB.S9S_MB_2U(SCH_1):PAGE106
   218 M_E_CPU1_CLK_DN<0> @S9S_MB_2U_LIB.S9S_MB_2U(SCH_1):M_E_CPU1_CLK_DN(0)   I180 @S9S_MB_2U_LIB.S9S_MB_2U(SCH_1):PAGE106
    96 M_E_CPU1_SB_CB<0> @S9S_MB_2U_LIB.S9S_MB_2U(SCH_1):M_E_CPU1_SB_CB(0)   I180 @S9S_MB_2U_LIB.S9S_MB_2U(SCH_1):PAGE106
    98 M_E_CPU1_SB_CB<1> @S9S_MB_2U_LIB.S9S_MB_2U(SCH_1):M_E_CPU1_SB_CB(1)   I180 @S9S_MB_2U_LIB.S9S_MB_2U(SCH_1):PAGE106
   241 M_E_CPU1_SB_CB<2> @S9S_MB_2U_LIB.S9S_MB_2U(SCH_1):M_E_CPU1_SB_CB(2)   I180 @S9S_MB_2U_LIB.S9S_MB_2U(SCH_1):PAGE106
   243 M_E_CPU1_SB_CB<3> @S9S_MB_2U_LIB.S9S_MB_2U(SCH_1):M_E_CPU1_SB_CB(3)   I180 @S9S_MB_2U_LIB.S9S_MB_2U(SCH_1):PAGE106
    89 M_E_CPU1_SB_CB<4> @S9S_MB_2U_LIB.S9S_MB_2U(SCH_1):M_E_CPU1_SB_CB(4)   I180 @S9S_MB_2U_LIB.S9S_MB_2U(SCH_1):PAGE106
    91 M_E_CPU1_SB_CB<5> @S9S_MB_2U_LIB.S9S_MB_2U(SCH_1):M_E_CPU1_SB_CB(5)   I180 @S9S_MB_2U_LIB.S9S_MB_2U(SCH_1):PAGE106
   234 M_E_CPU1_SB_CB<6> @S9S_MB_2U_LIB.S9S_MB_2U(SCH_1):M_E_CPU1_SB_CB(6)   I180 @S9S_MB_2U_LIB.S9S_MB_2U(SCH_1):PAGE106
    51 M_E_CPU1_SA_CB<0> @S9S_MB_2U_LIB.S9S_MB_2U(SCH_1):M_E_CPU1_SA_CB(0)   I180 @S9S_MB_2U_LIB.S9S_MB_2U(SCH_1):PAGE106
   196 M_E_CPU1_SA_CB<2> @S9S_MB_2U_LIB.S9S_MB_2U(SCH_1):M_E_CPU1_SA_CB(2)   I180 @S9S_MB_2U_LIB.S9S_MB_2U(SCH_1):PAGE106
   198 M_E_CPU1_SA_CB<3> @S9S_MB_2U_LIB.S9S_MB_2U(SCH_1):M_E_CPU1_SA_CB(3)   I180 @S9S_MB_2U_LIB.S9S_MB_2U(SCH_1):PAGE106
    60 M_E_CPU1_SA_CB<5> @S9S_MB_2U_LIB.S9S_MB_2U(SCH_1):M_E_CPU1_SA_CB(5)   I180 @S9S_MB_2U_LIB.S9S_MB_2U(SCH_1):PAGE106
   203 M_E_CPU1_SA_CB<6> @S9S_MB_2U_LIB.S9S_MB_2U(SCH_1):M_E_CPU1_SA_CB(6)   I180 @S9S_MB_2U_LIB.S9S_MB_2U(SCH_1):PAGE106
    82 M_E_CPU1_SB_CA<6> @S9S_MB_2U_LIB.S9S_MB_2U(SCH_1):M_E_CPU1_SB_CA(6)   I180 @S9S_MB_2U_LIB.S9S_MB_2U(SCH_1):PAGE106
    72 M_E_CPU1_SA_CA<6> @S9S_MB_2U_LIB.S9S_MB_2U(SCH_1):M_E_CPU1_SA_CA(6)   I180 @S9S_MB_2U_LIB.S9S_MB_2U(SCH_1):PAGE106
   225 M_E_CPU1_SB_CA<5> @S9S_MB_2U_LIB.S9S_MB_2U(SCH_1):M_E_CPU1_SB_CA(5)   I180 @S9S_MB_2U_LIB.S9S_MB_2U(SCH_1):PAGE106
   215 M_E_CPU1_SA_CA<5> @S9S_MB_2U_LIB.S9S_MB_2U(SCH_1):M_E_CPU1_SA_CA(5)   I180 @S9S_MB_2U_LIB.S9S_MB_2U(SCH_1):PAGE106
    80 M_E_CPU1_SB_CA<4> @S9S_MB_2U_LIB.S9S_MB_2U(SCH_1):M_E_CPU1_SB_CA(4)   I180 @S9S_MB_2U_LIB.S9S_MB_2U(SCH_1):PAGE106
    70 M_E_CPU1_SA_CA<4> @S9S_MB_2U_LIB.S9S_MB_2U(SCH_1):M_E_CPU1_SA_CA(4)   I180 @S9S_MB_2U_LIB.S9S_MB_2U(SCH_1):PAGE106
   223 M_E_CPU1_SB_CA<3> @S9S_MB_2U_LIB.S9S_MB_2U(SCH_1):M_E_CPU1_SB_CA(3)   I180 @S9S_MB_2U_LIB.S9S_MB_2U(SCH_1):PAGE106
   213 M_E_CPU1_SA_CA<3> @S9S_MB_2U_LIB.S9S_MB_2U(SCH_1):M_E_CPU1_SA_CA(3)   I180 @S9S_MB_2U_LIB.S9S_MB_2U(SCH_1):PAGE106
    78 M_E_CPU1_SB_CA<2> @S9S_MB_2U_LIB.S9S_MB_2U(SCH_1):M_E_CPU1_SB_CA(2)   I180 @S9S_MB_2U_LIB.S9S_MB_2U(SCH_1):PAGE106
    68 M_E_CPU1_SA_CA<2> @S9S_MB_2U_LIB.S9S_MB_2U(SCH_1):M_E_CPU1_SA_CA(2)   I180 @S9S_MB_2U_LIB.S9S_MB_2U(SCH_1):PAGE106
   221 M_E_CPU1_SB_CA<1> @S9S_MB_2U_LIB.S9S_MB_2U(SCH_1):M_E_CPU1_SB_CA(1)   I180 @S9S_MB_2U_LIB.S9S_MB_2U(SCH_1):PAGE106
   211 M_E_CPU1_SA_CA<1> @S9S_MB_2U_LIB.S9S_MB_2U(SCH_1):M_E_CPU1_SA_CA(1)   I180 @S9S_MB_2U_LIB.S9S_MB_2U(SCH_1):PAGE106
    76 M_E_CPU1_SB_CA<0> @S9S_MB_2U_LIB.S9S_MB_2U(SCH_1):M_E_CPU1_SB_CA(0)   I180 @S9S_MB_2U_LIB.S9S_MB_2U(SCH_1):PAGE106
    66 M_E_CPU1_SA_CA<0> @S9S_MB_2U_LIB.S9S_MB_2U(SCH_1):M_E_CPU1_SA_CA(0)   I180 @S9S_MB_2U_LIB.S9S_MB_2U(SCH_1):PAGE106
    62 M_E_CPU1_ALERT_N @S9S_MB_2U_LIB.S9S_MB_2U(SCH_1):M_E_CPU1_ALERT_N   I180 @S9S_MB_2U_LIB.S9S_MB_2U(SCH_1):PAGE106
   236 M_E_CPU1_SB_CB<7> @S9S_MB_2U_LIB.S9S_MB_2U(SCH_1):M_E_CPU1_SB_CB(7)   I180 @S9S_MB_2U_LIB.S9S_MB_2U(SCH_1):PAGE106
    53 M_E_CPU1_SA_CB<1> @S9S_MB_2U_LIB.S9S_MB_2U(SCH_1):M_E_CPU1_SA_CB(1)   I180 @S9S_MB_2U_LIB.S9S_MB_2U(SCH_1):PAGE106
    58 M_E_CPU1_SA_CB<4> @S9S_MB_2U_LIB.S9S_MB_2U(SCH_1):M_E_CPU1_SA_CB(4)   I180 @S9S_MB_2U_LIB.S9S_MB_2U(SCH_1):PAGE106
   205 M_E_CPU1_SA_CB<7> @S9S_MB_2U_LIB.S9S_MB_2U(SCH_1):M_E_CPU1_SA_CB(7)   I180 @S9S_MB_2U_LIB.S9S_MB_2U(SCH_1):PAGE106
   194 M_E_CPU1_SA_DQ<31> @S9S_MB_2U_LIB.S9S_MB_2U(SCH_1):M_E_CPU1_SA_DQ(31)   I180 @S9S_MB_2U_LIB.S9S_MB_2U(SCH_1):PAGE106
    93 M_E_CPU1_SB_DQS_DP<9> @S9S_MB_2U_LIB.S9S_MB_2U(SCH_1):M_E_CPU1_SB_DQS_DP(9)   I181 @S9S_MB_2U_LIB.S9S_MB_2U(SCH_1):PAGE106
    94 M_E_CPU1_SB_DQS_DN<9> @S9S_MB_2U_LIB.S9S_MB_2U(SCH_1):M_E_CPU1_SB_DQS_DN(9)   I181 @S9S_MB_2U_LIB.S9S_MB_2U(SCH_1):PAGE106
   201 M_E_CPU1_SA_DQS_DP<9> @S9S_MB_2U_LIB.S9S_MB_2U(SCH_1):M_E_CPU1_SA_DQS_DP(9)   I181 @S9S_MB_2U_LIB.S9S_MB_2U(SCH_1):PAGE106
   200 M_E_CPU1_SA_DQS_DN<9> @S9S_MB_2U_LIB.S9S_MB_2U(SCH_1):M_E_CPU1_SA_DQS_DN(9)   I181 @S9S_MB_2U_LIB.S9S_MB_2U(SCH_1):PAGE106
   190 M_E_CPU1_SA_DQS_DP<8> @S9S_MB_2U_LIB.S9S_MB_2U(SCH_1):M_E_CPU1_SA_DQS_DP(8)   I181 @S9S_MB_2U_LIB.S9S_MB_2U(SCH_1):PAGE106
   189 M_E_CPU1_SA_DQS_DN<8> @S9S_MB_2U_LIB.S9S_MB_2U(SCH_1):M_E_CPU1_SA_DQS_DN(8)   I181 @S9S_MB_2U_LIB.S9S_MB_2U(SCH_1):PAGE106
   271 M_E_CPU1_SB_DQS_DN<7> @S9S_MB_2U_LIB.S9S_MB_2U(SCH_1):M_E_CPU1_SB_DQS_DN(7)   I181 @S9S_MB_2U_LIB.S9S_MB_2U(SCH_1):PAGE106
   179 M_E_CPU1_SA_DQS_DP<7> @S9S_MB_2U_LIB.S9S_MB_2U(SCH_1):M_E_CPU1_SA_DQS_DP(7)   I181 @S9S_MB_2U_LIB.S9S_MB_2U(SCH_1):PAGE106
   261 M_E_CPU1_SB_DQS_DP<6> @S9S_MB_2U_LIB.S9S_MB_2U(SCH_1):M_E_CPU1_SB_DQS_DP(6)   I181 @S9S_MB_2U_LIB.S9S_MB_2U(SCH_1):PAGE106
   260 M_E_CPU1_SB_DQS_DN<6> @S9S_MB_2U_LIB.S9S_MB_2U(SCH_1):M_E_CPU1_SB_DQS_DN(6)   I181 @S9S_MB_2U_LIB.S9S_MB_2U(SCH_1):PAGE106
   167 M_E_CPU1_SA_DQS_DN<6> @S9S_MB_2U_LIB.S9S_MB_2U(SCH_1):M_E_CPU1_SA_DQS_DN(6)   I181 @S9S_MB_2U_LIB.S9S_MB_2U(SCH_1):PAGE106
   250 M_E_CPU1_SB_DQS_DP<5> @S9S_MB_2U_LIB.S9S_MB_2U(SCH_1):M_E_CPU1_SB_DQS_DP(5)   I181 @S9S_MB_2U_LIB.S9S_MB_2U(SCH_1):PAGE106
   249 M_E_CPU1_SB_DQS_DN<5> @S9S_MB_2U_LIB.S9S_MB_2U(SCH_1):M_E_CPU1_SB_DQS_DN(5)   I181 @S9S_MB_2U_LIB.S9S_MB_2U(SCH_1):PAGE106
   157 M_E_CPU1_SA_DQS_DP<5> @S9S_MB_2U_LIB.S9S_MB_2U(SCH_1):M_E_CPU1_SA_DQS_DP(5)   I181 @S9S_MB_2U_LIB.S9S_MB_2U(SCH_1):PAGE106
   156 M_E_CPU1_SA_DQS_DN<5> @S9S_MB_2U_LIB.S9S_MB_2U(SCH_1):M_E_CPU1_SA_DQS_DN(5)   I181 @S9S_MB_2U_LIB.S9S_MB_2U(SCH_1):PAGE106
   239 M_E_CPU1_SB_DQS_DP<4> @S9S_MB_2U_LIB.S9S_MB_2U(SCH_1):M_E_CPU1_SB_DQS_DP(4)   I181 @S9S_MB_2U_LIB.S9S_MB_2U(SCH_1):PAGE106
   238 M_E_CPU1_SB_DQS_DN<4> @S9S_MB_2U_LIB.S9S_MB_2U(SCH_1):M_E_CPU1_SB_DQS_DN(4)   I181 @S9S_MB_2U_LIB.S9S_MB_2U(SCH_1):PAGE106
    55 M_E_CPU1_SA_DQS_DP<4> @S9S_MB_2U_LIB.S9S_MB_2U(SCH_1):M_E_CPU1_SA_DQS_DP(4)   I181 @S9S_MB_2U_LIB.S9S_MB_2U(SCH_1):PAGE106
    56 M_E_CPU1_SA_DQS_DN<4> @S9S_MB_2U_LIB.S9S_MB_2U(SCH_1):M_E_CPU1_SA_DQS_DN(4)   I181 @S9S_MB_2U_LIB.S9S_MB_2U(SCH_1):PAGE106
   137 M_E_CPU1_SB_DQS_DP<3> @S9S_MB_2U_LIB.S9S_MB_2U(SCH_1):M_E_CPU1_SB_DQS_DP(3)   I181 @S9S_MB_2U_LIB.S9S_MB_2U(SCH_1):PAGE106
   138 M_E_CPU1_SB_DQS_DN<3> @S9S_MB_2U_LIB.S9S_MB_2U(SCH_1):M_E_CPU1_SB_DQS_DN(3)   I181 @S9S_MB_2U_LIB.S9S_MB_2U(SCH_1):PAGE106
    44 M_E_CPU1_SA_DQS_DP<3> @S9S_MB_2U_LIB.S9S_MB_2U(SCH_1):M_E_CPU1_SA_DQS_DP(3)   I181 @S9S_MB_2U_LIB.S9S_MB_2U(SCH_1):PAGE106
    45 M_E_CPU1_SA_DQS_DN<3> @S9S_MB_2U_LIB.S9S_MB_2U(SCH_1):M_E_CPU1_SA_DQS_DN(3)   I181 @S9S_MB_2U_LIB.S9S_MB_2U(SCH_1):PAGE106
   126 M_E_CPU1_SB_DQS_DP<2> @S9S_MB_2U_LIB.S9S_MB_2U(SCH_1):M_E_CPU1_SB_DQS_DP(2)   I181 @S9S_MB_2U_LIB.S9S_MB_2U(SCH_1):PAGE106
   127 M_E_CPU1_SB_DQS_DN<2> @S9S_MB_2U_LIB.S9S_MB_2U(SCH_1):M_E_CPU1_SB_DQS_DN(2)   I181 @S9S_MB_2U_LIB.S9S_MB_2U(SCH_1):PAGE106
    33 M_E_CPU1_SA_DQS_DP<2> @S9S_MB_2U_LIB.S9S_MB_2U(SCH_1):M_E_CPU1_SA_DQS_DP(2)   I181 @S9S_MB_2U_LIB.S9S_MB_2U(SCH_1):PAGE106
    34 M_E_CPU1_SA_DQS_DN<2> @S9S_MB_2U_LIB.S9S_MB_2U(SCH_1):M_E_CPU1_SA_DQS_DN(2)   I181 @S9S_MB_2U_LIB.S9S_MB_2U(SCH_1):PAGE106
   115 M_E_CPU1_SB_DQS_DP<1> @S9S_MB_2U_LIB.S9S_MB_2U(SCH_1):M_E_CPU1_SB_DQS_DP(1)   I181 @S9S_MB_2U_LIB.S9S_MB_2U(SCH_1):PAGE106
   116 M_E_CPU1_SB_DQS_DN<1> @S9S_MB_2U_LIB.S9S_MB_2U(SCH_1):M_E_CPU1_SB_DQS_DN(1)   I181 @S9S_MB_2U_LIB.S9S_MB_2U(SCH_1):PAGE106
    22 M_E_CPU1_SA_DQS_DP<1> @S9S_MB_2U_LIB.S9S_MB_2U(SCH_1):M_E_CPU1_SA_DQS_DP(1)   I181 @S9S_MB_2U_LIB.S9S_MB_2U(SCH_1):PAGE106
    23 M_E_CPU1_SA_DQS_DN<1> @S9S_MB_2U_LIB.S9S_MB_2U(SCH_1):M_E_CPU1_SA_DQS_DN(1)   I181 @S9S_MB_2U_LIB.S9S_MB_2U(SCH_1):PAGE106
   104 M_E_CPU1_SB_DQS_DP<0> @S9S_MB_2U_LIB.S9S_MB_2U(SCH_1):M_E_CPU1_SB_DQS_DP(0)   I181 @S9S_MB_2U_LIB.S9S_MB_2U(SCH_1):PAGE106
   105 M_E_CPU1_SB_DQS_DN<0> @S9S_MB_2U_LIB.S9S_MB_2U(SCH_1):M_E_CPU1_SB_DQS_DN(0)   I181 @S9S_MB_2U_LIB.S9S_MB_2U(SCH_1):PAGE106
    11 M_E_CPU1_SA_DQS_DP<0> @S9S_MB_2U_LIB.S9S_MB_2U(SCH_1):M_E_CPU1_SA_DQS_DP(0)   I181 @S9S_MB_2U_LIB.S9S_MB_2U(SCH_1):PAGE106
    12 M_E_CPU1_SA_DQS_DN<0> @S9S_MB_2U_LIB.S9S_MB_2U(SCH_1):M_E_CPU1_SA_DQS_DN(0)   I181 @S9S_MB_2U_LIB.S9S_MB_2U(SCH_1):PAGE106
   272 M_E_CPU1_SB_DQS_DP<7> @S9S_MB_2U_LIB.S9S_MB_2U(SCH_1):M_E_CPU1_SB_DQS_DP(7)   I181 @S9S_MB_2U_LIB.S9S_MB_2U(SCH_1):PAGE106
   282 M_E_CPU1_SB_DQS_DN<8> @S9S_MB_2U_LIB.S9S_MB_2U(SCH_1):M_E_CPU1_SB_DQS_DN(8)   I181 @S9S_MB_2U_LIB.S9S_MB_2U(SCH_1):PAGE106
   283 M_E_CPU1_SB_DQS_DP<8> @S9S_MB_2U_LIB.S9S_MB_2U(SCH_1):M_E_CPU1_SB_DQS_DP(8)   I181 @S9S_MB_2U_LIB.S9S_MB_2U(SCH_1):PAGE106
   168 M_E_CPU1_SA_DQS_DP<6> @S9S_MB_2U_LIB.S9S_MB_2U(SCH_1):M_E_CPU1_SA_DQS_DP(6)   I181 @S9S_MB_2U_LIB.S9S_MB_2U(SCH_1):PAGE106
   178 M_E_CPU1_SA_DQS_DN<7> @S9S_MB_2U_LIB.S9S_MB_2U(SCH_1):M_E_CPU1_SA_DQS_DN(7)   I181 @S9S_MB_2U_LIB.S9S_MB_2U(SCH_1):PAGE106
     6    GND @S9S_MB_2U_LIB.S9S_MB_2U(SCH_1):GND   I178 @S9S_MB_2U_LIB.S9S_MB_2U(SCH_1):PAGE106
     8    GND @S9S_MB_2U_LIB.S9S_MB_2U(SCH_1):GND   I178 @S9S_MB_2U_LIB.S9S_MB_2U(SCH_1):PAGE106
    10    GND @S9S_MB_2U_LIB.S9S_MB_2U(SCH_1):GND   I178 @S9S_MB_2U_LIB.S9S_MB_2U(SCH_1):PAGE106
    13    GND @S9S_MB_2U_LIB.S9S_MB_2U(SCH_1):GND   I178 @S9S_MB_2U_LIB.S9S_MB_2U(SCH_1):PAGE106
    15    GND @S9S_MB_2U_LIB.S9S_MB_2U(SCH_1):GND   I178 @S9S_MB_2U_LIB.S9S_MB_2U(SCH_1):PAGE106
    17    GND @S9S_MB_2U_LIB.S9S_MB_2U(SCH_1):GND   I178 @S9S_MB_2U_LIB.S9S_MB_2U(SCH_1):PAGE106
    19    GND @S9S_MB_2U_LIB.S9S_MB_2U(SCH_1):GND   I178 @S9S_MB_2U_LIB.S9S_MB_2U(SCH_1):PAGE106
    21    GND @S9S_MB_2U_LIB.S9S_MB_2U(SCH_1):GND   I178 @S9S_MB_2U_LIB.S9S_MB_2U(SCH_1):PAGE106
    24    GND @S9S_MB_2U_LIB.S9S_MB_2U(SCH_1):GND   I178 @S9S_MB_2U_LIB.S9S_MB_2U(SCH_1):PAGE106
    26    GND @S9S_MB_2U_LIB.S9S_MB_2U(SCH_1):GND   I178 @S9S_MB_2U_LIB.S9S_MB_2U(SCH_1):PAGE106
    28    GND @S9S_MB_2U_LIB.S9S_MB_2U(SCH_1):GND   I178 @S9S_MB_2U_LIB.S9S_MB_2U(SCH_1):PAGE106
    30    GND @S9S_MB_2U_LIB.S9S_MB_2U(SCH_1):GND   I178 @S9S_MB_2U_LIB.S9S_MB_2U(SCH_1):PAGE106
    32    GND @S9S_MB_2U_LIB.S9S_MB_2U(SCH_1):GND   I178 @S9S_MB_2U_LIB.S9S_MB_2U(SCH_1):PAGE106
    35    GND @S9S_MB_2U_LIB.S9S_MB_2U(SCH_1):GND   I178 @S9S_MB_2U_LIB.S9S_MB_2U(SCH_1):PAGE106
    37    GND @S9S_MB_2U_LIB.S9S_MB_2U(SCH_1):GND   I178 @S9S_MB_2U_LIB.S9S_MB_2U(SCH_1):PAGE106
    39    GND @S9S_MB_2U_LIB.S9S_MB_2U(SCH_1):GND   I178 @S9S_MB_2U_LIB.S9S_MB_2U(SCH_1):PAGE106
    41    GND @S9S_MB_2U_LIB.S9S_MB_2U(SCH_1):GND   I178 @S9S_MB_2U_LIB.S9S_MB_2U(SCH_1):PAGE106
    43    GND @S9S_MB_2U_LIB.S9S_MB_2U(SCH_1):GND   I178 @S9S_MB_2U_LIB.S9S_MB_2U(SCH_1):PAGE106
    46    GND @S9S_MB_2U_LIB.S9S_MB_2U(SCH_1):GND   I178 @S9S_MB_2U_LIB.S9S_MB_2U(SCH_1):PAGE106
    48    GND @S9S_MB_2U_LIB.S9S_MB_2U(SCH_1):GND   I178 @S9S_MB_2U_LIB.S9S_MB_2U(SCH_1):PAGE106
    50    GND @S9S_MB_2U_LIB.S9S_MB_2U(SCH_1):GND   I178 @S9S_MB_2U_LIB.S9S_MB_2U(SCH_1):PAGE106
    52    GND @S9S_MB_2U_LIB.S9S_MB_2U(SCH_1):GND   I178 @S9S_MB_2U_LIB.S9S_MB_2U(SCH_1):PAGE106
    54    GND @S9S_MB_2U_LIB.S9S_MB_2U(SCH_1):GND   I178 @S9S_MB_2U_LIB.S9S_MB_2U(SCH_1):PAGE106
    57    GND @S9S_MB_2U_LIB.S9S_MB_2U(SCH_1):GND   I178 @S9S_MB_2U_LIB.S9S_MB_2U(SCH_1):PAGE106
    59    GND @S9S_MB_2U_LIB.S9S_MB_2U(SCH_1):GND   I178 @S9S_MB_2U_LIB.S9S_MB_2U(SCH_1):PAGE106
    61    GND @S9S_MB_2U_LIB.S9S_MB_2U(SCH_1):GND   I178 @S9S_MB_2U_LIB.S9S_MB_2U(SCH_1):PAGE106
    63    GND @S9S_MB_2U_LIB.S9S_MB_2U(SCH_1):GND   I178 @S9S_MB_2U_LIB.S9S_MB_2U(SCH_1):PAGE106
    65    GND @S9S_MB_2U_LIB.S9S_MB_2U(SCH_1):GND   I178 @S9S_MB_2U_LIB.S9S_MB_2U(SCH_1):PAGE106
    67    GND @S9S_MB_2U_LIB.S9S_MB_2U(SCH_1):GND   I178 @S9S_MB_2U_LIB.S9S_MB_2U(SCH_1):PAGE106
    69    GND @S9S_MB_2U_LIB.S9S_MB_2U(SCH_1):GND   I178 @S9S_MB_2U_LIB.S9S_MB_2U(SCH_1):PAGE106
    71    GND @S9S_MB_2U_LIB.S9S_MB_2U(SCH_1):GND   I178 @S9S_MB_2U_LIB.S9S_MB_2U(SCH_1):PAGE106
    73    GND @S9S_MB_2U_LIB.S9S_MB_2U(SCH_1):GND   I178 @S9S_MB_2U_LIB.S9S_MB_2U(SCH_1):PAGE106
    75    GND @S9S_MB_2U_LIB.S9S_MB_2U(SCH_1):GND   I178 @S9S_MB_2U_LIB.S9S_MB_2U(SCH_1):PAGE106
    77    GND @S9S_MB_2U_LIB.S9S_MB_2U(SCH_1):GND   I178 @S9S_MB_2U_LIB.S9S_MB_2U(SCH_1):PAGE106
    79    GND @S9S_MB_2U_LIB.S9S_MB_2U(SCH_1):GND   I178 @S9S_MB_2U_LIB.S9S_MB_2U(SCH_1):PAGE106
    81    GND @S9S_MB_2U_LIB.S9S_MB_2U(SCH_1):GND   I178 @S9S_MB_2U_LIB.S9S_MB_2U(SCH_1):PAGE106
    83    GND @S9S_MB_2U_LIB.S9S_MB_2U(SCH_1):GND   I178 @S9S_MB_2U_LIB.S9S_MB_2U(SCH_1):PAGE106
    85    GND @S9S_MB_2U_LIB.S9S_MB_2U(SCH_1):GND   I178 @S9S_MB_2U_LIB.S9S_MB_2U(SCH_1):PAGE106
    88    GND @S9S_MB_2U_LIB.S9S_MB_2U(SCH_1):GND   I178 @S9S_MB_2U_LIB.S9S_MB_2U(SCH_1):PAGE106
    90    GND @S9S_MB_2U_LIB.S9S_MB_2U(SCH_1):GND   I178 @S9S_MB_2U_LIB.S9S_MB_2U(SCH_1):PAGE106
    92    GND @S9S_MB_2U_LIB.S9S_MB_2U(SCH_1):GND   I178 @S9S_MB_2U_LIB.S9S_MB_2U(SCH_1):PAGE106
    95    GND @S9S_MB_2U_LIB.S9S_MB_2U(SCH_1):GND   I178 @S9S_MB_2U_LIB.S9S_MB_2U(SCH_1):PAGE106
    97    GND @S9S_MB_2U_LIB.S9S_MB_2U(SCH_1):GND   I178 @S9S_MB_2U_LIB.S9S_MB_2U(SCH_1):PAGE106
    99    GND @S9S_MB_2U_LIB.S9S_MB_2U(SCH_1):GND   I178 @S9S_MB_2U_LIB.S9S_MB_2U(SCH_1):PAGE106
   101    GND @S9S_MB_2U_LIB.S9S_MB_2U(SCH_1):GND   I178 @S9S_MB_2U_LIB.S9S_MB_2U(SCH_1):PAGE106
   103    GND @S9S_MB_2U_LIB.S9S_MB_2U(SCH_1):GND   I178 @S9S_MB_2U_LIB.S9S_MB_2U(SCH_1):PAGE106
   106    GND @S9S_MB_2U_LIB.S9S_MB_2U(SCH_1):GND   I178 @S9S_MB_2U_LIB.S9S_MB_2U(SCH_1):PAGE106
   108    GND @S9S_MB_2U_LIB.S9S_MB_2U(SCH_1):GND   I178 @S9S_MB_2U_LIB.S9S_MB_2U(SCH_1):PAGE106
   110    GND @S9S_MB_2U_LIB.S9S_MB_2U(SCH_1):GND   I178 @S9S_MB_2U_LIB.S9S_MB_2U(SCH_1):PAGE106
   112    GND @S9S_MB_2U_LIB.S9S_MB_2U(SCH_1):GND   I178 @S9S_MB_2U_LIB.S9S_MB_2U(SCH_1):PAGE106
   114    GND @S9S_MB_2U_LIB.S9S_MB_2U(SCH_1):GND   I178 @S9S_MB_2U_LIB.S9S_MB_2U(SCH_1):PAGE106
   117    GND @S9S_MB_2U_LIB.S9S_MB_2U(SCH_1):GND   I178 @S9S_MB_2U_LIB.S9S_MB_2U(SCH_1):PAGE106
   119    GND @S9S_MB_2U_LIB.S9S_MB_2U(SCH_1):GND   I178 @S9S_MB_2U_LIB.S9S_MB_2U(SCH_1):PAGE106
   121    GND @S9S_MB_2U_LIB.S9S_MB_2U(SCH_1):GND   I178 @S9S_MB_2U_LIB.S9S_MB_2U(SCH_1):PAGE106
   123    GND @S9S_MB_2U_LIB.S9S_MB_2U(SCH_1):GND   I178 @S9S_MB_2U_LIB.S9S_MB_2U(SCH_1):PAGE106
   125    GND @S9S_MB_2U_LIB.S9S_MB_2U(SCH_1):GND   I178 @S9S_MB_2U_LIB.S9S_MB_2U(SCH_1):PAGE106
   128    GND @S9S_MB_2U_LIB.S9S_MB_2U(SCH_1):GND   I178 @S9S_MB_2U_LIB.S9S_MB_2U(SCH_1):PAGE106
   130    GND @S9S_MB_2U_LIB.S9S_MB_2U(SCH_1):GND   I178 @S9S_MB_2U_LIB.S9S_MB_2U(SCH_1):PAGE106
   134    GND @S9S_MB_2U_LIB.S9S_MB_2U(SCH_1):GND   I178 @S9S_MB_2U_LIB.S9S_MB_2U(SCH_1):PAGE106
   143    GND @S9S_MB_2U_LIB.S9S_MB_2U(SCH_1):GND   I178 @S9S_MB_2U_LIB.S9S_MB_2U(SCH_1):PAGE106
   151    GND @S9S_MB_2U_LIB.S9S_MB_2U(SCH_1):GND   I178 @S9S_MB_2U_LIB.S9S_MB_2U(SCH_1):PAGE106
   153    GND @S9S_MB_2U_LIB.S9S_MB_2U(SCH_1):GND   I178 @S9S_MB_2U_LIB.S9S_MB_2U(SCH_1):PAGE106
   155    GND @S9S_MB_2U_LIB.S9S_MB_2U(SCH_1):GND   I178 @S9S_MB_2U_LIB.S9S_MB_2U(SCH_1):PAGE106
   158    GND @S9S_MB_2U_LIB.S9S_MB_2U(SCH_1):GND   I178 @S9S_MB_2U_LIB.S9S_MB_2U(SCH_1):PAGE106
   160    GND @S9S_MB_2U_LIB.S9S_MB_2U(SCH_1):GND   I178 @S9S_MB_2U_LIB.S9S_MB_2U(SCH_1):PAGE106
   162    GND @S9S_MB_2U_LIB.S9S_MB_2U(SCH_1):GND   I178 @S9S_MB_2U_LIB.S9S_MB_2U(SCH_1):PAGE106
   164    GND @S9S_MB_2U_LIB.S9S_MB_2U(SCH_1):GND   I178 @S9S_MB_2U_LIB.S9S_MB_2U(SCH_1):PAGE106
   166    GND @S9S_MB_2U_LIB.S9S_MB_2U(SCH_1):GND   I178 @S9S_MB_2U_LIB.S9S_MB_2U(SCH_1):PAGE106
   169    GND @S9S_MB_2U_LIB.S9S_MB_2U(SCH_1):GND   I178 @S9S_MB_2U_LIB.S9S_MB_2U(SCH_1):PAGE106
   171    GND @S9S_MB_2U_LIB.S9S_MB_2U(SCH_1):GND   I178 @S9S_MB_2U_LIB.S9S_MB_2U(SCH_1):PAGE106
   173    GND @S9S_MB_2U_LIB.S9S_MB_2U(SCH_1):GND   I178 @S9S_MB_2U_LIB.S9S_MB_2U(SCH_1):PAGE106
   175    GND @S9S_MB_2U_LIB.S9S_MB_2U(SCH_1):GND   I178 @S9S_MB_2U_LIB.S9S_MB_2U(SCH_1):PAGE106
   177    GND @S9S_MB_2U_LIB.S9S_MB_2U(SCH_1):GND   I178 @S9S_MB_2U_LIB.S9S_MB_2U(SCH_1):PAGE106
   180    GND @S9S_MB_2U_LIB.S9S_MB_2U(SCH_1):GND   I178 @S9S_MB_2U_LIB.S9S_MB_2U(SCH_1):PAGE106
   182    GND @S9S_MB_2U_LIB.S9S_MB_2U(SCH_1):GND   I178 @S9S_MB_2U_LIB.S9S_MB_2U(SCH_1):PAGE106
   184    GND @S9S_MB_2U_LIB.S9S_MB_2U(SCH_1):GND   I178 @S9S_MB_2U_LIB.S9S_MB_2U(SCH_1):PAGE106
   186    GND @S9S_MB_2U_LIB.S9S_MB_2U(SCH_1):GND   I178 @S9S_MB_2U_LIB.S9S_MB_2U(SCH_1):PAGE106
   188    GND @S9S_MB_2U_LIB.S9S_MB_2U(SCH_1):GND   I178 @S9S_MB_2U_LIB.S9S_MB_2U(SCH_1):PAGE106
   191    GND @S9S_MB_2U_LIB.S9S_MB_2U(SCH_1):GND   I178 @S9S_MB_2U_LIB.S9S_MB_2U(SCH_1):PAGE106
   193    GND @S9S_MB_2U_LIB.S9S_MB_2U(SCH_1):GND   I178 @S9S_MB_2U_LIB.S9S_MB_2U(SCH_1):PAGE106
   195    GND @S9S_MB_2U_LIB.S9S_MB_2U(SCH_1):GND   I178 @S9S_MB_2U_LIB.S9S_MB_2U(SCH_1):PAGE106
   197    GND @S9S_MB_2U_LIB.S9S_MB_2U(SCH_1):GND   I178 @S9S_MB_2U_LIB.S9S_MB_2U(SCH_1):PAGE106
   199    GND @S9S_MB_2U_LIB.S9S_MB_2U(SCH_1):GND   I178 @S9S_MB_2U_LIB.S9S_MB_2U(SCH_1):PAGE106
   202    GND @S9S_MB_2U_LIB.S9S_MB_2U(SCH_1):GND   I178 @S9S_MB_2U_LIB.S9S_MB_2U(SCH_1):PAGE106
   204    GND @S9S_MB_2U_LIB.S9S_MB_2U(SCH_1):GND   I178 @S9S_MB_2U_LIB.S9S_MB_2U(SCH_1):PAGE106
   206    GND @S9S_MB_2U_LIB.S9S_MB_2U(SCH_1):GND   I178 @S9S_MB_2U_LIB.S9S_MB_2U(SCH_1):PAGE106
   208    GND @S9S_MB_2U_LIB.S9S_MB_2U(SCH_1):GND   I178 @S9S_MB_2U_LIB.S9S_MB_2U(SCH_1):PAGE106
   210    GND @S9S_MB_2U_LIB.S9S_MB_2U(SCH_1):GND   I178 @S9S_MB_2U_LIB.S9S_MB_2U(SCH_1):PAGE106
   212    GND @S9S_MB_2U_LIB.S9S_MB_2U(SCH_1):GND   I178 @S9S_MB_2U_LIB.S9S_MB_2U(SCH_1):PAGE106
   214    GND @S9S_MB_2U_LIB.S9S_MB_2U(SCH_1):GND   I178 @S9S_MB_2U_LIB.S9S_MB_2U(SCH_1):PAGE106
   216    GND @S9S_MB_2U_LIB.S9S_MB_2U(SCH_1):GND   I178 @S9S_MB_2U_LIB.S9S_MB_2U(SCH_1):PAGE106
   219    GND @S9S_MB_2U_LIB.S9S_MB_2U(SCH_1):GND   I178 @S9S_MB_2U_LIB.S9S_MB_2U(SCH_1):PAGE106
   222    GND @S9S_MB_2U_LIB.S9S_MB_2U(SCH_1):GND   I178 @S9S_MB_2U_LIB.S9S_MB_2U(SCH_1):PAGE106
   224    GND @S9S_MB_2U_LIB.S9S_MB_2U(SCH_1):GND   I178 @S9S_MB_2U_LIB.S9S_MB_2U(SCH_1):PAGE106
   226    GND @S9S_MB_2U_LIB.S9S_MB_2U(SCH_1):GND   I178 @S9S_MB_2U_LIB.S9S_MB_2U(SCH_1):PAGE106
   228    GND @S9S_MB_2U_LIB.S9S_MB_2U(SCH_1):GND   I178 @S9S_MB_2U_LIB.S9S_MB_2U(SCH_1):PAGE106
   233    GND @S9S_MB_2U_LIB.S9S_MB_2U(SCH_1):GND   I178 @S9S_MB_2U_LIB.S9S_MB_2U(SCH_1):PAGE106
   237    GND @S9S_MB_2U_LIB.S9S_MB_2U(SCH_1):GND   I178 @S9S_MB_2U_LIB.S9S_MB_2U(SCH_1):PAGE106
   242    GND @S9S_MB_2U_LIB.S9S_MB_2U(SCH_1):GND   I178 @S9S_MB_2U_LIB.S9S_MB_2U(SCH_1):PAGE106
   244    GND @S9S_MB_2U_LIB.S9S_MB_2U(SCH_1):GND   I178 @S9S_MB_2U_LIB.S9S_MB_2U(SCH_1):PAGE106
   246    GND @S9S_MB_2U_LIB.S9S_MB_2U(SCH_1):GND   I178 @S9S_MB_2U_LIB.S9S_MB_2U(SCH_1):PAGE106
   248    GND @S9S_MB_2U_LIB.S9S_MB_2U(SCH_1):GND   I178 @S9S_MB_2U_LIB.S9S_MB_2U(SCH_1):PAGE106
   251    GND @S9S_MB_2U_LIB.S9S_MB_2U(SCH_1):GND   I178 @S9S_MB_2U_LIB.S9S_MB_2U(SCH_1):PAGE106
   253    GND @S9S_MB_2U_LIB.S9S_MB_2U(SCH_1):GND   I178 @S9S_MB_2U_LIB.S9S_MB_2U(SCH_1):PAGE106
   255    GND @S9S_MB_2U_LIB.S9S_MB_2U(SCH_1):GND   I178 @S9S_MB_2U_LIB.S9S_MB_2U(SCH_1):PAGE106
   257    GND @S9S_MB_2U_LIB.S9S_MB_2U(SCH_1):GND   I178 @S9S_MB_2U_LIB.S9S_MB_2U(SCH_1):PAGE106
   259    GND @S9S_MB_2U_LIB.S9S_MB_2U(SCH_1):GND   I178 @S9S_MB_2U_LIB.S9S_MB_2U(SCH_1):PAGE106
   262    GND @S9S_MB_2U_LIB.S9S_MB_2U(SCH_1):GND   I178 @S9S_MB_2U_LIB.S9S_MB_2U(SCH_1):PAGE106
   264    GND @S9S_MB_2U_LIB.S9S_MB_2U(SCH_1):GND   I178 @S9S_MB_2U_LIB.S9S_MB_2U(SCH_1):PAGE106
   266    GND @S9S_MB_2U_LIB.S9S_MB_2U(SCH_1):GND   I178 @S9S_MB_2U_LIB.S9S_MB_2U(SCH_1):PAGE106
   268    GND @S9S_MB_2U_LIB.S9S_MB_2U(SCH_1):GND   I178 @S9S_MB_2U_LIB.S9S_MB_2U(SCH_1):PAGE106
   270    GND @S9S_MB_2U_LIB.S9S_MB_2U(SCH_1):GND   I178 @S9S_MB_2U_LIB.S9S_MB_2U(SCH_1):PAGE106
   273    GND @S9S_MB_2U_LIB.S9S_MB_2U(SCH_1):GND   I178 @S9S_MB_2U_LIB.S9S_MB_2U(SCH_1):PAGE106
   275    GND @S9S_MB_2U_LIB.S9S_MB_2U(SCH_1):GND   I178 @S9S_MB_2U_LIB.S9S_MB_2U(SCH_1):PAGE106
   277    GND @S9S_MB_2U_LIB.S9S_MB_2U(SCH_1):GND   I178 @S9S_MB_2U_LIB.S9S_MB_2U(SCH_1):PAGE106
   279    GND @S9S_MB_2U_LIB.S9S_MB_2U(SCH_1):GND   I178 @S9S_MB_2U_LIB.S9S_MB_2U(SCH_1):PAGE106
   281    GND @S9S_MB_2U_LIB.S9S_MB_2U(SCH_1):GND   I178 @S9S_MB_2U_LIB.S9S_MB_2U(SCH_1):PAGE106
   284    GND @S9S_MB_2U_LIB.S9S_MB_2U(SCH_1):GND   I178 @S9S_MB_2U_LIB.S9S_MB_2U(SCH_1):PAGE106
   286    GND @S9S_MB_2U_LIB.S9S_MB_2U(SCH_1):GND   I178 @S9S_MB_2U_LIB.S9S_MB_2U(SCH_1):PAGE106
   288    GND @S9S_MB_2U_LIB.S9S_MB_2U(SCH_1):GND   I178 @S9S_MB_2U_LIB.S9S_MB_2U(SCH_1):PAGE106
     1 P12V_S3_AUX_CPU1_NVDIMM @S9S_MB_2U_LIB.S9S_MB_2U(SCH_1):P12V_S3_AUX_CPU1_NVDIMM   I178 @S9S_MB_2U_LIB.S9S_MB_2U(SCH_1):PAGE106
   145 P12V_S3_AUX_CPU1_NVDIMM @S9S_MB_2U_LIB.S9S_MB_2U(SCH_1):P12V_S3_AUX_CPU1_NVDIMM   I178 @S9S_MB_2U_LIB.S9S_MB_2U(SCH_1):PAGE106
   146 P12V_S3_AUX_CPU1_NVDIMM @S9S_MB_2U_LIB.S9S_MB_2U(SCH_1):P12V_S3_AUX_CPU1_NVDIMM   I178 @S9S_MB_2U_LIB.S9S_MB_2U(SCH_1):PAGE106
   230    GND @S9S_MB_2U_LIB.S9S_MB_2U(SCH_1):GND   I178 @S9S_MB_2U_LIB.S9S_MB_2U(SCH_1):PAGE106
   235    GND @S9S_MB_2U_LIB.S9S_MB_2U(SCH_1):GND   I178 @S9S_MB_2U_LIB.S9S_MB_2U(SCH_1):PAGE106
   240    GND @S9S_MB_2U_LIB.S9S_MB_2U(SCH_1):GND   I178 @S9S_MB_2U_LIB.S9S_MB_2U(SCH_1):PAGE106
   132    GND @S9S_MB_2U_LIB.S9S_MB_2U(SCH_1):GND   I178 @S9S_MB_2U_LIB.S9S_MB_2U(SCH_1):PAGE106
   136    GND @S9S_MB_2U_LIB.S9S_MB_2U(SCH_1):GND   I178 @S9S_MB_2U_LIB.S9S_MB_2U(SCH_1):PAGE106
   139    GND @S9S_MB_2U_LIB.S9S_MB_2U(SCH_1):GND   I178 @S9S_MB_2U_LIB.S9S_MB_2U(SCH_1):PAGE106
   141    GND @S9S_MB_2U_LIB.S9S_MB_2U(SCH_1):GND   I178 @S9S_MB_2U_LIB.S9S_MB_2U(SCH_1):PAGE106
    G1    GND @S9S_MB_2U_LIB.S9S_MB_2U(SCH_1):GND   I178 @S9S_MB_2U_LIB.S9S_MB_2U(SCH_1):PAGE106
    G2    GND @S9S_MB_2U_LIB.S9S_MB_2U(SCH_1):GND   I178 @S9S_MB_2U_LIB.S9S_MB_2U(SCH_1):PAGE106
    G3    GND @S9S_MB_2U_LIB.S9S_MB_2U(SCH_1):GND   I178 @S9S_MB_2U_LIB.S9S_MB_2U(SCH_1):PAGE106

 J26 SCONN288_ADR50017P087CC-SCONN2A
     3 P3V3_AUX @S9S_MB_2U_LIB.S9S_MB_2U(SCH_1):P3V3_AUX   I180 @S9S_MB_2U_LIB.S9S_MB_2U(SCH_1):PAGE107
     2 TP_CHE_CPU1_DIMM2_FRU_0 @S9S_MB_2U_LIB.S9S_MB_2U(SCH_1):TP_CHE_CPU1_DIMM2_FRU_0   I180 @S9S_MB_2U_LIB.S9S_MB_2U(SCH_1):PAGE107
   144 TP_CHE_CPU1_DIMM2_FRU_1 @S9S_MB_2U_LIB.S9S_MB_2U(SCH_1):TP_CHE_CPU1_DIMM2_FRU_1   I180 @S9S_MB_2U_LIB.S9S_MB_2U(SCH_1):PAGE107
   149 TP_CHE_CPU1_DIMM2_FRU_2 @S9S_MB_2U_LIB.S9S_MB_2U(SCH_1):TP_CHE_CPU1_DIMM2_FRU_2   I180 @S9S_MB_2U_LIB.S9S_MB_2U(SCH_1):PAGE107
   150 TP_CHE_CPU1_DIMM2_FRU_3 @S9S_MB_2U_LIB.S9S_MB_2U(SCH_1):TP_CHE_CPU1_DIMM2_FRU_3   I180 @S9S_MB_2U_LIB.S9S_MB_2U(SCH_1):PAGE107
   220 TP_CHE_CPU1_DIMM2_FRU_4 @S9S_MB_2U_LIB.S9S_MB_2U(SCH_1):TP_CHE_CPU1_DIMM2_FRU_4   I180 @S9S_MB_2U_LIB.S9S_MB_2U(SCH_1):PAGE107
   231 TP_CHE_CPU1_DIMM2_FRU_5 @S9S_MB_2U_LIB.S9S_MB_2U(SCH_1):TP_CHE_CPU1_DIMM2_FRU_5   I180 @S9S_MB_2U_LIB.S9S_MB_2U(SCH_1):PAGE107
   232 TP_CHE_CPU1_DIMM2_FRU_6 @S9S_MB_2U_LIB.S9S_MB_2U(SCH_1):TP_CHE_CPU1_DIMM2_FRU_6   I180 @S9S_MB_2U_LIB.S9S_MB_2U(SCH_1):PAGE107
   207 RST_M_EF_CPU1_FPGA_N @S9S_MB_2U_LIB.S9S_MB_2U(SCH_1):RST_M_EF_CPU1_FPGA_N   I180 @S9S_MB_2U_LIB.S9S_MB_2U(SCH_1):PAGE107
   147 PWRGD_CHE_CPU1_DIMM2 @S9S_MB_2U_LIB.S9S_MB_2U(SCH_1):PWRGD_CHE_CPU1_DIMM2   I180 @S9S_MB_2U_LIB.S9S_MB_2U(SCH_1):PAGE107
   227 M_E_CPU1_SB_PAR @S9S_MB_2U_LIB.S9S_MB_2U(SCH_1):M_E_CPU1_SB_PAR   I180 @S9S_MB_2U_LIB.S9S_MB_2U(SCH_1):PAGE107
    74 M_E_CPU1_SA_PAR @S9S_MB_2U_LIB.S9S_MB_2U(SCH_1):M_E_CPU1_SA_PAR   I180 @S9S_MB_2U_LIB.S9S_MB_2U(SCH_1):PAGE107
    87 M_E_CPU1_SB_RSP<1> @S9S_MB_2U_LIB.S9S_MB_2U(SCH_1):M_E_CPU1_SB_RSP(1)   I180 @S9S_MB_2U_LIB.S9S_MB_2U(SCH_1):PAGE107
    86 M_E_CPU1_SA_RSP<1> @S9S_MB_2U_LIB.S9S_MB_2U(SCH_1):M_E_CPU1_SA_RSP(1)   I180 @S9S_MB_2U_LIB.S9S_MB_2U(SCH_1):PAGE107
     5 I3C_SPD_DDREFGH_CPU1_LVC1_SDA @S9S_MB_2U_LIB.S9S_MB_2U(SCH_1):I3C_SPD_DDREFGH_CPU1_LVC1_SDA   I180 @S9S_MB_2U_LIB.S9S_MB_2U(SCH_1):PAGE107
     4 I3C_SPD_DDREFGH_CPU1_LVC1_SCL_1 @S9S_MB_2U_LIB.S9S_MB_2U(SCH_1):I3C_SPD_DDREFGH_CPU1_LVC1_SCL_R2   I180 @S9S_MB_2U_LIB.S9S_MB_2U(SCH_1):PAGE107
   148 PD_CHE_CPU1_DIMM2_SAA @S9S_MB_2U_LIB.S9S_MB_2U(SCH_1):PD_CHE_CPU1_DIMM2_SAA   I180 @S9S_MB_2U_LIB.S9S_MB_2U(SCH_1):PAGE107
   100 M_E_CPU1_SB_DQ<0> @S9S_MB_2U_LIB.S9S_MB_2U(SCH_1):M_E_CPU1_SB_DQ(0)   I180 @S9S_MB_2U_LIB.S9S_MB_2U(SCH_1):PAGE107
   102 M_E_CPU1_SB_DQ<1> @S9S_MB_2U_LIB.S9S_MB_2U(SCH_1):M_E_CPU1_SB_DQ(1)   I180 @S9S_MB_2U_LIB.S9S_MB_2U(SCH_1):PAGE107
   245 M_E_CPU1_SB_DQ<2> @S9S_MB_2U_LIB.S9S_MB_2U(SCH_1):M_E_CPU1_SB_DQ(2)   I180 @S9S_MB_2U_LIB.S9S_MB_2U(SCH_1):PAGE107
   247 M_E_CPU1_SB_DQ<3> @S9S_MB_2U_LIB.S9S_MB_2U(SCH_1):M_E_CPU1_SB_DQ(3)   I180 @S9S_MB_2U_LIB.S9S_MB_2U(SCH_1):PAGE107
   107 M_E_CPU1_SB_DQ<4> @S9S_MB_2U_LIB.S9S_MB_2U(SCH_1):M_E_CPU1_SB_DQ(4)   I180 @S9S_MB_2U_LIB.S9S_MB_2U(SCH_1):PAGE107
   109 M_E_CPU1_SB_DQ<5> @S9S_MB_2U_LIB.S9S_MB_2U(SCH_1):M_E_CPU1_SB_DQ(5)   I180 @S9S_MB_2U_LIB.S9S_MB_2U(SCH_1):PAGE107
   252 M_E_CPU1_SB_DQ<6> @S9S_MB_2U_LIB.S9S_MB_2U(SCH_1):M_E_CPU1_SB_DQ(6)   I180 @S9S_MB_2U_LIB.S9S_MB_2U(SCH_1):PAGE107
   254 M_E_CPU1_SB_DQ<7> @S9S_MB_2U_LIB.S9S_MB_2U(SCH_1):M_E_CPU1_SB_DQ(7)   I180 @S9S_MB_2U_LIB.S9S_MB_2U(SCH_1):PAGE107
   111 M_E_CPU1_SB_DQ<8> @S9S_MB_2U_LIB.S9S_MB_2U(SCH_1):M_E_CPU1_SB_DQ(8)   I180 @S9S_MB_2U_LIB.S9S_MB_2U(SCH_1):PAGE107
   113 M_E_CPU1_SB_DQ<9> @S9S_MB_2U_LIB.S9S_MB_2U(SCH_1):M_E_CPU1_SB_DQ(9)   I180 @S9S_MB_2U_LIB.S9S_MB_2U(SCH_1):PAGE107
   256 M_E_CPU1_SB_DQ<10> @S9S_MB_2U_LIB.S9S_MB_2U(SCH_1):M_E_CPU1_SB_DQ(10)   I180 @S9S_MB_2U_LIB.S9S_MB_2U(SCH_1):PAGE107
   258 M_E_CPU1_SB_DQ<11> @S9S_MB_2U_LIB.S9S_MB_2U(SCH_1):M_E_CPU1_SB_DQ(11)   I180 @S9S_MB_2U_LIB.S9S_MB_2U(SCH_1):PAGE107
   118 M_E_CPU1_SB_DQ<12> @S9S_MB_2U_LIB.S9S_MB_2U(SCH_1):M_E_CPU1_SB_DQ(12)   I180 @S9S_MB_2U_LIB.S9S_MB_2U(SCH_1):PAGE107
   120 M_E_CPU1_SB_DQ<13> @S9S_MB_2U_LIB.S9S_MB_2U(SCH_1):M_E_CPU1_SB_DQ(13)   I180 @S9S_MB_2U_LIB.S9S_MB_2U(SCH_1):PAGE107
   263 M_E_CPU1_SB_DQ<14> @S9S_MB_2U_LIB.S9S_MB_2U(SCH_1):M_E_CPU1_SB_DQ(14)   I180 @S9S_MB_2U_LIB.S9S_MB_2U(SCH_1):PAGE107
   265 M_E_CPU1_SB_DQ<15> @S9S_MB_2U_LIB.S9S_MB_2U(SCH_1):M_E_CPU1_SB_DQ(15)   I180 @S9S_MB_2U_LIB.S9S_MB_2U(SCH_1):PAGE107
   122 M_E_CPU1_SB_DQ<16> @S9S_MB_2U_LIB.S9S_MB_2U(SCH_1):M_E_CPU1_SB_DQ(16)   I180 @S9S_MB_2U_LIB.S9S_MB_2U(SCH_1):PAGE107
   124 M_E_CPU1_SB_DQ<17> @S9S_MB_2U_LIB.S9S_MB_2U(SCH_1):M_E_CPU1_SB_DQ(17)   I180 @S9S_MB_2U_LIB.S9S_MB_2U(SCH_1):PAGE107
   267 M_E_CPU1_SB_DQ<18> @S9S_MB_2U_LIB.S9S_MB_2U(SCH_1):M_E_CPU1_SB_DQ(18)   I180 @S9S_MB_2U_LIB.S9S_MB_2U(SCH_1):PAGE107
   269 M_E_CPU1_SB_DQ<19> @S9S_MB_2U_LIB.S9S_MB_2U(SCH_1):M_E_CPU1_SB_DQ(19)   I180 @S9S_MB_2U_LIB.S9S_MB_2U(SCH_1):PAGE107
   129 M_E_CPU1_SB_DQ<20> @S9S_MB_2U_LIB.S9S_MB_2U(SCH_1):M_E_CPU1_SB_DQ(20)   I180 @S9S_MB_2U_LIB.S9S_MB_2U(SCH_1):PAGE107
   131 M_E_CPU1_SB_DQ<21> @S9S_MB_2U_LIB.S9S_MB_2U(SCH_1):M_E_CPU1_SB_DQ(21)   I180 @S9S_MB_2U_LIB.S9S_MB_2U(SCH_1):PAGE107
   274 M_E_CPU1_SB_DQ<22> @S9S_MB_2U_LIB.S9S_MB_2U(SCH_1):M_E_CPU1_SB_DQ(22)   I180 @S9S_MB_2U_LIB.S9S_MB_2U(SCH_1):PAGE107
   276 M_E_CPU1_SB_DQ<23> @S9S_MB_2U_LIB.S9S_MB_2U(SCH_1):M_E_CPU1_SB_DQ(23)   I180 @S9S_MB_2U_LIB.S9S_MB_2U(SCH_1):PAGE107
   133 M_E_CPU1_SB_DQ<24> @S9S_MB_2U_LIB.S9S_MB_2U(SCH_1):M_E_CPU1_SB_DQ(24)   I180 @S9S_MB_2U_LIB.S9S_MB_2U(SCH_1):PAGE107
   135 M_E_CPU1_SB_DQ<25> @S9S_MB_2U_LIB.S9S_MB_2U(SCH_1):M_E_CPU1_SB_DQ(25)   I180 @S9S_MB_2U_LIB.S9S_MB_2U(SCH_1):PAGE107
   278 M_E_CPU1_SB_DQ<26> @S9S_MB_2U_LIB.S9S_MB_2U(SCH_1):M_E_CPU1_SB_DQ(26)   I180 @S9S_MB_2U_LIB.S9S_MB_2U(SCH_1):PAGE107
   280 M_E_CPU1_SB_DQ<27> @S9S_MB_2U_LIB.S9S_MB_2U(SCH_1):M_E_CPU1_SB_DQ(27)   I180 @S9S_MB_2U_LIB.S9S_MB_2U(SCH_1):PAGE107
   140 M_E_CPU1_SB_DQ<28> @S9S_MB_2U_LIB.S9S_MB_2U(SCH_1):M_E_CPU1_SB_DQ(28)   I180 @S9S_MB_2U_LIB.S9S_MB_2U(SCH_1):PAGE107
   142 M_E_CPU1_SB_DQ<29> @S9S_MB_2U_LIB.S9S_MB_2U(SCH_1):M_E_CPU1_SB_DQ(29)   I180 @S9S_MB_2U_LIB.S9S_MB_2U(SCH_1):PAGE107
   285 M_E_CPU1_SB_DQ<30> @S9S_MB_2U_LIB.S9S_MB_2U(SCH_1):M_E_CPU1_SB_DQ(30)   I180 @S9S_MB_2U_LIB.S9S_MB_2U(SCH_1):PAGE107
   287 M_E_CPU1_SB_DQ<31> @S9S_MB_2U_LIB.S9S_MB_2U(SCH_1):M_E_CPU1_SB_DQ(31)   I180 @S9S_MB_2U_LIB.S9S_MB_2U(SCH_1):PAGE107
     7 M_E_CPU1_SA_DQ<0> @S9S_MB_2U_LIB.S9S_MB_2U(SCH_1):M_E_CPU1_SA_DQ(0)   I180 @S9S_MB_2U_LIB.S9S_MB_2U(SCH_1):PAGE107
     9 M_E_CPU1_SA_DQ<1> @S9S_MB_2U_LIB.S9S_MB_2U(SCH_1):M_E_CPU1_SA_DQ(1)   I180 @S9S_MB_2U_LIB.S9S_MB_2U(SCH_1):PAGE107
   152 M_E_CPU1_SA_DQ<2> @S9S_MB_2U_LIB.S9S_MB_2U(SCH_1):M_E_CPU1_SA_DQ(2)   I180 @S9S_MB_2U_LIB.S9S_MB_2U(SCH_1):PAGE107
   154 M_E_CPU1_SA_DQ<3> @S9S_MB_2U_LIB.S9S_MB_2U(SCH_1):M_E_CPU1_SA_DQ(3)   I180 @S9S_MB_2U_LIB.S9S_MB_2U(SCH_1):PAGE107
    14 M_E_CPU1_SA_DQ<4> @S9S_MB_2U_LIB.S9S_MB_2U(SCH_1):M_E_CPU1_SA_DQ(4)   I180 @S9S_MB_2U_LIB.S9S_MB_2U(SCH_1):PAGE107
    16 M_E_CPU1_SA_DQ<5> @S9S_MB_2U_LIB.S9S_MB_2U(SCH_1):M_E_CPU1_SA_DQ(5)   I180 @S9S_MB_2U_LIB.S9S_MB_2U(SCH_1):PAGE107
   159 M_E_CPU1_SA_DQ<6> @S9S_MB_2U_LIB.S9S_MB_2U(SCH_1):M_E_CPU1_SA_DQ(6)   I180 @S9S_MB_2U_LIB.S9S_MB_2U(SCH_1):PAGE107
   161 M_E_CPU1_SA_DQ<7> @S9S_MB_2U_LIB.S9S_MB_2U(SCH_1):M_E_CPU1_SA_DQ(7)   I180 @S9S_MB_2U_LIB.S9S_MB_2U(SCH_1):PAGE107
    18 M_E_CPU1_SA_DQ<8> @S9S_MB_2U_LIB.S9S_MB_2U(SCH_1):M_E_CPU1_SA_DQ(8)   I180 @S9S_MB_2U_LIB.S9S_MB_2U(SCH_1):PAGE107
    20 M_E_CPU1_SA_DQ<9> @S9S_MB_2U_LIB.S9S_MB_2U(SCH_1):M_E_CPU1_SA_DQ(9)   I180 @S9S_MB_2U_LIB.S9S_MB_2U(SCH_1):PAGE107
   163 M_E_CPU1_SA_DQ<10> @S9S_MB_2U_LIB.S9S_MB_2U(SCH_1):M_E_CPU1_SA_DQ(10)   I180 @S9S_MB_2U_LIB.S9S_MB_2U(SCH_1):PAGE107
   165 M_E_CPU1_SA_DQ<11> @S9S_MB_2U_LIB.S9S_MB_2U(SCH_1):M_E_CPU1_SA_DQ(11)   I180 @S9S_MB_2U_LIB.S9S_MB_2U(SCH_1):PAGE107
    25 M_E_CPU1_SA_DQ<12> @S9S_MB_2U_LIB.S9S_MB_2U(SCH_1):M_E_CPU1_SA_DQ(12)   I180 @S9S_MB_2U_LIB.S9S_MB_2U(SCH_1):PAGE107
    27 M_E_CPU1_SA_DQ<13> @S9S_MB_2U_LIB.S9S_MB_2U(SCH_1):M_E_CPU1_SA_DQ(13)   I180 @S9S_MB_2U_LIB.S9S_MB_2U(SCH_1):PAGE107
   170 M_E_CPU1_SA_DQ<14> @S9S_MB_2U_LIB.S9S_MB_2U(SCH_1):M_E_CPU1_SA_DQ(14)   I180 @S9S_MB_2U_LIB.S9S_MB_2U(SCH_1):PAGE107
   172 M_E_CPU1_SA_DQ<15> @S9S_MB_2U_LIB.S9S_MB_2U(SCH_1):M_E_CPU1_SA_DQ(15)   I180 @S9S_MB_2U_LIB.S9S_MB_2U(SCH_1):PAGE107
    29 M_E_CPU1_SA_DQ<16> @S9S_MB_2U_LIB.S9S_MB_2U(SCH_1):M_E_CPU1_SA_DQ(16)   I180 @S9S_MB_2U_LIB.S9S_MB_2U(SCH_1):PAGE107
    31 M_E_CPU1_SA_DQ<17> @S9S_MB_2U_LIB.S9S_MB_2U(SCH_1):M_E_CPU1_SA_DQ(17)   I180 @S9S_MB_2U_LIB.S9S_MB_2U(SCH_1):PAGE107
   174 M_E_CPU1_SA_DQ<18> @S9S_MB_2U_LIB.S9S_MB_2U(SCH_1):M_E_CPU1_SA_DQ(18)   I180 @S9S_MB_2U_LIB.S9S_MB_2U(SCH_1):PAGE107
   176 M_E_CPU1_SA_DQ<19> @S9S_MB_2U_LIB.S9S_MB_2U(SCH_1):M_E_CPU1_SA_DQ(19)   I180 @S9S_MB_2U_LIB.S9S_MB_2U(SCH_1):PAGE107
    36 M_E_CPU1_SA_DQ<20> @S9S_MB_2U_LIB.S9S_MB_2U(SCH_1):M_E_CPU1_SA_DQ(20)   I180 @S9S_MB_2U_LIB.S9S_MB_2U(SCH_1):PAGE107
    38 M_E_CPU1_SA_DQ<21> @S9S_MB_2U_LIB.S9S_MB_2U(SCH_1):M_E_CPU1_SA_DQ(21)   I180 @S9S_MB_2U_LIB.S9S_MB_2U(SCH_1):PAGE107
   181 M_E_CPU1_SA_DQ<22> @S9S_MB_2U_LIB.S9S_MB_2U(SCH_1):M_E_CPU1_SA_DQ(22)   I180 @S9S_MB_2U_LIB.S9S_MB_2U(SCH_1):PAGE107
   183 M_E_CPU1_SA_DQ<23> @S9S_MB_2U_LIB.S9S_MB_2U(SCH_1):M_E_CPU1_SA_DQ(23)   I180 @S9S_MB_2U_LIB.S9S_MB_2U(SCH_1):PAGE107
    40 M_E_CPU1_SA_DQ<24> @S9S_MB_2U_LIB.S9S_MB_2U(SCH_1):M_E_CPU1_SA_DQ(24)   I180 @S9S_MB_2U_LIB.S9S_MB_2U(SCH_1):PAGE107
    42 M_E_CPU1_SA_DQ<25> @S9S_MB_2U_LIB.S9S_MB_2U(SCH_1):M_E_CPU1_SA_DQ(25)   I180 @S9S_MB_2U_LIB.S9S_MB_2U(SCH_1):PAGE107
   185 M_E_CPU1_SA_DQ<26> @S9S_MB_2U_LIB.S9S_MB_2U(SCH_1):M_E_CPU1_SA_DQ(26)   I180 @S9S_MB_2U_LIB.S9S_MB_2U(SCH_1):PAGE107
   187 M_E_CPU1_SA_DQ<27> @S9S_MB_2U_LIB.S9S_MB_2U(SCH_1):M_E_CPU1_SA_DQ(27)   I180 @S9S_MB_2U_LIB.S9S_MB_2U(SCH_1):PAGE107
    47 M_E_CPU1_SA_DQ<28> @S9S_MB_2U_LIB.S9S_MB_2U(SCH_1):M_E_CPU1_SA_DQ(28)   I180 @S9S_MB_2U_LIB.S9S_MB_2U(SCH_1):PAGE107
    49 M_E_CPU1_SA_DQ<29> @S9S_MB_2U_LIB.S9S_MB_2U(SCH_1):M_E_CPU1_SA_DQ(29)   I180 @S9S_MB_2U_LIB.S9S_MB_2U(SCH_1):PAGE107
   192 M_E_CPU1_SA_DQ<30> @S9S_MB_2U_LIB.S9S_MB_2U(SCH_1):M_E_CPU1_SA_DQ(30)   I180 @S9S_MB_2U_LIB.S9S_MB_2U(SCH_1):PAGE107
   229 M_E_CPU1_SB_CS_N<3> @S9S_MB_2U_LIB.S9S_MB_2U(SCH_1):M_E_CPU1_SB_CS_N(3)   I180 @S9S_MB_2U_LIB.S9S_MB_2U(SCH_1):PAGE107
   209 M_E_CPU1_SA_CS_N<3> @S9S_MB_2U_LIB.S9S_MB_2U(SCH_1):M_E_CPU1_SA_CS_N(3)   I180 @S9S_MB_2U_LIB.S9S_MB_2U(SCH_1):PAGE107
    84 M_E_CPU1_SB_CS_N<2> @S9S_MB_2U_LIB.S9S_MB_2U(SCH_1):M_E_CPU1_SB_CS_N(2)   I180 @S9S_MB_2U_LIB.S9S_MB_2U(SCH_1):PAGE107
    64 M_E_CPU1_SA_CS_N<2> @S9S_MB_2U_LIB.S9S_MB_2U(SCH_1):M_E_CPU1_SA_CS_N(2)   I180 @S9S_MB_2U_LIB.S9S_MB_2U(SCH_1):PAGE107
   217 M_E_CPU1_CLK_DP<1> @S9S_MB_2U_LIB.S9S_MB_2U(SCH_1):M_E_CPU1_CLK_DP(1)   I180 @S9S_MB_2U_LIB.S9S_MB_2U(SCH_1):PAGE107
   218 M_E_CPU1_CLK_DN<1> @S9S_MB_2U_LIB.S9S_MB_2U(SCH_1):M_E_CPU1_CLK_DN(1)   I180 @S9S_MB_2U_LIB.S9S_MB_2U(SCH_1):PAGE107
    96 M_E_CPU1_SB_CB<0> @S9S_MB_2U_LIB.S9S_MB_2U(SCH_1):M_E_CPU1_SB_CB(0)   I180 @S9S_MB_2U_LIB.S9S_MB_2U(SCH_1):PAGE107
    98 M_E_CPU1_SB_CB<1> @S9S_MB_2U_LIB.S9S_MB_2U(SCH_1):M_E_CPU1_SB_CB(1)   I180 @S9S_MB_2U_LIB.S9S_MB_2U(SCH_1):PAGE107
   241 M_E_CPU1_SB_CB<2> @S9S_MB_2U_LIB.S9S_MB_2U(SCH_1):M_E_CPU1_SB_CB(2)   I180 @S9S_MB_2U_LIB.S9S_MB_2U(SCH_1):PAGE107
   243 M_E_CPU1_SB_CB<3> @S9S_MB_2U_LIB.S9S_MB_2U(SCH_1):M_E_CPU1_SB_CB(3)   I180 @S9S_MB_2U_LIB.S9S_MB_2U(SCH_1):PAGE107
    89 M_E_CPU1_SB_CB<4> @S9S_MB_2U_LIB.S9S_MB_2U(SCH_1):M_E_CPU1_SB_CB(4)   I180 @S9S_MB_2U_LIB.S9S_MB_2U(SCH_1):PAGE107
    91 M_E_CPU1_SB_CB<5> @S9S_MB_2U_LIB.S9S_MB_2U(SCH_1):M_E_CPU1_SB_CB(5)   I180 @S9S_MB_2U_LIB.S9S_MB_2U(SCH_1):PAGE107
   234 M_E_CPU1_SB_CB<6> @S9S_MB_2U_LIB.S9S_MB_2U(SCH_1):M_E_CPU1_SB_CB(6)   I180 @S9S_MB_2U_LIB.S9S_MB_2U(SCH_1):PAGE107
    51 M_E_CPU1_SA_CB<0> @S9S_MB_2U_LIB.S9S_MB_2U(SCH_1):M_E_CPU1_SA_CB(0)   I180 @S9S_MB_2U_LIB.S9S_MB_2U(SCH_1):PAGE107
   196 M_E_CPU1_SA_CB<2> @S9S_MB_2U_LIB.S9S_MB_2U(SCH_1):M_E_CPU1_SA_CB(2)   I180 @S9S_MB_2U_LIB.S9S_MB_2U(SCH_1):PAGE107
   198 M_E_CPU1_SA_CB<3> @S9S_MB_2U_LIB.S9S_MB_2U(SCH_1):M_E_CPU1_SA_CB(3)   I180 @S9S_MB_2U_LIB.S9S_MB_2U(SCH_1):PAGE107
    60 M_E_CPU1_SA_CB<5> @S9S_MB_2U_LIB.S9S_MB_2U(SCH_1):M_E_CPU1_SA_CB(5)   I180 @S9S_MB_2U_LIB.S9S_MB_2U(SCH_1):PAGE107
   203 M_E_CPU1_SA_CB<6> @S9S_MB_2U_LIB.S9S_MB_2U(SCH_1):M_E_CPU1_SA_CB(6)   I180 @S9S_MB_2U_LIB.S9S_MB_2U(SCH_1):PAGE107
    82 M_E_CPU1_SB_CA<6> @S9S_MB_2U_LIB.S9S_MB_2U(SCH_1):M_E_CPU1_SB_CA(6)   I180 @S9S_MB_2U_LIB.S9S_MB_2U(SCH_1):PAGE107
    72 M_E_CPU1_SA_CA<6> @S9S_MB_2U_LIB.S9S_MB_2U(SCH_1):M_E_CPU1_SA_CA(6)   I180 @S9S_MB_2U_LIB.S9S_MB_2U(SCH_1):PAGE107
   225 M_E_CPU1_SB_CA<5> @S9S_MB_2U_LIB.S9S_MB_2U(SCH_1):M_E_CPU1_SB_CA(5)   I180 @S9S_MB_2U_LIB.S9S_MB_2U(SCH_1):PAGE107
   215 M_E_CPU1_SA_CA<5> @S9S_MB_2U_LIB.S9S_MB_2U(SCH_1):M_E_CPU1_SA_CA(5)   I180 @S9S_MB_2U_LIB.S9S_MB_2U(SCH_1):PAGE107
    80 M_E_CPU1_SB_CA<4> @S9S_MB_2U_LIB.S9S_MB_2U(SCH_1):M_E_CPU1_SB_CA(4)   I180 @S9S_MB_2U_LIB.S9S_MB_2U(SCH_1):PAGE107
    70 M_E_CPU1_SA_CA<4> @S9S_MB_2U_LIB.S9S_MB_2U(SCH_1):M_E_CPU1_SA_CA(4)   I180 @S9S_MB_2U_LIB.S9S_MB_2U(SCH_1):PAGE107
   223 M_E_CPU1_SB_CA<3> @S9S_MB_2U_LIB.S9S_MB_2U(SCH_1):M_E_CPU1_SB_CA(3)   I180 @S9S_MB_2U_LIB.S9S_MB_2U(SCH_1):PAGE107
   213 M_E_CPU1_SA_CA<3> @S9S_MB_2U_LIB.S9S_MB_2U(SCH_1):M_E_CPU1_SA_CA(3)   I180 @S9S_MB_2U_LIB.S9S_MB_2U(SCH_1):PAGE107
    78 M_E_CPU1_SB_CA<2> @S9S_MB_2U_LIB.S9S_MB_2U(SCH_1):M_E_CPU1_SB_CA(2)   I180 @S9S_MB_2U_LIB.S9S_MB_2U(SCH_1):PAGE107
    68 M_E_CPU1_SA_CA<2> @S9S_MB_2U_LIB.S9S_MB_2U(SCH_1):M_E_CPU1_SA_CA(2)   I180 @S9S_MB_2U_LIB.S9S_MB_2U(SCH_1):PAGE107
   221 M_E_CPU1_SB_CA<1> @S9S_MB_2U_LIB.S9S_MB_2U(SCH_1):M_E_CPU1_SB_CA(1)   I180 @S9S_MB_2U_LIB.S9S_MB_2U(SCH_1):PAGE107
   211 M_E_CPU1_SA_CA<1> @S9S_MB_2U_LIB.S9S_MB_2U(SCH_1):M_E_CPU1_SA_CA(1)   I180 @S9S_MB_2U_LIB.S9S_MB_2U(SCH_1):PAGE107
    76 M_E_CPU1_SB_CA<0> @S9S_MB_2U_LIB.S9S_MB_2U(SCH_1):M_E_CPU1_SB_CA(0)   I180 @S9S_MB_2U_LIB.S9S_MB_2U(SCH_1):PAGE107
    66 M_E_CPU1_SA_CA<0> @S9S_MB_2U_LIB.S9S_MB_2U(SCH_1):M_E_CPU1_SA_CA(0)   I180 @S9S_MB_2U_LIB.S9S_MB_2U(SCH_1):PAGE107
    62 M_E_CPU1_ALERT_N @S9S_MB_2U_LIB.S9S_MB_2U(SCH_1):M_E_CPU1_ALERT_N   I180 @S9S_MB_2U_LIB.S9S_MB_2U(SCH_1):PAGE107
   236 M_E_CPU1_SB_CB<7> @S9S_MB_2U_LIB.S9S_MB_2U(SCH_1):M_E_CPU1_SB_CB(7)   I180 @S9S_MB_2U_LIB.S9S_MB_2U(SCH_1):PAGE107
    53 M_E_CPU1_SA_CB<1> @S9S_MB_2U_LIB.S9S_MB_2U(SCH_1):M_E_CPU1_SA_CB(1)   I180 @S9S_MB_2U_LIB.S9S_MB_2U(SCH_1):PAGE107
    58 M_E_CPU1_SA_CB<4> @S9S_MB_2U_LIB.S9S_MB_2U(SCH_1):M_E_CPU1_SA_CB(4)   I180 @S9S_MB_2U_LIB.S9S_MB_2U(SCH_1):PAGE107
   205 M_E_CPU1_SA_CB<7> @S9S_MB_2U_LIB.S9S_MB_2U(SCH_1):M_E_CPU1_SA_CB(7)   I180 @S9S_MB_2U_LIB.S9S_MB_2U(SCH_1):PAGE107
   194 M_E_CPU1_SA_DQ<31> @S9S_MB_2U_LIB.S9S_MB_2U(SCH_1):M_E_CPU1_SA_DQ(31)   I180 @S9S_MB_2U_LIB.S9S_MB_2U(SCH_1):PAGE107
    93 M_E_CPU1_SB_DQS_DP<9> @S9S_MB_2U_LIB.S9S_MB_2U(SCH_1):M_E_CPU1_SB_DQS_DP(9)   I181 @S9S_MB_2U_LIB.S9S_MB_2U(SCH_1):PAGE107
    94 M_E_CPU1_SB_DQS_DN<9> @S9S_MB_2U_LIB.S9S_MB_2U(SCH_1):M_E_CPU1_SB_DQS_DN(9)   I181 @S9S_MB_2U_LIB.S9S_MB_2U(SCH_1):PAGE107
   201 M_E_CPU1_SA_DQS_DP<9> @S9S_MB_2U_LIB.S9S_MB_2U(SCH_1):M_E_CPU1_SA_DQS_DP(9)   I181 @S9S_MB_2U_LIB.S9S_MB_2U(SCH_1):PAGE107
   200 M_E_CPU1_SA_DQS_DN<9> @S9S_MB_2U_LIB.S9S_MB_2U(SCH_1):M_E_CPU1_SA_DQS_DN(9)   I181 @S9S_MB_2U_LIB.S9S_MB_2U(SCH_1):PAGE107
   190 M_E_CPU1_SA_DQS_DP<8> @S9S_MB_2U_LIB.S9S_MB_2U(SCH_1):M_E_CPU1_SA_DQS_DP(8)   I181 @S9S_MB_2U_LIB.S9S_MB_2U(SCH_1):PAGE107
   189 M_E_CPU1_SA_DQS_DN<8> @S9S_MB_2U_LIB.S9S_MB_2U(SCH_1):M_E_CPU1_SA_DQS_DN(8)   I181 @S9S_MB_2U_LIB.S9S_MB_2U(SCH_1):PAGE107
   271 M_E_CPU1_SB_DQS_DN<7> @S9S_MB_2U_LIB.S9S_MB_2U(SCH_1):M_E_CPU1_SB_DQS_DN(7)   I181 @S9S_MB_2U_LIB.S9S_MB_2U(SCH_1):PAGE107
   179 M_E_CPU1_SA_DQS_DP<7> @S9S_MB_2U_LIB.S9S_MB_2U(SCH_1):M_E_CPU1_SA_DQS_DP(7)   I181 @S9S_MB_2U_LIB.S9S_MB_2U(SCH_1):PAGE107
   261 M_E_CPU1_SB_DQS_DP<6> @S9S_MB_2U_LIB.S9S_MB_2U(SCH_1):M_E_CPU1_SB_DQS_DP(6)   I181 @S9S_MB_2U_LIB.S9S_MB_2U(SCH_1):PAGE107
   260 M_E_CPU1_SB_DQS_DN<6> @S9S_MB_2U_LIB.S9S_MB_2U(SCH_1):M_E_CPU1_SB_DQS_DN(6)   I181 @S9S_MB_2U_LIB.S9S_MB_2U(SCH_1):PAGE107
   167 M_E_CPU1_SA_DQS_DN<6> @S9S_MB_2U_LIB.S9S_MB_2U(SCH_1):M_E_CPU1_SA_DQS_DN(6)   I181 @S9S_MB_2U_LIB.S9S_MB_2U(SCH_1):PAGE107
   250 M_E_CPU1_SB_DQS_DP<5> @S9S_MB_2U_LIB.S9S_MB_2U(SCH_1):M_E_CPU1_SB_DQS_DP(5)   I181 @S9S_MB_2U_LIB.S9S_MB_2U(SCH_1):PAGE107
   249 M_E_CPU1_SB_DQS_DN<5> @S9S_MB_2U_LIB.S9S_MB_2U(SCH_1):M_E_CPU1_SB_DQS_DN(5)   I181 @S9S_MB_2U_LIB.S9S_MB_2U(SCH_1):PAGE107
   157 M_E_CPU1_SA_DQS_DP<5> @S9S_MB_2U_LIB.S9S_MB_2U(SCH_1):M_E_CPU1_SA_DQS_DP(5)   I181 @S9S_MB_2U_LIB.S9S_MB_2U(SCH_1):PAGE107
   156 M_E_CPU1_SA_DQS_DN<5> @S9S_MB_2U_LIB.S9S_MB_2U(SCH_1):M_E_CPU1_SA_DQS_DN(5)   I181 @S9S_MB_2U_LIB.S9S_MB_2U(SCH_1):PAGE107
   239 M_E_CPU1_SB_DQS_DP<4> @S9S_MB_2U_LIB.S9S_MB_2U(SCH_1):M_E_CPU1_SB_DQS_DP(4)   I181 @S9S_MB_2U_LIB.S9S_MB_2U(SCH_1):PAGE107
   238 M_E_CPU1_SB_DQS_DN<4> @S9S_MB_2U_LIB.S9S_MB_2U(SCH_1):M_E_CPU1_SB_DQS_DN(4)   I181 @S9S_MB_2U_LIB.S9S_MB_2U(SCH_1):PAGE107
    55 M_E_CPU1_SA_DQS_DP<4> @S9S_MB_2U_LIB.S9S_MB_2U(SCH_1):M_E_CPU1_SA_DQS_DP(4)   I181 @S9S_MB_2U_LIB.S9S_MB_2U(SCH_1):PAGE107
    56 M_E_CPU1_SA_DQS_DN<4> @S9S_MB_2U_LIB.S9S_MB_2U(SCH_1):M_E_CPU1_SA_DQS_DN(4)   I181 @S9S_MB_2U_LIB.S9S_MB_2U(SCH_1):PAGE107
   137 M_E_CPU1_SB_DQS_DP<3> @S9S_MB_2U_LIB.S9S_MB_2U(SCH_1):M_E_CPU1_SB_DQS_DP(3)   I181 @S9S_MB_2U_LIB.S9S_MB_2U(SCH_1):PAGE107
   138 M_E_CPU1_SB_DQS_DN<3> @S9S_MB_2U_LIB.S9S_MB_2U(SCH_1):M_E_CPU1_SB_DQS_DN(3)   I181 @S9S_MB_2U_LIB.S9S_MB_2U(SCH_1):PAGE107
    44 M_E_CPU1_SA_DQS_DP<3> @S9S_MB_2U_LIB.S9S_MB_2U(SCH_1):M_E_CPU1_SA_DQS_DP(3)   I181 @S9S_MB_2U_LIB.S9S_MB_2U(SCH_1):PAGE107
    45 M_E_CPU1_SA_DQS_DN<3> @S9S_MB_2U_LIB.S9S_MB_2U(SCH_1):M_E_CPU1_SA_DQS_DN(3)   I181 @S9S_MB_2U_LIB.S9S_MB_2U(SCH_1):PAGE107
   126 M_E_CPU1_SB_DQS_DP<2> @S9S_MB_2U_LIB.S9S_MB_2U(SCH_1):M_E_CPU1_SB_DQS_DP(2)   I181 @S9S_MB_2U_LIB.S9S_MB_2U(SCH_1):PAGE107
   127 M_E_CPU1_SB_DQS_DN<2> @S9S_MB_2U_LIB.S9S_MB_2U(SCH_1):M_E_CPU1_SB_DQS_DN(2)   I181 @S9S_MB_2U_LIB.S9S_MB_2U(SCH_1):PAGE107
    33 M_E_CPU1_SA_DQS_DP<2> @S9S_MB_2U_LIB.S9S_MB_2U(SCH_1):M_E_CPU1_SA_DQS_DP(2)   I181 @S9S_MB_2U_LIB.S9S_MB_2U(SCH_1):PAGE107
    34 M_E_CPU1_SA_DQS_DN<2> @S9S_MB_2U_LIB.S9S_MB_2U(SCH_1):M_E_CPU1_SA_DQS_DN(2)   I181 @S9S_MB_2U_LIB.S9S_MB_2U(SCH_1):PAGE107
   115 M_E_CPU1_SB_DQS_DP<1> @S9S_MB_2U_LIB.S9S_MB_2U(SCH_1):M_E_CPU1_SB_DQS_DP(1)   I181 @S9S_MB_2U_LIB.S9S_MB_2U(SCH_1):PAGE107
   116 M_E_CPU1_SB_DQS_DN<1> @S9S_MB_2U_LIB.S9S_MB_2U(SCH_1):M_E_CPU1_SB_DQS_DN(1)   I181 @S9S_MB_2U_LIB.S9S_MB_2U(SCH_1):PAGE107
    22 M_E_CPU1_SA_DQS_DP<1> @S9S_MB_2U_LIB.S9S_MB_2U(SCH_1):M_E_CPU1_SA_DQS_DP(1)   I181 @S9S_MB_2U_LIB.S9S_MB_2U(SCH_1):PAGE107
    23 M_E_CPU1_SA_DQS_DN<1> @S9S_MB_2U_LIB.S9S_MB_2U(SCH_1):M_E_CPU1_SA_DQS_DN(1)   I181 @S9S_MB_2U_LIB.S9S_MB_2U(SCH_1):PAGE107
   104 M_E_CPU1_SB_DQS_DP<0> @S9S_MB_2U_LIB.S9S_MB_2U(SCH_1):M_E_CPU1_SB_DQS_DP(0)   I181 @S9S_MB_2U_LIB.S9S_MB_2U(SCH_1):PAGE107
   105 M_E_CPU1_SB_DQS_DN<0> @S9S_MB_2U_LIB.S9S_MB_2U(SCH_1):M_E_CPU1_SB_DQS_DN(0)   I181 @S9S_MB_2U_LIB.S9S_MB_2U(SCH_1):PAGE107
    11 M_E_CPU1_SA_DQS_DP<0> @S9S_MB_2U_LIB.S9S_MB_2U(SCH_1):M_E_CPU1_SA_DQS_DP(0)   I181 @S9S_MB_2U_LIB.S9S_MB_2U(SCH_1):PAGE107
    12 M_E_CPU1_SA_DQS_DN<0> @S9S_MB_2U_LIB.S9S_MB_2U(SCH_1):M_E_CPU1_SA_DQS_DN(0)   I181 @S9S_MB_2U_LIB.S9S_MB_2U(SCH_1):PAGE107
   272 M_E_CPU1_SB_DQS_DP<7> @S9S_MB_2U_LIB.S9S_MB_2U(SCH_1):M_E_CPU1_SB_DQS_DP(7)   I181 @S9S_MB_2U_LIB.S9S_MB_2U(SCH_1):PAGE107
   282 M_E_CPU1_SB_DQS_DN<8> @S9S_MB_2U_LIB.S9S_MB_2U(SCH_1):M_E_CPU1_SB_DQS_DN(8)   I181 @S9S_MB_2U_LIB.S9S_MB_2U(SCH_1):PAGE107
   283 M_E_CPU1_SB_DQS_DP<8> @S9S_MB_2U_LIB.S9S_MB_2U(SCH_1):M_E_CPU1_SB_DQS_DP(8)   I181 @S9S_MB_2U_LIB.S9S_MB_2U(SCH_1):PAGE107
   168 M_E_CPU1_SA_DQS_DP<6> @S9S_MB_2U_LIB.S9S_MB_2U(SCH_1):M_E_CPU1_SA_DQS_DP(6)   I181 @S9S_MB_2U_LIB.S9S_MB_2U(SCH_1):PAGE107
   178 M_E_CPU1_SA_DQS_DN<7> @S9S_MB_2U_LIB.S9S_MB_2U(SCH_1):M_E_CPU1_SA_DQS_DN(7)   I181 @S9S_MB_2U_LIB.S9S_MB_2U(SCH_1):PAGE107
     6    GND @S9S_MB_2U_LIB.S9S_MB_2U(SCH_1):GND   I179 @S9S_MB_2U_LIB.S9S_MB_2U(SCH_1):PAGE107
     8    GND @S9S_MB_2U_LIB.S9S_MB_2U(SCH_1):GND   I179 @S9S_MB_2U_LIB.S9S_MB_2U(SCH_1):PAGE107
    10    GND @S9S_MB_2U_LIB.S9S_MB_2U(SCH_1):GND   I179 @S9S_MB_2U_LIB.S9S_MB_2U(SCH_1):PAGE107
    13    GND @S9S_MB_2U_LIB.S9S_MB_2U(SCH_1):GND   I179 @S9S_MB_2U_LIB.S9S_MB_2U(SCH_1):PAGE107
    15    GND @S9S_MB_2U_LIB.S9S_MB_2U(SCH_1):GND   I179 @S9S_MB_2U_LIB.S9S_MB_2U(SCH_1):PAGE107
    17    GND @S9S_MB_2U_LIB.S9S_MB_2U(SCH_1):GND   I179 @S9S_MB_2U_LIB.S9S_MB_2U(SCH_1):PAGE107
    19    GND @S9S_MB_2U_LIB.S9S_MB_2U(SCH_1):GND   I179 @S9S_MB_2U_LIB.S9S_MB_2U(SCH_1):PAGE107
    21    GND @S9S_MB_2U_LIB.S9S_MB_2U(SCH_1):GND   I179 @S9S_MB_2U_LIB.S9S_MB_2U(SCH_1):PAGE107
    24    GND @S9S_MB_2U_LIB.S9S_MB_2U(SCH_1):GND   I179 @S9S_MB_2U_LIB.S9S_MB_2U(SCH_1):PAGE107
    26    GND @S9S_MB_2U_LIB.S9S_MB_2U(SCH_1):GND   I179 @S9S_MB_2U_LIB.S9S_MB_2U(SCH_1):PAGE107
    28    GND @S9S_MB_2U_LIB.S9S_MB_2U(SCH_1):GND   I179 @S9S_MB_2U_LIB.S9S_MB_2U(SCH_1):PAGE107
    30    GND @S9S_MB_2U_LIB.S9S_MB_2U(SCH_1):GND   I179 @S9S_MB_2U_LIB.S9S_MB_2U(SCH_1):PAGE107
    32    GND @S9S_MB_2U_LIB.S9S_MB_2U(SCH_1):GND   I179 @S9S_MB_2U_LIB.S9S_MB_2U(SCH_1):PAGE107
    35    GND @S9S_MB_2U_LIB.S9S_MB_2U(SCH_1):GND   I179 @S9S_MB_2U_LIB.S9S_MB_2U(SCH_1):PAGE107
    37    GND @S9S_MB_2U_LIB.S9S_MB_2U(SCH_1):GND   I179 @S9S_MB_2U_LIB.S9S_MB_2U(SCH_1):PAGE107
    39    GND @S9S_MB_2U_LIB.S9S_MB_2U(SCH_1):GND   I179 @S9S_MB_2U_LIB.S9S_MB_2U(SCH_1):PAGE107
    41    GND @S9S_MB_2U_LIB.S9S_MB_2U(SCH_1):GND   I179 @S9S_MB_2U_LIB.S9S_MB_2U(SCH_1):PAGE107
    43    GND @S9S_MB_2U_LIB.S9S_MB_2U(SCH_1):GND   I179 @S9S_MB_2U_LIB.S9S_MB_2U(SCH_1):PAGE107
    46    GND @S9S_MB_2U_LIB.S9S_MB_2U(SCH_1):GND   I179 @S9S_MB_2U_LIB.S9S_MB_2U(SCH_1):PAGE107
    48    GND @S9S_MB_2U_LIB.S9S_MB_2U(SCH_1):GND   I179 @S9S_MB_2U_LIB.S9S_MB_2U(SCH_1):PAGE107
    50    GND @S9S_MB_2U_LIB.S9S_MB_2U(SCH_1):GND   I179 @S9S_MB_2U_LIB.S9S_MB_2U(SCH_1):PAGE107
    52    GND @S9S_MB_2U_LIB.S9S_MB_2U(SCH_1):GND   I179 @S9S_MB_2U_LIB.S9S_MB_2U(SCH_1):PAGE107
    54    GND @S9S_MB_2U_LIB.S9S_MB_2U(SCH_1):GND   I179 @S9S_MB_2U_LIB.S9S_MB_2U(SCH_1):PAGE107
    57    GND @S9S_MB_2U_LIB.S9S_MB_2U(SCH_1):GND   I179 @S9S_MB_2U_LIB.S9S_MB_2U(SCH_1):PAGE107
    59    GND @S9S_MB_2U_LIB.S9S_MB_2U(SCH_1):GND   I179 @S9S_MB_2U_LIB.S9S_MB_2U(SCH_1):PAGE107
    61    GND @S9S_MB_2U_LIB.S9S_MB_2U(SCH_1):GND   I179 @S9S_MB_2U_LIB.S9S_MB_2U(SCH_1):PAGE107
    63    GND @S9S_MB_2U_LIB.S9S_MB_2U(SCH_1):GND   I179 @S9S_MB_2U_LIB.S9S_MB_2U(SCH_1):PAGE107
    65    GND @S9S_MB_2U_LIB.S9S_MB_2U(SCH_1):GND   I179 @S9S_MB_2U_LIB.S9S_MB_2U(SCH_1):PAGE107
    67    GND @S9S_MB_2U_LIB.S9S_MB_2U(SCH_1):GND   I179 @S9S_MB_2U_LIB.S9S_MB_2U(SCH_1):PAGE107
    69    GND @S9S_MB_2U_LIB.S9S_MB_2U(SCH_1):GND   I179 @S9S_MB_2U_LIB.S9S_MB_2U(SCH_1):PAGE107
    71    GND @S9S_MB_2U_LIB.S9S_MB_2U(SCH_1):GND   I179 @S9S_MB_2U_LIB.S9S_MB_2U(SCH_1):PAGE107
    73    GND @S9S_MB_2U_LIB.S9S_MB_2U(SCH_1):GND   I179 @S9S_MB_2U_LIB.S9S_MB_2U(SCH_1):PAGE107
    75    GND @S9S_MB_2U_LIB.S9S_MB_2U(SCH_1):GND   I179 @S9S_MB_2U_LIB.S9S_MB_2U(SCH_1):PAGE107
    77    GND @S9S_MB_2U_LIB.S9S_MB_2U(SCH_1):GND   I179 @S9S_MB_2U_LIB.S9S_MB_2U(SCH_1):PAGE107
    79    GND @S9S_MB_2U_LIB.S9S_MB_2U(SCH_1):GND   I179 @S9S_MB_2U_LIB.S9S_MB_2U(SCH_1):PAGE107
    81    GND @S9S_MB_2U_LIB.S9S_MB_2U(SCH_1):GND   I179 @S9S_MB_2U_LIB.S9S_MB_2U(SCH_1):PAGE107
    83    GND @S9S_MB_2U_LIB.S9S_MB_2U(SCH_1):GND   I179 @S9S_MB_2U_LIB.S9S_MB_2U(SCH_1):PAGE107
    85    GND @S9S_MB_2U_LIB.S9S_MB_2U(SCH_1):GND   I179 @S9S_MB_2U_LIB.S9S_MB_2U(SCH_1):PAGE107
    88    GND @S9S_MB_2U_LIB.S9S_MB_2U(SCH_1):GND   I179 @S9S_MB_2U_LIB.S9S_MB_2U(SCH_1):PAGE107
    90    GND @S9S_MB_2U_LIB.S9S_MB_2U(SCH_1):GND   I179 @S9S_MB_2U_LIB.S9S_MB_2U(SCH_1):PAGE107
    92    GND @S9S_MB_2U_LIB.S9S_MB_2U(SCH_1):GND   I179 @S9S_MB_2U_LIB.S9S_MB_2U(SCH_1):PAGE107
    95    GND @S9S_MB_2U_LIB.S9S_MB_2U(SCH_1):GND   I179 @S9S_MB_2U_LIB.S9S_MB_2U(SCH_1):PAGE107
    97    GND @S9S_MB_2U_LIB.S9S_MB_2U(SCH_1):GND   I179 @S9S_MB_2U_LIB.S9S_MB_2U(SCH_1):PAGE107
    99    GND @S9S_MB_2U_LIB.S9S_MB_2U(SCH_1):GND   I179 @S9S_MB_2U_LIB.S9S_MB_2U(SCH_1):PAGE107
   101    GND @S9S_MB_2U_LIB.S9S_MB_2U(SCH_1):GND   I179 @S9S_MB_2U_LIB.S9S_MB_2U(SCH_1):PAGE107
   103    GND @S9S_MB_2U_LIB.S9S_MB_2U(SCH_1):GND   I179 @S9S_MB_2U_LIB.S9S_MB_2U(SCH_1):PAGE107
   106    GND @S9S_MB_2U_LIB.S9S_MB_2U(SCH_1):GND   I179 @S9S_MB_2U_LIB.S9S_MB_2U(SCH_1):PAGE107
   108    GND @S9S_MB_2U_LIB.S9S_MB_2U(SCH_1):GND   I179 @S9S_MB_2U_LIB.S9S_MB_2U(SCH_1):PAGE107
   110    GND @S9S_MB_2U_LIB.S9S_MB_2U(SCH_1):GND   I179 @S9S_MB_2U_LIB.S9S_MB_2U(SCH_1):PAGE107
   112    GND @S9S_MB_2U_LIB.S9S_MB_2U(SCH_1):GND   I179 @S9S_MB_2U_LIB.S9S_MB_2U(SCH_1):PAGE107
   114    GND @S9S_MB_2U_LIB.S9S_MB_2U(SCH_1):GND   I179 @S9S_MB_2U_LIB.S9S_MB_2U(SCH_1):PAGE107
   117    GND @S9S_MB_2U_LIB.S9S_MB_2U(SCH_1):GND   I179 @S9S_MB_2U_LIB.S9S_MB_2U(SCH_1):PAGE107
   119    GND @S9S_MB_2U_LIB.S9S_MB_2U(SCH_1):GND   I179 @S9S_MB_2U_LIB.S9S_MB_2U(SCH_1):PAGE107
   121    GND @S9S_MB_2U_LIB.S9S_MB_2U(SCH_1):GND   I179 @S9S_MB_2U_LIB.S9S_MB_2U(SCH_1):PAGE107
   123    GND @S9S_MB_2U_LIB.S9S_MB_2U(SCH_1):GND   I179 @S9S_MB_2U_LIB.S9S_MB_2U(SCH_1):PAGE107
   125    GND @S9S_MB_2U_LIB.S9S_MB_2U(SCH_1):GND   I179 @S9S_MB_2U_LIB.S9S_MB_2U(SCH_1):PAGE107
   128    GND @S9S_MB_2U_LIB.S9S_MB_2U(SCH_1):GND   I179 @S9S_MB_2U_LIB.S9S_MB_2U(SCH_1):PAGE107
   130    GND @S9S_MB_2U_LIB.S9S_MB_2U(SCH_1):GND   I179 @S9S_MB_2U_LIB.S9S_MB_2U(SCH_1):PAGE107
   134    GND @S9S_MB_2U_LIB.S9S_MB_2U(SCH_1):GND   I179 @S9S_MB_2U_LIB.S9S_MB_2U(SCH_1):PAGE107
   143    GND @S9S_MB_2U_LIB.S9S_MB_2U(SCH_1):GND   I179 @S9S_MB_2U_LIB.S9S_MB_2U(SCH_1):PAGE107
   151    GND @S9S_MB_2U_LIB.S9S_MB_2U(SCH_1):GND   I179 @S9S_MB_2U_LIB.S9S_MB_2U(SCH_1):PAGE107
   153    GND @S9S_MB_2U_LIB.S9S_MB_2U(SCH_1):GND   I179 @S9S_MB_2U_LIB.S9S_MB_2U(SCH_1):PAGE107
   155    GND @S9S_MB_2U_LIB.S9S_MB_2U(SCH_1):GND   I179 @S9S_MB_2U_LIB.S9S_MB_2U(SCH_1):PAGE107
   158    GND @S9S_MB_2U_LIB.S9S_MB_2U(SCH_1):GND   I179 @S9S_MB_2U_LIB.S9S_MB_2U(SCH_1):PAGE107
   160    GND @S9S_MB_2U_LIB.S9S_MB_2U(SCH_1):GND   I179 @S9S_MB_2U_LIB.S9S_MB_2U(SCH_1):PAGE107
   162    GND @S9S_MB_2U_LIB.S9S_MB_2U(SCH_1):GND   I179 @S9S_MB_2U_LIB.S9S_MB_2U(SCH_1):PAGE107
   164    GND @S9S_MB_2U_LIB.S9S_MB_2U(SCH_1):GND   I179 @S9S_MB_2U_LIB.S9S_MB_2U(SCH_1):PAGE107
   166    GND @S9S_MB_2U_LIB.S9S_MB_2U(SCH_1):GND   I179 @S9S_MB_2U_LIB.S9S_MB_2U(SCH_1):PAGE107
   169    GND @S9S_MB_2U_LIB.S9S_MB_2U(SCH_1):GND   I179 @S9S_MB_2U_LIB.S9S_MB_2U(SCH_1):PAGE107
   171    GND @S9S_MB_2U_LIB.S9S_MB_2U(SCH_1):GND   I179 @S9S_MB_2U_LIB.S9S_MB_2U(SCH_1):PAGE107
   173    GND @S9S_MB_2U_LIB.S9S_MB_2U(SCH_1):GND   I179 @S9S_MB_2U_LIB.S9S_MB_2U(SCH_1):PAGE107
   175    GND @S9S_MB_2U_LIB.S9S_MB_2U(SCH_1):GND   I179 @S9S_MB_2U_LIB.S9S_MB_2U(SCH_1):PAGE107
   177    GND @S9S_MB_2U_LIB.S9S_MB_2U(SCH_1):GND   I179 @S9S_MB_2U_LIB.S9S_MB_2U(SCH_1):PAGE107
   180    GND @S9S_MB_2U_LIB.S9S_MB_2U(SCH_1):GND   I179 @S9S_MB_2U_LIB.S9S_MB_2U(SCH_1):PAGE107
   182    GND @S9S_MB_2U_LIB.S9S_MB_2U(SCH_1):GND   I179 @S9S_MB_2U_LIB.S9S_MB_2U(SCH_1):PAGE107
   184    GND @S9S_MB_2U_LIB.S9S_MB_2U(SCH_1):GND   I179 @S9S_MB_2U_LIB.S9S_MB_2U(SCH_1):PAGE107
   186    GND @S9S_MB_2U_LIB.S9S_MB_2U(SCH_1):GND   I179 @S9S_MB_2U_LIB.S9S_MB_2U(SCH_1):PAGE107
   188    GND @S9S_MB_2U_LIB.S9S_MB_2U(SCH_1):GND   I179 @S9S_MB_2U_LIB.S9S_MB_2U(SCH_1):PAGE107
   191    GND @S9S_MB_2U_LIB.S9S_MB_2U(SCH_1):GND   I179 @S9S_MB_2U_LIB.S9S_MB_2U(SCH_1):PAGE107
   193    GND @S9S_MB_2U_LIB.S9S_MB_2U(SCH_1):GND   I179 @S9S_MB_2U_LIB.S9S_MB_2U(SCH_1):PAGE107
   195    GND @S9S_MB_2U_LIB.S9S_MB_2U(SCH_1):GND   I179 @S9S_MB_2U_LIB.S9S_MB_2U(SCH_1):PAGE107
   197    GND @S9S_MB_2U_LIB.S9S_MB_2U(SCH_1):GND   I179 @S9S_MB_2U_LIB.S9S_MB_2U(SCH_1):PAGE107
   199    GND @S9S_MB_2U_LIB.S9S_MB_2U(SCH_1):GND   I179 @S9S_MB_2U_LIB.S9S_MB_2U(SCH_1):PAGE107
   202    GND @S9S_MB_2U_LIB.S9S_MB_2U(SCH_1):GND   I179 @S9S_MB_2U_LIB.S9S_MB_2U(SCH_1):PAGE107
   204    GND @S9S_MB_2U_LIB.S9S_MB_2U(SCH_1):GND   I179 @S9S_MB_2U_LIB.S9S_MB_2U(SCH_1):PAGE107
   206    GND @S9S_MB_2U_LIB.S9S_MB_2U(SCH_1):GND   I179 @S9S_MB_2U_LIB.S9S_MB_2U(SCH_1):PAGE107
   208    GND @S9S_MB_2U_LIB.S9S_MB_2U(SCH_1):GND   I179 @S9S_MB_2U_LIB.S9S_MB_2U(SCH_1):PAGE107
   210    GND @S9S_MB_2U_LIB.S9S_MB_2U(SCH_1):GND   I179 @S9S_MB_2U_LIB.S9S_MB_2U(SCH_1):PAGE107
   212    GND @S9S_MB_2U_LIB.S9S_MB_2U(SCH_1):GND   I179 @S9S_MB_2U_LIB.S9S_MB_2U(SCH_1):PAGE107
   214    GND @S9S_MB_2U_LIB.S9S_MB_2U(SCH_1):GND   I179 @S9S_MB_2U_LIB.S9S_MB_2U(SCH_1):PAGE107
   216    GND @S9S_MB_2U_LIB.S9S_MB_2U(SCH_1):GND   I179 @S9S_MB_2U_LIB.S9S_MB_2U(SCH_1):PAGE107
   219    GND @S9S_MB_2U_LIB.S9S_MB_2U(SCH_1):GND   I179 @S9S_MB_2U_LIB.S9S_MB_2U(SCH_1):PAGE107
   222    GND @S9S_MB_2U_LIB.S9S_MB_2U(SCH_1):GND   I179 @S9S_MB_2U_LIB.S9S_MB_2U(SCH_1):PAGE107
   224    GND @S9S_MB_2U_LIB.S9S_MB_2U(SCH_1):GND   I179 @S9S_MB_2U_LIB.S9S_MB_2U(SCH_1):PAGE107
   226    GND @S9S_MB_2U_LIB.S9S_MB_2U(SCH_1):GND   I179 @S9S_MB_2U_LIB.S9S_MB_2U(SCH_1):PAGE107
   228    GND @S9S_MB_2U_LIB.S9S_MB_2U(SCH_1):GND   I179 @S9S_MB_2U_LIB.S9S_MB_2U(SCH_1):PAGE107
   233    GND @S9S_MB_2U_LIB.S9S_MB_2U(SCH_1):GND   I179 @S9S_MB_2U_LIB.S9S_MB_2U(SCH_1):PAGE107
   237    GND @S9S_MB_2U_LIB.S9S_MB_2U(SCH_1):GND   I179 @S9S_MB_2U_LIB.S9S_MB_2U(SCH_1):PAGE107
   242    GND @S9S_MB_2U_LIB.S9S_MB_2U(SCH_1):GND   I179 @S9S_MB_2U_LIB.S9S_MB_2U(SCH_1):PAGE107
   244    GND @S9S_MB_2U_LIB.S9S_MB_2U(SCH_1):GND   I179 @S9S_MB_2U_LIB.S9S_MB_2U(SCH_1):PAGE107
   246    GND @S9S_MB_2U_LIB.S9S_MB_2U(SCH_1):GND   I179 @S9S_MB_2U_LIB.S9S_MB_2U(SCH_1):PAGE107
   248    GND @S9S_MB_2U_LIB.S9S_MB_2U(SCH_1):GND   I179 @S9S_MB_2U_LIB.S9S_MB_2U(SCH_1):PAGE107
   251    GND @S9S_MB_2U_LIB.S9S_MB_2U(SCH_1):GND   I179 @S9S_MB_2U_LIB.S9S_MB_2U(SCH_1):PAGE107
   253    GND @S9S_MB_2U_LIB.S9S_MB_2U(SCH_1):GND   I179 @S9S_MB_2U_LIB.S9S_MB_2U(SCH_1):PAGE107
   255    GND @S9S_MB_2U_LIB.S9S_MB_2U(SCH_1):GND   I179 @S9S_MB_2U_LIB.S9S_MB_2U(SCH_1):PAGE107
   257    GND @S9S_MB_2U_LIB.S9S_MB_2U(SCH_1):GND   I179 @S9S_MB_2U_LIB.S9S_MB_2U(SCH_1):PAGE107
   259    GND @S9S_MB_2U_LIB.S9S_MB_2U(SCH_1):GND   I179 @S9S_MB_2U_LIB.S9S_MB_2U(SCH_1):PAGE107
   262    GND @S9S_MB_2U_LIB.S9S_MB_2U(SCH_1):GND   I179 @S9S_MB_2U_LIB.S9S_MB_2U(SCH_1):PAGE107
   264    GND @S9S_MB_2U_LIB.S9S_MB_2U(SCH_1):GND   I179 @S9S_MB_2U_LIB.S9S_MB_2U(SCH_1):PAGE107
   266    GND @S9S_MB_2U_LIB.S9S_MB_2U(SCH_1):GND   I179 @S9S_MB_2U_LIB.S9S_MB_2U(SCH_1):PAGE107
   268    GND @S9S_MB_2U_LIB.S9S_MB_2U(SCH_1):GND   I179 @S9S_MB_2U_LIB.S9S_MB_2U(SCH_1):PAGE107
   270    GND @S9S_MB_2U_LIB.S9S_MB_2U(SCH_1):GND   I179 @S9S_MB_2U_LIB.S9S_MB_2U(SCH_1):PAGE107
   273    GND @S9S_MB_2U_LIB.S9S_MB_2U(SCH_1):GND   I179 @S9S_MB_2U_LIB.S9S_MB_2U(SCH_1):PAGE107
   275    GND @S9S_MB_2U_LIB.S9S_MB_2U(SCH_1):GND   I179 @S9S_MB_2U_LIB.S9S_MB_2U(SCH_1):PAGE107
   277    GND @S9S_MB_2U_LIB.S9S_MB_2U(SCH_1):GND   I179 @S9S_MB_2U_LIB.S9S_MB_2U(SCH_1):PAGE107
   279    GND @S9S_MB_2U_LIB.S9S_MB_2U(SCH_1):GND   I179 @S9S_MB_2U_LIB.S9S_MB_2U(SCH_1):PAGE107
   281    GND @S9S_MB_2U_LIB.S9S_MB_2U(SCH_1):GND   I179 @S9S_MB_2U_LIB.S9S_MB_2U(SCH_1):PAGE107
   284    GND @S9S_MB_2U_LIB.S9S_MB_2U(SCH_1):GND   I179 @S9S_MB_2U_LIB.S9S_MB_2U(SCH_1):PAGE107
   286    GND @S9S_MB_2U_LIB.S9S_MB_2U(SCH_1):GND   I179 @S9S_MB_2U_LIB.S9S_MB_2U(SCH_1):PAGE107
   288    GND @S9S_MB_2U_LIB.S9S_MB_2U(SCH_1):GND   I179 @S9S_MB_2U_LIB.S9S_MB_2U(SCH_1):PAGE107
     1 P12V_S3_AUX_CPU1_NVDIMM @S9S_MB_2U_LIB.S9S_MB_2U(SCH_1):P12V_S3_AUX_CPU1_NVDIMM   I179 @S9S_MB_2U_LIB.S9S_MB_2U(SCH_1):PAGE107
   145 P12V_S3_AUX_CPU1_NVDIMM @S9S_MB_2U_LIB.S9S_MB_2U(SCH_1):P12V_S3_AUX_CPU1_NVDIMM   I179 @S9S_MB_2U_LIB.S9S_MB_2U(SCH_1):PAGE107
   146 P12V_S3_AUX_CPU1_NVDIMM @S9S_MB_2U_LIB.S9S_MB_2U(SCH_1):P12V_S3_AUX_CPU1_NVDIMM   I179 @S9S_MB_2U_LIB.S9S_MB_2U(SCH_1):PAGE107
   230    GND @S9S_MB_2U_LIB.S9S_MB_2U(SCH_1):GND   I179 @S9S_MB_2U_LIB.S9S_MB_2U(SCH_1):PAGE107
   235    GND @S9S_MB_2U_LIB.S9S_MB_2U(SCH_1):GND   I179 @S9S_MB_2U_LIB.S9S_MB_2U(SCH_1):PAGE107
   240    GND @S9S_MB_2U_LIB.S9S_MB_2U(SCH_1):GND   I179 @S9S_MB_2U_LIB.S9S_MB_2U(SCH_1):PAGE107
   132    GND @S9S_MB_2U_LIB.S9S_MB_2U(SCH_1):GND   I179 @S9S_MB_2U_LIB.S9S_MB_2U(SCH_1):PAGE107
   136    GND @S9S_MB_2U_LIB.S9S_MB_2U(SCH_1):GND   I179 @S9S_MB_2U_LIB.S9S_MB_2U(SCH_1):PAGE107
   139    GND @S9S_MB_2U_LIB.S9S_MB_2U(SCH_1):GND   I179 @S9S_MB_2U_LIB.S9S_MB_2U(SCH_1):PAGE107
   141    GND @S9S_MB_2U_LIB.S9S_MB_2U(SCH_1):GND   I179 @S9S_MB_2U_LIB.S9S_MB_2U(SCH_1):PAGE107
    G1    GND @S9S_MB_2U_LIB.S9S_MB_2U(SCH_1):GND   I179 @S9S_MB_2U_LIB.S9S_MB_2U(SCH_1):PAGE107
    G2    GND @S9S_MB_2U_LIB.S9S_MB_2U(SCH_1):GND   I179 @S9S_MB_2U_LIB.S9S_MB_2U(SCH_1):PAGE107
    G3    GND @S9S_MB_2U_LIB.S9S_MB_2U(SCH_1):GND   I179 @S9S_MB_2U_LIB.S9S_MB_2U(SCH_1):PAGE107

 J27 SCONN288_ADR50017P130CC-SCONN2A
     3 P3V3_AUX @S9S_MB_2U_LIB.S9S_MB_2U(SCH_1):P3V3_AUX   I179 @S9S_MB_2U_LIB.S9S_MB_2U(SCH_1):PAGE108
     2 TP_CHF_CPU1_DIMM1_FRU_0 @S9S_MB_2U_LIB.S9S_MB_2U(SCH_1):TP_CHF_CPU1_DIMM1_FRU_0   I179 @S9S_MB_2U_LIB.S9S_MB_2U(SCH_1):PAGE108
   144 TP_CHF_CPU1_DIMM1_FRU_1 @S9S_MB_2U_LIB.S9S_MB_2U(SCH_1):TP_CHF_CPU1_DIMM1_FRU_1   I179 @S9S_MB_2U_LIB.S9S_MB_2U(SCH_1):PAGE108
   149 TP_CHF_CPU1_DIMM1_FRU_2 @S9S_MB_2U_LIB.S9S_MB_2U(SCH_1):TP_CHF_CPU1_DIMM1_FRU_2   I179 @S9S_MB_2U_LIB.S9S_MB_2U(SCH_1):PAGE108
   150 TP_CHF_CPU1_DIMM1_FRU_3 @S9S_MB_2U_LIB.S9S_MB_2U(SCH_1):TP_CHF_CPU1_DIMM1_FRU_3   I179 @S9S_MB_2U_LIB.S9S_MB_2U(SCH_1):PAGE108
   220 TP_CHF_CPU1_DIMM1_FRU_4 @S9S_MB_2U_LIB.S9S_MB_2U(SCH_1):TP_CHF_CPU1_DIMM1_FRU_4   I179 @S9S_MB_2U_LIB.S9S_MB_2U(SCH_1):PAGE108
   231 TP_CHF_CPU1_DIMM1_FRU_5 @S9S_MB_2U_LIB.S9S_MB_2U(SCH_1):TP_CHF_CPU1_DIMM1_FRU_5   I179 @S9S_MB_2U_LIB.S9S_MB_2U(SCH_1):PAGE108
   232 TP_CHF_CPU1_DIMM1_FRU_6 @S9S_MB_2U_LIB.S9S_MB_2U(SCH_1):TP_CHF_CPU1_DIMM1_FRU_6   I179 @S9S_MB_2U_LIB.S9S_MB_2U(SCH_1):PAGE108
   207 RST_M_EF_CPU1_FPGA_N @S9S_MB_2U_LIB.S9S_MB_2U(SCH_1):RST_M_EF_CPU1_FPGA_N   I179 @S9S_MB_2U_LIB.S9S_MB_2U(SCH_1):PAGE108
   147 PWRGD_CHF_CPU1_DIMM1 @S9S_MB_2U_LIB.S9S_MB_2U(SCH_1):PWRGD_CHF_CPU1_DIMM1   I179 @S9S_MB_2U_LIB.S9S_MB_2U(SCH_1):PAGE108
   227 M_F_CPU1_SB_PAR @S9S_MB_2U_LIB.S9S_MB_2U(SCH_1):M_F_CPU1_SB_PAR   I179 @S9S_MB_2U_LIB.S9S_MB_2U(SCH_1):PAGE108
    74 M_F_CPU1_SA_PAR @S9S_MB_2U_LIB.S9S_MB_2U(SCH_1):M_F_CPU1_SA_PAR   I179 @S9S_MB_2U_LIB.S9S_MB_2U(SCH_1):PAGE108
    87 M_F_CPU1_SB_RSP<0> @S9S_MB_2U_LIB.S9S_MB_2U(SCH_1):M_F_CPU1_SB_RSP(0)   I179 @S9S_MB_2U_LIB.S9S_MB_2U(SCH_1):PAGE108
    86 M_F_CPU1_SA_RSP<0> @S9S_MB_2U_LIB.S9S_MB_2U(SCH_1):M_F_CPU1_SA_RSP(0)   I179 @S9S_MB_2U_LIB.S9S_MB_2U(SCH_1):PAGE108
     5 I3C_SPD_DDREFGH_CPU1_LVC1_SDA @S9S_MB_2U_LIB.S9S_MB_2U(SCH_1):I3C_SPD_DDREFGH_CPU1_LVC1_SDA   I179 @S9S_MB_2U_LIB.S9S_MB_2U(SCH_1):PAGE108
     4 I3C_SPD_DDREFGH_CPU1_LVC1_SCL_2 @S9S_MB_2U_LIB.S9S_MB_2U(SCH_1):I3C_SPD_DDREFGH_CPU1_LVC1_SCL_R3   I179 @S9S_MB_2U_LIB.S9S_MB_2U(SCH_1):PAGE108
   148 PD_CHF_CPU1_DIMM1_SAA @S9S_MB_2U_LIB.S9S_MB_2U(SCH_1):PD_CHF_CPU1_DIMM1_SAA   I179 @S9S_MB_2U_LIB.S9S_MB_2U(SCH_1):PAGE108
   100 M_F_CPU1_SB_DQ<0> @S9S_MB_2U_LIB.S9S_MB_2U(SCH_1):M_F_CPU1_SB_DQ(0)   I179 @S9S_MB_2U_LIB.S9S_MB_2U(SCH_1):PAGE108
   102 M_F_CPU1_SB_DQ<1> @S9S_MB_2U_LIB.S9S_MB_2U(SCH_1):M_F_CPU1_SB_DQ(1)   I179 @S9S_MB_2U_LIB.S9S_MB_2U(SCH_1):PAGE108
   245 M_F_CPU1_SB_DQ<2> @S9S_MB_2U_LIB.S9S_MB_2U(SCH_1):M_F_CPU1_SB_DQ(2)   I179 @S9S_MB_2U_LIB.S9S_MB_2U(SCH_1):PAGE108
   247 M_F_CPU1_SB_DQ<3> @S9S_MB_2U_LIB.S9S_MB_2U(SCH_1):M_F_CPU1_SB_DQ(3)   I179 @S9S_MB_2U_LIB.S9S_MB_2U(SCH_1):PAGE108
   107 M_F_CPU1_SB_DQ<4> @S9S_MB_2U_LIB.S9S_MB_2U(SCH_1):M_F_CPU1_SB_DQ(4)   I179 @S9S_MB_2U_LIB.S9S_MB_2U(SCH_1):PAGE108
   109 M_F_CPU1_SB_DQ<5> @S9S_MB_2U_LIB.S9S_MB_2U(SCH_1):M_F_CPU1_SB_DQ(5)   I179 @S9S_MB_2U_LIB.S9S_MB_2U(SCH_1):PAGE108
   252 M_F_CPU1_SB_DQ<6> @S9S_MB_2U_LIB.S9S_MB_2U(SCH_1):M_F_CPU1_SB_DQ(6)   I179 @S9S_MB_2U_LIB.S9S_MB_2U(SCH_1):PAGE108
   254 M_F_CPU1_SB_DQ<7> @S9S_MB_2U_LIB.S9S_MB_2U(SCH_1):M_F_CPU1_SB_DQ(7)   I179 @S9S_MB_2U_LIB.S9S_MB_2U(SCH_1):PAGE108
   111 M_F_CPU1_SB_DQ<8> @S9S_MB_2U_LIB.S9S_MB_2U(SCH_1):M_F_CPU1_SB_DQ(8)   I179 @S9S_MB_2U_LIB.S9S_MB_2U(SCH_1):PAGE108
   113 M_F_CPU1_SB_DQ<9> @S9S_MB_2U_LIB.S9S_MB_2U(SCH_1):M_F_CPU1_SB_DQ(9)   I179 @S9S_MB_2U_LIB.S9S_MB_2U(SCH_1):PAGE108
   256 M_F_CPU1_SB_DQ<10> @S9S_MB_2U_LIB.S9S_MB_2U(SCH_1):M_F_CPU1_SB_DQ(10)   I179 @S9S_MB_2U_LIB.S9S_MB_2U(SCH_1):PAGE108
   258 M_F_CPU1_SB_DQ<11> @S9S_MB_2U_LIB.S9S_MB_2U(SCH_1):M_F_CPU1_SB_DQ(11)   I179 @S9S_MB_2U_LIB.S9S_MB_2U(SCH_1):PAGE108
   118 M_F_CPU1_SB_DQ<12> @S9S_MB_2U_LIB.S9S_MB_2U(SCH_1):M_F_CPU1_SB_DQ(12)   I179 @S9S_MB_2U_LIB.S9S_MB_2U(SCH_1):PAGE108
   120 M_F_CPU1_SB_DQ<13> @S9S_MB_2U_LIB.S9S_MB_2U(SCH_1):M_F_CPU1_SB_DQ(13)   I179 @S9S_MB_2U_LIB.S9S_MB_2U(SCH_1):PAGE108
   263 M_F_CPU1_SB_DQ<14> @S9S_MB_2U_LIB.S9S_MB_2U(SCH_1):M_F_CPU1_SB_DQ(14)   I179 @S9S_MB_2U_LIB.S9S_MB_2U(SCH_1):PAGE108
   265 M_F_CPU1_SB_DQ<15> @S9S_MB_2U_LIB.S9S_MB_2U(SCH_1):M_F_CPU1_SB_DQ(15)   I179 @S9S_MB_2U_LIB.S9S_MB_2U(SCH_1):PAGE108
   122 M_F_CPU1_SB_DQ<16> @S9S_MB_2U_LIB.S9S_MB_2U(SCH_1):M_F_CPU1_SB_DQ(16)   I179 @S9S_MB_2U_LIB.S9S_MB_2U(SCH_1):PAGE108
   124 M_F_CPU1_SB_DQ<17> @S9S_MB_2U_LIB.S9S_MB_2U(SCH_1):M_F_CPU1_SB_DQ(17)   I179 @S9S_MB_2U_LIB.S9S_MB_2U(SCH_1):PAGE108
   267 M_F_CPU1_SB_DQ<18> @S9S_MB_2U_LIB.S9S_MB_2U(SCH_1):M_F_CPU1_SB_DQ(18)   I179 @S9S_MB_2U_LIB.S9S_MB_2U(SCH_1):PAGE108
   269 M_F_CPU1_SB_DQ<19> @S9S_MB_2U_LIB.S9S_MB_2U(SCH_1):M_F_CPU1_SB_DQ(19)   I179 @S9S_MB_2U_LIB.S9S_MB_2U(SCH_1):PAGE108
   129 M_F_CPU1_SB_DQ<20> @S9S_MB_2U_LIB.S9S_MB_2U(SCH_1):M_F_CPU1_SB_DQ(20)   I179 @S9S_MB_2U_LIB.S9S_MB_2U(SCH_1):PAGE108
   131 M_F_CPU1_SB_DQ<21> @S9S_MB_2U_LIB.S9S_MB_2U(SCH_1):M_F_CPU1_SB_DQ(21)   I179 @S9S_MB_2U_LIB.S9S_MB_2U(SCH_1):PAGE108
   274 M_F_CPU1_SB_DQ<22> @S9S_MB_2U_LIB.S9S_MB_2U(SCH_1):M_F_CPU1_SB_DQ(22)   I179 @S9S_MB_2U_LIB.S9S_MB_2U(SCH_1):PAGE108
   276 M_F_CPU1_SB_DQ<23> @S9S_MB_2U_LIB.S9S_MB_2U(SCH_1):M_F_CPU1_SB_DQ(23)   I179 @S9S_MB_2U_LIB.S9S_MB_2U(SCH_1):PAGE108
   133 M_F_CPU1_SB_DQ<24> @S9S_MB_2U_LIB.S9S_MB_2U(SCH_1):M_F_CPU1_SB_DQ(24)   I179 @S9S_MB_2U_LIB.S9S_MB_2U(SCH_1):PAGE108
   135 M_F_CPU1_SB_DQ<25> @S9S_MB_2U_LIB.S9S_MB_2U(SCH_1):M_F_CPU1_SB_DQ(25)   I179 @S9S_MB_2U_LIB.S9S_MB_2U(SCH_1):PAGE108
   278 M_F_CPU1_SB_DQ<26> @S9S_MB_2U_LIB.S9S_MB_2U(SCH_1):M_F_CPU1_SB_DQ(26)   I179 @S9S_MB_2U_LIB.S9S_MB_2U(SCH_1):PAGE108
   280 M_F_CPU1_SB_DQ<27> @S9S_MB_2U_LIB.S9S_MB_2U(SCH_1):M_F_CPU1_SB_DQ(27)   I179 @S9S_MB_2U_LIB.S9S_MB_2U(SCH_1):PAGE108
   140 M_F_CPU1_SB_DQ<28> @S9S_MB_2U_LIB.S9S_MB_2U(SCH_1):M_F_CPU1_SB_DQ(28)   I179 @S9S_MB_2U_LIB.S9S_MB_2U(SCH_1):PAGE108
   142 M_F_CPU1_SB_DQ<29> @S9S_MB_2U_LIB.S9S_MB_2U(SCH_1):M_F_CPU1_SB_DQ(29)   I179 @S9S_MB_2U_LIB.S9S_MB_2U(SCH_1):PAGE108
   285 M_F_CPU1_SB_DQ<30> @S9S_MB_2U_LIB.S9S_MB_2U(SCH_1):M_F_CPU1_SB_DQ(30)   I179 @S9S_MB_2U_LIB.S9S_MB_2U(SCH_1):PAGE108
   287 M_F_CPU1_SB_DQ<31> @S9S_MB_2U_LIB.S9S_MB_2U(SCH_1):M_F_CPU1_SB_DQ(31)   I179 @S9S_MB_2U_LIB.S9S_MB_2U(SCH_1):PAGE108
     7 M_F_CPU1_SA_DQ<0> @S9S_MB_2U_LIB.S9S_MB_2U(SCH_1):M_F_CPU1_SA_DQ(0)   I179 @S9S_MB_2U_LIB.S9S_MB_2U(SCH_1):PAGE108
     9 M_F_CPU1_SA_DQ<1> @S9S_MB_2U_LIB.S9S_MB_2U(SCH_1):M_F_CPU1_SA_DQ(1)   I179 @S9S_MB_2U_LIB.S9S_MB_2U(SCH_1):PAGE108
   152 M_F_CPU1_SA_DQ<2> @S9S_MB_2U_LIB.S9S_MB_2U(SCH_1):M_F_CPU1_SA_DQ(2)   I179 @S9S_MB_2U_LIB.S9S_MB_2U(SCH_1):PAGE108
   154 M_F_CPU1_SA_DQ<3> @S9S_MB_2U_LIB.S9S_MB_2U(SCH_1):M_F_CPU1_SA_DQ(3)   I179 @S9S_MB_2U_LIB.S9S_MB_2U(SCH_1):PAGE108
    14 M_F_CPU1_SA_DQ<4> @S9S_MB_2U_LIB.S9S_MB_2U(SCH_1):M_F_CPU1_SA_DQ(4)   I179 @S9S_MB_2U_LIB.S9S_MB_2U(SCH_1):PAGE108
    16 M_F_CPU1_SA_DQ<5> @S9S_MB_2U_LIB.S9S_MB_2U(SCH_1):M_F_CPU1_SA_DQ(5)   I179 @S9S_MB_2U_LIB.S9S_MB_2U(SCH_1):PAGE108
   159 M_F_CPU1_SA_DQ<6> @S9S_MB_2U_LIB.S9S_MB_2U(SCH_1):M_F_CPU1_SA_DQ(6)   I179 @S9S_MB_2U_LIB.S9S_MB_2U(SCH_1):PAGE108
   161 M_F_CPU1_SA_DQ<7> @S9S_MB_2U_LIB.S9S_MB_2U(SCH_1):M_F_CPU1_SA_DQ(7)   I179 @S9S_MB_2U_LIB.S9S_MB_2U(SCH_1):PAGE108
    18 M_F_CPU1_SA_DQ<8> @S9S_MB_2U_LIB.S9S_MB_2U(SCH_1):M_F_CPU1_SA_DQ(8)   I179 @S9S_MB_2U_LIB.S9S_MB_2U(SCH_1):PAGE108
    20 M_F_CPU1_SA_DQ<9> @S9S_MB_2U_LIB.S9S_MB_2U(SCH_1):M_F_CPU1_SA_DQ(9)   I179 @S9S_MB_2U_LIB.S9S_MB_2U(SCH_1):PAGE108
   163 M_F_CPU1_SA_DQ<10> @S9S_MB_2U_LIB.S9S_MB_2U(SCH_1):M_F_CPU1_SA_DQ(10)   I179 @S9S_MB_2U_LIB.S9S_MB_2U(SCH_1):PAGE108
   165 M_F_CPU1_SA_DQ<11> @S9S_MB_2U_LIB.S9S_MB_2U(SCH_1):M_F_CPU1_SA_DQ(11)   I179 @S9S_MB_2U_LIB.S9S_MB_2U(SCH_1):PAGE108
    25 M_F_CPU1_SA_DQ<12> @S9S_MB_2U_LIB.S9S_MB_2U(SCH_1):M_F_CPU1_SA_DQ(12)   I179 @S9S_MB_2U_LIB.S9S_MB_2U(SCH_1):PAGE108
    27 M_F_CPU1_SA_DQ<13> @S9S_MB_2U_LIB.S9S_MB_2U(SCH_1):M_F_CPU1_SA_DQ(13)   I179 @S9S_MB_2U_LIB.S9S_MB_2U(SCH_1):PAGE108
   170 M_F_CPU1_SA_DQ<14> @S9S_MB_2U_LIB.S9S_MB_2U(SCH_1):M_F_CPU1_SA_DQ(14)   I179 @S9S_MB_2U_LIB.S9S_MB_2U(SCH_1):PAGE108
   172 M_F_CPU1_SA_DQ<15> @S9S_MB_2U_LIB.S9S_MB_2U(SCH_1):M_F_CPU1_SA_DQ(15)   I179 @S9S_MB_2U_LIB.S9S_MB_2U(SCH_1):PAGE108
    29 M_F_CPU1_SA_DQ<16> @S9S_MB_2U_LIB.S9S_MB_2U(SCH_1):M_F_CPU1_SA_DQ(16)   I179 @S9S_MB_2U_LIB.S9S_MB_2U(SCH_1):PAGE108
    31 M_F_CPU1_SA_DQ<17> @S9S_MB_2U_LIB.S9S_MB_2U(SCH_1):M_F_CPU1_SA_DQ(17)   I179 @S9S_MB_2U_LIB.S9S_MB_2U(SCH_1):PAGE108
   174 M_F_CPU1_SA_DQ<18> @S9S_MB_2U_LIB.S9S_MB_2U(SCH_1):M_F_CPU1_SA_DQ(18)   I179 @S9S_MB_2U_LIB.S9S_MB_2U(SCH_1):PAGE108
   176 M_F_CPU1_SA_DQ<19> @S9S_MB_2U_LIB.S9S_MB_2U(SCH_1):M_F_CPU1_SA_DQ(19)   I179 @S9S_MB_2U_LIB.S9S_MB_2U(SCH_1):PAGE108
    36 M_F_CPU1_SA_DQ<20> @S9S_MB_2U_LIB.S9S_MB_2U(SCH_1):M_F_CPU1_SA_DQ(20)   I179 @S9S_MB_2U_LIB.S9S_MB_2U(SCH_1):PAGE108
    38 M_F_CPU1_SA_DQ<21> @S9S_MB_2U_LIB.S9S_MB_2U(SCH_1):M_F_CPU1_SA_DQ(21)   I179 @S9S_MB_2U_LIB.S9S_MB_2U(SCH_1):PAGE108
   181 M_F_CPU1_SA_DQ<22> @S9S_MB_2U_LIB.S9S_MB_2U(SCH_1):M_F_CPU1_SA_DQ(22)   I179 @S9S_MB_2U_LIB.S9S_MB_2U(SCH_1):PAGE108
   183 M_F_CPU1_SA_DQ<23> @S9S_MB_2U_LIB.S9S_MB_2U(SCH_1):M_F_CPU1_SA_DQ(23)   I179 @S9S_MB_2U_LIB.S9S_MB_2U(SCH_1):PAGE108
    40 M_F_CPU1_SA_DQ<24> @S9S_MB_2U_LIB.S9S_MB_2U(SCH_1):M_F_CPU1_SA_DQ(24)   I179 @S9S_MB_2U_LIB.S9S_MB_2U(SCH_1):PAGE108
    42 M_F_CPU1_SA_DQ<25> @S9S_MB_2U_LIB.S9S_MB_2U(SCH_1):M_F_CPU1_SA_DQ(25)   I179 @S9S_MB_2U_LIB.S9S_MB_2U(SCH_1):PAGE108
   185 M_F_CPU1_SA_DQ<26> @S9S_MB_2U_LIB.S9S_MB_2U(SCH_1):M_F_CPU1_SA_DQ(26)   I179 @S9S_MB_2U_LIB.S9S_MB_2U(SCH_1):PAGE108
   187 M_F_CPU1_SA_DQ<27> @S9S_MB_2U_LIB.S9S_MB_2U(SCH_1):M_F_CPU1_SA_DQ(27)   I179 @S9S_MB_2U_LIB.S9S_MB_2U(SCH_1):PAGE108
    47 M_F_CPU1_SA_DQ<28> @S9S_MB_2U_LIB.S9S_MB_2U(SCH_1):M_F_CPU1_SA_DQ(28)   I179 @S9S_MB_2U_LIB.S9S_MB_2U(SCH_1):PAGE108
    49 M_F_CPU1_SA_DQ<29> @S9S_MB_2U_LIB.S9S_MB_2U(SCH_1):M_F_CPU1_SA_DQ(29)   I179 @S9S_MB_2U_LIB.S9S_MB_2U(SCH_1):PAGE108
   192 M_F_CPU1_SA_DQ<30> @S9S_MB_2U_LIB.S9S_MB_2U(SCH_1):M_F_CPU1_SA_DQ(30)   I179 @S9S_MB_2U_LIB.S9S_MB_2U(SCH_1):PAGE108
   229 M_F_CPU1_SB_CS_N<1> @S9S_MB_2U_LIB.S9S_MB_2U(SCH_1):M_F_CPU1_SB_CS_N(1)   I179 @S9S_MB_2U_LIB.S9S_MB_2U(SCH_1):PAGE108
   209 M_F_CPU1_SA_CS_N<1> @S9S_MB_2U_LIB.S9S_MB_2U(SCH_1):M_F_CPU1_SA_CS_N(1)   I179 @S9S_MB_2U_LIB.S9S_MB_2U(SCH_1):PAGE108
    84 M_F_CPU1_SB_CS_N<0> @S9S_MB_2U_LIB.S9S_MB_2U(SCH_1):M_F_CPU1_SB_CS_N(0)   I179 @S9S_MB_2U_LIB.S9S_MB_2U(SCH_1):PAGE108
    64 M_F_CPU1_SA_CS_N<0> @S9S_MB_2U_LIB.S9S_MB_2U(SCH_1):M_F_CPU1_SA_CS_N(0)   I179 @S9S_MB_2U_LIB.S9S_MB_2U(SCH_1):PAGE108
   217 M_F_CPU1_CLK_DP<0> @S9S_MB_2U_LIB.S9S_MB_2U(SCH_1):M_F_CPU1_CLK_DP(0)   I179 @S9S_MB_2U_LIB.S9S_MB_2U(SCH_1):PAGE108
   218 M_F_CPU1_CLK_DN<0> @S9S_MB_2U_LIB.S9S_MB_2U(SCH_1):M_F_CPU1_CLK_DN(0)   I179 @S9S_MB_2U_LIB.S9S_MB_2U(SCH_1):PAGE108
    96 M_F_CPU1_SB_CB<0> @S9S_MB_2U_LIB.S9S_MB_2U(SCH_1):M_F_CPU1_SB_CB(0)   I179 @S9S_MB_2U_LIB.S9S_MB_2U(SCH_1):PAGE108
    98 M_F_CPU1_SB_CB<1> @S9S_MB_2U_LIB.S9S_MB_2U(SCH_1):M_F_CPU1_SB_CB(1)   I179 @S9S_MB_2U_LIB.S9S_MB_2U(SCH_1):PAGE108
   241 M_F_CPU1_SB_CB<2> @S9S_MB_2U_LIB.S9S_MB_2U(SCH_1):M_F_CPU1_SB_CB(2)   I179 @S9S_MB_2U_LIB.S9S_MB_2U(SCH_1):PAGE108
   243 M_F_CPU1_SB_CB<3> @S9S_MB_2U_LIB.S9S_MB_2U(SCH_1):M_F_CPU1_SB_CB(3)   I179 @S9S_MB_2U_LIB.S9S_MB_2U(SCH_1):PAGE108
    89 M_F_CPU1_SB_CB<4> @S9S_MB_2U_LIB.S9S_MB_2U(SCH_1):M_F_CPU1_SB_CB(4)   I179 @S9S_MB_2U_LIB.S9S_MB_2U(SCH_1):PAGE108
    91 M_F_CPU1_SB_CB<5> @S9S_MB_2U_LIB.S9S_MB_2U(SCH_1):M_F_CPU1_SB_CB(5)   I179 @S9S_MB_2U_LIB.S9S_MB_2U(SCH_1):PAGE108
   234 M_F_CPU1_SB_CB<6> @S9S_MB_2U_LIB.S9S_MB_2U(SCH_1):M_F_CPU1_SB_CB(6)   I179 @S9S_MB_2U_LIB.S9S_MB_2U(SCH_1):PAGE108
    51 M_F_CPU1_SA_CB<0> @S9S_MB_2U_LIB.S9S_MB_2U(SCH_1):M_F_CPU1_SA_CB(0)   I179 @S9S_MB_2U_LIB.S9S_MB_2U(SCH_1):PAGE108
   196 M_F_CPU1_SA_CB<2> @S9S_MB_2U_LIB.S9S_MB_2U(SCH_1):M_F_CPU1_SA_CB(2)   I179 @S9S_MB_2U_LIB.S9S_MB_2U(SCH_1):PAGE108
   198 M_F_CPU1_SA_CB<3> @S9S_MB_2U_LIB.S9S_MB_2U(SCH_1):M_F_CPU1_SA_CB(3)   I179 @S9S_MB_2U_LIB.S9S_MB_2U(SCH_1):PAGE108
    60 M_F_CPU1_SA_CB<5> @S9S_MB_2U_LIB.S9S_MB_2U(SCH_1):M_F_CPU1_SA_CB(5)   I179 @S9S_MB_2U_LIB.S9S_MB_2U(SCH_1):PAGE108
   203 M_F_CPU1_SA_CB<6> @S9S_MB_2U_LIB.S9S_MB_2U(SCH_1):M_F_CPU1_SA_CB(6)   I179 @S9S_MB_2U_LIB.S9S_MB_2U(SCH_1):PAGE108
    82 M_F_CPU1_SB_CA<6> @S9S_MB_2U_LIB.S9S_MB_2U(SCH_1):M_F_CPU1_SB_CA(6)   I179 @S9S_MB_2U_LIB.S9S_MB_2U(SCH_1):PAGE108
    72 M_F_CPU1_SA_CA<6> @S9S_MB_2U_LIB.S9S_MB_2U(SCH_1):M_F_CPU1_SA_CA(6)   I179 @S9S_MB_2U_LIB.S9S_MB_2U(SCH_1):PAGE108
   225 M_F_CPU1_SB_CA<5> @S9S_MB_2U_LIB.S9S_MB_2U(SCH_1):M_F_CPU1_SB_CA(5)   I179 @S9S_MB_2U_LIB.S9S_MB_2U(SCH_1):PAGE108
   215 M_F_CPU1_SA_CA<5> @S9S_MB_2U_LIB.S9S_MB_2U(SCH_1):M_F_CPU1_SA_CA(5)   I179 @S9S_MB_2U_LIB.S9S_MB_2U(SCH_1):PAGE108
    80 M_F_CPU1_SB_CA<4> @S9S_MB_2U_LIB.S9S_MB_2U(SCH_1):M_F_CPU1_SB_CA(4)   I179 @S9S_MB_2U_LIB.S9S_MB_2U(SCH_1):PAGE108
    70 M_F_CPU1_SA_CA<4> @S9S_MB_2U_LIB.S9S_MB_2U(SCH_1):M_F_CPU1_SA_CA(4)   I179 @S9S_MB_2U_LIB.S9S_MB_2U(SCH_1):PAGE108
   223 M_F_CPU1_SB_CA<3> @S9S_MB_2U_LIB.S9S_MB_2U(SCH_1):M_F_CPU1_SB_CA(3)   I179 @S9S_MB_2U_LIB.S9S_MB_2U(SCH_1):PAGE108
   213 M_F_CPU1_SA_CA<3> @S9S_MB_2U_LIB.S9S_MB_2U(SCH_1):M_F_CPU1_SA_CA(3)   I179 @S9S_MB_2U_LIB.S9S_MB_2U(SCH_1):PAGE108
    78 M_F_CPU1_SB_CA<2> @S9S_MB_2U_LIB.S9S_MB_2U(SCH_1):M_F_CPU1_SB_CA(2)   I179 @S9S_MB_2U_LIB.S9S_MB_2U(SCH_1):PAGE108
    68 M_F_CPU1_SA_CA<2> @S9S_MB_2U_LIB.S9S_MB_2U(SCH_1):M_F_CPU1_SA_CA(2)   I179 @S9S_MB_2U_LIB.S9S_MB_2U(SCH_1):PAGE108
   221 M_F_CPU1_SB_CA<1> @S9S_MB_2U_LIB.S9S_MB_2U(SCH_1):M_F_CPU1_SB_CA(1)   I179 @S9S_MB_2U_LIB.S9S_MB_2U(SCH_1):PAGE108
   211 M_F_CPU1_SA_CA<1> @S9S_MB_2U_LIB.S9S_MB_2U(SCH_1):M_F_CPU1_SA_CA(1)   I179 @S9S_MB_2U_LIB.S9S_MB_2U(SCH_1):PAGE108
    76 M_F_CPU1_SB_CA<0> @S9S_MB_2U_LIB.S9S_MB_2U(SCH_1):M_F_CPU1_SB_CA(0)   I179 @S9S_MB_2U_LIB.S9S_MB_2U(SCH_1):PAGE108
    66 M_F_CPU1_SA_CA<0> @S9S_MB_2U_LIB.S9S_MB_2U(SCH_1):M_F_CPU1_SA_CA(0)   I179 @S9S_MB_2U_LIB.S9S_MB_2U(SCH_1):PAGE108
    62 M_F_CPU1_ALERT_N @S9S_MB_2U_LIB.S9S_MB_2U(SCH_1):M_F_CPU1_ALERT_N   I179 @S9S_MB_2U_LIB.S9S_MB_2U(SCH_1):PAGE108
   236 M_F_CPU1_SB_CB<7> @S9S_MB_2U_LIB.S9S_MB_2U(SCH_1):M_F_CPU1_SB_CB(7)   I179 @S9S_MB_2U_LIB.S9S_MB_2U(SCH_1):PAGE108
    53 M_F_CPU1_SA_CB<1> @S9S_MB_2U_LIB.S9S_MB_2U(SCH_1):M_F_CPU1_SA_CB(1)   I179 @S9S_MB_2U_LIB.S9S_MB_2U(SCH_1):PAGE108
    58 M_F_CPU1_SA_CB<4> @S9S_MB_2U_LIB.S9S_MB_2U(SCH_1):M_F_CPU1_SA_CB(4)   I179 @S9S_MB_2U_LIB.S9S_MB_2U(SCH_1):PAGE108
   205 M_F_CPU1_SA_CB<7> @S9S_MB_2U_LIB.S9S_MB_2U(SCH_1):M_F_CPU1_SA_CB(7)   I179 @S9S_MB_2U_LIB.S9S_MB_2U(SCH_1):PAGE108
   194 M_F_CPU1_SA_DQ<31> @S9S_MB_2U_LIB.S9S_MB_2U(SCH_1):M_F_CPU1_SA_DQ(31)   I179 @S9S_MB_2U_LIB.S9S_MB_2U(SCH_1):PAGE108
    93 M_F_CPU1_SB_DQS_DP<9> @S9S_MB_2U_LIB.S9S_MB_2U(SCH_1):M_F_CPU1_SB_DQS_DP(9)   I180 @S9S_MB_2U_LIB.S9S_MB_2U(SCH_1):PAGE108
    94 M_F_CPU1_SB_DQS_DN<9> @S9S_MB_2U_LIB.S9S_MB_2U(SCH_1):M_F_CPU1_SB_DQS_DN(9)   I180 @S9S_MB_2U_LIB.S9S_MB_2U(SCH_1):PAGE108
   201 M_F_CPU1_SA_DQS_DP<9> @S9S_MB_2U_LIB.S9S_MB_2U(SCH_1):M_F_CPU1_SA_DQS_DP(9)   I180 @S9S_MB_2U_LIB.S9S_MB_2U(SCH_1):PAGE108
   200 M_F_CPU1_SA_DQS_DN<9> @S9S_MB_2U_LIB.S9S_MB_2U(SCH_1):M_F_CPU1_SA_DQS_DN(9)   I180 @S9S_MB_2U_LIB.S9S_MB_2U(SCH_1):PAGE108
   190 M_F_CPU1_SA_DQS_DP<8> @S9S_MB_2U_LIB.S9S_MB_2U(SCH_1):M_F_CPU1_SA_DQS_DP(8)   I180 @S9S_MB_2U_LIB.S9S_MB_2U(SCH_1):PAGE108
   189 M_F_CPU1_SA_DQS_DN<8> @S9S_MB_2U_LIB.S9S_MB_2U(SCH_1):M_F_CPU1_SA_DQS_DN(8)   I180 @S9S_MB_2U_LIB.S9S_MB_2U(SCH_1):PAGE108
   271 M_F_CPU1_SB_DQS_DN<7> @S9S_MB_2U_LIB.S9S_MB_2U(SCH_1):M_F_CPU1_SB_DQS_DN(7)   I180 @S9S_MB_2U_LIB.S9S_MB_2U(SCH_1):PAGE108
   179 M_F_CPU1_SA_DQS_DP<7> @S9S_MB_2U_LIB.S9S_MB_2U(SCH_1):M_F_CPU1_SA_DQS_DP(7)   I180 @S9S_MB_2U_LIB.S9S_MB_2U(SCH_1):PAGE108
   261 M_F_CPU1_SB_DQS_DP<6> @S9S_MB_2U_LIB.S9S_MB_2U(SCH_1):M_F_CPU1_SB_DQS_DP(6)   I180 @S9S_MB_2U_LIB.S9S_MB_2U(SCH_1):PAGE108
   260 M_F_CPU1_SB_DQS_DN<6> @S9S_MB_2U_LIB.S9S_MB_2U(SCH_1):M_F_CPU1_SB_DQS_DN(6)   I180 @S9S_MB_2U_LIB.S9S_MB_2U(SCH_1):PAGE108
   167 M_F_CPU1_SA_DQS_DN<6> @S9S_MB_2U_LIB.S9S_MB_2U(SCH_1):M_F_CPU1_SA_DQS_DN(6)   I180 @S9S_MB_2U_LIB.S9S_MB_2U(SCH_1):PAGE108
   250 M_F_CPU1_SB_DQS_DP<5> @S9S_MB_2U_LIB.S9S_MB_2U(SCH_1):M_F_CPU1_SB_DQS_DP(5)   I180 @S9S_MB_2U_LIB.S9S_MB_2U(SCH_1):PAGE108
   249 M_F_CPU1_SB_DQS_DN<5> @S9S_MB_2U_LIB.S9S_MB_2U(SCH_1):M_F_CPU1_SB_DQS_DN(5)   I180 @S9S_MB_2U_LIB.S9S_MB_2U(SCH_1):PAGE108
   157 M_F_CPU1_SA_DQS_DP<5> @S9S_MB_2U_LIB.S9S_MB_2U(SCH_1):M_F_CPU1_SA_DQS_DP(5)   I180 @S9S_MB_2U_LIB.S9S_MB_2U(SCH_1):PAGE108
   156 M_F_CPU1_SA_DQS_DN<5> @S9S_MB_2U_LIB.S9S_MB_2U(SCH_1):M_F_CPU1_SA_DQS_DN(5)   I180 @S9S_MB_2U_LIB.S9S_MB_2U(SCH_1):PAGE108
   239 M_F_CPU1_SB_DQS_DP<4> @S9S_MB_2U_LIB.S9S_MB_2U(SCH_1):M_F_CPU1_SB_DQS_DP(4)   I180 @S9S_MB_2U_LIB.S9S_MB_2U(SCH_1):PAGE108
   238 M_F_CPU1_SB_DQS_DN<4> @S9S_MB_2U_LIB.S9S_MB_2U(SCH_1):M_F_CPU1_SB_DQS_DN(4)   I180 @S9S_MB_2U_LIB.S9S_MB_2U(SCH_1):PAGE108
    55 M_F_CPU1_SA_DQS_DP<4> @S9S_MB_2U_LIB.S9S_MB_2U(SCH_1):M_F_CPU1_SA_DQS_DP(4)   I180 @S9S_MB_2U_LIB.S9S_MB_2U(SCH_1):PAGE108
    56 M_F_CPU1_SA_DQS_DN<4> @S9S_MB_2U_LIB.S9S_MB_2U(SCH_1):M_F_CPU1_SA_DQS_DN(4)   I180 @S9S_MB_2U_LIB.S9S_MB_2U(SCH_1):PAGE108
   137 M_F_CPU1_SB_DQS_DP<3> @S9S_MB_2U_LIB.S9S_MB_2U(SCH_1):M_F_CPU1_SB_DQS_DP(3)   I180 @S9S_MB_2U_LIB.S9S_MB_2U(SCH_1):PAGE108
   138 M_F_CPU1_SB_DQS_DN<3> @S9S_MB_2U_LIB.S9S_MB_2U(SCH_1):M_F_CPU1_SB_DQS_DN(3)   I180 @S9S_MB_2U_LIB.S9S_MB_2U(SCH_1):PAGE108
    44 M_F_CPU1_SA_DQS_DP<3> @S9S_MB_2U_LIB.S9S_MB_2U(SCH_1):M_F_CPU1_SA_DQS_DP(3)   I180 @S9S_MB_2U_LIB.S9S_MB_2U(SCH_1):PAGE108
    45 M_F_CPU1_SA_DQS_DN<3> @S9S_MB_2U_LIB.S9S_MB_2U(SCH_1):M_F_CPU1_SA_DQS_DN(3)   I180 @S9S_MB_2U_LIB.S9S_MB_2U(SCH_1):PAGE108
   126 M_F_CPU1_SB_DQS_DP<2> @S9S_MB_2U_LIB.S9S_MB_2U(SCH_1):M_F_CPU1_SB_DQS_DP(2)   I180 @S9S_MB_2U_LIB.S9S_MB_2U(SCH_1):PAGE108
   127 M_F_CPU1_SB_DQS_DN<2> @S9S_MB_2U_LIB.S9S_MB_2U(SCH_1):M_F_CPU1_SB_DQS_DN(2)   I180 @S9S_MB_2U_LIB.S9S_MB_2U(SCH_1):PAGE108
    33 M_F_CPU1_SA_DQS_DP<2> @S9S_MB_2U_LIB.S9S_MB_2U(SCH_1):M_F_CPU1_SA_DQS_DP(2)   I180 @S9S_MB_2U_LIB.S9S_MB_2U(SCH_1):PAGE108
    34 M_F_CPU1_SA_DQS_DN<2> @S9S_MB_2U_LIB.S9S_MB_2U(SCH_1):M_F_CPU1_SA_DQS_DN(2)   I180 @S9S_MB_2U_LIB.S9S_MB_2U(SCH_1):PAGE108
   115 M_F_CPU1_SB_DQS_DP<1> @S9S_MB_2U_LIB.S9S_MB_2U(SCH_1):M_F_CPU1_SB_DQS_DP(1)   I180 @S9S_MB_2U_LIB.S9S_MB_2U(SCH_1):PAGE108
   116 M_F_CPU1_SB_DQS_DN<1> @S9S_MB_2U_LIB.S9S_MB_2U(SCH_1):M_F_CPU1_SB_DQS_DN(1)   I180 @S9S_MB_2U_LIB.S9S_MB_2U(SCH_1):PAGE108
    22 M_F_CPU1_SA_DQS_DP<1> @S9S_MB_2U_LIB.S9S_MB_2U(SCH_1):M_F_CPU1_SA_DQS_DP(1)   I180 @S9S_MB_2U_LIB.S9S_MB_2U(SCH_1):PAGE108
    23 M_F_CPU1_SA_DQS_DN<1> @S9S_MB_2U_LIB.S9S_MB_2U(SCH_1):M_F_CPU1_SA_DQS_DN(1)   I180 @S9S_MB_2U_LIB.S9S_MB_2U(SCH_1):PAGE108
   104 M_F_CPU1_SB_DQS_DP<0> @S9S_MB_2U_LIB.S9S_MB_2U(SCH_1):M_F_CPU1_SB_DQS_DP(0)   I180 @S9S_MB_2U_LIB.S9S_MB_2U(SCH_1):PAGE108
   105 M_F_CPU1_SB_DQS_DN<0> @S9S_MB_2U_LIB.S9S_MB_2U(SCH_1):M_F_CPU1_SB_DQS_DN(0)   I180 @S9S_MB_2U_LIB.S9S_MB_2U(SCH_1):PAGE108
    11 M_F_CPU1_SA_DQS_DP<0> @S9S_MB_2U_LIB.S9S_MB_2U(SCH_1):M_F_CPU1_SA_DQS_DP(0)   I180 @S9S_MB_2U_LIB.S9S_MB_2U(SCH_1):PAGE108
    12 M_F_CPU1_SA_DQS_DN<0> @S9S_MB_2U_LIB.S9S_MB_2U(SCH_1):M_F_CPU1_SA_DQS_DN(0)   I180 @S9S_MB_2U_LIB.S9S_MB_2U(SCH_1):PAGE108
   272 M_F_CPU1_SB_DQS_DP<7> @S9S_MB_2U_LIB.S9S_MB_2U(SCH_1):M_F_CPU1_SB_DQS_DP(7)   I180 @S9S_MB_2U_LIB.S9S_MB_2U(SCH_1):PAGE108
   282 M_F_CPU1_SB_DQS_DN<8> @S9S_MB_2U_LIB.S9S_MB_2U(SCH_1):M_F_CPU1_SB_DQS_DN(8)   I180 @S9S_MB_2U_LIB.S9S_MB_2U(SCH_1):PAGE108
   283 M_F_CPU1_SB_DQS_DP<8> @S9S_MB_2U_LIB.S9S_MB_2U(SCH_1):M_F_CPU1_SB_DQS_DP(8)   I180 @S9S_MB_2U_LIB.S9S_MB_2U(SCH_1):PAGE108
   168 M_F_CPU1_SA_DQS_DP<6> @S9S_MB_2U_LIB.S9S_MB_2U(SCH_1):M_F_CPU1_SA_DQS_DP(6)   I180 @S9S_MB_2U_LIB.S9S_MB_2U(SCH_1):PAGE108
   178 M_F_CPU1_SA_DQS_DN<7> @S9S_MB_2U_LIB.S9S_MB_2U(SCH_1):M_F_CPU1_SA_DQS_DN(7)   I180 @S9S_MB_2U_LIB.S9S_MB_2U(SCH_1):PAGE108
     6    GND @S9S_MB_2U_LIB.S9S_MB_2U(SCH_1):GND   I178 @S9S_MB_2U_LIB.S9S_MB_2U(SCH_1):PAGE108
     8    GND @S9S_MB_2U_LIB.S9S_MB_2U(SCH_1):GND   I178 @S9S_MB_2U_LIB.S9S_MB_2U(SCH_1):PAGE108
    10    GND @S9S_MB_2U_LIB.S9S_MB_2U(SCH_1):GND   I178 @S9S_MB_2U_LIB.S9S_MB_2U(SCH_1):PAGE108
    13    GND @S9S_MB_2U_LIB.S9S_MB_2U(SCH_1):GND   I178 @S9S_MB_2U_LIB.S9S_MB_2U(SCH_1):PAGE108
    15    GND @S9S_MB_2U_LIB.S9S_MB_2U(SCH_1):GND   I178 @S9S_MB_2U_LIB.S9S_MB_2U(SCH_1):PAGE108
    17    GND @S9S_MB_2U_LIB.S9S_MB_2U(SCH_1):GND   I178 @S9S_MB_2U_LIB.S9S_MB_2U(SCH_1):PAGE108
    19    GND @S9S_MB_2U_LIB.S9S_MB_2U(SCH_1):GND   I178 @S9S_MB_2U_LIB.S9S_MB_2U(SCH_1):PAGE108
    21    GND @S9S_MB_2U_LIB.S9S_MB_2U(SCH_1):GND   I178 @S9S_MB_2U_LIB.S9S_MB_2U(SCH_1):PAGE108
    24    GND @S9S_MB_2U_LIB.S9S_MB_2U(SCH_1):GND   I178 @S9S_MB_2U_LIB.S9S_MB_2U(SCH_1):PAGE108
    26    GND @S9S_MB_2U_LIB.S9S_MB_2U(SCH_1):GND   I178 @S9S_MB_2U_LIB.S9S_MB_2U(SCH_1):PAGE108
    28    GND @S9S_MB_2U_LIB.S9S_MB_2U(SCH_1):GND   I178 @S9S_MB_2U_LIB.S9S_MB_2U(SCH_1):PAGE108
    30    GND @S9S_MB_2U_LIB.S9S_MB_2U(SCH_1):GND   I178 @S9S_MB_2U_LIB.S9S_MB_2U(SCH_1):PAGE108
    32    GND @S9S_MB_2U_LIB.S9S_MB_2U(SCH_1):GND   I178 @S9S_MB_2U_LIB.S9S_MB_2U(SCH_1):PAGE108
    35    GND @S9S_MB_2U_LIB.S9S_MB_2U(SCH_1):GND   I178 @S9S_MB_2U_LIB.S9S_MB_2U(SCH_1):PAGE108
    37    GND @S9S_MB_2U_LIB.S9S_MB_2U(SCH_1):GND   I178 @S9S_MB_2U_LIB.S9S_MB_2U(SCH_1):PAGE108
    39    GND @S9S_MB_2U_LIB.S9S_MB_2U(SCH_1):GND   I178 @S9S_MB_2U_LIB.S9S_MB_2U(SCH_1):PAGE108
    41    GND @S9S_MB_2U_LIB.S9S_MB_2U(SCH_1):GND   I178 @S9S_MB_2U_LIB.S9S_MB_2U(SCH_1):PAGE108
    43    GND @S9S_MB_2U_LIB.S9S_MB_2U(SCH_1):GND   I178 @S9S_MB_2U_LIB.S9S_MB_2U(SCH_1):PAGE108
    46    GND @S9S_MB_2U_LIB.S9S_MB_2U(SCH_1):GND   I178 @S9S_MB_2U_LIB.S9S_MB_2U(SCH_1):PAGE108
    48    GND @S9S_MB_2U_LIB.S9S_MB_2U(SCH_1):GND   I178 @S9S_MB_2U_LIB.S9S_MB_2U(SCH_1):PAGE108
    50    GND @S9S_MB_2U_LIB.S9S_MB_2U(SCH_1):GND   I178 @S9S_MB_2U_LIB.S9S_MB_2U(SCH_1):PAGE108
    52    GND @S9S_MB_2U_LIB.S9S_MB_2U(SCH_1):GND   I178 @S9S_MB_2U_LIB.S9S_MB_2U(SCH_1):PAGE108
    54    GND @S9S_MB_2U_LIB.S9S_MB_2U(SCH_1):GND   I178 @S9S_MB_2U_LIB.S9S_MB_2U(SCH_1):PAGE108
    57    GND @S9S_MB_2U_LIB.S9S_MB_2U(SCH_1):GND   I178 @S9S_MB_2U_LIB.S9S_MB_2U(SCH_1):PAGE108
    59    GND @S9S_MB_2U_LIB.S9S_MB_2U(SCH_1):GND   I178 @S9S_MB_2U_LIB.S9S_MB_2U(SCH_1):PAGE108
    61    GND @S9S_MB_2U_LIB.S9S_MB_2U(SCH_1):GND   I178 @S9S_MB_2U_LIB.S9S_MB_2U(SCH_1):PAGE108
    63    GND @S9S_MB_2U_LIB.S9S_MB_2U(SCH_1):GND   I178 @S9S_MB_2U_LIB.S9S_MB_2U(SCH_1):PAGE108
    65    GND @S9S_MB_2U_LIB.S9S_MB_2U(SCH_1):GND   I178 @S9S_MB_2U_LIB.S9S_MB_2U(SCH_1):PAGE108
    67    GND @S9S_MB_2U_LIB.S9S_MB_2U(SCH_1):GND   I178 @S9S_MB_2U_LIB.S9S_MB_2U(SCH_1):PAGE108
    69    GND @S9S_MB_2U_LIB.S9S_MB_2U(SCH_1):GND   I178 @S9S_MB_2U_LIB.S9S_MB_2U(SCH_1):PAGE108
    71    GND @S9S_MB_2U_LIB.S9S_MB_2U(SCH_1):GND   I178 @S9S_MB_2U_LIB.S9S_MB_2U(SCH_1):PAGE108
    73    GND @S9S_MB_2U_LIB.S9S_MB_2U(SCH_1):GND   I178 @S9S_MB_2U_LIB.S9S_MB_2U(SCH_1):PAGE108
    75    GND @S9S_MB_2U_LIB.S9S_MB_2U(SCH_1):GND   I178 @S9S_MB_2U_LIB.S9S_MB_2U(SCH_1):PAGE108
    77    GND @S9S_MB_2U_LIB.S9S_MB_2U(SCH_1):GND   I178 @S9S_MB_2U_LIB.S9S_MB_2U(SCH_1):PAGE108
    79    GND @S9S_MB_2U_LIB.S9S_MB_2U(SCH_1):GND   I178 @S9S_MB_2U_LIB.S9S_MB_2U(SCH_1):PAGE108
    81    GND @S9S_MB_2U_LIB.S9S_MB_2U(SCH_1):GND   I178 @S9S_MB_2U_LIB.S9S_MB_2U(SCH_1):PAGE108
    83    GND @S9S_MB_2U_LIB.S9S_MB_2U(SCH_1):GND   I178 @S9S_MB_2U_LIB.S9S_MB_2U(SCH_1):PAGE108
    85    GND @S9S_MB_2U_LIB.S9S_MB_2U(SCH_1):GND   I178 @S9S_MB_2U_LIB.S9S_MB_2U(SCH_1):PAGE108
    88    GND @S9S_MB_2U_LIB.S9S_MB_2U(SCH_1):GND   I178 @S9S_MB_2U_LIB.S9S_MB_2U(SCH_1):PAGE108
    90    GND @S9S_MB_2U_LIB.S9S_MB_2U(SCH_1):GND   I178 @S9S_MB_2U_LIB.S9S_MB_2U(SCH_1):PAGE108
    92    GND @S9S_MB_2U_LIB.S9S_MB_2U(SCH_1):GND   I178 @S9S_MB_2U_LIB.S9S_MB_2U(SCH_1):PAGE108
    95    GND @S9S_MB_2U_LIB.S9S_MB_2U(SCH_1):GND   I178 @S9S_MB_2U_LIB.S9S_MB_2U(SCH_1):PAGE108
    97    GND @S9S_MB_2U_LIB.S9S_MB_2U(SCH_1):GND   I178 @S9S_MB_2U_LIB.S9S_MB_2U(SCH_1):PAGE108
    99    GND @S9S_MB_2U_LIB.S9S_MB_2U(SCH_1):GND   I178 @S9S_MB_2U_LIB.S9S_MB_2U(SCH_1):PAGE108
   101    GND @S9S_MB_2U_LIB.S9S_MB_2U(SCH_1):GND   I178 @S9S_MB_2U_LIB.S9S_MB_2U(SCH_1):PAGE108
   103    GND @S9S_MB_2U_LIB.S9S_MB_2U(SCH_1):GND   I178 @S9S_MB_2U_LIB.S9S_MB_2U(SCH_1):PAGE108
   106    GND @S9S_MB_2U_LIB.S9S_MB_2U(SCH_1):GND   I178 @S9S_MB_2U_LIB.S9S_MB_2U(SCH_1):PAGE108
   108    GND @S9S_MB_2U_LIB.S9S_MB_2U(SCH_1):GND   I178 @S9S_MB_2U_LIB.S9S_MB_2U(SCH_1):PAGE108
   110    GND @S9S_MB_2U_LIB.S9S_MB_2U(SCH_1):GND   I178 @S9S_MB_2U_LIB.S9S_MB_2U(SCH_1):PAGE108
   112    GND @S9S_MB_2U_LIB.S9S_MB_2U(SCH_1):GND   I178 @S9S_MB_2U_LIB.S9S_MB_2U(SCH_1):PAGE108
   114    GND @S9S_MB_2U_LIB.S9S_MB_2U(SCH_1):GND   I178 @S9S_MB_2U_LIB.S9S_MB_2U(SCH_1):PAGE108
   117    GND @S9S_MB_2U_LIB.S9S_MB_2U(SCH_1):GND   I178 @S9S_MB_2U_LIB.S9S_MB_2U(SCH_1):PAGE108
   119    GND @S9S_MB_2U_LIB.S9S_MB_2U(SCH_1):GND   I178 @S9S_MB_2U_LIB.S9S_MB_2U(SCH_1):PAGE108
   121    GND @S9S_MB_2U_LIB.S9S_MB_2U(SCH_1):GND   I178 @S9S_MB_2U_LIB.S9S_MB_2U(SCH_1):PAGE108
   123    GND @S9S_MB_2U_LIB.S9S_MB_2U(SCH_1):GND   I178 @S9S_MB_2U_LIB.S9S_MB_2U(SCH_1):PAGE108
   125    GND @S9S_MB_2U_LIB.S9S_MB_2U(SCH_1):GND   I178 @S9S_MB_2U_LIB.S9S_MB_2U(SCH_1):PAGE108
   128    GND @S9S_MB_2U_LIB.S9S_MB_2U(SCH_1):GND   I178 @S9S_MB_2U_LIB.S9S_MB_2U(SCH_1):PAGE108
   130    GND @S9S_MB_2U_LIB.S9S_MB_2U(SCH_1):GND   I178 @S9S_MB_2U_LIB.S9S_MB_2U(SCH_1):PAGE108
   134    GND @S9S_MB_2U_LIB.S9S_MB_2U(SCH_1):GND   I178 @S9S_MB_2U_LIB.S9S_MB_2U(SCH_1):PAGE108
   143    GND @S9S_MB_2U_LIB.S9S_MB_2U(SCH_1):GND   I178 @S9S_MB_2U_LIB.S9S_MB_2U(SCH_1):PAGE108
   151    GND @S9S_MB_2U_LIB.S9S_MB_2U(SCH_1):GND   I178 @S9S_MB_2U_LIB.S9S_MB_2U(SCH_1):PAGE108
   153    GND @S9S_MB_2U_LIB.S9S_MB_2U(SCH_1):GND   I178 @S9S_MB_2U_LIB.S9S_MB_2U(SCH_1):PAGE108
   155    GND @S9S_MB_2U_LIB.S9S_MB_2U(SCH_1):GND   I178 @S9S_MB_2U_LIB.S9S_MB_2U(SCH_1):PAGE108
   158    GND @S9S_MB_2U_LIB.S9S_MB_2U(SCH_1):GND   I178 @S9S_MB_2U_LIB.S9S_MB_2U(SCH_1):PAGE108
   160    GND @S9S_MB_2U_LIB.S9S_MB_2U(SCH_1):GND   I178 @S9S_MB_2U_LIB.S9S_MB_2U(SCH_1):PAGE108
   162    GND @S9S_MB_2U_LIB.S9S_MB_2U(SCH_1):GND   I178 @S9S_MB_2U_LIB.S9S_MB_2U(SCH_1):PAGE108
   164    GND @S9S_MB_2U_LIB.S9S_MB_2U(SCH_1):GND   I178 @S9S_MB_2U_LIB.S9S_MB_2U(SCH_1):PAGE108
   166    GND @S9S_MB_2U_LIB.S9S_MB_2U(SCH_1):GND   I178 @S9S_MB_2U_LIB.S9S_MB_2U(SCH_1):PAGE108
   169    GND @S9S_MB_2U_LIB.S9S_MB_2U(SCH_1):GND   I178 @S9S_MB_2U_LIB.S9S_MB_2U(SCH_1):PAGE108
   171    GND @S9S_MB_2U_LIB.S9S_MB_2U(SCH_1):GND   I178 @S9S_MB_2U_LIB.S9S_MB_2U(SCH_1):PAGE108
   173    GND @S9S_MB_2U_LIB.S9S_MB_2U(SCH_1):GND   I178 @S9S_MB_2U_LIB.S9S_MB_2U(SCH_1):PAGE108
   175    GND @S9S_MB_2U_LIB.S9S_MB_2U(SCH_1):GND   I178 @S9S_MB_2U_LIB.S9S_MB_2U(SCH_1):PAGE108
   177    GND @S9S_MB_2U_LIB.S9S_MB_2U(SCH_1):GND   I178 @S9S_MB_2U_LIB.S9S_MB_2U(SCH_1):PAGE108
   180    GND @S9S_MB_2U_LIB.S9S_MB_2U(SCH_1):GND   I178 @S9S_MB_2U_LIB.S9S_MB_2U(SCH_1):PAGE108
   182    GND @S9S_MB_2U_LIB.S9S_MB_2U(SCH_1):GND   I178 @S9S_MB_2U_LIB.S9S_MB_2U(SCH_1):PAGE108
   184    GND @S9S_MB_2U_LIB.S9S_MB_2U(SCH_1):GND   I178 @S9S_MB_2U_LIB.S9S_MB_2U(SCH_1):PAGE108
   186    GND @S9S_MB_2U_LIB.S9S_MB_2U(SCH_1):GND   I178 @S9S_MB_2U_LIB.S9S_MB_2U(SCH_1):PAGE108
   188    GND @S9S_MB_2U_LIB.S9S_MB_2U(SCH_1):GND   I178 @S9S_MB_2U_LIB.S9S_MB_2U(SCH_1):PAGE108
   191    GND @S9S_MB_2U_LIB.S9S_MB_2U(SCH_1):GND   I178 @S9S_MB_2U_LIB.S9S_MB_2U(SCH_1):PAGE108
   193    GND @S9S_MB_2U_LIB.S9S_MB_2U(SCH_1):GND   I178 @S9S_MB_2U_LIB.S9S_MB_2U(SCH_1):PAGE108
   195    GND @S9S_MB_2U_LIB.S9S_MB_2U(SCH_1):GND   I178 @S9S_MB_2U_LIB.S9S_MB_2U(SCH_1):PAGE108
   197    GND @S9S_MB_2U_LIB.S9S_MB_2U(SCH_1):GND   I178 @S9S_MB_2U_LIB.S9S_MB_2U(SCH_1):PAGE108
   199    GND @S9S_MB_2U_LIB.S9S_MB_2U(SCH_1):GND   I178 @S9S_MB_2U_LIB.S9S_MB_2U(SCH_1):PAGE108
   202    GND @S9S_MB_2U_LIB.S9S_MB_2U(SCH_1):GND   I178 @S9S_MB_2U_LIB.S9S_MB_2U(SCH_1):PAGE108
   204    GND @S9S_MB_2U_LIB.S9S_MB_2U(SCH_1):GND   I178 @S9S_MB_2U_LIB.S9S_MB_2U(SCH_1):PAGE108
   206    GND @S9S_MB_2U_LIB.S9S_MB_2U(SCH_1):GND   I178 @S9S_MB_2U_LIB.S9S_MB_2U(SCH_1):PAGE108
   208    GND @S9S_MB_2U_LIB.S9S_MB_2U(SCH_1):GND   I178 @S9S_MB_2U_LIB.S9S_MB_2U(SCH_1):PAGE108
   210    GND @S9S_MB_2U_LIB.S9S_MB_2U(SCH_1):GND   I178 @S9S_MB_2U_LIB.S9S_MB_2U(SCH_1):PAGE108
   212    GND @S9S_MB_2U_LIB.S9S_MB_2U(SCH_1):GND   I178 @S9S_MB_2U_LIB.S9S_MB_2U(SCH_1):PAGE108
   214    GND @S9S_MB_2U_LIB.S9S_MB_2U(SCH_1):GND   I178 @S9S_MB_2U_LIB.S9S_MB_2U(SCH_1):PAGE108
   216    GND @S9S_MB_2U_LIB.S9S_MB_2U(SCH_1):GND   I178 @S9S_MB_2U_LIB.S9S_MB_2U(SCH_1):PAGE108
   219    GND @S9S_MB_2U_LIB.S9S_MB_2U(SCH_1):GND   I178 @S9S_MB_2U_LIB.S9S_MB_2U(SCH_1):PAGE108
   222    GND @S9S_MB_2U_LIB.S9S_MB_2U(SCH_1):GND   I178 @S9S_MB_2U_LIB.S9S_MB_2U(SCH_1):PAGE108
   224    GND @S9S_MB_2U_LIB.S9S_MB_2U(SCH_1):GND   I178 @S9S_MB_2U_LIB.S9S_MB_2U(SCH_1):PAGE108
   226    GND @S9S_MB_2U_LIB.S9S_MB_2U(SCH_1):GND   I178 @S9S_MB_2U_LIB.S9S_MB_2U(SCH_1):PAGE108
   228    GND @S9S_MB_2U_LIB.S9S_MB_2U(SCH_1):GND   I178 @S9S_MB_2U_LIB.S9S_MB_2U(SCH_1):PAGE108
   233    GND @S9S_MB_2U_LIB.S9S_MB_2U(SCH_1):GND   I178 @S9S_MB_2U_LIB.S9S_MB_2U(SCH_1):PAGE108
   237    GND @S9S_MB_2U_LIB.S9S_MB_2U(SCH_1):GND   I178 @S9S_MB_2U_LIB.S9S_MB_2U(SCH_1):PAGE108
   242    GND @S9S_MB_2U_LIB.S9S_MB_2U(SCH_1):GND   I178 @S9S_MB_2U_LIB.S9S_MB_2U(SCH_1):PAGE108
   244    GND @S9S_MB_2U_LIB.S9S_MB_2U(SCH_1):GND   I178 @S9S_MB_2U_LIB.S9S_MB_2U(SCH_1):PAGE108
   246    GND @S9S_MB_2U_LIB.S9S_MB_2U(SCH_1):GND   I178 @S9S_MB_2U_LIB.S9S_MB_2U(SCH_1):PAGE108
   248    GND @S9S_MB_2U_LIB.S9S_MB_2U(SCH_1):GND   I178 @S9S_MB_2U_LIB.S9S_MB_2U(SCH_1):PAGE108
   251    GND @S9S_MB_2U_LIB.S9S_MB_2U(SCH_1):GND   I178 @S9S_MB_2U_LIB.S9S_MB_2U(SCH_1):PAGE108
   253    GND @S9S_MB_2U_LIB.S9S_MB_2U(SCH_1):GND   I178 @S9S_MB_2U_LIB.S9S_MB_2U(SCH_1):PAGE108
   255    GND @S9S_MB_2U_LIB.S9S_MB_2U(SCH_1):GND   I178 @S9S_MB_2U_LIB.S9S_MB_2U(SCH_1):PAGE108
   257    GND @S9S_MB_2U_LIB.S9S_MB_2U(SCH_1):GND   I178 @S9S_MB_2U_LIB.S9S_MB_2U(SCH_1):PAGE108
   259    GND @S9S_MB_2U_LIB.S9S_MB_2U(SCH_1):GND   I178 @S9S_MB_2U_LIB.S9S_MB_2U(SCH_1):PAGE108
   262    GND @S9S_MB_2U_LIB.S9S_MB_2U(SCH_1):GND   I178 @S9S_MB_2U_LIB.S9S_MB_2U(SCH_1):PAGE108
   264    GND @S9S_MB_2U_LIB.S9S_MB_2U(SCH_1):GND   I178 @S9S_MB_2U_LIB.S9S_MB_2U(SCH_1):PAGE108
   266    GND @S9S_MB_2U_LIB.S9S_MB_2U(SCH_1):GND   I178 @S9S_MB_2U_LIB.S9S_MB_2U(SCH_1):PAGE108
   268    GND @S9S_MB_2U_LIB.S9S_MB_2U(SCH_1):GND   I178 @S9S_MB_2U_LIB.S9S_MB_2U(SCH_1):PAGE108
   270    GND @S9S_MB_2U_LIB.S9S_MB_2U(SCH_1):GND   I178 @S9S_MB_2U_LIB.S9S_MB_2U(SCH_1):PAGE108
   273    GND @S9S_MB_2U_LIB.S9S_MB_2U(SCH_1):GND   I178 @S9S_MB_2U_LIB.S9S_MB_2U(SCH_1):PAGE108
   275    GND @S9S_MB_2U_LIB.S9S_MB_2U(SCH_1):GND   I178 @S9S_MB_2U_LIB.S9S_MB_2U(SCH_1):PAGE108
   277    GND @S9S_MB_2U_LIB.S9S_MB_2U(SCH_1):GND   I178 @S9S_MB_2U_LIB.S9S_MB_2U(SCH_1):PAGE108
   279    GND @S9S_MB_2U_LIB.S9S_MB_2U(SCH_1):GND   I178 @S9S_MB_2U_LIB.S9S_MB_2U(SCH_1):PAGE108
   281    GND @S9S_MB_2U_LIB.S9S_MB_2U(SCH_1):GND   I178 @S9S_MB_2U_LIB.S9S_MB_2U(SCH_1):PAGE108
   284    GND @S9S_MB_2U_LIB.S9S_MB_2U(SCH_1):GND   I178 @S9S_MB_2U_LIB.S9S_MB_2U(SCH_1):PAGE108
   286    GND @S9S_MB_2U_LIB.S9S_MB_2U(SCH_1):GND   I178 @S9S_MB_2U_LIB.S9S_MB_2U(SCH_1):PAGE108
   288    GND @S9S_MB_2U_LIB.S9S_MB_2U(SCH_1):GND   I178 @S9S_MB_2U_LIB.S9S_MB_2U(SCH_1):PAGE108
     1 P12V_S3_AUX_CPU1_NVDIMM @S9S_MB_2U_LIB.S9S_MB_2U(SCH_1):P12V_S3_AUX_CPU1_NVDIMM   I178 @S9S_MB_2U_LIB.S9S_MB_2U(SCH_1):PAGE108
   145 P12V_S3_AUX_CPU1_NVDIMM @S9S_MB_2U_LIB.S9S_MB_2U(SCH_1):P12V_S3_AUX_CPU1_NVDIMM   I178 @S9S_MB_2U_LIB.S9S_MB_2U(SCH_1):PAGE108
   146 P12V_S3_AUX_CPU1_NVDIMM @S9S_MB_2U_LIB.S9S_MB_2U(SCH_1):P12V_S3_AUX_CPU1_NVDIMM   I178 @S9S_MB_2U_LIB.S9S_MB_2U(SCH_1):PAGE108
   230    GND @S9S_MB_2U_LIB.S9S_MB_2U(SCH_1):GND   I178 @S9S_MB_2U_LIB.S9S_MB_2U(SCH_1):PAGE108
   235    GND @S9S_MB_2U_LIB.S9S_MB_2U(SCH_1):GND   I178 @S9S_MB_2U_LIB.S9S_MB_2U(SCH_1):PAGE108
   240    GND @S9S_MB_2U_LIB.S9S_MB_2U(SCH_1):GND   I178 @S9S_MB_2U_LIB.S9S_MB_2U(SCH_1):PAGE108
   132    GND @S9S_MB_2U_LIB.S9S_MB_2U(SCH_1):GND   I178 @S9S_MB_2U_LIB.S9S_MB_2U(SCH_1):PAGE108
   136    GND @S9S_MB_2U_LIB.S9S_MB_2U(SCH_1):GND   I178 @S9S_MB_2U_LIB.S9S_MB_2U(SCH_1):PAGE108
   139    GND @S9S_MB_2U_LIB.S9S_MB_2U(SCH_1):GND   I178 @S9S_MB_2U_LIB.S9S_MB_2U(SCH_1):PAGE108
   141    GND @S9S_MB_2U_LIB.S9S_MB_2U(SCH_1):GND   I178 @S9S_MB_2U_LIB.S9S_MB_2U(SCH_1):PAGE108
    G1    GND @S9S_MB_2U_LIB.S9S_MB_2U(SCH_1):GND   I178 @S9S_MB_2U_LIB.S9S_MB_2U(SCH_1):PAGE108
    G2    GND @S9S_MB_2U_LIB.S9S_MB_2U(SCH_1):GND   I178 @S9S_MB_2U_LIB.S9S_MB_2U(SCH_1):PAGE108
    G3    GND @S9S_MB_2U_LIB.S9S_MB_2U(SCH_1):GND   I178 @S9S_MB_2U_LIB.S9S_MB_2U(SCH_1):PAGE108

 J28 SCONN288_ADR50017P087CC-SCONN2A
     3 P3V3_AUX @S9S_MB_2U_LIB.S9S_MB_2U(SCH_1):P3V3_AUX    I47 @S9S_MB_2U_LIB.S9S_MB_2U(SCH_1):PAGE109
     2 TP_CHF_CPU1_DIMM2_FRU_0 @S9S_MB_2U_LIB.S9S_MB_2U(SCH_1):TP_CHF_CPU1_DIMM2_FRU_0    I47 @S9S_MB_2U_LIB.S9S_MB_2U(SCH_1):PAGE109
   144 TP_CHF_CPU1_DIMM2_FRU_1 @S9S_MB_2U_LIB.S9S_MB_2U(SCH_1):TP_CHF_CPU1_DIMM2_FRU_1    I47 @S9S_MB_2U_LIB.S9S_MB_2U(SCH_1):PAGE109
   149 TP_CHF_CPU1_DIMM2_FRU_2 @S9S_MB_2U_LIB.S9S_MB_2U(SCH_1):TP_CHF_CPU1_DIMM2_FRU_2    I47 @S9S_MB_2U_LIB.S9S_MB_2U(SCH_1):PAGE109
   150 TP_CHF_CPU1_DIMM2_FRU_3 @S9S_MB_2U_LIB.S9S_MB_2U(SCH_1):TP_CHF_CPU1_DIMM2_FRU_3    I47 @S9S_MB_2U_LIB.S9S_MB_2U(SCH_1):PAGE109
   220 TP_CHF_CPU1_DIMM2_FRU_4 @S9S_MB_2U_LIB.S9S_MB_2U(SCH_1):TP_CHF_CPU1_DIMM2_FRU_4    I47 @S9S_MB_2U_LIB.S9S_MB_2U(SCH_1):PAGE109
   231 TP_CHF_CPU1_DIMM2_FRU_5 @S9S_MB_2U_LIB.S9S_MB_2U(SCH_1):TP_CHF_CPU1_DIMM2_FRU_5    I47 @S9S_MB_2U_LIB.S9S_MB_2U(SCH_1):PAGE109
   232 TP_CHF_CPU1_DIMM2_FRU_6 @S9S_MB_2U_LIB.S9S_MB_2U(SCH_1):TP_CHF_CPU1_DIMM2_FRU_6    I47 @S9S_MB_2U_LIB.S9S_MB_2U(SCH_1):PAGE109
   207 RST_M_EF_CPU1_FPGA_N @S9S_MB_2U_LIB.S9S_MB_2U(SCH_1):RST_M_EF_CPU1_FPGA_N    I47 @S9S_MB_2U_LIB.S9S_MB_2U(SCH_1):PAGE109
   147 PWRGD_CHF_CPU1_DIMM2 @S9S_MB_2U_LIB.S9S_MB_2U(SCH_1):PWRGD_CHF_CPU1_DIMM2    I47 @S9S_MB_2U_LIB.S9S_MB_2U(SCH_1):PAGE109
   227 M_F_CPU1_SB_PAR @S9S_MB_2U_LIB.S9S_MB_2U(SCH_1):M_F_CPU1_SB_PAR    I47 @S9S_MB_2U_LIB.S9S_MB_2U(SCH_1):PAGE109
    74 M_F_CPU1_SA_PAR @S9S_MB_2U_LIB.S9S_MB_2U(SCH_1):M_F_CPU1_SA_PAR    I47 @S9S_MB_2U_LIB.S9S_MB_2U(SCH_1):PAGE109
    87 M_F_CPU1_SB_RSP<1> @S9S_MB_2U_LIB.S9S_MB_2U(SCH_1):M_F_CPU1_SB_RSP(1)    I47 @S9S_MB_2U_LIB.S9S_MB_2U(SCH_1):PAGE109
    86 M_F_CPU1_SA_RSP<1> @S9S_MB_2U_LIB.S9S_MB_2U(SCH_1):M_F_CPU1_SA_RSP(1)    I47 @S9S_MB_2U_LIB.S9S_MB_2U(SCH_1):PAGE109
     5 I3C_SPD_DDREFGH_CPU1_LVC1_SDA @S9S_MB_2U_LIB.S9S_MB_2U(SCH_1):I3C_SPD_DDREFGH_CPU1_LVC1_SDA    I47 @S9S_MB_2U_LIB.S9S_MB_2U(SCH_1):PAGE109
     4 I3C_SPD_DDREFGH_CPU1_LVC1_SCL_3 @S9S_MB_2U_LIB.S9S_MB_2U(SCH_1):I3C_SPD_DDREFGH_CPU1_LVC1_SCL_R4    I47 @S9S_MB_2U_LIB.S9S_MB_2U(SCH_1):PAGE109
   148 PD_CHF_CPU1_DIMM2_SAA @S9S_MB_2U_LIB.S9S_MB_2U(SCH_1):PD_CHF_CPU1_DIMM2_SAA    I47 @S9S_MB_2U_LIB.S9S_MB_2U(SCH_1):PAGE109
   100 M_F_CPU1_SB_DQ<0> @S9S_MB_2U_LIB.S9S_MB_2U(SCH_1):M_F_CPU1_SB_DQ(0)    I47 @S9S_MB_2U_LIB.S9S_MB_2U(SCH_1):PAGE109
   102 M_F_CPU1_SB_DQ<1> @S9S_MB_2U_LIB.S9S_MB_2U(SCH_1):M_F_CPU1_SB_DQ(1)    I47 @S9S_MB_2U_LIB.S9S_MB_2U(SCH_1):PAGE109
   245 M_F_CPU1_SB_DQ<2> @S9S_MB_2U_LIB.S9S_MB_2U(SCH_1):M_F_CPU1_SB_DQ(2)    I47 @S9S_MB_2U_LIB.S9S_MB_2U(SCH_1):PAGE109
   247 M_F_CPU1_SB_DQ<3> @S9S_MB_2U_LIB.S9S_MB_2U(SCH_1):M_F_CPU1_SB_DQ(3)    I47 @S9S_MB_2U_LIB.S9S_MB_2U(SCH_1):PAGE109
   107 M_F_CPU1_SB_DQ<4> @S9S_MB_2U_LIB.S9S_MB_2U(SCH_1):M_F_CPU1_SB_DQ(4)    I47 @S9S_MB_2U_LIB.S9S_MB_2U(SCH_1):PAGE109
   109 M_F_CPU1_SB_DQ<5> @S9S_MB_2U_LIB.S9S_MB_2U(SCH_1):M_F_CPU1_SB_DQ(5)    I47 @S9S_MB_2U_LIB.S9S_MB_2U(SCH_1):PAGE109
   252 M_F_CPU1_SB_DQ<6> @S9S_MB_2U_LIB.S9S_MB_2U(SCH_1):M_F_CPU1_SB_DQ(6)    I47 @S9S_MB_2U_LIB.S9S_MB_2U(SCH_1):PAGE109
   254 M_F_CPU1_SB_DQ<7> @S9S_MB_2U_LIB.S9S_MB_2U(SCH_1):M_F_CPU1_SB_DQ(7)    I47 @S9S_MB_2U_LIB.S9S_MB_2U(SCH_1):PAGE109
   111 M_F_CPU1_SB_DQ<8> @S9S_MB_2U_LIB.S9S_MB_2U(SCH_1):M_F_CPU1_SB_DQ(8)    I47 @S9S_MB_2U_LIB.S9S_MB_2U(SCH_1):PAGE109
   113 M_F_CPU1_SB_DQ<9> @S9S_MB_2U_LIB.S9S_MB_2U(SCH_1):M_F_CPU1_SB_DQ(9)    I47 @S9S_MB_2U_LIB.S9S_MB_2U(SCH_1):PAGE109
   256 M_F_CPU1_SB_DQ<10> @S9S_MB_2U_LIB.S9S_MB_2U(SCH_1):M_F_CPU1_SB_DQ(10)    I47 @S9S_MB_2U_LIB.S9S_MB_2U(SCH_1):PAGE109
   258 M_F_CPU1_SB_DQ<11> @S9S_MB_2U_LIB.S9S_MB_2U(SCH_1):M_F_CPU1_SB_DQ(11)    I47 @S9S_MB_2U_LIB.S9S_MB_2U(SCH_1):PAGE109
   118 M_F_CPU1_SB_DQ<12> @S9S_MB_2U_LIB.S9S_MB_2U(SCH_1):M_F_CPU1_SB_DQ(12)    I47 @S9S_MB_2U_LIB.S9S_MB_2U(SCH_1):PAGE109
   120 M_F_CPU1_SB_DQ<13> @S9S_MB_2U_LIB.S9S_MB_2U(SCH_1):M_F_CPU1_SB_DQ(13)    I47 @S9S_MB_2U_LIB.S9S_MB_2U(SCH_1):PAGE109
   263 M_F_CPU1_SB_DQ<14> @S9S_MB_2U_LIB.S9S_MB_2U(SCH_1):M_F_CPU1_SB_DQ(14)    I47 @S9S_MB_2U_LIB.S9S_MB_2U(SCH_1):PAGE109
   265 M_F_CPU1_SB_DQ<15> @S9S_MB_2U_LIB.S9S_MB_2U(SCH_1):M_F_CPU1_SB_DQ(15)    I47 @S9S_MB_2U_LIB.S9S_MB_2U(SCH_1):PAGE109
   122 M_F_CPU1_SB_DQ<16> @S9S_MB_2U_LIB.S9S_MB_2U(SCH_1):M_F_CPU1_SB_DQ(16)    I47 @S9S_MB_2U_LIB.S9S_MB_2U(SCH_1):PAGE109
   124 M_F_CPU1_SB_DQ<17> @S9S_MB_2U_LIB.S9S_MB_2U(SCH_1):M_F_CPU1_SB_DQ(17)    I47 @S9S_MB_2U_LIB.S9S_MB_2U(SCH_1):PAGE109
   267 M_F_CPU1_SB_DQ<18> @S9S_MB_2U_LIB.S9S_MB_2U(SCH_1):M_F_CPU1_SB_DQ(18)    I47 @S9S_MB_2U_LIB.S9S_MB_2U(SCH_1):PAGE109
   269 M_F_CPU1_SB_DQ<19> @S9S_MB_2U_LIB.S9S_MB_2U(SCH_1):M_F_CPU1_SB_DQ(19)    I47 @S9S_MB_2U_LIB.S9S_MB_2U(SCH_1):PAGE109
   129 M_F_CPU1_SB_DQ<20> @S9S_MB_2U_LIB.S9S_MB_2U(SCH_1):M_F_CPU1_SB_DQ(20)    I47 @S9S_MB_2U_LIB.S9S_MB_2U(SCH_1):PAGE109
   131 M_F_CPU1_SB_DQ<21> @S9S_MB_2U_LIB.S9S_MB_2U(SCH_1):M_F_CPU1_SB_DQ(21)    I47 @S9S_MB_2U_LIB.S9S_MB_2U(SCH_1):PAGE109
   274 M_F_CPU1_SB_DQ<22> @S9S_MB_2U_LIB.S9S_MB_2U(SCH_1):M_F_CPU1_SB_DQ(22)    I47 @S9S_MB_2U_LIB.S9S_MB_2U(SCH_1):PAGE109
   276 M_F_CPU1_SB_DQ<23> @S9S_MB_2U_LIB.S9S_MB_2U(SCH_1):M_F_CPU1_SB_DQ(23)    I47 @S9S_MB_2U_LIB.S9S_MB_2U(SCH_1):PAGE109
   133 M_F_CPU1_SB_DQ<24> @S9S_MB_2U_LIB.S9S_MB_2U(SCH_1):M_F_CPU1_SB_DQ(24)    I47 @S9S_MB_2U_LIB.S9S_MB_2U(SCH_1):PAGE109
   135 M_F_CPU1_SB_DQ<25> @S9S_MB_2U_LIB.S9S_MB_2U(SCH_1):M_F_CPU1_SB_DQ(25)    I47 @S9S_MB_2U_LIB.S9S_MB_2U(SCH_1):PAGE109
   278 M_F_CPU1_SB_DQ<26> @S9S_MB_2U_LIB.S9S_MB_2U(SCH_1):M_F_CPU1_SB_DQ(26)    I47 @S9S_MB_2U_LIB.S9S_MB_2U(SCH_1):PAGE109
   280 M_F_CPU1_SB_DQ<27> @S9S_MB_2U_LIB.S9S_MB_2U(SCH_1):M_F_CPU1_SB_DQ(27)    I47 @S9S_MB_2U_LIB.S9S_MB_2U(SCH_1):PAGE109
   140 M_F_CPU1_SB_DQ<28> @S9S_MB_2U_LIB.S9S_MB_2U(SCH_1):M_F_CPU1_SB_DQ(28)    I47 @S9S_MB_2U_LIB.S9S_MB_2U(SCH_1):PAGE109
   142 M_F_CPU1_SB_DQ<29> @S9S_MB_2U_LIB.S9S_MB_2U(SCH_1):M_F_CPU1_SB_DQ(29)    I47 @S9S_MB_2U_LIB.S9S_MB_2U(SCH_1):PAGE109
   285 M_F_CPU1_SB_DQ<30> @S9S_MB_2U_LIB.S9S_MB_2U(SCH_1):M_F_CPU1_SB_DQ(30)    I47 @S9S_MB_2U_LIB.S9S_MB_2U(SCH_1):PAGE109
   287 M_F_CPU1_SB_DQ<31> @S9S_MB_2U_LIB.S9S_MB_2U(SCH_1):M_F_CPU1_SB_DQ(31)    I47 @S9S_MB_2U_LIB.S9S_MB_2U(SCH_1):PAGE109
     7 M_F_CPU1_SA_DQ<0> @S9S_MB_2U_LIB.S9S_MB_2U(SCH_1):M_F_CPU1_SA_DQ(0)    I47 @S9S_MB_2U_LIB.S9S_MB_2U(SCH_1):PAGE109
     9 M_F_CPU1_SA_DQ<1> @S9S_MB_2U_LIB.S9S_MB_2U(SCH_1):M_F_CPU1_SA_DQ(1)    I47 @S9S_MB_2U_LIB.S9S_MB_2U(SCH_1):PAGE109
   152 M_F_CPU1_SA_DQ<2> @S9S_MB_2U_LIB.S9S_MB_2U(SCH_1):M_F_CPU1_SA_DQ(2)    I47 @S9S_MB_2U_LIB.S9S_MB_2U(SCH_1):PAGE109
   154 M_F_CPU1_SA_DQ<3> @S9S_MB_2U_LIB.S9S_MB_2U(SCH_1):M_F_CPU1_SA_DQ(3)    I47 @S9S_MB_2U_LIB.S9S_MB_2U(SCH_1):PAGE109
    14 M_F_CPU1_SA_DQ<4> @S9S_MB_2U_LIB.S9S_MB_2U(SCH_1):M_F_CPU1_SA_DQ(4)    I47 @S9S_MB_2U_LIB.S9S_MB_2U(SCH_1):PAGE109
    16 M_F_CPU1_SA_DQ<5> @S9S_MB_2U_LIB.S9S_MB_2U(SCH_1):M_F_CPU1_SA_DQ(5)    I47 @S9S_MB_2U_LIB.S9S_MB_2U(SCH_1):PAGE109
   159 M_F_CPU1_SA_DQ<6> @S9S_MB_2U_LIB.S9S_MB_2U(SCH_1):M_F_CPU1_SA_DQ(6)    I47 @S9S_MB_2U_LIB.S9S_MB_2U(SCH_1):PAGE109
   161 M_F_CPU1_SA_DQ<7> @S9S_MB_2U_LIB.S9S_MB_2U(SCH_1):M_F_CPU1_SA_DQ(7)    I47 @S9S_MB_2U_LIB.S9S_MB_2U(SCH_1):PAGE109
    18 M_F_CPU1_SA_DQ<8> @S9S_MB_2U_LIB.S9S_MB_2U(SCH_1):M_F_CPU1_SA_DQ(8)    I47 @S9S_MB_2U_LIB.S9S_MB_2U(SCH_1):PAGE109
    20 M_F_CPU1_SA_DQ<9> @S9S_MB_2U_LIB.S9S_MB_2U(SCH_1):M_F_CPU1_SA_DQ(9)    I47 @S9S_MB_2U_LIB.S9S_MB_2U(SCH_1):PAGE109
   163 M_F_CPU1_SA_DQ<10> @S9S_MB_2U_LIB.S9S_MB_2U(SCH_1):M_F_CPU1_SA_DQ(10)    I47 @S9S_MB_2U_LIB.S9S_MB_2U(SCH_1):PAGE109
   165 M_F_CPU1_SA_DQ<11> @S9S_MB_2U_LIB.S9S_MB_2U(SCH_1):M_F_CPU1_SA_DQ(11)    I47 @S9S_MB_2U_LIB.S9S_MB_2U(SCH_1):PAGE109
    25 M_F_CPU1_SA_DQ<12> @S9S_MB_2U_LIB.S9S_MB_2U(SCH_1):M_F_CPU1_SA_DQ(12)    I47 @S9S_MB_2U_LIB.S9S_MB_2U(SCH_1):PAGE109
    27 M_F_CPU1_SA_DQ<13> @S9S_MB_2U_LIB.S9S_MB_2U(SCH_1):M_F_CPU1_SA_DQ(13)    I47 @S9S_MB_2U_LIB.S9S_MB_2U(SCH_1):PAGE109
   170 M_F_CPU1_SA_DQ<14> @S9S_MB_2U_LIB.S9S_MB_2U(SCH_1):M_F_CPU1_SA_DQ(14)    I47 @S9S_MB_2U_LIB.S9S_MB_2U(SCH_1):PAGE109
   172 M_F_CPU1_SA_DQ<15> @S9S_MB_2U_LIB.S9S_MB_2U(SCH_1):M_F_CPU1_SA_DQ(15)    I47 @S9S_MB_2U_LIB.S9S_MB_2U(SCH_1):PAGE109
    29 M_F_CPU1_SA_DQ<16> @S9S_MB_2U_LIB.S9S_MB_2U(SCH_1):M_F_CPU1_SA_DQ(16)    I47 @S9S_MB_2U_LIB.S9S_MB_2U(SCH_1):PAGE109
    31 M_F_CPU1_SA_DQ<17> @S9S_MB_2U_LIB.S9S_MB_2U(SCH_1):M_F_CPU1_SA_DQ(17)    I47 @S9S_MB_2U_LIB.S9S_MB_2U(SCH_1):PAGE109
   174 M_F_CPU1_SA_DQ<18> @S9S_MB_2U_LIB.S9S_MB_2U(SCH_1):M_F_CPU1_SA_DQ(18)    I47 @S9S_MB_2U_LIB.S9S_MB_2U(SCH_1):PAGE109
   176 M_F_CPU1_SA_DQ<19> @S9S_MB_2U_LIB.S9S_MB_2U(SCH_1):M_F_CPU1_SA_DQ(19)    I47 @S9S_MB_2U_LIB.S9S_MB_2U(SCH_1):PAGE109
    36 M_F_CPU1_SA_DQ<20> @S9S_MB_2U_LIB.S9S_MB_2U(SCH_1):M_F_CPU1_SA_DQ(20)    I47 @S9S_MB_2U_LIB.S9S_MB_2U(SCH_1):PAGE109
    38 M_F_CPU1_SA_DQ<21> @S9S_MB_2U_LIB.S9S_MB_2U(SCH_1):M_F_CPU1_SA_DQ(21)    I47 @S9S_MB_2U_LIB.S9S_MB_2U(SCH_1):PAGE109
   181 M_F_CPU1_SA_DQ<22> @S9S_MB_2U_LIB.S9S_MB_2U(SCH_1):M_F_CPU1_SA_DQ(22)    I47 @S9S_MB_2U_LIB.S9S_MB_2U(SCH_1):PAGE109
   183 M_F_CPU1_SA_DQ<23> @S9S_MB_2U_LIB.S9S_MB_2U(SCH_1):M_F_CPU1_SA_DQ(23)    I47 @S9S_MB_2U_LIB.S9S_MB_2U(SCH_1):PAGE109
    40 M_F_CPU1_SA_DQ<24> @S9S_MB_2U_LIB.S9S_MB_2U(SCH_1):M_F_CPU1_SA_DQ(24)    I47 @S9S_MB_2U_LIB.S9S_MB_2U(SCH_1):PAGE109
    42 M_F_CPU1_SA_DQ<25> @S9S_MB_2U_LIB.S9S_MB_2U(SCH_1):M_F_CPU1_SA_DQ(25)    I47 @S9S_MB_2U_LIB.S9S_MB_2U(SCH_1):PAGE109
   185 M_F_CPU1_SA_DQ<26> @S9S_MB_2U_LIB.S9S_MB_2U(SCH_1):M_F_CPU1_SA_DQ(26)    I47 @S9S_MB_2U_LIB.S9S_MB_2U(SCH_1):PAGE109
   187 M_F_CPU1_SA_DQ<27> @S9S_MB_2U_LIB.S9S_MB_2U(SCH_1):M_F_CPU1_SA_DQ(27)    I47 @S9S_MB_2U_LIB.S9S_MB_2U(SCH_1):PAGE109
    47 M_F_CPU1_SA_DQ<28> @S9S_MB_2U_LIB.S9S_MB_2U(SCH_1):M_F_CPU1_SA_DQ(28)    I47 @S9S_MB_2U_LIB.S9S_MB_2U(SCH_1):PAGE109
    49 M_F_CPU1_SA_DQ<29> @S9S_MB_2U_LIB.S9S_MB_2U(SCH_1):M_F_CPU1_SA_DQ(29)    I47 @S9S_MB_2U_LIB.S9S_MB_2U(SCH_1):PAGE109
   192 M_F_CPU1_SA_DQ<30> @S9S_MB_2U_LIB.S9S_MB_2U(SCH_1):M_F_CPU1_SA_DQ(30)    I47 @S9S_MB_2U_LIB.S9S_MB_2U(SCH_1):PAGE109
   229 M_F_CPU1_SB_CS_N<3> @S9S_MB_2U_LIB.S9S_MB_2U(SCH_1):M_F_CPU1_SB_CS_N(3)    I47 @S9S_MB_2U_LIB.S9S_MB_2U(SCH_1):PAGE109
   209 M_F_CPU1_SA_CS_N<3> @S9S_MB_2U_LIB.S9S_MB_2U(SCH_1):M_F_CPU1_SA_CS_N(3)    I47 @S9S_MB_2U_LIB.S9S_MB_2U(SCH_1):PAGE109
    84 M_F_CPU1_SB_CS_N<2> @S9S_MB_2U_LIB.S9S_MB_2U(SCH_1):M_F_CPU1_SB_CS_N(2)    I47 @S9S_MB_2U_LIB.S9S_MB_2U(SCH_1):PAGE109
    64 M_F_CPU1_SA_CS_N<2> @S9S_MB_2U_LIB.S9S_MB_2U(SCH_1):M_F_CPU1_SA_CS_N(2)    I47 @S9S_MB_2U_LIB.S9S_MB_2U(SCH_1):PAGE109
   217 M_F_CPU1_CLK_DP<1> @S9S_MB_2U_LIB.S9S_MB_2U(SCH_1):M_F_CPU1_CLK_DP(1)    I47 @S9S_MB_2U_LIB.S9S_MB_2U(SCH_1):PAGE109
   218 M_F_CPU1_CLK_DN<1> @S9S_MB_2U_LIB.S9S_MB_2U(SCH_1):M_F_CPU1_CLK_DN(1)    I47 @S9S_MB_2U_LIB.S9S_MB_2U(SCH_1):PAGE109
    96 M_F_CPU1_SB_CB<0> @S9S_MB_2U_LIB.S9S_MB_2U(SCH_1):M_F_CPU1_SB_CB(0)    I47 @S9S_MB_2U_LIB.S9S_MB_2U(SCH_1):PAGE109
    98 M_F_CPU1_SB_CB<1> @S9S_MB_2U_LIB.S9S_MB_2U(SCH_1):M_F_CPU1_SB_CB(1)    I47 @S9S_MB_2U_LIB.S9S_MB_2U(SCH_1):PAGE109
   241 M_F_CPU1_SB_CB<2> @S9S_MB_2U_LIB.S9S_MB_2U(SCH_1):M_F_CPU1_SB_CB(2)    I47 @S9S_MB_2U_LIB.S9S_MB_2U(SCH_1):PAGE109
   243 M_F_CPU1_SB_CB<3> @S9S_MB_2U_LIB.S9S_MB_2U(SCH_1):M_F_CPU1_SB_CB(3)    I47 @S9S_MB_2U_LIB.S9S_MB_2U(SCH_1):PAGE109
    89 M_F_CPU1_SB_CB<4> @S9S_MB_2U_LIB.S9S_MB_2U(SCH_1):M_F_CPU1_SB_CB(4)    I47 @S9S_MB_2U_LIB.S9S_MB_2U(SCH_1):PAGE109
    91 M_F_CPU1_SB_CB<5> @S9S_MB_2U_LIB.S9S_MB_2U(SCH_1):M_F_CPU1_SB_CB(5)    I47 @S9S_MB_2U_LIB.S9S_MB_2U(SCH_1):PAGE109
   234 M_F_CPU1_SB_CB<6> @S9S_MB_2U_LIB.S9S_MB_2U(SCH_1):M_F_CPU1_SB_CB(6)    I47 @S9S_MB_2U_LIB.S9S_MB_2U(SCH_1):PAGE109
    51 M_F_CPU1_SA_CB<0> @S9S_MB_2U_LIB.S9S_MB_2U(SCH_1):M_F_CPU1_SA_CB(0)    I47 @S9S_MB_2U_LIB.S9S_MB_2U(SCH_1):PAGE109
   196 M_F_CPU1_SA_CB<2> @S9S_MB_2U_LIB.S9S_MB_2U(SCH_1):M_F_CPU1_SA_CB(2)    I47 @S9S_MB_2U_LIB.S9S_MB_2U(SCH_1):PAGE109
   198 M_F_CPU1_SA_CB<3> @S9S_MB_2U_LIB.S9S_MB_2U(SCH_1):M_F_CPU1_SA_CB(3)    I47 @S9S_MB_2U_LIB.S9S_MB_2U(SCH_1):PAGE109
    60 M_F_CPU1_SA_CB<5> @S9S_MB_2U_LIB.S9S_MB_2U(SCH_1):M_F_CPU1_SA_CB(5)    I47 @S9S_MB_2U_LIB.S9S_MB_2U(SCH_1):PAGE109
   203 M_F_CPU1_SA_CB<6> @S9S_MB_2U_LIB.S9S_MB_2U(SCH_1):M_F_CPU1_SA_CB(6)    I47 @S9S_MB_2U_LIB.S9S_MB_2U(SCH_1):PAGE109
    82 M_F_CPU1_SB_CA<6> @S9S_MB_2U_LIB.S9S_MB_2U(SCH_1):M_F_CPU1_SB_CA(6)    I47 @S9S_MB_2U_LIB.S9S_MB_2U(SCH_1):PAGE109
    72 M_F_CPU1_SA_CA<6> @S9S_MB_2U_LIB.S9S_MB_2U(SCH_1):M_F_CPU1_SA_CA(6)    I47 @S9S_MB_2U_LIB.S9S_MB_2U(SCH_1):PAGE109
   225 M_F_CPU1_SB_CA<5> @S9S_MB_2U_LIB.S9S_MB_2U(SCH_1):M_F_CPU1_SB_CA(5)    I47 @S9S_MB_2U_LIB.S9S_MB_2U(SCH_1):PAGE109
   215 M_F_CPU1_SA_CA<5> @S9S_MB_2U_LIB.S9S_MB_2U(SCH_1):M_F_CPU1_SA_CA(5)    I47 @S9S_MB_2U_LIB.S9S_MB_2U(SCH_1):PAGE109
    80 M_F_CPU1_SB_CA<4> @S9S_MB_2U_LIB.S9S_MB_2U(SCH_1):M_F_CPU1_SB_CA(4)    I47 @S9S_MB_2U_LIB.S9S_MB_2U(SCH_1):PAGE109
    70 M_F_CPU1_SA_CA<4> @S9S_MB_2U_LIB.S9S_MB_2U(SCH_1):M_F_CPU1_SA_CA(4)    I47 @S9S_MB_2U_LIB.S9S_MB_2U(SCH_1):PAGE109
   223 M_F_CPU1_SB_CA<3> @S9S_MB_2U_LIB.S9S_MB_2U(SCH_1):M_F_CPU1_SB_CA(3)    I47 @S9S_MB_2U_LIB.S9S_MB_2U(SCH_1):PAGE109
   213 M_F_CPU1_SA_CA<3> @S9S_MB_2U_LIB.S9S_MB_2U(SCH_1):M_F_CPU1_SA_CA(3)    I47 @S9S_MB_2U_LIB.S9S_MB_2U(SCH_1):PAGE109
    78 M_F_CPU1_SB_CA<2> @S9S_MB_2U_LIB.S9S_MB_2U(SCH_1):M_F_CPU1_SB_CA(2)    I47 @S9S_MB_2U_LIB.S9S_MB_2U(SCH_1):PAGE109
    68 M_F_CPU1_SA_CA<2> @S9S_MB_2U_LIB.S9S_MB_2U(SCH_1):M_F_CPU1_SA_CA(2)    I47 @S9S_MB_2U_LIB.S9S_MB_2U(SCH_1):PAGE109
   221 M_F_CPU1_SB_CA<1> @S9S_MB_2U_LIB.S9S_MB_2U(SCH_1):M_F_CPU1_SB_CA(1)    I47 @S9S_MB_2U_LIB.S9S_MB_2U(SCH_1):PAGE109
   211 M_F_CPU1_SA_CA<1> @S9S_MB_2U_LIB.S9S_MB_2U(SCH_1):M_F_CPU1_SA_CA(1)    I47 @S9S_MB_2U_LIB.S9S_MB_2U(SCH_1):PAGE109
    76 M_F_CPU1_SB_CA<0> @S9S_MB_2U_LIB.S9S_MB_2U(SCH_1):M_F_CPU1_SB_CA(0)    I47 @S9S_MB_2U_LIB.S9S_MB_2U(SCH_1):PAGE109
    66 M_F_CPU1_SA_CA<0> @S9S_MB_2U_LIB.S9S_MB_2U(SCH_1):M_F_CPU1_SA_CA(0)    I47 @S9S_MB_2U_LIB.S9S_MB_2U(SCH_1):PAGE109
    62 M_F_CPU1_ALERT_N @S9S_MB_2U_LIB.S9S_MB_2U(SCH_1):M_F_CPU1_ALERT_N    I47 @S9S_MB_2U_LIB.S9S_MB_2U(SCH_1):PAGE109
   236 M_F_CPU1_SB_CB<7> @S9S_MB_2U_LIB.S9S_MB_2U(SCH_1):M_F_CPU1_SB_CB(7)    I47 @S9S_MB_2U_LIB.S9S_MB_2U(SCH_1):PAGE109
    53 M_F_CPU1_SA_CB<1> @S9S_MB_2U_LIB.S9S_MB_2U(SCH_1):M_F_CPU1_SA_CB(1)    I47 @S9S_MB_2U_LIB.S9S_MB_2U(SCH_1):PAGE109
    58 M_F_CPU1_SA_CB<4> @S9S_MB_2U_LIB.S9S_MB_2U(SCH_1):M_F_CPU1_SA_CB(4)    I47 @S9S_MB_2U_LIB.S9S_MB_2U(SCH_1):PAGE109
   205 M_F_CPU1_SA_CB<7> @S9S_MB_2U_LIB.S9S_MB_2U(SCH_1):M_F_CPU1_SA_CB(7)    I47 @S9S_MB_2U_LIB.S9S_MB_2U(SCH_1):PAGE109
   194 M_F_CPU1_SA_DQ<31> @S9S_MB_2U_LIB.S9S_MB_2U(SCH_1):M_F_CPU1_SA_DQ(31)    I47 @S9S_MB_2U_LIB.S9S_MB_2U(SCH_1):PAGE109
    93 M_F_CPU1_SB_DQS_DP<9> @S9S_MB_2U_LIB.S9S_MB_2U(SCH_1):M_F_CPU1_SB_DQS_DP(9)   I178 @S9S_MB_2U_LIB.S9S_MB_2U(SCH_1):PAGE109
    94 M_F_CPU1_SB_DQS_DN<9> @S9S_MB_2U_LIB.S9S_MB_2U(SCH_1):M_F_CPU1_SB_DQS_DN(9)   I178 @S9S_MB_2U_LIB.S9S_MB_2U(SCH_1):PAGE109
   201 M_F_CPU1_SA_DQS_DP<9> @S9S_MB_2U_LIB.S9S_MB_2U(SCH_1):M_F_CPU1_SA_DQS_DP(9)   I178 @S9S_MB_2U_LIB.S9S_MB_2U(SCH_1):PAGE109
   200 M_F_CPU1_SA_DQS_DN<9> @S9S_MB_2U_LIB.S9S_MB_2U(SCH_1):M_F_CPU1_SA_DQS_DN(9)   I178 @S9S_MB_2U_LIB.S9S_MB_2U(SCH_1):PAGE109
   190 M_F_CPU1_SA_DQS_DP<8> @S9S_MB_2U_LIB.S9S_MB_2U(SCH_1):M_F_CPU1_SA_DQS_DP(8)   I178 @S9S_MB_2U_LIB.S9S_MB_2U(SCH_1):PAGE109
   189 M_F_CPU1_SA_DQS_DN<8> @S9S_MB_2U_LIB.S9S_MB_2U(SCH_1):M_F_CPU1_SA_DQS_DN(8)   I178 @S9S_MB_2U_LIB.S9S_MB_2U(SCH_1):PAGE109
   271 M_F_CPU1_SB_DQS_DN<7> @S9S_MB_2U_LIB.S9S_MB_2U(SCH_1):M_F_CPU1_SB_DQS_DN(7)   I178 @S9S_MB_2U_LIB.S9S_MB_2U(SCH_1):PAGE109
   179 M_F_CPU1_SA_DQS_DP<7> @S9S_MB_2U_LIB.S9S_MB_2U(SCH_1):M_F_CPU1_SA_DQS_DP(7)   I178 @S9S_MB_2U_LIB.S9S_MB_2U(SCH_1):PAGE109
   261 M_F_CPU1_SB_DQS_DP<6> @S9S_MB_2U_LIB.S9S_MB_2U(SCH_1):M_F_CPU1_SB_DQS_DP(6)   I178 @S9S_MB_2U_LIB.S9S_MB_2U(SCH_1):PAGE109
   260 M_F_CPU1_SB_DQS_DN<6> @S9S_MB_2U_LIB.S9S_MB_2U(SCH_1):M_F_CPU1_SB_DQS_DN(6)   I178 @S9S_MB_2U_LIB.S9S_MB_2U(SCH_1):PAGE109
   167 M_F_CPU1_SA_DQS_DN<6> @S9S_MB_2U_LIB.S9S_MB_2U(SCH_1):M_F_CPU1_SA_DQS_DN(6)   I178 @S9S_MB_2U_LIB.S9S_MB_2U(SCH_1):PAGE109
   250 M_F_CPU1_SB_DQS_DP<5> @S9S_MB_2U_LIB.S9S_MB_2U(SCH_1):M_F_CPU1_SB_DQS_DP(5)   I178 @S9S_MB_2U_LIB.S9S_MB_2U(SCH_1):PAGE109
   249 M_F_CPU1_SB_DQS_DN<5> @S9S_MB_2U_LIB.S9S_MB_2U(SCH_1):M_F_CPU1_SB_DQS_DN(5)   I178 @S9S_MB_2U_LIB.S9S_MB_2U(SCH_1):PAGE109
   157 M_F_CPU1_SA_DQS_DP<5> @S9S_MB_2U_LIB.S9S_MB_2U(SCH_1):M_F_CPU1_SA_DQS_DP(5)   I178 @S9S_MB_2U_LIB.S9S_MB_2U(SCH_1):PAGE109
   156 M_F_CPU1_SA_DQS_DN<5> @S9S_MB_2U_LIB.S9S_MB_2U(SCH_1):M_F_CPU1_SA_DQS_DN(5)   I178 @S9S_MB_2U_LIB.S9S_MB_2U(SCH_1):PAGE109
   239 M_F_CPU1_SB_DQS_DP<4> @S9S_MB_2U_LIB.S9S_MB_2U(SCH_1):M_F_CPU1_SB_DQS_DP(4)   I178 @S9S_MB_2U_LIB.S9S_MB_2U(SCH_1):PAGE109
   238 M_F_CPU1_SB_DQS_DN<4> @S9S_MB_2U_LIB.S9S_MB_2U(SCH_1):M_F_CPU1_SB_DQS_DN(4)   I178 @S9S_MB_2U_LIB.S9S_MB_2U(SCH_1):PAGE109
    55 M_F_CPU1_SA_DQS_DP<4> @S9S_MB_2U_LIB.S9S_MB_2U(SCH_1):M_F_CPU1_SA_DQS_DP(4)   I178 @S9S_MB_2U_LIB.S9S_MB_2U(SCH_1):PAGE109
    56 M_F_CPU1_SA_DQS_DN<4> @S9S_MB_2U_LIB.S9S_MB_2U(SCH_1):M_F_CPU1_SA_DQS_DN(4)   I178 @S9S_MB_2U_LIB.S9S_MB_2U(SCH_1):PAGE109
   137 M_F_CPU1_SB_DQS_DP<3> @S9S_MB_2U_LIB.S9S_MB_2U(SCH_1):M_F_CPU1_SB_DQS_DP(3)   I178 @S9S_MB_2U_LIB.S9S_MB_2U(SCH_1):PAGE109
   138 M_F_CPU1_SB_DQS_DN<3> @S9S_MB_2U_LIB.S9S_MB_2U(SCH_1):M_F_CPU1_SB_DQS_DN(3)   I178 @S9S_MB_2U_LIB.S9S_MB_2U(SCH_1):PAGE109
    44 M_F_CPU1_SA_DQS_DP<3> @S9S_MB_2U_LIB.S9S_MB_2U(SCH_1):M_F_CPU1_SA_DQS_DP(3)   I178 @S9S_MB_2U_LIB.S9S_MB_2U(SCH_1):PAGE109
    45 M_F_CPU1_SA_DQS_DN<3> @S9S_MB_2U_LIB.S9S_MB_2U(SCH_1):M_F_CPU1_SA_DQS_DN(3)   I178 @S9S_MB_2U_LIB.S9S_MB_2U(SCH_1):PAGE109
   126 M_F_CPU1_SB_DQS_DP<2> @S9S_MB_2U_LIB.S9S_MB_2U(SCH_1):M_F_CPU1_SB_DQS_DP(2)   I178 @S9S_MB_2U_LIB.S9S_MB_2U(SCH_1):PAGE109
   127 M_F_CPU1_SB_DQS_DN<2> @S9S_MB_2U_LIB.S9S_MB_2U(SCH_1):M_F_CPU1_SB_DQS_DN(2)   I178 @S9S_MB_2U_LIB.S9S_MB_2U(SCH_1):PAGE109
    33 M_F_CPU1_SA_DQS_DP<2> @S9S_MB_2U_LIB.S9S_MB_2U(SCH_1):M_F_CPU1_SA_DQS_DP(2)   I178 @S9S_MB_2U_LIB.S9S_MB_2U(SCH_1):PAGE109
    34 M_F_CPU1_SA_DQS_DN<2> @S9S_MB_2U_LIB.S9S_MB_2U(SCH_1):M_F_CPU1_SA_DQS_DN(2)   I178 @S9S_MB_2U_LIB.S9S_MB_2U(SCH_1):PAGE109
   115 M_F_CPU1_SB_DQS_DP<1> @S9S_MB_2U_LIB.S9S_MB_2U(SCH_1):M_F_CPU1_SB_DQS_DP(1)   I178 @S9S_MB_2U_LIB.S9S_MB_2U(SCH_1):PAGE109
   116 M_F_CPU1_SB_DQS_DN<1> @S9S_MB_2U_LIB.S9S_MB_2U(SCH_1):M_F_CPU1_SB_DQS_DN(1)   I178 @S9S_MB_2U_LIB.S9S_MB_2U(SCH_1):PAGE109
    22 M_F_CPU1_SA_DQS_DP<1> @S9S_MB_2U_LIB.S9S_MB_2U(SCH_1):M_F_CPU1_SA_DQS_DP(1)   I178 @S9S_MB_2U_LIB.S9S_MB_2U(SCH_1):PAGE109
    23 M_F_CPU1_SA_DQS_DN<1> @S9S_MB_2U_LIB.S9S_MB_2U(SCH_1):M_F_CPU1_SA_DQS_DN(1)   I178 @S9S_MB_2U_LIB.S9S_MB_2U(SCH_1):PAGE109
   104 M_F_CPU1_SB_DQS_DP<0> @S9S_MB_2U_LIB.S9S_MB_2U(SCH_1):M_F_CPU1_SB_DQS_DP(0)   I178 @S9S_MB_2U_LIB.S9S_MB_2U(SCH_1):PAGE109
   105 M_F_CPU1_SB_DQS_DN<0> @S9S_MB_2U_LIB.S9S_MB_2U(SCH_1):M_F_CPU1_SB_DQS_DN(0)   I178 @S9S_MB_2U_LIB.S9S_MB_2U(SCH_1):PAGE109
    11 M_F_CPU1_SA_DQS_DP<0> @S9S_MB_2U_LIB.S9S_MB_2U(SCH_1):M_F_CPU1_SA_DQS_DP(0)   I178 @S9S_MB_2U_LIB.S9S_MB_2U(SCH_1):PAGE109
    12 M_F_CPU1_SA_DQS_DN<0> @S9S_MB_2U_LIB.S9S_MB_2U(SCH_1):M_F_CPU1_SA_DQS_DN(0)   I178 @S9S_MB_2U_LIB.S9S_MB_2U(SCH_1):PAGE109
   272 M_F_CPU1_SB_DQS_DP<7> @S9S_MB_2U_LIB.S9S_MB_2U(SCH_1):M_F_CPU1_SB_DQS_DP(7)   I178 @S9S_MB_2U_LIB.S9S_MB_2U(SCH_1):PAGE109
   282 M_F_CPU1_SB_DQS_DN<8> @S9S_MB_2U_LIB.S9S_MB_2U(SCH_1):M_F_CPU1_SB_DQS_DN(8)   I178 @S9S_MB_2U_LIB.S9S_MB_2U(SCH_1):PAGE109
   283 M_F_CPU1_SB_DQS_DP<8> @S9S_MB_2U_LIB.S9S_MB_2U(SCH_1):M_F_CPU1_SB_DQS_DP(8)   I178 @S9S_MB_2U_LIB.S9S_MB_2U(SCH_1):PAGE109
   168 M_F_CPU1_SA_DQS_DP<6> @S9S_MB_2U_LIB.S9S_MB_2U(SCH_1):M_F_CPU1_SA_DQS_DP(6)   I178 @S9S_MB_2U_LIB.S9S_MB_2U(SCH_1):PAGE109
   178 M_F_CPU1_SA_DQS_DN<7> @S9S_MB_2U_LIB.S9S_MB_2U(SCH_1):M_F_CPU1_SA_DQS_DN(7)   I178 @S9S_MB_2U_LIB.S9S_MB_2U(SCH_1):PAGE109
     6    GND @S9S_MB_2U_LIB.S9S_MB_2U(SCH_1):GND   I176 @S9S_MB_2U_LIB.S9S_MB_2U(SCH_1):PAGE109
     8    GND @S9S_MB_2U_LIB.S9S_MB_2U(SCH_1):GND   I176 @S9S_MB_2U_LIB.S9S_MB_2U(SCH_1):PAGE109
    10    GND @S9S_MB_2U_LIB.S9S_MB_2U(SCH_1):GND   I176 @S9S_MB_2U_LIB.S9S_MB_2U(SCH_1):PAGE109
    13    GND @S9S_MB_2U_LIB.S9S_MB_2U(SCH_1):GND   I176 @S9S_MB_2U_LIB.S9S_MB_2U(SCH_1):PAGE109
    15    GND @S9S_MB_2U_LIB.S9S_MB_2U(SCH_1):GND   I176 @S9S_MB_2U_LIB.S9S_MB_2U(SCH_1):PAGE109
    17    GND @S9S_MB_2U_LIB.S9S_MB_2U(SCH_1):GND   I176 @S9S_MB_2U_LIB.S9S_MB_2U(SCH_1):PAGE109
    19    GND @S9S_MB_2U_LIB.S9S_MB_2U(SCH_1):GND   I176 @S9S_MB_2U_LIB.S9S_MB_2U(SCH_1):PAGE109
    21    GND @S9S_MB_2U_LIB.S9S_MB_2U(SCH_1):GND   I176 @S9S_MB_2U_LIB.S9S_MB_2U(SCH_1):PAGE109
    24    GND @S9S_MB_2U_LIB.S9S_MB_2U(SCH_1):GND   I176 @S9S_MB_2U_LIB.S9S_MB_2U(SCH_1):PAGE109
    26    GND @S9S_MB_2U_LIB.S9S_MB_2U(SCH_1):GND   I176 @S9S_MB_2U_LIB.S9S_MB_2U(SCH_1):PAGE109
    28    GND @S9S_MB_2U_LIB.S9S_MB_2U(SCH_1):GND   I176 @S9S_MB_2U_LIB.S9S_MB_2U(SCH_1):PAGE109
    30    GND @S9S_MB_2U_LIB.S9S_MB_2U(SCH_1):GND   I176 @S9S_MB_2U_LIB.S9S_MB_2U(SCH_1):PAGE109
    32    GND @S9S_MB_2U_LIB.S9S_MB_2U(SCH_1):GND   I176 @S9S_MB_2U_LIB.S9S_MB_2U(SCH_1):PAGE109
    35    GND @S9S_MB_2U_LIB.S9S_MB_2U(SCH_1):GND   I176 @S9S_MB_2U_LIB.S9S_MB_2U(SCH_1):PAGE109
    37    GND @S9S_MB_2U_LIB.S9S_MB_2U(SCH_1):GND   I176 @S9S_MB_2U_LIB.S9S_MB_2U(SCH_1):PAGE109
    39    GND @S9S_MB_2U_LIB.S9S_MB_2U(SCH_1):GND   I176 @S9S_MB_2U_LIB.S9S_MB_2U(SCH_1):PAGE109
    41    GND @S9S_MB_2U_LIB.S9S_MB_2U(SCH_1):GND   I176 @S9S_MB_2U_LIB.S9S_MB_2U(SCH_1):PAGE109
    43    GND @S9S_MB_2U_LIB.S9S_MB_2U(SCH_1):GND   I176 @S9S_MB_2U_LIB.S9S_MB_2U(SCH_1):PAGE109
    46    GND @S9S_MB_2U_LIB.S9S_MB_2U(SCH_1):GND   I176 @S9S_MB_2U_LIB.S9S_MB_2U(SCH_1):PAGE109
    48    GND @S9S_MB_2U_LIB.S9S_MB_2U(SCH_1):GND   I176 @S9S_MB_2U_LIB.S9S_MB_2U(SCH_1):PAGE109
    50    GND @S9S_MB_2U_LIB.S9S_MB_2U(SCH_1):GND   I176 @S9S_MB_2U_LIB.S9S_MB_2U(SCH_1):PAGE109
    52    GND @S9S_MB_2U_LIB.S9S_MB_2U(SCH_1):GND   I176 @S9S_MB_2U_LIB.S9S_MB_2U(SCH_1):PAGE109
    54    GND @S9S_MB_2U_LIB.S9S_MB_2U(SCH_1):GND   I176 @S9S_MB_2U_LIB.S9S_MB_2U(SCH_1):PAGE109
    57    GND @S9S_MB_2U_LIB.S9S_MB_2U(SCH_1):GND   I176 @S9S_MB_2U_LIB.S9S_MB_2U(SCH_1):PAGE109
    59    GND @S9S_MB_2U_LIB.S9S_MB_2U(SCH_1):GND   I176 @S9S_MB_2U_LIB.S9S_MB_2U(SCH_1):PAGE109
    61    GND @S9S_MB_2U_LIB.S9S_MB_2U(SCH_1):GND   I176 @S9S_MB_2U_LIB.S9S_MB_2U(SCH_1):PAGE109
    63    GND @S9S_MB_2U_LIB.S9S_MB_2U(SCH_1):GND   I176 @S9S_MB_2U_LIB.S9S_MB_2U(SCH_1):PAGE109
    65    GND @S9S_MB_2U_LIB.S9S_MB_2U(SCH_1):GND   I176 @S9S_MB_2U_LIB.S9S_MB_2U(SCH_1):PAGE109
    67    GND @S9S_MB_2U_LIB.S9S_MB_2U(SCH_1):GND   I176 @S9S_MB_2U_LIB.S9S_MB_2U(SCH_1):PAGE109
    69    GND @S9S_MB_2U_LIB.S9S_MB_2U(SCH_1):GND   I176 @S9S_MB_2U_LIB.S9S_MB_2U(SCH_1):PAGE109
    71    GND @S9S_MB_2U_LIB.S9S_MB_2U(SCH_1):GND   I176 @S9S_MB_2U_LIB.S9S_MB_2U(SCH_1):PAGE109
    73    GND @S9S_MB_2U_LIB.S9S_MB_2U(SCH_1):GND   I176 @S9S_MB_2U_LIB.S9S_MB_2U(SCH_1):PAGE109
    75    GND @S9S_MB_2U_LIB.S9S_MB_2U(SCH_1):GND   I176 @S9S_MB_2U_LIB.S9S_MB_2U(SCH_1):PAGE109
    77    GND @S9S_MB_2U_LIB.S9S_MB_2U(SCH_1):GND   I176 @S9S_MB_2U_LIB.S9S_MB_2U(SCH_1):PAGE109
    79    GND @S9S_MB_2U_LIB.S9S_MB_2U(SCH_1):GND   I176 @S9S_MB_2U_LIB.S9S_MB_2U(SCH_1):PAGE109
    81    GND @S9S_MB_2U_LIB.S9S_MB_2U(SCH_1):GND   I176 @S9S_MB_2U_LIB.S9S_MB_2U(SCH_1):PAGE109
    83    GND @S9S_MB_2U_LIB.S9S_MB_2U(SCH_1):GND   I176 @S9S_MB_2U_LIB.S9S_MB_2U(SCH_1):PAGE109
    85    GND @S9S_MB_2U_LIB.S9S_MB_2U(SCH_1):GND   I176 @S9S_MB_2U_LIB.S9S_MB_2U(SCH_1):PAGE109
    88    GND @S9S_MB_2U_LIB.S9S_MB_2U(SCH_1):GND   I176 @S9S_MB_2U_LIB.S9S_MB_2U(SCH_1):PAGE109
    90    GND @S9S_MB_2U_LIB.S9S_MB_2U(SCH_1):GND   I176 @S9S_MB_2U_LIB.S9S_MB_2U(SCH_1):PAGE109
    92    GND @S9S_MB_2U_LIB.S9S_MB_2U(SCH_1):GND   I176 @S9S_MB_2U_LIB.S9S_MB_2U(SCH_1):PAGE109
    95    GND @S9S_MB_2U_LIB.S9S_MB_2U(SCH_1):GND   I176 @S9S_MB_2U_LIB.S9S_MB_2U(SCH_1):PAGE109
    97    GND @S9S_MB_2U_LIB.S9S_MB_2U(SCH_1):GND   I176 @S9S_MB_2U_LIB.S9S_MB_2U(SCH_1):PAGE109
    99    GND @S9S_MB_2U_LIB.S9S_MB_2U(SCH_1):GND   I176 @S9S_MB_2U_LIB.S9S_MB_2U(SCH_1):PAGE109
   101    GND @S9S_MB_2U_LIB.S9S_MB_2U(SCH_1):GND   I176 @S9S_MB_2U_LIB.S9S_MB_2U(SCH_1):PAGE109
   103    GND @S9S_MB_2U_LIB.S9S_MB_2U(SCH_1):GND   I176 @S9S_MB_2U_LIB.S9S_MB_2U(SCH_1):PAGE109
   106    GND @S9S_MB_2U_LIB.S9S_MB_2U(SCH_1):GND   I176 @S9S_MB_2U_LIB.S9S_MB_2U(SCH_1):PAGE109
   108    GND @S9S_MB_2U_LIB.S9S_MB_2U(SCH_1):GND   I176 @S9S_MB_2U_LIB.S9S_MB_2U(SCH_1):PAGE109
   110    GND @S9S_MB_2U_LIB.S9S_MB_2U(SCH_1):GND   I176 @S9S_MB_2U_LIB.S9S_MB_2U(SCH_1):PAGE109
   112    GND @S9S_MB_2U_LIB.S9S_MB_2U(SCH_1):GND   I176 @S9S_MB_2U_LIB.S9S_MB_2U(SCH_1):PAGE109
   114    GND @S9S_MB_2U_LIB.S9S_MB_2U(SCH_1):GND   I176 @S9S_MB_2U_LIB.S9S_MB_2U(SCH_1):PAGE109
   117    GND @S9S_MB_2U_LIB.S9S_MB_2U(SCH_1):GND   I176 @S9S_MB_2U_LIB.S9S_MB_2U(SCH_1):PAGE109
   119    GND @S9S_MB_2U_LIB.S9S_MB_2U(SCH_1):GND   I176 @S9S_MB_2U_LIB.S9S_MB_2U(SCH_1):PAGE109
   121    GND @S9S_MB_2U_LIB.S9S_MB_2U(SCH_1):GND   I176 @S9S_MB_2U_LIB.S9S_MB_2U(SCH_1):PAGE109
   123    GND @S9S_MB_2U_LIB.S9S_MB_2U(SCH_1):GND   I176 @S9S_MB_2U_LIB.S9S_MB_2U(SCH_1):PAGE109
   125    GND @S9S_MB_2U_LIB.S9S_MB_2U(SCH_1):GND   I176 @S9S_MB_2U_LIB.S9S_MB_2U(SCH_1):PAGE109
   128    GND @S9S_MB_2U_LIB.S9S_MB_2U(SCH_1):GND   I176 @S9S_MB_2U_LIB.S9S_MB_2U(SCH_1):PAGE109
   130    GND @S9S_MB_2U_LIB.S9S_MB_2U(SCH_1):GND   I176 @S9S_MB_2U_LIB.S9S_MB_2U(SCH_1):PAGE109
   134    GND @S9S_MB_2U_LIB.S9S_MB_2U(SCH_1):GND   I176 @S9S_MB_2U_LIB.S9S_MB_2U(SCH_1):PAGE109
   143    GND @S9S_MB_2U_LIB.S9S_MB_2U(SCH_1):GND   I176 @S9S_MB_2U_LIB.S9S_MB_2U(SCH_1):PAGE109
   151    GND @S9S_MB_2U_LIB.S9S_MB_2U(SCH_1):GND   I176 @S9S_MB_2U_LIB.S9S_MB_2U(SCH_1):PAGE109
   153    GND @S9S_MB_2U_LIB.S9S_MB_2U(SCH_1):GND   I176 @S9S_MB_2U_LIB.S9S_MB_2U(SCH_1):PAGE109
   155    GND @S9S_MB_2U_LIB.S9S_MB_2U(SCH_1):GND   I176 @S9S_MB_2U_LIB.S9S_MB_2U(SCH_1):PAGE109
   158    GND @S9S_MB_2U_LIB.S9S_MB_2U(SCH_1):GND   I176 @S9S_MB_2U_LIB.S9S_MB_2U(SCH_1):PAGE109
   160    GND @S9S_MB_2U_LIB.S9S_MB_2U(SCH_1):GND   I176 @S9S_MB_2U_LIB.S9S_MB_2U(SCH_1):PAGE109
   162    GND @S9S_MB_2U_LIB.S9S_MB_2U(SCH_1):GND   I176 @S9S_MB_2U_LIB.S9S_MB_2U(SCH_1):PAGE109
   164    GND @S9S_MB_2U_LIB.S9S_MB_2U(SCH_1):GND   I176 @S9S_MB_2U_LIB.S9S_MB_2U(SCH_1):PAGE109
   166    GND @S9S_MB_2U_LIB.S9S_MB_2U(SCH_1):GND   I176 @S9S_MB_2U_LIB.S9S_MB_2U(SCH_1):PAGE109
   169    GND @S9S_MB_2U_LIB.S9S_MB_2U(SCH_1):GND   I176 @S9S_MB_2U_LIB.S9S_MB_2U(SCH_1):PAGE109
   171    GND @S9S_MB_2U_LIB.S9S_MB_2U(SCH_1):GND   I176 @S9S_MB_2U_LIB.S9S_MB_2U(SCH_1):PAGE109
   173    GND @S9S_MB_2U_LIB.S9S_MB_2U(SCH_1):GND   I176 @S9S_MB_2U_LIB.S9S_MB_2U(SCH_1):PAGE109
   175    GND @S9S_MB_2U_LIB.S9S_MB_2U(SCH_1):GND   I176 @S9S_MB_2U_LIB.S9S_MB_2U(SCH_1):PAGE109
   177    GND @S9S_MB_2U_LIB.S9S_MB_2U(SCH_1):GND   I176 @S9S_MB_2U_LIB.S9S_MB_2U(SCH_1):PAGE109
   180    GND @S9S_MB_2U_LIB.S9S_MB_2U(SCH_1):GND   I176 @S9S_MB_2U_LIB.S9S_MB_2U(SCH_1):PAGE109
   182    GND @S9S_MB_2U_LIB.S9S_MB_2U(SCH_1):GND   I176 @S9S_MB_2U_LIB.S9S_MB_2U(SCH_1):PAGE109
   184    GND @S9S_MB_2U_LIB.S9S_MB_2U(SCH_1):GND   I176 @S9S_MB_2U_LIB.S9S_MB_2U(SCH_1):PAGE109
   186    GND @S9S_MB_2U_LIB.S9S_MB_2U(SCH_1):GND   I176 @S9S_MB_2U_LIB.S9S_MB_2U(SCH_1):PAGE109
   188    GND @S9S_MB_2U_LIB.S9S_MB_2U(SCH_1):GND   I176 @S9S_MB_2U_LIB.S9S_MB_2U(SCH_1):PAGE109
   191    GND @S9S_MB_2U_LIB.S9S_MB_2U(SCH_1):GND   I176 @S9S_MB_2U_LIB.S9S_MB_2U(SCH_1):PAGE109
   193    GND @S9S_MB_2U_LIB.S9S_MB_2U(SCH_1):GND   I176 @S9S_MB_2U_LIB.S9S_MB_2U(SCH_1):PAGE109
   195    GND @S9S_MB_2U_LIB.S9S_MB_2U(SCH_1):GND   I176 @S9S_MB_2U_LIB.S9S_MB_2U(SCH_1):PAGE109
   197    GND @S9S_MB_2U_LIB.S9S_MB_2U(SCH_1):GND   I176 @S9S_MB_2U_LIB.S9S_MB_2U(SCH_1):PAGE109
   199    GND @S9S_MB_2U_LIB.S9S_MB_2U(SCH_1):GND   I176 @S9S_MB_2U_LIB.S9S_MB_2U(SCH_1):PAGE109
   202    GND @S9S_MB_2U_LIB.S9S_MB_2U(SCH_1):GND   I176 @S9S_MB_2U_LIB.S9S_MB_2U(SCH_1):PAGE109
   204    GND @S9S_MB_2U_LIB.S9S_MB_2U(SCH_1):GND   I176 @S9S_MB_2U_LIB.S9S_MB_2U(SCH_1):PAGE109
   206    GND @S9S_MB_2U_LIB.S9S_MB_2U(SCH_1):GND   I176 @S9S_MB_2U_LIB.S9S_MB_2U(SCH_1):PAGE109
   208    GND @S9S_MB_2U_LIB.S9S_MB_2U(SCH_1):GND   I176 @S9S_MB_2U_LIB.S9S_MB_2U(SCH_1):PAGE109
   210    GND @S9S_MB_2U_LIB.S9S_MB_2U(SCH_1):GND   I176 @S9S_MB_2U_LIB.S9S_MB_2U(SCH_1):PAGE109
   212    GND @S9S_MB_2U_LIB.S9S_MB_2U(SCH_1):GND   I176 @S9S_MB_2U_LIB.S9S_MB_2U(SCH_1):PAGE109
   214    GND @S9S_MB_2U_LIB.S9S_MB_2U(SCH_1):GND   I176 @S9S_MB_2U_LIB.S9S_MB_2U(SCH_1):PAGE109
   216    GND @S9S_MB_2U_LIB.S9S_MB_2U(SCH_1):GND   I176 @S9S_MB_2U_LIB.S9S_MB_2U(SCH_1):PAGE109
   219    GND @S9S_MB_2U_LIB.S9S_MB_2U(SCH_1):GND   I176 @S9S_MB_2U_LIB.S9S_MB_2U(SCH_1):PAGE109
   222    GND @S9S_MB_2U_LIB.S9S_MB_2U(SCH_1):GND   I176 @S9S_MB_2U_LIB.S9S_MB_2U(SCH_1):PAGE109
   224    GND @S9S_MB_2U_LIB.S9S_MB_2U(SCH_1):GND   I176 @S9S_MB_2U_LIB.S9S_MB_2U(SCH_1):PAGE109
   226    GND @S9S_MB_2U_LIB.S9S_MB_2U(SCH_1):GND   I176 @S9S_MB_2U_LIB.S9S_MB_2U(SCH_1):PAGE109
   228    GND @S9S_MB_2U_LIB.S9S_MB_2U(SCH_1):GND   I176 @S9S_MB_2U_LIB.S9S_MB_2U(SCH_1):PAGE109
   233    GND @S9S_MB_2U_LIB.S9S_MB_2U(SCH_1):GND   I176 @S9S_MB_2U_LIB.S9S_MB_2U(SCH_1):PAGE109
   237    GND @S9S_MB_2U_LIB.S9S_MB_2U(SCH_1):GND   I176 @S9S_MB_2U_LIB.S9S_MB_2U(SCH_1):PAGE109
   242    GND @S9S_MB_2U_LIB.S9S_MB_2U(SCH_1):GND   I176 @S9S_MB_2U_LIB.S9S_MB_2U(SCH_1):PAGE109
   244    GND @S9S_MB_2U_LIB.S9S_MB_2U(SCH_1):GND   I176 @S9S_MB_2U_LIB.S9S_MB_2U(SCH_1):PAGE109
   246    GND @S9S_MB_2U_LIB.S9S_MB_2U(SCH_1):GND   I176 @S9S_MB_2U_LIB.S9S_MB_2U(SCH_1):PAGE109
   248    GND @S9S_MB_2U_LIB.S9S_MB_2U(SCH_1):GND   I176 @S9S_MB_2U_LIB.S9S_MB_2U(SCH_1):PAGE109
   251    GND @S9S_MB_2U_LIB.S9S_MB_2U(SCH_1):GND   I176 @S9S_MB_2U_LIB.S9S_MB_2U(SCH_1):PAGE109
   253    GND @S9S_MB_2U_LIB.S9S_MB_2U(SCH_1):GND   I176 @S9S_MB_2U_LIB.S9S_MB_2U(SCH_1):PAGE109
   255    GND @S9S_MB_2U_LIB.S9S_MB_2U(SCH_1):GND   I176 @S9S_MB_2U_LIB.S9S_MB_2U(SCH_1):PAGE109
   257    GND @S9S_MB_2U_LIB.S9S_MB_2U(SCH_1):GND   I176 @S9S_MB_2U_LIB.S9S_MB_2U(SCH_1):PAGE109
   259    GND @S9S_MB_2U_LIB.S9S_MB_2U(SCH_1):GND   I176 @S9S_MB_2U_LIB.S9S_MB_2U(SCH_1):PAGE109
   262    GND @S9S_MB_2U_LIB.S9S_MB_2U(SCH_1):GND   I176 @S9S_MB_2U_LIB.S9S_MB_2U(SCH_1):PAGE109
   264    GND @S9S_MB_2U_LIB.S9S_MB_2U(SCH_1):GND   I176 @S9S_MB_2U_LIB.S9S_MB_2U(SCH_1):PAGE109
   266    GND @S9S_MB_2U_LIB.S9S_MB_2U(SCH_1):GND   I176 @S9S_MB_2U_LIB.S9S_MB_2U(SCH_1):PAGE109
   268    GND @S9S_MB_2U_LIB.S9S_MB_2U(SCH_1):GND   I176 @S9S_MB_2U_LIB.S9S_MB_2U(SCH_1):PAGE109
   270    GND @S9S_MB_2U_LIB.S9S_MB_2U(SCH_1):GND   I176 @S9S_MB_2U_LIB.S9S_MB_2U(SCH_1):PAGE109
   273    GND @S9S_MB_2U_LIB.S9S_MB_2U(SCH_1):GND   I176 @S9S_MB_2U_LIB.S9S_MB_2U(SCH_1):PAGE109
   275    GND @S9S_MB_2U_LIB.S9S_MB_2U(SCH_1):GND   I176 @S9S_MB_2U_LIB.S9S_MB_2U(SCH_1):PAGE109
   277    GND @S9S_MB_2U_LIB.S9S_MB_2U(SCH_1):GND   I176 @S9S_MB_2U_LIB.S9S_MB_2U(SCH_1):PAGE109
   279    GND @S9S_MB_2U_LIB.S9S_MB_2U(SCH_1):GND   I176 @S9S_MB_2U_LIB.S9S_MB_2U(SCH_1):PAGE109
   281    GND @S9S_MB_2U_LIB.S9S_MB_2U(SCH_1):GND   I176 @S9S_MB_2U_LIB.S9S_MB_2U(SCH_1):PAGE109
   284    GND @S9S_MB_2U_LIB.S9S_MB_2U(SCH_1):GND   I176 @S9S_MB_2U_LIB.S9S_MB_2U(SCH_1):PAGE109
   286    GND @S9S_MB_2U_LIB.S9S_MB_2U(SCH_1):GND   I176 @S9S_MB_2U_LIB.S9S_MB_2U(SCH_1):PAGE109
   288    GND @S9S_MB_2U_LIB.S9S_MB_2U(SCH_1):GND   I176 @S9S_MB_2U_LIB.S9S_MB_2U(SCH_1):PAGE109
     1 P12V_S3_AUX_CPU1_NVDIMM @S9S_MB_2U_LIB.S9S_MB_2U(SCH_1):P12V_S3_AUX_CPU1_NVDIMM   I176 @S9S_MB_2U_LIB.S9S_MB_2U(SCH_1):PAGE109
   145 P12V_S3_AUX_CPU1_NVDIMM @S9S_MB_2U_LIB.S9S_MB_2U(SCH_1):P12V_S3_AUX_CPU1_NVDIMM   I176 @S9S_MB_2U_LIB.S9S_MB_2U(SCH_1):PAGE109
   146 P12V_S3_AUX_CPU1_NVDIMM @S9S_MB_2U_LIB.S9S_MB_2U(SCH_1):P12V_S3_AUX_CPU1_NVDIMM   I176 @S9S_MB_2U_LIB.S9S_MB_2U(SCH_1):PAGE109
   230    GND @S9S_MB_2U_LIB.S9S_MB_2U(SCH_1):GND   I176 @S9S_MB_2U_LIB.S9S_MB_2U(SCH_1):PAGE109
   235    GND @S9S_MB_2U_LIB.S9S_MB_2U(SCH_1):GND   I176 @S9S_MB_2U_LIB.S9S_MB_2U(SCH_1):PAGE109
   240    GND @S9S_MB_2U_LIB.S9S_MB_2U(SCH_1):GND   I176 @S9S_MB_2U_LIB.S9S_MB_2U(SCH_1):PAGE109
   132    GND @S9S_MB_2U_LIB.S9S_MB_2U(SCH_1):GND   I176 @S9S_MB_2U_LIB.S9S_MB_2U(SCH_1):PAGE109
   136    GND @S9S_MB_2U_LIB.S9S_MB_2U(SCH_1):GND   I176 @S9S_MB_2U_LIB.S9S_MB_2U(SCH_1):PAGE109
   139    GND @S9S_MB_2U_LIB.S9S_MB_2U(SCH_1):GND   I176 @S9S_MB_2U_LIB.S9S_MB_2U(SCH_1):PAGE109
   141    GND @S9S_MB_2U_LIB.S9S_MB_2U(SCH_1):GND   I176 @S9S_MB_2U_LIB.S9S_MB_2U(SCH_1):PAGE109
    G1    GND @S9S_MB_2U_LIB.S9S_MB_2U(SCH_1):GND   I176 @S9S_MB_2U_LIB.S9S_MB_2U(SCH_1):PAGE109
    G2    GND @S9S_MB_2U_LIB.S9S_MB_2U(SCH_1):GND   I176 @S9S_MB_2U_LIB.S9S_MB_2U(SCH_1):PAGE109
    G3    GND @S9S_MB_2U_LIB.S9S_MB_2U(SCH_1):GND   I176 @S9S_MB_2U_LIB.S9S_MB_2U(SCH_1):PAGE109

 J29 SCONN288_ADR50017P130CC-SCONN2A
     3 P3V3_AUX @S9S_MB_2U_LIB.S9S_MB_2U(SCH_1):P3V3_AUX   I179 @S9S_MB_2U_LIB.S9S_MB_2U(SCH_1):PAGE110
     2 TP_CHG_CPU1_DIMM1_FRU_0 @S9S_MB_2U_LIB.S9S_MB_2U(SCH_1):TP_CHG_CPU1_DIMM1_FRU_0   I179 @S9S_MB_2U_LIB.S9S_MB_2U(SCH_1):PAGE110
   144 TP_CHG_CPU1_DIMM1_FRU_1 @S9S_MB_2U_LIB.S9S_MB_2U(SCH_1):TP_CHG_CPU1_DIMM1_FRU_1   I179 @S9S_MB_2U_LIB.S9S_MB_2U(SCH_1):PAGE110
   149 TP_CHG_CPU1_DIMM1_FRU_2 @S9S_MB_2U_LIB.S9S_MB_2U(SCH_1):TP_CHG_CPU1_DIMM1_FRU_2   I179 @S9S_MB_2U_LIB.S9S_MB_2U(SCH_1):PAGE110
   150 TP_CHG_CPU1_DIMM1_FRU_3 @S9S_MB_2U_LIB.S9S_MB_2U(SCH_1):TP_CHG_CPU1_DIMM1_FRU_3   I179 @S9S_MB_2U_LIB.S9S_MB_2U(SCH_1):PAGE110
   220 TP_CHG_CPU1_DIMM1_FRU_4 @S9S_MB_2U_LIB.S9S_MB_2U(SCH_1):TP_CHG_CPU1_DIMM1_FRU_4   I179 @S9S_MB_2U_LIB.S9S_MB_2U(SCH_1):PAGE110
   231 TP_CHG_CPU1_DIMM1_FRU_5 @S9S_MB_2U_LIB.S9S_MB_2U(SCH_1):TP_CHG_CPU1_DIMM1_FRU_5   I179 @S9S_MB_2U_LIB.S9S_MB_2U(SCH_1):PAGE110
   232 TP_CHG_CPU1_DIMM1_FRU_6 @S9S_MB_2U_LIB.S9S_MB_2U(SCH_1):TP_CHG_CPU1_DIMM1_FRU_6   I179 @S9S_MB_2U_LIB.S9S_MB_2U(SCH_1):PAGE110
   207 RST_M_GH_CPU1_FPGA_N @S9S_MB_2U_LIB.S9S_MB_2U(SCH_1):RST_M_GH_CPU1_FPGA_N   I179 @S9S_MB_2U_LIB.S9S_MB_2U(SCH_1):PAGE110
   147 PWRGD_CHG_CPU1_DIMM1 @S9S_MB_2U_LIB.S9S_MB_2U(SCH_1):PWRGD_CHG_CPU1_DIMM1   I179 @S9S_MB_2U_LIB.S9S_MB_2U(SCH_1):PAGE110
   227 M_G_CPU1_SB_PAR @S9S_MB_2U_LIB.S9S_MB_2U(SCH_1):M_G_CPU1_SB_PAR   I179 @S9S_MB_2U_LIB.S9S_MB_2U(SCH_1):PAGE110
    74 M_G_CPU1_SA_PAR @S9S_MB_2U_LIB.S9S_MB_2U(SCH_1):M_G_CPU1_SA_PAR   I179 @S9S_MB_2U_LIB.S9S_MB_2U(SCH_1):PAGE110
    87 M_G_CPU1_SB_RSP<0> @S9S_MB_2U_LIB.S9S_MB_2U(SCH_1):M_G_CPU1_SB_RSP(0)   I179 @S9S_MB_2U_LIB.S9S_MB_2U(SCH_1):PAGE110
    86 M_G_CPU1_SA_RSP<0> @S9S_MB_2U_LIB.S9S_MB_2U(SCH_1):M_G_CPU1_SA_RSP(0)   I179 @S9S_MB_2U_LIB.S9S_MB_2U(SCH_1):PAGE110
     5 I3C_SPD_DDREFGH_CPU1_LVC1_SDA @S9S_MB_2U_LIB.S9S_MB_2U(SCH_1):I3C_SPD_DDREFGH_CPU1_LVC1_SDA   I179 @S9S_MB_2U_LIB.S9S_MB_2U(SCH_1):PAGE110
     4 I3C_SPD_DDREFGH_CPU1_LVC1_SCL_4 @S9S_MB_2U_LIB.S9S_MB_2U(SCH_1):I3C_SPD_DDREFGH_CPU1_LVC1_SCL_R5   I179 @S9S_MB_2U_LIB.S9S_MB_2U(SCH_1):PAGE110
   148 PD_CHG_CPU1_DIMM1_SAA @S9S_MB_2U_LIB.S9S_MB_2U(SCH_1):PD_CHG_CPU1_DIMM1_SAA   I179 @S9S_MB_2U_LIB.S9S_MB_2U(SCH_1):PAGE110
   100 M_G_CPU1_SB_DQ<0> @S9S_MB_2U_LIB.S9S_MB_2U(SCH_1):M_G_CPU1_SB_DQ(0)   I179 @S9S_MB_2U_LIB.S9S_MB_2U(SCH_1):PAGE110
   102 M_G_CPU1_SB_DQ<1> @S9S_MB_2U_LIB.S9S_MB_2U(SCH_1):M_G_CPU1_SB_DQ(1)   I179 @S9S_MB_2U_LIB.S9S_MB_2U(SCH_1):PAGE110
   245 M_G_CPU1_SB_DQ<2> @S9S_MB_2U_LIB.S9S_MB_2U(SCH_1):M_G_CPU1_SB_DQ(2)   I179 @S9S_MB_2U_LIB.S9S_MB_2U(SCH_1):PAGE110
   247 M_G_CPU1_SB_DQ<3> @S9S_MB_2U_LIB.S9S_MB_2U(SCH_1):M_G_CPU1_SB_DQ(3)   I179 @S9S_MB_2U_LIB.S9S_MB_2U(SCH_1):PAGE110
   107 M_G_CPU1_SB_DQ<4> @S9S_MB_2U_LIB.S9S_MB_2U(SCH_1):M_G_CPU1_SB_DQ(4)   I179 @S9S_MB_2U_LIB.S9S_MB_2U(SCH_1):PAGE110
   109 M_G_CPU1_SB_DQ<5> @S9S_MB_2U_LIB.S9S_MB_2U(SCH_1):M_G_CPU1_SB_DQ(5)   I179 @S9S_MB_2U_LIB.S9S_MB_2U(SCH_1):PAGE110
   252 M_G_CPU1_SB_DQ<6> @S9S_MB_2U_LIB.S9S_MB_2U(SCH_1):M_G_CPU1_SB_DQ(6)   I179 @S9S_MB_2U_LIB.S9S_MB_2U(SCH_1):PAGE110
   254 M_G_CPU1_SB_DQ<7> @S9S_MB_2U_LIB.S9S_MB_2U(SCH_1):M_G_CPU1_SB_DQ(7)   I179 @S9S_MB_2U_LIB.S9S_MB_2U(SCH_1):PAGE110
   111 M_G_CPU1_SB_DQ<8> @S9S_MB_2U_LIB.S9S_MB_2U(SCH_1):M_G_CPU1_SB_DQ(8)   I179 @S9S_MB_2U_LIB.S9S_MB_2U(SCH_1):PAGE110
   113 M_G_CPU1_SB_DQ<9> @S9S_MB_2U_LIB.S9S_MB_2U(SCH_1):M_G_CPU1_SB_DQ(9)   I179 @S9S_MB_2U_LIB.S9S_MB_2U(SCH_1):PAGE110
   256 M_G_CPU1_SB_DQ<10> @S9S_MB_2U_LIB.S9S_MB_2U(SCH_1):M_G_CPU1_SB_DQ(10)   I179 @S9S_MB_2U_LIB.S9S_MB_2U(SCH_1):PAGE110
   258 M_G_CPU1_SB_DQ<11> @S9S_MB_2U_LIB.S9S_MB_2U(SCH_1):M_G_CPU1_SB_DQ(11)   I179 @S9S_MB_2U_LIB.S9S_MB_2U(SCH_1):PAGE110
   118 M_G_CPU1_SB_DQ<12> @S9S_MB_2U_LIB.S9S_MB_2U(SCH_1):M_G_CPU1_SB_DQ(12)   I179 @S9S_MB_2U_LIB.S9S_MB_2U(SCH_1):PAGE110
   120 M_G_CPU1_SB_DQ<13> @S9S_MB_2U_LIB.S9S_MB_2U(SCH_1):M_G_CPU1_SB_DQ(13)   I179 @S9S_MB_2U_LIB.S9S_MB_2U(SCH_1):PAGE110
   263 M_G_CPU1_SB_DQ<14> @S9S_MB_2U_LIB.S9S_MB_2U(SCH_1):M_G_CPU1_SB_DQ(14)   I179 @S9S_MB_2U_LIB.S9S_MB_2U(SCH_1):PAGE110
   265 M_G_CPU1_SB_DQ<15> @S9S_MB_2U_LIB.S9S_MB_2U(SCH_1):M_G_CPU1_SB_DQ(15)   I179 @S9S_MB_2U_LIB.S9S_MB_2U(SCH_1):PAGE110
   122 M_G_CPU1_SB_DQ<16> @S9S_MB_2U_LIB.S9S_MB_2U(SCH_1):M_G_CPU1_SB_DQ(16)   I179 @S9S_MB_2U_LIB.S9S_MB_2U(SCH_1):PAGE110
   124 M_G_CPU1_SB_DQ<17> @S9S_MB_2U_LIB.S9S_MB_2U(SCH_1):M_G_CPU1_SB_DQ(17)   I179 @S9S_MB_2U_LIB.S9S_MB_2U(SCH_1):PAGE110
   267 M_G_CPU1_SB_DQ<18> @S9S_MB_2U_LIB.S9S_MB_2U(SCH_1):M_G_CPU1_SB_DQ(18)   I179 @S9S_MB_2U_LIB.S9S_MB_2U(SCH_1):PAGE110
   269 M_G_CPU1_SB_DQ<19> @S9S_MB_2U_LIB.S9S_MB_2U(SCH_1):M_G_CPU1_SB_DQ(19)   I179 @S9S_MB_2U_LIB.S9S_MB_2U(SCH_1):PAGE110
   129 M_G_CPU1_SB_DQ<20> @S9S_MB_2U_LIB.S9S_MB_2U(SCH_1):M_G_CPU1_SB_DQ(20)   I179 @S9S_MB_2U_LIB.S9S_MB_2U(SCH_1):PAGE110
   131 M_G_CPU1_SB_DQ<21> @S9S_MB_2U_LIB.S9S_MB_2U(SCH_1):M_G_CPU1_SB_DQ(21)   I179 @S9S_MB_2U_LIB.S9S_MB_2U(SCH_1):PAGE110
   274 M_G_CPU1_SB_DQ<22> @S9S_MB_2U_LIB.S9S_MB_2U(SCH_1):M_G_CPU1_SB_DQ(22)   I179 @S9S_MB_2U_LIB.S9S_MB_2U(SCH_1):PAGE110
   276 M_G_CPU1_SB_DQ<23> @S9S_MB_2U_LIB.S9S_MB_2U(SCH_1):M_G_CPU1_SB_DQ(23)   I179 @S9S_MB_2U_LIB.S9S_MB_2U(SCH_1):PAGE110
   133 M_G_CPU1_SB_DQ<24> @S9S_MB_2U_LIB.S9S_MB_2U(SCH_1):M_G_CPU1_SB_DQ(24)   I179 @S9S_MB_2U_LIB.S9S_MB_2U(SCH_1):PAGE110
   135 M_G_CPU1_SB_DQ<25> @S9S_MB_2U_LIB.S9S_MB_2U(SCH_1):M_G_CPU1_SB_DQ(25)   I179 @S9S_MB_2U_LIB.S9S_MB_2U(SCH_1):PAGE110
   278 M_G_CPU1_SB_DQ<26> @S9S_MB_2U_LIB.S9S_MB_2U(SCH_1):M_G_CPU1_SB_DQ(26)   I179 @S9S_MB_2U_LIB.S9S_MB_2U(SCH_1):PAGE110
   280 M_G_CPU1_SB_DQ<27> @S9S_MB_2U_LIB.S9S_MB_2U(SCH_1):M_G_CPU1_SB_DQ(27)   I179 @S9S_MB_2U_LIB.S9S_MB_2U(SCH_1):PAGE110
   140 M_G_CPU1_SB_DQ<28> @S9S_MB_2U_LIB.S9S_MB_2U(SCH_1):M_G_CPU1_SB_DQ(28)   I179 @S9S_MB_2U_LIB.S9S_MB_2U(SCH_1):PAGE110
   142 M_G_CPU1_SB_DQ<29> @S9S_MB_2U_LIB.S9S_MB_2U(SCH_1):M_G_CPU1_SB_DQ(29)   I179 @S9S_MB_2U_LIB.S9S_MB_2U(SCH_1):PAGE110
   285 M_G_CPU1_SB_DQ<30> @S9S_MB_2U_LIB.S9S_MB_2U(SCH_1):M_G_CPU1_SB_DQ(30)   I179 @S9S_MB_2U_LIB.S9S_MB_2U(SCH_1):PAGE110
   287 M_G_CPU1_SB_DQ<31> @S9S_MB_2U_LIB.S9S_MB_2U(SCH_1):M_G_CPU1_SB_DQ(31)   I179 @S9S_MB_2U_LIB.S9S_MB_2U(SCH_1):PAGE110
     7 M_G_CPU1_SA_DQ<0> @S9S_MB_2U_LIB.S9S_MB_2U(SCH_1):M_G_CPU1_SA_DQ(0)   I179 @S9S_MB_2U_LIB.S9S_MB_2U(SCH_1):PAGE110
     9 M_G_CPU1_SA_DQ<1> @S9S_MB_2U_LIB.S9S_MB_2U(SCH_1):M_G_CPU1_SA_DQ(1)   I179 @S9S_MB_2U_LIB.S9S_MB_2U(SCH_1):PAGE110
   152 M_G_CPU1_SA_DQ<2> @S9S_MB_2U_LIB.S9S_MB_2U(SCH_1):M_G_CPU1_SA_DQ(2)   I179 @S9S_MB_2U_LIB.S9S_MB_2U(SCH_1):PAGE110
   154 M_G_CPU1_SA_DQ<3> @S9S_MB_2U_LIB.S9S_MB_2U(SCH_1):M_G_CPU1_SA_DQ(3)   I179 @S9S_MB_2U_LIB.S9S_MB_2U(SCH_1):PAGE110
    14 M_G_CPU1_SA_DQ<4> @S9S_MB_2U_LIB.S9S_MB_2U(SCH_1):M_G_CPU1_SA_DQ(4)   I179 @S9S_MB_2U_LIB.S9S_MB_2U(SCH_1):PAGE110
    16 M_G_CPU1_SA_DQ<5> @S9S_MB_2U_LIB.S9S_MB_2U(SCH_1):M_G_CPU1_SA_DQ(5)   I179 @S9S_MB_2U_LIB.S9S_MB_2U(SCH_1):PAGE110
   159 M_G_CPU1_SA_DQ<6> @S9S_MB_2U_LIB.S9S_MB_2U(SCH_1):M_G_CPU1_SA_DQ(6)   I179 @S9S_MB_2U_LIB.S9S_MB_2U(SCH_1):PAGE110
   161 M_G_CPU1_SA_DQ<7> @S9S_MB_2U_LIB.S9S_MB_2U(SCH_1):M_G_CPU1_SA_DQ(7)   I179 @S9S_MB_2U_LIB.S9S_MB_2U(SCH_1):PAGE110
    18 M_G_CPU1_SA_DQ<8> @S9S_MB_2U_LIB.S9S_MB_2U(SCH_1):M_G_CPU1_SA_DQ(8)   I179 @S9S_MB_2U_LIB.S9S_MB_2U(SCH_1):PAGE110
    20 M_G_CPU1_SA_DQ<9> @S9S_MB_2U_LIB.S9S_MB_2U(SCH_1):M_G_CPU1_SA_DQ(9)   I179 @S9S_MB_2U_LIB.S9S_MB_2U(SCH_1):PAGE110
   163 M_G_CPU1_SA_DQ<10> @S9S_MB_2U_LIB.S9S_MB_2U(SCH_1):M_G_CPU1_SA_DQ(10)   I179 @S9S_MB_2U_LIB.S9S_MB_2U(SCH_1):PAGE110
   165 M_G_CPU1_SA_DQ<11> @S9S_MB_2U_LIB.S9S_MB_2U(SCH_1):M_G_CPU1_SA_DQ(11)   I179 @S9S_MB_2U_LIB.S9S_MB_2U(SCH_1):PAGE110
    25 M_G_CPU1_SA_DQ<12> @S9S_MB_2U_LIB.S9S_MB_2U(SCH_1):M_G_CPU1_SA_DQ(12)   I179 @S9S_MB_2U_LIB.S9S_MB_2U(SCH_1):PAGE110
    27 M_G_CPU1_SA_DQ<13> @S9S_MB_2U_LIB.S9S_MB_2U(SCH_1):M_G_CPU1_SA_DQ(13)   I179 @S9S_MB_2U_LIB.S9S_MB_2U(SCH_1):PAGE110
   170 M_G_CPU1_SA_DQ<14> @S9S_MB_2U_LIB.S9S_MB_2U(SCH_1):M_G_CPU1_SA_DQ(14)   I179 @S9S_MB_2U_LIB.S9S_MB_2U(SCH_1):PAGE110
   172 M_G_CPU1_SA_DQ<15> @S9S_MB_2U_LIB.S9S_MB_2U(SCH_1):M_G_CPU1_SA_DQ(15)   I179 @S9S_MB_2U_LIB.S9S_MB_2U(SCH_1):PAGE110
    29 M_G_CPU1_SA_DQ<16> @S9S_MB_2U_LIB.S9S_MB_2U(SCH_1):M_G_CPU1_SA_DQ(16)   I179 @S9S_MB_2U_LIB.S9S_MB_2U(SCH_1):PAGE110
    31 M_G_CPU1_SA_DQ<17> @S9S_MB_2U_LIB.S9S_MB_2U(SCH_1):M_G_CPU1_SA_DQ(17)   I179 @S9S_MB_2U_LIB.S9S_MB_2U(SCH_1):PAGE110
   174 M_G_CPU1_SA_DQ<18> @S9S_MB_2U_LIB.S9S_MB_2U(SCH_1):M_G_CPU1_SA_DQ(18)   I179 @S9S_MB_2U_LIB.S9S_MB_2U(SCH_1):PAGE110
   176 M_G_CPU1_SA_DQ<19> @S9S_MB_2U_LIB.S9S_MB_2U(SCH_1):M_G_CPU1_SA_DQ(19)   I179 @S9S_MB_2U_LIB.S9S_MB_2U(SCH_1):PAGE110
    36 M_G_CPU1_SA_DQ<20> @S9S_MB_2U_LIB.S9S_MB_2U(SCH_1):M_G_CPU1_SA_DQ(20)   I179 @S9S_MB_2U_LIB.S9S_MB_2U(SCH_1):PAGE110
    38 M_G_CPU1_SA_DQ<21> @S9S_MB_2U_LIB.S9S_MB_2U(SCH_1):M_G_CPU1_SA_DQ(21)   I179 @S9S_MB_2U_LIB.S9S_MB_2U(SCH_1):PAGE110
   181 M_G_CPU1_SA_DQ<22> @S9S_MB_2U_LIB.S9S_MB_2U(SCH_1):M_G_CPU1_SA_DQ(22)   I179 @S9S_MB_2U_LIB.S9S_MB_2U(SCH_1):PAGE110
   183 M_G_CPU1_SA_DQ<23> @S9S_MB_2U_LIB.S9S_MB_2U(SCH_1):M_G_CPU1_SA_DQ(23)   I179 @S9S_MB_2U_LIB.S9S_MB_2U(SCH_1):PAGE110
    40 M_G_CPU1_SA_DQ<24> @S9S_MB_2U_LIB.S9S_MB_2U(SCH_1):M_G_CPU1_SA_DQ(24)   I179 @S9S_MB_2U_LIB.S9S_MB_2U(SCH_1):PAGE110
    42 M_G_CPU1_SA_DQ<25> @S9S_MB_2U_LIB.S9S_MB_2U(SCH_1):M_G_CPU1_SA_DQ(25)   I179 @S9S_MB_2U_LIB.S9S_MB_2U(SCH_1):PAGE110
   185 M_G_CPU1_SA_DQ<26> @S9S_MB_2U_LIB.S9S_MB_2U(SCH_1):M_G_CPU1_SA_DQ(26)   I179 @S9S_MB_2U_LIB.S9S_MB_2U(SCH_1):PAGE110
   187 M_G_CPU1_SA_DQ<27> @S9S_MB_2U_LIB.S9S_MB_2U(SCH_1):M_G_CPU1_SA_DQ(27)   I179 @S9S_MB_2U_LIB.S9S_MB_2U(SCH_1):PAGE110
    47 M_G_CPU1_SA_DQ<28> @S9S_MB_2U_LIB.S9S_MB_2U(SCH_1):M_G_CPU1_SA_DQ(28)   I179 @S9S_MB_2U_LIB.S9S_MB_2U(SCH_1):PAGE110
    49 M_G_CPU1_SA_DQ<29> @S9S_MB_2U_LIB.S9S_MB_2U(SCH_1):M_G_CPU1_SA_DQ(29)   I179 @S9S_MB_2U_LIB.S9S_MB_2U(SCH_1):PAGE110
   192 M_G_CPU1_SA_DQ<30> @S9S_MB_2U_LIB.S9S_MB_2U(SCH_1):M_G_CPU1_SA_DQ(30)   I179 @S9S_MB_2U_LIB.S9S_MB_2U(SCH_1):PAGE110
   229 M_G_CPU1_SB_CS_N<1> @S9S_MB_2U_LIB.S9S_MB_2U(SCH_1):M_G_CPU1_SB_CS_N(1)   I179 @S9S_MB_2U_LIB.S9S_MB_2U(SCH_1):PAGE110
   209 M_G_CPU1_SA_CS_N<1> @S9S_MB_2U_LIB.S9S_MB_2U(SCH_1):M_G_CPU1_SA_CS_N(1)   I179 @S9S_MB_2U_LIB.S9S_MB_2U(SCH_1):PAGE110
    84 M_G_CPU1_SB_CS_N<0> @S9S_MB_2U_LIB.S9S_MB_2U(SCH_1):M_G_CPU1_SB_CS_N(0)   I179 @S9S_MB_2U_LIB.S9S_MB_2U(SCH_1):PAGE110
    64 M_G_CPU1_SA_CS_N<0> @S9S_MB_2U_LIB.S9S_MB_2U(SCH_1):M_G_CPU1_SA_CS_N(0)   I179 @S9S_MB_2U_LIB.S9S_MB_2U(SCH_1):PAGE110
   217 M_G_CPU1_CLK_DP<0> @S9S_MB_2U_LIB.S9S_MB_2U(SCH_1):M_G_CPU1_CLK_DP(0)   I179 @S9S_MB_2U_LIB.S9S_MB_2U(SCH_1):PAGE110
   218 M_G_CPU1_CLK_DN<0> @S9S_MB_2U_LIB.S9S_MB_2U(SCH_1):M_G_CPU1_CLK_DN(0)   I179 @S9S_MB_2U_LIB.S9S_MB_2U(SCH_1):PAGE110
    96 M_G_CPU1_SB_CB<0> @S9S_MB_2U_LIB.S9S_MB_2U(SCH_1):M_G_CPU1_SB_CB(0)   I179 @S9S_MB_2U_LIB.S9S_MB_2U(SCH_1):PAGE110
    98 M_G_CPU1_SB_CB<1> @S9S_MB_2U_LIB.S9S_MB_2U(SCH_1):M_G_CPU1_SB_CB(1)   I179 @S9S_MB_2U_LIB.S9S_MB_2U(SCH_1):PAGE110
   241 M_G_CPU1_SB_CB<2> @S9S_MB_2U_LIB.S9S_MB_2U(SCH_1):M_G_CPU1_SB_CB(2)   I179 @S9S_MB_2U_LIB.S9S_MB_2U(SCH_1):PAGE110
   243 M_G_CPU1_SB_CB<3> @S9S_MB_2U_LIB.S9S_MB_2U(SCH_1):M_G_CPU1_SB_CB(3)   I179 @S9S_MB_2U_LIB.S9S_MB_2U(SCH_1):PAGE110
    89 M_G_CPU1_SB_CB<4> @S9S_MB_2U_LIB.S9S_MB_2U(SCH_1):M_G_CPU1_SB_CB(4)   I179 @S9S_MB_2U_LIB.S9S_MB_2U(SCH_1):PAGE110
    91 M_G_CPU1_SB_CB<5> @S9S_MB_2U_LIB.S9S_MB_2U(SCH_1):M_G_CPU1_SB_CB(5)   I179 @S9S_MB_2U_LIB.S9S_MB_2U(SCH_1):PAGE110
   234 M_G_CPU1_SB_CB<6> @S9S_MB_2U_LIB.S9S_MB_2U(SCH_1):M_G_CPU1_SB_CB(6)   I179 @S9S_MB_2U_LIB.S9S_MB_2U(SCH_1):PAGE110
    51 M_G_CPU1_SA_CB<0> @S9S_MB_2U_LIB.S9S_MB_2U(SCH_1):M_G_CPU1_SA_CB(0)   I179 @S9S_MB_2U_LIB.S9S_MB_2U(SCH_1):PAGE110
   196 M_G_CPU1_SA_CB<2> @S9S_MB_2U_LIB.S9S_MB_2U(SCH_1):M_G_CPU1_SA_CB(2)   I179 @S9S_MB_2U_LIB.S9S_MB_2U(SCH_1):PAGE110
   198 M_G_CPU1_SA_CB<3> @S9S_MB_2U_LIB.S9S_MB_2U(SCH_1):M_G_CPU1_SA_CB(3)   I179 @S9S_MB_2U_LIB.S9S_MB_2U(SCH_1):PAGE110
    60 M_G_CPU1_SA_CB<5> @S9S_MB_2U_LIB.S9S_MB_2U(SCH_1):M_G_CPU1_SA_CB(5)   I179 @S9S_MB_2U_LIB.S9S_MB_2U(SCH_1):PAGE110
   203 M_G_CPU1_SA_CB<6> @S9S_MB_2U_LIB.S9S_MB_2U(SCH_1):M_G_CPU1_SA_CB(6)   I179 @S9S_MB_2U_LIB.S9S_MB_2U(SCH_1):PAGE110
    82 M_G_CPU1_SB_CA<6> @S9S_MB_2U_LIB.S9S_MB_2U(SCH_1):M_G_CPU1_SB_CA(6)   I179 @S9S_MB_2U_LIB.S9S_MB_2U(SCH_1):PAGE110
    72 M_G_CPU1_SA_CA<6> @S9S_MB_2U_LIB.S9S_MB_2U(SCH_1):M_G_CPU1_SA_CA(6)   I179 @S9S_MB_2U_LIB.S9S_MB_2U(SCH_1):PAGE110
   225 M_G_CPU1_SB_CA<5> @S9S_MB_2U_LIB.S9S_MB_2U(SCH_1):M_G_CPU1_SB_CA(5)   I179 @S9S_MB_2U_LIB.S9S_MB_2U(SCH_1):PAGE110
   215 M_G_CPU1_SA_CA<5> @S9S_MB_2U_LIB.S9S_MB_2U(SCH_1):M_G_CPU1_SA_CA(5)   I179 @S9S_MB_2U_LIB.S9S_MB_2U(SCH_1):PAGE110
    80 M_G_CPU1_SB_CA<4> @S9S_MB_2U_LIB.S9S_MB_2U(SCH_1):M_G_CPU1_SB_CA(4)   I179 @S9S_MB_2U_LIB.S9S_MB_2U(SCH_1):PAGE110
    70 M_G_CPU1_SA_CA<4> @S9S_MB_2U_LIB.S9S_MB_2U(SCH_1):M_G_CPU1_SA_CA(4)   I179 @S9S_MB_2U_LIB.S9S_MB_2U(SCH_1):PAGE110
   223 M_G_CPU1_SB_CA<3> @S9S_MB_2U_LIB.S9S_MB_2U(SCH_1):M_G_CPU1_SB_CA(3)   I179 @S9S_MB_2U_LIB.S9S_MB_2U(SCH_1):PAGE110
   213 M_G_CPU1_SA_CA<3> @S9S_MB_2U_LIB.S9S_MB_2U(SCH_1):M_G_CPU1_SA_CA(3)   I179 @S9S_MB_2U_LIB.S9S_MB_2U(SCH_1):PAGE110
    78 M_G_CPU1_SB_CA<2> @S9S_MB_2U_LIB.S9S_MB_2U(SCH_1):M_G_CPU1_SB_CA(2)   I179 @S9S_MB_2U_LIB.S9S_MB_2U(SCH_1):PAGE110
    68 M_G_CPU1_SA_CA<2> @S9S_MB_2U_LIB.S9S_MB_2U(SCH_1):M_G_CPU1_SA_CA(2)   I179 @S9S_MB_2U_LIB.S9S_MB_2U(SCH_1):PAGE110
   221 M_G_CPU1_SB_CA<1> @S9S_MB_2U_LIB.S9S_MB_2U(SCH_1):M_G_CPU1_SB_CA(1)   I179 @S9S_MB_2U_LIB.S9S_MB_2U(SCH_1):PAGE110
   211 M_G_CPU1_SA_CA<1> @S9S_MB_2U_LIB.S9S_MB_2U(SCH_1):M_G_CPU1_SA_CA(1)   I179 @S9S_MB_2U_LIB.S9S_MB_2U(SCH_1):PAGE110
    76 M_G_CPU1_SB_CA<0> @S9S_MB_2U_LIB.S9S_MB_2U(SCH_1):M_G_CPU1_SB_CA(0)   I179 @S9S_MB_2U_LIB.S9S_MB_2U(SCH_1):PAGE110
    66 M_G_CPU1_SA_CA<0> @S9S_MB_2U_LIB.S9S_MB_2U(SCH_1):M_G_CPU1_SA_CA(0)   I179 @S9S_MB_2U_LIB.S9S_MB_2U(SCH_1):PAGE110
    62 M_G_CPU1_ALERT_N @S9S_MB_2U_LIB.S9S_MB_2U(SCH_1):M_G_CPU1_ALERT_N   I179 @S9S_MB_2U_LIB.S9S_MB_2U(SCH_1):PAGE110
   236 M_G_CPU1_SB_CB<7> @S9S_MB_2U_LIB.S9S_MB_2U(SCH_1):M_G_CPU1_SB_CB(7)   I179 @S9S_MB_2U_LIB.S9S_MB_2U(SCH_1):PAGE110
    53 M_G_CPU1_SA_CB<1> @S9S_MB_2U_LIB.S9S_MB_2U(SCH_1):M_G_CPU1_SA_CB(1)   I179 @S9S_MB_2U_LIB.S9S_MB_2U(SCH_1):PAGE110
    58 M_G_CPU1_SA_CB<4> @S9S_MB_2U_LIB.S9S_MB_2U(SCH_1):M_G_CPU1_SA_CB(4)   I179 @S9S_MB_2U_LIB.S9S_MB_2U(SCH_1):PAGE110
   205 M_G_CPU1_SA_CB<7> @S9S_MB_2U_LIB.S9S_MB_2U(SCH_1):M_G_CPU1_SA_CB(7)   I179 @S9S_MB_2U_LIB.S9S_MB_2U(SCH_1):PAGE110
   194 M_G_CPU1_SA_DQ<31> @S9S_MB_2U_LIB.S9S_MB_2U(SCH_1):M_G_CPU1_SA_DQ(31)   I179 @S9S_MB_2U_LIB.S9S_MB_2U(SCH_1):PAGE110
    93 M_G_CPU1_SB_DQS_DP<9> @S9S_MB_2U_LIB.S9S_MB_2U(SCH_1):M_G_CPU1_SB_DQS_DP(9)   I180 @S9S_MB_2U_LIB.S9S_MB_2U(SCH_1):PAGE110
    94 M_G_CPU1_SB_DQS_DN<9> @S9S_MB_2U_LIB.S9S_MB_2U(SCH_1):M_G_CPU1_SB_DQS_DN(9)   I180 @S9S_MB_2U_LIB.S9S_MB_2U(SCH_1):PAGE110
   201 M_G_CPU1_SA_DQS_DP<9> @S9S_MB_2U_LIB.S9S_MB_2U(SCH_1):M_G_CPU1_SA_DQS_DP(9)   I180 @S9S_MB_2U_LIB.S9S_MB_2U(SCH_1):PAGE110
   200 M_G_CPU1_SA_DQS_DN<9> @S9S_MB_2U_LIB.S9S_MB_2U(SCH_1):M_G_CPU1_SA_DQS_DN(9)   I180 @S9S_MB_2U_LIB.S9S_MB_2U(SCH_1):PAGE110
   190 M_G_CPU1_SA_DQS_DP<8> @S9S_MB_2U_LIB.S9S_MB_2U(SCH_1):M_G_CPU1_SA_DQS_DP(8)   I180 @S9S_MB_2U_LIB.S9S_MB_2U(SCH_1):PAGE110
   189 M_G_CPU1_SA_DQS_DN<8> @S9S_MB_2U_LIB.S9S_MB_2U(SCH_1):M_G_CPU1_SA_DQS_DN(8)   I180 @S9S_MB_2U_LIB.S9S_MB_2U(SCH_1):PAGE110
   271 M_G_CPU1_SB_DQS_DN<7> @S9S_MB_2U_LIB.S9S_MB_2U(SCH_1):M_G_CPU1_SB_DQS_DN(7)   I180 @S9S_MB_2U_LIB.S9S_MB_2U(SCH_1):PAGE110
   179 M_G_CPU1_SA_DQS_DP<7> @S9S_MB_2U_LIB.S9S_MB_2U(SCH_1):M_G_CPU1_SA_DQS_DP(7)   I180 @S9S_MB_2U_LIB.S9S_MB_2U(SCH_1):PAGE110
   261 M_G_CPU1_SB_DQS_DP<6> @S9S_MB_2U_LIB.S9S_MB_2U(SCH_1):M_G_CPU1_SB_DQS_DP(6)   I180 @S9S_MB_2U_LIB.S9S_MB_2U(SCH_1):PAGE110
   260 M_G_CPU1_SB_DQS_DN<6> @S9S_MB_2U_LIB.S9S_MB_2U(SCH_1):M_G_CPU1_SB_DQS_DN(6)   I180 @S9S_MB_2U_LIB.S9S_MB_2U(SCH_1):PAGE110
   167 M_G_CPU1_SA_DQS_DN<6> @S9S_MB_2U_LIB.S9S_MB_2U(SCH_1):M_G_CPU1_SA_DQS_DN(6)   I180 @S9S_MB_2U_LIB.S9S_MB_2U(SCH_1):PAGE110
   250 M_G_CPU1_SB_DQS_DP<5> @S9S_MB_2U_LIB.S9S_MB_2U(SCH_1):M_G_CPU1_SB_DQS_DP(5)   I180 @S9S_MB_2U_LIB.S9S_MB_2U(SCH_1):PAGE110
   249 M_G_CPU1_SB_DQS_DN<5> @S9S_MB_2U_LIB.S9S_MB_2U(SCH_1):M_G_CPU1_SB_DQS_DN(5)   I180 @S9S_MB_2U_LIB.S9S_MB_2U(SCH_1):PAGE110
   157 M_G_CPU1_SA_DQS_DP<5> @S9S_MB_2U_LIB.S9S_MB_2U(SCH_1):M_G_CPU1_SA_DQS_DP(5)   I180 @S9S_MB_2U_LIB.S9S_MB_2U(SCH_1):PAGE110
   156 M_G_CPU1_SA_DQS_DN<5> @S9S_MB_2U_LIB.S9S_MB_2U(SCH_1):M_G_CPU1_SA_DQS_DN(5)   I180 @S9S_MB_2U_LIB.S9S_MB_2U(SCH_1):PAGE110
   239 M_G_CPU1_SB_DQS_DP<4> @S9S_MB_2U_LIB.S9S_MB_2U(SCH_1):M_G_CPU1_SB_DQS_DP(4)   I180 @S9S_MB_2U_LIB.S9S_MB_2U(SCH_1):PAGE110
   238 M_G_CPU1_SB_DQS_DN<4> @S9S_MB_2U_LIB.S9S_MB_2U(SCH_1):M_G_CPU1_SB_DQS_DN(4)   I180 @S9S_MB_2U_LIB.S9S_MB_2U(SCH_1):PAGE110
    55 M_G_CPU1_SA_DQS_DP<4> @S9S_MB_2U_LIB.S9S_MB_2U(SCH_1):M_G_CPU1_SA_DQS_DP(4)   I180 @S9S_MB_2U_LIB.S9S_MB_2U(SCH_1):PAGE110
    56 M_G_CPU1_SA_DQS_DN<4> @S9S_MB_2U_LIB.S9S_MB_2U(SCH_1):M_G_CPU1_SA_DQS_DN(4)   I180 @S9S_MB_2U_LIB.S9S_MB_2U(SCH_1):PAGE110
   137 M_G_CPU1_SB_DQS_DP<3> @S9S_MB_2U_LIB.S9S_MB_2U(SCH_1):M_G_CPU1_SB_DQS_DP(3)   I180 @S9S_MB_2U_LIB.S9S_MB_2U(SCH_1):PAGE110
   138 M_G_CPU1_SB_DQS_DN<3> @S9S_MB_2U_LIB.S9S_MB_2U(SCH_1):M_G_CPU1_SB_DQS_DN(3)   I180 @S9S_MB_2U_LIB.S9S_MB_2U(SCH_1):PAGE110
    44 M_G_CPU1_SA_DQS_DP<3> @S9S_MB_2U_LIB.S9S_MB_2U(SCH_1):M_G_CPU1_SA_DQS_DP(3)   I180 @S9S_MB_2U_LIB.S9S_MB_2U(SCH_1):PAGE110
    45 M_G_CPU1_SA_DQS_DN<3> @S9S_MB_2U_LIB.S9S_MB_2U(SCH_1):M_G_CPU1_SA_DQS_DN(3)   I180 @S9S_MB_2U_LIB.S9S_MB_2U(SCH_1):PAGE110
   126 M_G_CPU1_SB_DQS_DP<2> @S9S_MB_2U_LIB.S9S_MB_2U(SCH_1):M_G_CPU1_SB_DQS_DP(2)   I180 @S9S_MB_2U_LIB.S9S_MB_2U(SCH_1):PAGE110
   127 M_G_CPU1_SB_DQS_DN<2> @S9S_MB_2U_LIB.S9S_MB_2U(SCH_1):M_G_CPU1_SB_DQS_DN(2)   I180 @S9S_MB_2U_LIB.S9S_MB_2U(SCH_1):PAGE110
    33 M_G_CPU1_SA_DQS_DP<2> @S9S_MB_2U_LIB.S9S_MB_2U(SCH_1):M_G_CPU1_SA_DQS_DP(2)   I180 @S9S_MB_2U_LIB.S9S_MB_2U(SCH_1):PAGE110
    34 M_G_CPU1_SA_DQS_DN<2> @S9S_MB_2U_LIB.S9S_MB_2U(SCH_1):M_G_CPU1_SA_DQS_DN(2)   I180 @S9S_MB_2U_LIB.S9S_MB_2U(SCH_1):PAGE110
   115 M_G_CPU1_SB_DQS_DP<1> @S9S_MB_2U_LIB.S9S_MB_2U(SCH_1):M_G_CPU1_SB_DQS_DP(1)   I180 @S9S_MB_2U_LIB.S9S_MB_2U(SCH_1):PAGE110
   116 M_G_CPU1_SB_DQS_DN<1> @S9S_MB_2U_LIB.S9S_MB_2U(SCH_1):M_G_CPU1_SB_DQS_DN(1)   I180 @S9S_MB_2U_LIB.S9S_MB_2U(SCH_1):PAGE110
    22 M_G_CPU1_SA_DQS_DP<1> @S9S_MB_2U_LIB.S9S_MB_2U(SCH_1):M_G_CPU1_SA_DQS_DP(1)   I180 @S9S_MB_2U_LIB.S9S_MB_2U(SCH_1):PAGE110
    23 M_G_CPU1_SA_DQS_DN<1> @S9S_MB_2U_LIB.S9S_MB_2U(SCH_1):M_G_CPU1_SA_DQS_DN(1)   I180 @S9S_MB_2U_LIB.S9S_MB_2U(SCH_1):PAGE110
   104 M_G_CPU1_SB_DQS_DP<0> @S9S_MB_2U_LIB.S9S_MB_2U(SCH_1):M_G_CPU1_SB_DQS_DP(0)   I180 @S9S_MB_2U_LIB.S9S_MB_2U(SCH_1):PAGE110
   105 M_G_CPU1_SB_DQS_DN<0> @S9S_MB_2U_LIB.S9S_MB_2U(SCH_1):M_G_CPU1_SB_DQS_DN(0)   I180 @S9S_MB_2U_LIB.S9S_MB_2U(SCH_1):PAGE110
    11 M_G_CPU1_SA_DQS_DP<0> @S9S_MB_2U_LIB.S9S_MB_2U(SCH_1):M_G_CPU1_SA_DQS_DP(0)   I180 @S9S_MB_2U_LIB.S9S_MB_2U(SCH_1):PAGE110
    12 M_G_CPU1_SA_DQS_DN<0> @S9S_MB_2U_LIB.S9S_MB_2U(SCH_1):M_G_CPU1_SA_DQS_DN(0)   I180 @S9S_MB_2U_LIB.S9S_MB_2U(SCH_1):PAGE110
   272 M_G_CPU1_SB_DQS_DP<7> @S9S_MB_2U_LIB.S9S_MB_2U(SCH_1):M_G_CPU1_SB_DQS_DP(7)   I180 @S9S_MB_2U_LIB.S9S_MB_2U(SCH_1):PAGE110
   282 M_G_CPU1_SB_DQS_DN<8> @S9S_MB_2U_LIB.S9S_MB_2U(SCH_1):M_G_CPU1_SB_DQS_DN(8)   I180 @S9S_MB_2U_LIB.S9S_MB_2U(SCH_1):PAGE110
   283 M_G_CPU1_SB_DQS_DP<8> @S9S_MB_2U_LIB.S9S_MB_2U(SCH_1):M_G_CPU1_SB_DQS_DP(8)   I180 @S9S_MB_2U_LIB.S9S_MB_2U(SCH_1):PAGE110
   168 M_G_CPU1_SA_DQS_DP<6> @S9S_MB_2U_LIB.S9S_MB_2U(SCH_1):M_G_CPU1_SA_DQS_DP(6)   I180 @S9S_MB_2U_LIB.S9S_MB_2U(SCH_1):PAGE110
   178 M_G_CPU1_SA_DQS_DN<7> @S9S_MB_2U_LIB.S9S_MB_2U(SCH_1):M_G_CPU1_SA_DQS_DN(7)   I180 @S9S_MB_2U_LIB.S9S_MB_2U(SCH_1):PAGE110
     6    GND @S9S_MB_2U_LIB.S9S_MB_2U(SCH_1):GND   I178 @S9S_MB_2U_LIB.S9S_MB_2U(SCH_1):PAGE110
     8    GND @S9S_MB_2U_LIB.S9S_MB_2U(SCH_1):GND   I178 @S9S_MB_2U_LIB.S9S_MB_2U(SCH_1):PAGE110
    10    GND @S9S_MB_2U_LIB.S9S_MB_2U(SCH_1):GND   I178 @S9S_MB_2U_LIB.S9S_MB_2U(SCH_1):PAGE110
    13    GND @S9S_MB_2U_LIB.S9S_MB_2U(SCH_1):GND   I178 @S9S_MB_2U_LIB.S9S_MB_2U(SCH_1):PAGE110
    15    GND @S9S_MB_2U_LIB.S9S_MB_2U(SCH_1):GND   I178 @S9S_MB_2U_LIB.S9S_MB_2U(SCH_1):PAGE110
    17    GND @S9S_MB_2U_LIB.S9S_MB_2U(SCH_1):GND   I178 @S9S_MB_2U_LIB.S9S_MB_2U(SCH_1):PAGE110
    19    GND @S9S_MB_2U_LIB.S9S_MB_2U(SCH_1):GND   I178 @S9S_MB_2U_LIB.S9S_MB_2U(SCH_1):PAGE110
    21    GND @S9S_MB_2U_LIB.S9S_MB_2U(SCH_1):GND   I178 @S9S_MB_2U_LIB.S9S_MB_2U(SCH_1):PAGE110
    24    GND @S9S_MB_2U_LIB.S9S_MB_2U(SCH_1):GND   I178 @S9S_MB_2U_LIB.S9S_MB_2U(SCH_1):PAGE110
    26    GND @S9S_MB_2U_LIB.S9S_MB_2U(SCH_1):GND   I178 @S9S_MB_2U_LIB.S9S_MB_2U(SCH_1):PAGE110
    28    GND @S9S_MB_2U_LIB.S9S_MB_2U(SCH_1):GND   I178 @S9S_MB_2U_LIB.S9S_MB_2U(SCH_1):PAGE110
    30    GND @S9S_MB_2U_LIB.S9S_MB_2U(SCH_1):GND   I178 @S9S_MB_2U_LIB.S9S_MB_2U(SCH_1):PAGE110
    32    GND @S9S_MB_2U_LIB.S9S_MB_2U(SCH_1):GND   I178 @S9S_MB_2U_LIB.S9S_MB_2U(SCH_1):PAGE110
    35    GND @S9S_MB_2U_LIB.S9S_MB_2U(SCH_1):GND   I178 @S9S_MB_2U_LIB.S9S_MB_2U(SCH_1):PAGE110
    37    GND @S9S_MB_2U_LIB.S9S_MB_2U(SCH_1):GND   I178 @S9S_MB_2U_LIB.S9S_MB_2U(SCH_1):PAGE110
    39    GND @S9S_MB_2U_LIB.S9S_MB_2U(SCH_1):GND   I178 @S9S_MB_2U_LIB.S9S_MB_2U(SCH_1):PAGE110
    41    GND @S9S_MB_2U_LIB.S9S_MB_2U(SCH_1):GND   I178 @S9S_MB_2U_LIB.S9S_MB_2U(SCH_1):PAGE110
    43    GND @S9S_MB_2U_LIB.S9S_MB_2U(SCH_1):GND   I178 @S9S_MB_2U_LIB.S9S_MB_2U(SCH_1):PAGE110
    46    GND @S9S_MB_2U_LIB.S9S_MB_2U(SCH_1):GND   I178 @S9S_MB_2U_LIB.S9S_MB_2U(SCH_1):PAGE110
    48    GND @S9S_MB_2U_LIB.S9S_MB_2U(SCH_1):GND   I178 @S9S_MB_2U_LIB.S9S_MB_2U(SCH_1):PAGE110
    50    GND @S9S_MB_2U_LIB.S9S_MB_2U(SCH_1):GND   I178 @S9S_MB_2U_LIB.S9S_MB_2U(SCH_1):PAGE110
    52    GND @S9S_MB_2U_LIB.S9S_MB_2U(SCH_1):GND   I178 @S9S_MB_2U_LIB.S9S_MB_2U(SCH_1):PAGE110
    54    GND @S9S_MB_2U_LIB.S9S_MB_2U(SCH_1):GND   I178 @S9S_MB_2U_LIB.S9S_MB_2U(SCH_1):PAGE110
    57    GND @S9S_MB_2U_LIB.S9S_MB_2U(SCH_1):GND   I178 @S9S_MB_2U_LIB.S9S_MB_2U(SCH_1):PAGE110
    59    GND @S9S_MB_2U_LIB.S9S_MB_2U(SCH_1):GND   I178 @S9S_MB_2U_LIB.S9S_MB_2U(SCH_1):PAGE110
    61    GND @S9S_MB_2U_LIB.S9S_MB_2U(SCH_1):GND   I178 @S9S_MB_2U_LIB.S9S_MB_2U(SCH_1):PAGE110
    63    GND @S9S_MB_2U_LIB.S9S_MB_2U(SCH_1):GND   I178 @S9S_MB_2U_LIB.S9S_MB_2U(SCH_1):PAGE110
    65    GND @S9S_MB_2U_LIB.S9S_MB_2U(SCH_1):GND   I178 @S9S_MB_2U_LIB.S9S_MB_2U(SCH_1):PAGE110
    67    GND @S9S_MB_2U_LIB.S9S_MB_2U(SCH_1):GND   I178 @S9S_MB_2U_LIB.S9S_MB_2U(SCH_1):PAGE110
    69    GND @S9S_MB_2U_LIB.S9S_MB_2U(SCH_1):GND   I178 @S9S_MB_2U_LIB.S9S_MB_2U(SCH_1):PAGE110
    71    GND @S9S_MB_2U_LIB.S9S_MB_2U(SCH_1):GND   I178 @S9S_MB_2U_LIB.S9S_MB_2U(SCH_1):PAGE110
    73    GND @S9S_MB_2U_LIB.S9S_MB_2U(SCH_1):GND   I178 @S9S_MB_2U_LIB.S9S_MB_2U(SCH_1):PAGE110
    75    GND @S9S_MB_2U_LIB.S9S_MB_2U(SCH_1):GND   I178 @S9S_MB_2U_LIB.S9S_MB_2U(SCH_1):PAGE110
    77    GND @S9S_MB_2U_LIB.S9S_MB_2U(SCH_1):GND   I178 @S9S_MB_2U_LIB.S9S_MB_2U(SCH_1):PAGE110
    79    GND @S9S_MB_2U_LIB.S9S_MB_2U(SCH_1):GND   I178 @S9S_MB_2U_LIB.S9S_MB_2U(SCH_1):PAGE110
    81    GND @S9S_MB_2U_LIB.S9S_MB_2U(SCH_1):GND   I178 @S9S_MB_2U_LIB.S9S_MB_2U(SCH_1):PAGE110
    83    GND @S9S_MB_2U_LIB.S9S_MB_2U(SCH_1):GND   I178 @S9S_MB_2U_LIB.S9S_MB_2U(SCH_1):PAGE110
    85    GND @S9S_MB_2U_LIB.S9S_MB_2U(SCH_1):GND   I178 @S9S_MB_2U_LIB.S9S_MB_2U(SCH_1):PAGE110
    88    GND @S9S_MB_2U_LIB.S9S_MB_2U(SCH_1):GND   I178 @S9S_MB_2U_LIB.S9S_MB_2U(SCH_1):PAGE110
    90    GND @S9S_MB_2U_LIB.S9S_MB_2U(SCH_1):GND   I178 @S9S_MB_2U_LIB.S9S_MB_2U(SCH_1):PAGE110
    92    GND @S9S_MB_2U_LIB.S9S_MB_2U(SCH_1):GND   I178 @S9S_MB_2U_LIB.S9S_MB_2U(SCH_1):PAGE110
    95    GND @S9S_MB_2U_LIB.S9S_MB_2U(SCH_1):GND   I178 @S9S_MB_2U_LIB.S9S_MB_2U(SCH_1):PAGE110
    97    GND @S9S_MB_2U_LIB.S9S_MB_2U(SCH_1):GND   I178 @S9S_MB_2U_LIB.S9S_MB_2U(SCH_1):PAGE110
    99    GND @S9S_MB_2U_LIB.S9S_MB_2U(SCH_1):GND   I178 @S9S_MB_2U_LIB.S9S_MB_2U(SCH_1):PAGE110
   101    GND @S9S_MB_2U_LIB.S9S_MB_2U(SCH_1):GND   I178 @S9S_MB_2U_LIB.S9S_MB_2U(SCH_1):PAGE110
   103    GND @S9S_MB_2U_LIB.S9S_MB_2U(SCH_1):GND   I178 @S9S_MB_2U_LIB.S9S_MB_2U(SCH_1):PAGE110
   106    GND @S9S_MB_2U_LIB.S9S_MB_2U(SCH_1):GND   I178 @S9S_MB_2U_LIB.S9S_MB_2U(SCH_1):PAGE110
   108    GND @S9S_MB_2U_LIB.S9S_MB_2U(SCH_1):GND   I178 @S9S_MB_2U_LIB.S9S_MB_2U(SCH_1):PAGE110
   110    GND @S9S_MB_2U_LIB.S9S_MB_2U(SCH_1):GND   I178 @S9S_MB_2U_LIB.S9S_MB_2U(SCH_1):PAGE110
   112    GND @S9S_MB_2U_LIB.S9S_MB_2U(SCH_1):GND   I178 @S9S_MB_2U_LIB.S9S_MB_2U(SCH_1):PAGE110
   114    GND @S9S_MB_2U_LIB.S9S_MB_2U(SCH_1):GND   I178 @S9S_MB_2U_LIB.S9S_MB_2U(SCH_1):PAGE110
   117    GND @S9S_MB_2U_LIB.S9S_MB_2U(SCH_1):GND   I178 @S9S_MB_2U_LIB.S9S_MB_2U(SCH_1):PAGE110
   119    GND @S9S_MB_2U_LIB.S9S_MB_2U(SCH_1):GND   I178 @S9S_MB_2U_LIB.S9S_MB_2U(SCH_1):PAGE110
   121    GND @S9S_MB_2U_LIB.S9S_MB_2U(SCH_1):GND   I178 @S9S_MB_2U_LIB.S9S_MB_2U(SCH_1):PAGE110
   123    GND @S9S_MB_2U_LIB.S9S_MB_2U(SCH_1):GND   I178 @S9S_MB_2U_LIB.S9S_MB_2U(SCH_1):PAGE110
   125    GND @S9S_MB_2U_LIB.S9S_MB_2U(SCH_1):GND   I178 @S9S_MB_2U_LIB.S9S_MB_2U(SCH_1):PAGE110
   128    GND @S9S_MB_2U_LIB.S9S_MB_2U(SCH_1):GND   I178 @S9S_MB_2U_LIB.S9S_MB_2U(SCH_1):PAGE110
   130    GND @S9S_MB_2U_LIB.S9S_MB_2U(SCH_1):GND   I178 @S9S_MB_2U_LIB.S9S_MB_2U(SCH_1):PAGE110
   134    GND @S9S_MB_2U_LIB.S9S_MB_2U(SCH_1):GND   I178 @S9S_MB_2U_LIB.S9S_MB_2U(SCH_1):PAGE110
   143    GND @S9S_MB_2U_LIB.S9S_MB_2U(SCH_1):GND   I178 @S9S_MB_2U_LIB.S9S_MB_2U(SCH_1):PAGE110
   151    GND @S9S_MB_2U_LIB.S9S_MB_2U(SCH_1):GND   I178 @S9S_MB_2U_LIB.S9S_MB_2U(SCH_1):PAGE110
   153    GND @S9S_MB_2U_LIB.S9S_MB_2U(SCH_1):GND   I178 @S9S_MB_2U_LIB.S9S_MB_2U(SCH_1):PAGE110
   155    GND @S9S_MB_2U_LIB.S9S_MB_2U(SCH_1):GND   I178 @S9S_MB_2U_LIB.S9S_MB_2U(SCH_1):PAGE110
   158    GND @S9S_MB_2U_LIB.S9S_MB_2U(SCH_1):GND   I178 @S9S_MB_2U_LIB.S9S_MB_2U(SCH_1):PAGE110
   160    GND @S9S_MB_2U_LIB.S9S_MB_2U(SCH_1):GND   I178 @S9S_MB_2U_LIB.S9S_MB_2U(SCH_1):PAGE110
   162    GND @S9S_MB_2U_LIB.S9S_MB_2U(SCH_1):GND   I178 @S9S_MB_2U_LIB.S9S_MB_2U(SCH_1):PAGE110
   164    GND @S9S_MB_2U_LIB.S9S_MB_2U(SCH_1):GND   I178 @S9S_MB_2U_LIB.S9S_MB_2U(SCH_1):PAGE110
   166    GND @S9S_MB_2U_LIB.S9S_MB_2U(SCH_1):GND   I178 @S9S_MB_2U_LIB.S9S_MB_2U(SCH_1):PAGE110
   169    GND @S9S_MB_2U_LIB.S9S_MB_2U(SCH_1):GND   I178 @S9S_MB_2U_LIB.S9S_MB_2U(SCH_1):PAGE110
   171    GND @S9S_MB_2U_LIB.S9S_MB_2U(SCH_1):GND   I178 @S9S_MB_2U_LIB.S9S_MB_2U(SCH_1):PAGE110
   173    GND @S9S_MB_2U_LIB.S9S_MB_2U(SCH_1):GND   I178 @S9S_MB_2U_LIB.S9S_MB_2U(SCH_1):PAGE110
   175    GND @S9S_MB_2U_LIB.S9S_MB_2U(SCH_1):GND   I178 @S9S_MB_2U_LIB.S9S_MB_2U(SCH_1):PAGE110
   177    GND @S9S_MB_2U_LIB.S9S_MB_2U(SCH_1):GND   I178 @S9S_MB_2U_LIB.S9S_MB_2U(SCH_1):PAGE110
   180    GND @S9S_MB_2U_LIB.S9S_MB_2U(SCH_1):GND   I178 @S9S_MB_2U_LIB.S9S_MB_2U(SCH_1):PAGE110
   182    GND @S9S_MB_2U_LIB.S9S_MB_2U(SCH_1):GND   I178 @S9S_MB_2U_LIB.S9S_MB_2U(SCH_1):PAGE110
   184    GND @S9S_MB_2U_LIB.S9S_MB_2U(SCH_1):GND   I178 @S9S_MB_2U_LIB.S9S_MB_2U(SCH_1):PAGE110
   186    GND @S9S_MB_2U_LIB.S9S_MB_2U(SCH_1):GND   I178 @S9S_MB_2U_LIB.S9S_MB_2U(SCH_1):PAGE110
   188    GND @S9S_MB_2U_LIB.S9S_MB_2U(SCH_1):GND   I178 @S9S_MB_2U_LIB.S9S_MB_2U(SCH_1):PAGE110
   191    GND @S9S_MB_2U_LIB.S9S_MB_2U(SCH_1):GND   I178 @S9S_MB_2U_LIB.S9S_MB_2U(SCH_1):PAGE110
   193    GND @S9S_MB_2U_LIB.S9S_MB_2U(SCH_1):GND   I178 @S9S_MB_2U_LIB.S9S_MB_2U(SCH_1):PAGE110
   195    GND @S9S_MB_2U_LIB.S9S_MB_2U(SCH_1):GND   I178 @S9S_MB_2U_LIB.S9S_MB_2U(SCH_1):PAGE110
   197    GND @S9S_MB_2U_LIB.S9S_MB_2U(SCH_1):GND   I178 @S9S_MB_2U_LIB.S9S_MB_2U(SCH_1):PAGE110
   199    GND @S9S_MB_2U_LIB.S9S_MB_2U(SCH_1):GND   I178 @S9S_MB_2U_LIB.S9S_MB_2U(SCH_1):PAGE110
   202    GND @S9S_MB_2U_LIB.S9S_MB_2U(SCH_1):GND   I178 @S9S_MB_2U_LIB.S9S_MB_2U(SCH_1):PAGE110
   204    GND @S9S_MB_2U_LIB.S9S_MB_2U(SCH_1):GND   I178 @S9S_MB_2U_LIB.S9S_MB_2U(SCH_1):PAGE110
   206    GND @S9S_MB_2U_LIB.S9S_MB_2U(SCH_1):GND   I178 @S9S_MB_2U_LIB.S9S_MB_2U(SCH_1):PAGE110
   208    GND @S9S_MB_2U_LIB.S9S_MB_2U(SCH_1):GND   I178 @S9S_MB_2U_LIB.S9S_MB_2U(SCH_1):PAGE110
   210    GND @S9S_MB_2U_LIB.S9S_MB_2U(SCH_1):GND   I178 @S9S_MB_2U_LIB.S9S_MB_2U(SCH_1):PAGE110
   212    GND @S9S_MB_2U_LIB.S9S_MB_2U(SCH_1):GND   I178 @S9S_MB_2U_LIB.S9S_MB_2U(SCH_1):PAGE110
   214    GND @S9S_MB_2U_LIB.S9S_MB_2U(SCH_1):GND   I178 @S9S_MB_2U_LIB.S9S_MB_2U(SCH_1):PAGE110
   216    GND @S9S_MB_2U_LIB.S9S_MB_2U(SCH_1):GND   I178 @S9S_MB_2U_LIB.S9S_MB_2U(SCH_1):PAGE110
   219    GND @S9S_MB_2U_LIB.S9S_MB_2U(SCH_1):GND   I178 @S9S_MB_2U_LIB.S9S_MB_2U(SCH_1):PAGE110
   222    GND @S9S_MB_2U_LIB.S9S_MB_2U(SCH_1):GND   I178 @S9S_MB_2U_LIB.S9S_MB_2U(SCH_1):PAGE110
   224    GND @S9S_MB_2U_LIB.S9S_MB_2U(SCH_1):GND   I178 @S9S_MB_2U_LIB.S9S_MB_2U(SCH_1):PAGE110
   226    GND @S9S_MB_2U_LIB.S9S_MB_2U(SCH_1):GND   I178 @S9S_MB_2U_LIB.S9S_MB_2U(SCH_1):PAGE110
   228    GND @S9S_MB_2U_LIB.S9S_MB_2U(SCH_1):GND   I178 @S9S_MB_2U_LIB.S9S_MB_2U(SCH_1):PAGE110
   233    GND @S9S_MB_2U_LIB.S9S_MB_2U(SCH_1):GND   I178 @S9S_MB_2U_LIB.S9S_MB_2U(SCH_1):PAGE110
   237    GND @S9S_MB_2U_LIB.S9S_MB_2U(SCH_1):GND   I178 @S9S_MB_2U_LIB.S9S_MB_2U(SCH_1):PAGE110
   242    GND @S9S_MB_2U_LIB.S9S_MB_2U(SCH_1):GND   I178 @S9S_MB_2U_LIB.S9S_MB_2U(SCH_1):PAGE110
   244    GND @S9S_MB_2U_LIB.S9S_MB_2U(SCH_1):GND   I178 @S9S_MB_2U_LIB.S9S_MB_2U(SCH_1):PAGE110
   246    GND @S9S_MB_2U_LIB.S9S_MB_2U(SCH_1):GND   I178 @S9S_MB_2U_LIB.S9S_MB_2U(SCH_1):PAGE110
   248    GND @S9S_MB_2U_LIB.S9S_MB_2U(SCH_1):GND   I178 @S9S_MB_2U_LIB.S9S_MB_2U(SCH_1):PAGE110
   251    GND @S9S_MB_2U_LIB.S9S_MB_2U(SCH_1):GND   I178 @S9S_MB_2U_LIB.S9S_MB_2U(SCH_1):PAGE110
   253    GND @S9S_MB_2U_LIB.S9S_MB_2U(SCH_1):GND   I178 @S9S_MB_2U_LIB.S9S_MB_2U(SCH_1):PAGE110
   255    GND @S9S_MB_2U_LIB.S9S_MB_2U(SCH_1):GND   I178 @S9S_MB_2U_LIB.S9S_MB_2U(SCH_1):PAGE110
   257    GND @S9S_MB_2U_LIB.S9S_MB_2U(SCH_1):GND   I178 @S9S_MB_2U_LIB.S9S_MB_2U(SCH_1):PAGE110
   259    GND @S9S_MB_2U_LIB.S9S_MB_2U(SCH_1):GND   I178 @S9S_MB_2U_LIB.S9S_MB_2U(SCH_1):PAGE110
   262    GND @S9S_MB_2U_LIB.S9S_MB_2U(SCH_1):GND   I178 @S9S_MB_2U_LIB.S9S_MB_2U(SCH_1):PAGE110
   264    GND @S9S_MB_2U_LIB.S9S_MB_2U(SCH_1):GND   I178 @S9S_MB_2U_LIB.S9S_MB_2U(SCH_1):PAGE110
   266    GND @S9S_MB_2U_LIB.S9S_MB_2U(SCH_1):GND   I178 @S9S_MB_2U_LIB.S9S_MB_2U(SCH_1):PAGE110
   268    GND @S9S_MB_2U_LIB.S9S_MB_2U(SCH_1):GND   I178 @S9S_MB_2U_LIB.S9S_MB_2U(SCH_1):PAGE110
   270    GND @S9S_MB_2U_LIB.S9S_MB_2U(SCH_1):GND   I178 @S9S_MB_2U_LIB.S9S_MB_2U(SCH_1):PAGE110
   273    GND @S9S_MB_2U_LIB.S9S_MB_2U(SCH_1):GND   I178 @S9S_MB_2U_LIB.S9S_MB_2U(SCH_1):PAGE110
   275    GND @S9S_MB_2U_LIB.S9S_MB_2U(SCH_1):GND   I178 @S9S_MB_2U_LIB.S9S_MB_2U(SCH_1):PAGE110
   277    GND @S9S_MB_2U_LIB.S9S_MB_2U(SCH_1):GND   I178 @S9S_MB_2U_LIB.S9S_MB_2U(SCH_1):PAGE110
   279    GND @S9S_MB_2U_LIB.S9S_MB_2U(SCH_1):GND   I178 @S9S_MB_2U_LIB.S9S_MB_2U(SCH_1):PAGE110
   281    GND @S9S_MB_2U_LIB.S9S_MB_2U(SCH_1):GND   I178 @S9S_MB_2U_LIB.S9S_MB_2U(SCH_1):PAGE110
   284    GND @S9S_MB_2U_LIB.S9S_MB_2U(SCH_1):GND   I178 @S9S_MB_2U_LIB.S9S_MB_2U(SCH_1):PAGE110
   286    GND @S9S_MB_2U_LIB.S9S_MB_2U(SCH_1):GND   I178 @S9S_MB_2U_LIB.S9S_MB_2U(SCH_1):PAGE110
   288    GND @S9S_MB_2U_LIB.S9S_MB_2U(SCH_1):GND   I178 @S9S_MB_2U_LIB.S9S_MB_2U(SCH_1):PAGE110
     1 P12V_S3_AUX_CPU1_NVDIMM @S9S_MB_2U_LIB.S9S_MB_2U(SCH_1):P12V_S3_AUX_CPU1_NVDIMM   I178 @S9S_MB_2U_LIB.S9S_MB_2U(SCH_1):PAGE110
   145 P12V_S3_AUX_CPU1_NVDIMM @S9S_MB_2U_LIB.S9S_MB_2U(SCH_1):P12V_S3_AUX_CPU1_NVDIMM   I178 @S9S_MB_2U_LIB.S9S_MB_2U(SCH_1):PAGE110
   146 P12V_S3_AUX_CPU1_NVDIMM @S9S_MB_2U_LIB.S9S_MB_2U(SCH_1):P12V_S3_AUX_CPU1_NVDIMM   I178 @S9S_MB_2U_LIB.S9S_MB_2U(SCH_1):PAGE110
   230    GND @S9S_MB_2U_LIB.S9S_MB_2U(SCH_1):GND   I178 @S9S_MB_2U_LIB.S9S_MB_2U(SCH_1):PAGE110
   235    GND @S9S_MB_2U_LIB.S9S_MB_2U(SCH_1):GND   I178 @S9S_MB_2U_LIB.S9S_MB_2U(SCH_1):PAGE110
   240    GND @S9S_MB_2U_LIB.S9S_MB_2U(SCH_1):GND   I178 @S9S_MB_2U_LIB.S9S_MB_2U(SCH_1):PAGE110
   132    GND @S9S_MB_2U_LIB.S9S_MB_2U(SCH_1):GND   I178 @S9S_MB_2U_LIB.S9S_MB_2U(SCH_1):PAGE110
   136    GND @S9S_MB_2U_LIB.S9S_MB_2U(SCH_1):GND   I178 @S9S_MB_2U_LIB.S9S_MB_2U(SCH_1):PAGE110
   139    GND @S9S_MB_2U_LIB.S9S_MB_2U(SCH_1):GND   I178 @S9S_MB_2U_LIB.S9S_MB_2U(SCH_1):PAGE110
   141    GND @S9S_MB_2U_LIB.S9S_MB_2U(SCH_1):GND   I178 @S9S_MB_2U_LIB.S9S_MB_2U(SCH_1):PAGE110
    G1    GND @S9S_MB_2U_LIB.S9S_MB_2U(SCH_1):GND   I178 @S9S_MB_2U_LIB.S9S_MB_2U(SCH_1):PAGE110
    G2    GND @S9S_MB_2U_LIB.S9S_MB_2U(SCH_1):GND   I178 @S9S_MB_2U_LIB.S9S_MB_2U(SCH_1):PAGE110
    G3    GND @S9S_MB_2U_LIB.S9S_MB_2U(SCH_1):GND   I178 @S9S_MB_2U_LIB.S9S_MB_2U(SCH_1):PAGE110

 J30 SCONN288_ADR50017P087CC-SCONN2A
     3 P3V3_AUX @S9S_MB_2U_LIB.S9S_MB_2U(SCH_1):P3V3_AUX   I179 @S9S_MB_2U_LIB.S9S_MB_2U(SCH_1):PAGE111
     2 TP_CHG_CPU1_DIMM2_FRU_0 @S9S_MB_2U_LIB.S9S_MB_2U(SCH_1):TP_CHG_CPU1_DIMM2_FRU_0   I179 @S9S_MB_2U_LIB.S9S_MB_2U(SCH_1):PAGE111
   144 TP_CHG_CPU1_DIMM2_FRU_1 @S9S_MB_2U_LIB.S9S_MB_2U(SCH_1):TP_CHG_CPU1_DIMM2_FRU_1   I179 @S9S_MB_2U_LIB.S9S_MB_2U(SCH_1):PAGE111
   149 TP_CHG_CPU1_DIMM2_FRU_2 @S9S_MB_2U_LIB.S9S_MB_2U(SCH_1):TP_CHG_CPU1_DIMM2_FRU_2   I179 @S9S_MB_2U_LIB.S9S_MB_2U(SCH_1):PAGE111
   150 TP_CHG_CPU1_DIMM2_FRU_3 @S9S_MB_2U_LIB.S9S_MB_2U(SCH_1):TP_CHG_CPU1_DIMM2_FRU_3   I179 @S9S_MB_2U_LIB.S9S_MB_2U(SCH_1):PAGE111
   220 TP_CHG_CPU1_DIMM2_FRU_4 @S9S_MB_2U_LIB.S9S_MB_2U(SCH_1):TP_CHG_CPU1_DIMM2_FRU_4   I179 @S9S_MB_2U_LIB.S9S_MB_2U(SCH_1):PAGE111
   231 TP_CHG_CPU1_DIMM2_FRU_5 @S9S_MB_2U_LIB.S9S_MB_2U(SCH_1):TP_CHG_CPU1_DIMM2_FRU_5   I179 @S9S_MB_2U_LIB.S9S_MB_2U(SCH_1):PAGE111
   232 TP_CHG_CPU1_DIMM2_FRU_6 @S9S_MB_2U_LIB.S9S_MB_2U(SCH_1):TP_CHG_CPU1_DIMM2_FRU_6   I179 @S9S_MB_2U_LIB.S9S_MB_2U(SCH_1):PAGE111
   207 RST_M_GH_CPU1_FPGA_N @S9S_MB_2U_LIB.S9S_MB_2U(SCH_1):RST_M_GH_CPU1_FPGA_N   I179 @S9S_MB_2U_LIB.S9S_MB_2U(SCH_1):PAGE111
   147 PWRGD_CHG_CPU1_DIMM2 @S9S_MB_2U_LIB.S9S_MB_2U(SCH_1):PWRGD_CHG_CPU1_DIMM2   I179 @S9S_MB_2U_LIB.S9S_MB_2U(SCH_1):PAGE111
   227 M_G_CPU1_SB_PAR @S9S_MB_2U_LIB.S9S_MB_2U(SCH_1):M_G_CPU1_SB_PAR   I179 @S9S_MB_2U_LIB.S9S_MB_2U(SCH_1):PAGE111
    74 M_G_CPU1_SA_PAR @S9S_MB_2U_LIB.S9S_MB_2U(SCH_1):M_G_CPU1_SA_PAR   I179 @S9S_MB_2U_LIB.S9S_MB_2U(SCH_1):PAGE111
    87 M_G_CPU1_SB_RSP<1> @S9S_MB_2U_LIB.S9S_MB_2U(SCH_1):M_G_CPU1_SB_RSP(1)   I179 @S9S_MB_2U_LIB.S9S_MB_2U(SCH_1):PAGE111
    86 M_G_CPU1_SA_RSP<1> @S9S_MB_2U_LIB.S9S_MB_2U(SCH_1):M_G_CPU1_SA_RSP(1)   I179 @S9S_MB_2U_LIB.S9S_MB_2U(SCH_1):PAGE111
     5 I3C_SPD_DDREFGH_CPU1_LVC1_SDA @S9S_MB_2U_LIB.S9S_MB_2U(SCH_1):I3C_SPD_DDREFGH_CPU1_LVC1_SDA   I179 @S9S_MB_2U_LIB.S9S_MB_2U(SCH_1):PAGE111
     4 I3C_SPD_DDREFGH_CPU1_LVC1_SCL_5 @S9S_MB_2U_LIB.S9S_MB_2U(SCH_1):I3C_SPD_DDREFGH_CPU1_LVC1_SCL_R6   I179 @S9S_MB_2U_LIB.S9S_MB_2U(SCH_1):PAGE111
   148 PD_CHG_CPU1_DIMM2_SAA @S9S_MB_2U_LIB.S9S_MB_2U(SCH_1):PD_CHG_CPU1_DIMM2_SAA   I179 @S9S_MB_2U_LIB.S9S_MB_2U(SCH_1):PAGE111
   100 M_G_CPU1_SB_DQ<0> @S9S_MB_2U_LIB.S9S_MB_2U(SCH_1):M_G_CPU1_SB_DQ(0)   I179 @S9S_MB_2U_LIB.S9S_MB_2U(SCH_1):PAGE111
   102 M_G_CPU1_SB_DQ<1> @S9S_MB_2U_LIB.S9S_MB_2U(SCH_1):M_G_CPU1_SB_DQ(1)   I179 @S9S_MB_2U_LIB.S9S_MB_2U(SCH_1):PAGE111
   245 M_G_CPU1_SB_DQ<2> @S9S_MB_2U_LIB.S9S_MB_2U(SCH_1):M_G_CPU1_SB_DQ(2)   I179 @S9S_MB_2U_LIB.S9S_MB_2U(SCH_1):PAGE111
   247 M_G_CPU1_SB_DQ<3> @S9S_MB_2U_LIB.S9S_MB_2U(SCH_1):M_G_CPU1_SB_DQ(3)   I179 @S9S_MB_2U_LIB.S9S_MB_2U(SCH_1):PAGE111
   107 M_G_CPU1_SB_DQ<4> @S9S_MB_2U_LIB.S9S_MB_2U(SCH_1):M_G_CPU1_SB_DQ(4)   I179 @S9S_MB_2U_LIB.S9S_MB_2U(SCH_1):PAGE111
   109 M_G_CPU1_SB_DQ<5> @S9S_MB_2U_LIB.S9S_MB_2U(SCH_1):M_G_CPU1_SB_DQ(5)   I179 @S9S_MB_2U_LIB.S9S_MB_2U(SCH_1):PAGE111
   252 M_G_CPU1_SB_DQ<6> @S9S_MB_2U_LIB.S9S_MB_2U(SCH_1):M_G_CPU1_SB_DQ(6)   I179 @S9S_MB_2U_LIB.S9S_MB_2U(SCH_1):PAGE111
   254 M_G_CPU1_SB_DQ<7> @S9S_MB_2U_LIB.S9S_MB_2U(SCH_1):M_G_CPU1_SB_DQ(7)   I179 @S9S_MB_2U_LIB.S9S_MB_2U(SCH_1):PAGE111
   111 M_G_CPU1_SB_DQ<8> @S9S_MB_2U_LIB.S9S_MB_2U(SCH_1):M_G_CPU1_SB_DQ(8)   I179 @S9S_MB_2U_LIB.S9S_MB_2U(SCH_1):PAGE111
   113 M_G_CPU1_SB_DQ<9> @S9S_MB_2U_LIB.S9S_MB_2U(SCH_1):M_G_CPU1_SB_DQ(9)   I179 @S9S_MB_2U_LIB.S9S_MB_2U(SCH_1):PAGE111
   256 M_G_CPU1_SB_DQ<10> @S9S_MB_2U_LIB.S9S_MB_2U(SCH_1):M_G_CPU1_SB_DQ(10)   I179 @S9S_MB_2U_LIB.S9S_MB_2U(SCH_1):PAGE111
   258 M_G_CPU1_SB_DQ<11> @S9S_MB_2U_LIB.S9S_MB_2U(SCH_1):M_G_CPU1_SB_DQ(11)   I179 @S9S_MB_2U_LIB.S9S_MB_2U(SCH_1):PAGE111
   118 M_G_CPU1_SB_DQ<12> @S9S_MB_2U_LIB.S9S_MB_2U(SCH_1):M_G_CPU1_SB_DQ(12)   I179 @S9S_MB_2U_LIB.S9S_MB_2U(SCH_1):PAGE111
   120 M_G_CPU1_SB_DQ<13> @S9S_MB_2U_LIB.S9S_MB_2U(SCH_1):M_G_CPU1_SB_DQ(13)   I179 @S9S_MB_2U_LIB.S9S_MB_2U(SCH_1):PAGE111
   263 M_G_CPU1_SB_DQ<14> @S9S_MB_2U_LIB.S9S_MB_2U(SCH_1):M_G_CPU1_SB_DQ(14)   I179 @S9S_MB_2U_LIB.S9S_MB_2U(SCH_1):PAGE111
   265 M_G_CPU1_SB_DQ<15> @S9S_MB_2U_LIB.S9S_MB_2U(SCH_1):M_G_CPU1_SB_DQ(15)   I179 @S9S_MB_2U_LIB.S9S_MB_2U(SCH_1):PAGE111
   122 M_G_CPU1_SB_DQ<16> @S9S_MB_2U_LIB.S9S_MB_2U(SCH_1):M_G_CPU1_SB_DQ(16)   I179 @S9S_MB_2U_LIB.S9S_MB_2U(SCH_1):PAGE111
   124 M_G_CPU1_SB_DQ<17> @S9S_MB_2U_LIB.S9S_MB_2U(SCH_1):M_G_CPU1_SB_DQ(17)   I179 @S9S_MB_2U_LIB.S9S_MB_2U(SCH_1):PAGE111
   267 M_G_CPU1_SB_DQ<18> @S9S_MB_2U_LIB.S9S_MB_2U(SCH_1):M_G_CPU1_SB_DQ(18)   I179 @S9S_MB_2U_LIB.S9S_MB_2U(SCH_1):PAGE111
   269 M_G_CPU1_SB_DQ<19> @S9S_MB_2U_LIB.S9S_MB_2U(SCH_1):M_G_CPU1_SB_DQ(19)   I179 @S9S_MB_2U_LIB.S9S_MB_2U(SCH_1):PAGE111
   129 M_G_CPU1_SB_DQ<20> @S9S_MB_2U_LIB.S9S_MB_2U(SCH_1):M_G_CPU1_SB_DQ(20)   I179 @S9S_MB_2U_LIB.S9S_MB_2U(SCH_1):PAGE111
   131 M_G_CPU1_SB_DQ<21> @S9S_MB_2U_LIB.S9S_MB_2U(SCH_1):M_G_CPU1_SB_DQ(21)   I179 @S9S_MB_2U_LIB.S9S_MB_2U(SCH_1):PAGE111
   274 M_G_CPU1_SB_DQ<22> @S9S_MB_2U_LIB.S9S_MB_2U(SCH_1):M_G_CPU1_SB_DQ(22)   I179 @S9S_MB_2U_LIB.S9S_MB_2U(SCH_1):PAGE111
   276 M_G_CPU1_SB_DQ<23> @S9S_MB_2U_LIB.S9S_MB_2U(SCH_1):M_G_CPU1_SB_DQ(23)   I179 @S9S_MB_2U_LIB.S9S_MB_2U(SCH_1):PAGE111
   133 M_G_CPU1_SB_DQ<24> @S9S_MB_2U_LIB.S9S_MB_2U(SCH_1):M_G_CPU1_SB_DQ(24)   I179 @S9S_MB_2U_LIB.S9S_MB_2U(SCH_1):PAGE111
   135 M_G_CPU1_SB_DQ<25> @S9S_MB_2U_LIB.S9S_MB_2U(SCH_1):M_G_CPU1_SB_DQ(25)   I179 @S9S_MB_2U_LIB.S9S_MB_2U(SCH_1):PAGE111
   278 M_G_CPU1_SB_DQ<26> @S9S_MB_2U_LIB.S9S_MB_2U(SCH_1):M_G_CPU1_SB_DQ(26)   I179 @S9S_MB_2U_LIB.S9S_MB_2U(SCH_1):PAGE111
   280 M_G_CPU1_SB_DQ<27> @S9S_MB_2U_LIB.S9S_MB_2U(SCH_1):M_G_CPU1_SB_DQ(27)   I179 @S9S_MB_2U_LIB.S9S_MB_2U(SCH_1):PAGE111
   140 M_G_CPU1_SB_DQ<28> @S9S_MB_2U_LIB.S9S_MB_2U(SCH_1):M_G_CPU1_SB_DQ(28)   I179 @S9S_MB_2U_LIB.S9S_MB_2U(SCH_1):PAGE111
   142 M_G_CPU1_SB_DQ<29> @S9S_MB_2U_LIB.S9S_MB_2U(SCH_1):M_G_CPU1_SB_DQ(29)   I179 @S9S_MB_2U_LIB.S9S_MB_2U(SCH_1):PAGE111
   285 M_G_CPU1_SB_DQ<30> @S9S_MB_2U_LIB.S9S_MB_2U(SCH_1):M_G_CPU1_SB_DQ(30)   I179 @S9S_MB_2U_LIB.S9S_MB_2U(SCH_1):PAGE111
   287 M_G_CPU1_SB_DQ<31> @S9S_MB_2U_LIB.S9S_MB_2U(SCH_1):M_G_CPU1_SB_DQ(31)   I179 @S9S_MB_2U_LIB.S9S_MB_2U(SCH_1):PAGE111
     7 M_G_CPU1_SA_DQ<0> @S9S_MB_2U_LIB.S9S_MB_2U(SCH_1):M_G_CPU1_SA_DQ(0)   I179 @S9S_MB_2U_LIB.S9S_MB_2U(SCH_1):PAGE111
     9 M_G_CPU1_SA_DQ<1> @S9S_MB_2U_LIB.S9S_MB_2U(SCH_1):M_G_CPU1_SA_DQ(1)   I179 @S9S_MB_2U_LIB.S9S_MB_2U(SCH_1):PAGE111
   152 M_G_CPU1_SA_DQ<2> @S9S_MB_2U_LIB.S9S_MB_2U(SCH_1):M_G_CPU1_SA_DQ(2)   I179 @S9S_MB_2U_LIB.S9S_MB_2U(SCH_1):PAGE111
   154 M_G_CPU1_SA_DQ<3> @S9S_MB_2U_LIB.S9S_MB_2U(SCH_1):M_G_CPU1_SA_DQ(3)   I179 @S9S_MB_2U_LIB.S9S_MB_2U(SCH_1):PAGE111
    14 M_G_CPU1_SA_DQ<4> @S9S_MB_2U_LIB.S9S_MB_2U(SCH_1):M_G_CPU1_SA_DQ(4)   I179 @S9S_MB_2U_LIB.S9S_MB_2U(SCH_1):PAGE111
    16 M_G_CPU1_SA_DQ<5> @S9S_MB_2U_LIB.S9S_MB_2U(SCH_1):M_G_CPU1_SA_DQ(5)   I179 @S9S_MB_2U_LIB.S9S_MB_2U(SCH_1):PAGE111
   159 M_G_CPU1_SA_DQ<6> @S9S_MB_2U_LIB.S9S_MB_2U(SCH_1):M_G_CPU1_SA_DQ(6)   I179 @S9S_MB_2U_LIB.S9S_MB_2U(SCH_1):PAGE111
   161 M_G_CPU1_SA_DQ<7> @S9S_MB_2U_LIB.S9S_MB_2U(SCH_1):M_G_CPU1_SA_DQ(7)   I179 @S9S_MB_2U_LIB.S9S_MB_2U(SCH_1):PAGE111
    18 M_G_CPU1_SA_DQ<8> @S9S_MB_2U_LIB.S9S_MB_2U(SCH_1):M_G_CPU1_SA_DQ(8)   I179 @S9S_MB_2U_LIB.S9S_MB_2U(SCH_1):PAGE111
    20 M_G_CPU1_SA_DQ<9> @S9S_MB_2U_LIB.S9S_MB_2U(SCH_1):M_G_CPU1_SA_DQ(9)   I179 @S9S_MB_2U_LIB.S9S_MB_2U(SCH_1):PAGE111
   163 M_G_CPU1_SA_DQ<10> @S9S_MB_2U_LIB.S9S_MB_2U(SCH_1):M_G_CPU1_SA_DQ(10)   I179 @S9S_MB_2U_LIB.S9S_MB_2U(SCH_1):PAGE111
   165 M_G_CPU1_SA_DQ<11> @S9S_MB_2U_LIB.S9S_MB_2U(SCH_1):M_G_CPU1_SA_DQ(11)   I179 @S9S_MB_2U_LIB.S9S_MB_2U(SCH_1):PAGE111
    25 M_G_CPU1_SA_DQ<12> @S9S_MB_2U_LIB.S9S_MB_2U(SCH_1):M_G_CPU1_SA_DQ(12)   I179 @S9S_MB_2U_LIB.S9S_MB_2U(SCH_1):PAGE111
    27 M_G_CPU1_SA_DQ<13> @S9S_MB_2U_LIB.S9S_MB_2U(SCH_1):M_G_CPU1_SA_DQ(13)   I179 @S9S_MB_2U_LIB.S9S_MB_2U(SCH_1):PAGE111
   170 M_G_CPU1_SA_DQ<14> @S9S_MB_2U_LIB.S9S_MB_2U(SCH_1):M_G_CPU1_SA_DQ(14)   I179 @S9S_MB_2U_LIB.S9S_MB_2U(SCH_1):PAGE111
   172 M_G_CPU1_SA_DQ<15> @S9S_MB_2U_LIB.S9S_MB_2U(SCH_1):M_G_CPU1_SA_DQ(15)   I179 @S9S_MB_2U_LIB.S9S_MB_2U(SCH_1):PAGE111
    29 M_G_CPU1_SA_DQ<16> @S9S_MB_2U_LIB.S9S_MB_2U(SCH_1):M_G_CPU1_SA_DQ(16)   I179 @S9S_MB_2U_LIB.S9S_MB_2U(SCH_1):PAGE111
    31 M_G_CPU1_SA_DQ<17> @S9S_MB_2U_LIB.S9S_MB_2U(SCH_1):M_G_CPU1_SA_DQ(17)   I179 @S9S_MB_2U_LIB.S9S_MB_2U(SCH_1):PAGE111
   174 M_G_CPU1_SA_DQ<18> @S9S_MB_2U_LIB.S9S_MB_2U(SCH_1):M_G_CPU1_SA_DQ(18)   I179 @S9S_MB_2U_LIB.S9S_MB_2U(SCH_1):PAGE111
   176 M_G_CPU1_SA_DQ<19> @S9S_MB_2U_LIB.S9S_MB_2U(SCH_1):M_G_CPU1_SA_DQ(19)   I179 @S9S_MB_2U_LIB.S9S_MB_2U(SCH_1):PAGE111
    36 M_G_CPU1_SA_DQ<20> @S9S_MB_2U_LIB.S9S_MB_2U(SCH_1):M_G_CPU1_SA_DQ(20)   I179 @S9S_MB_2U_LIB.S9S_MB_2U(SCH_1):PAGE111
    38 M_G_CPU1_SA_DQ<21> @S9S_MB_2U_LIB.S9S_MB_2U(SCH_1):M_G_CPU1_SA_DQ(21)   I179 @S9S_MB_2U_LIB.S9S_MB_2U(SCH_1):PAGE111
   181 M_G_CPU1_SA_DQ<22> @S9S_MB_2U_LIB.S9S_MB_2U(SCH_1):M_G_CPU1_SA_DQ(22)   I179 @S9S_MB_2U_LIB.S9S_MB_2U(SCH_1):PAGE111
   183 M_G_CPU1_SA_DQ<23> @S9S_MB_2U_LIB.S9S_MB_2U(SCH_1):M_G_CPU1_SA_DQ(23)   I179 @S9S_MB_2U_LIB.S9S_MB_2U(SCH_1):PAGE111
    40 M_G_CPU1_SA_DQ<24> @S9S_MB_2U_LIB.S9S_MB_2U(SCH_1):M_G_CPU1_SA_DQ(24)   I179 @S9S_MB_2U_LIB.S9S_MB_2U(SCH_1):PAGE111
    42 M_G_CPU1_SA_DQ<25> @S9S_MB_2U_LIB.S9S_MB_2U(SCH_1):M_G_CPU1_SA_DQ(25)   I179 @S9S_MB_2U_LIB.S9S_MB_2U(SCH_1):PAGE111
   185 M_G_CPU1_SA_DQ<26> @S9S_MB_2U_LIB.S9S_MB_2U(SCH_1):M_G_CPU1_SA_DQ(26)   I179 @S9S_MB_2U_LIB.S9S_MB_2U(SCH_1):PAGE111
   187 M_G_CPU1_SA_DQ<27> @S9S_MB_2U_LIB.S9S_MB_2U(SCH_1):M_G_CPU1_SA_DQ(27)   I179 @S9S_MB_2U_LIB.S9S_MB_2U(SCH_1):PAGE111
    47 M_G_CPU1_SA_DQ<28> @S9S_MB_2U_LIB.S9S_MB_2U(SCH_1):M_G_CPU1_SA_DQ(28)   I179 @S9S_MB_2U_LIB.S9S_MB_2U(SCH_1):PAGE111
    49 M_G_CPU1_SA_DQ<29> @S9S_MB_2U_LIB.S9S_MB_2U(SCH_1):M_G_CPU1_SA_DQ(29)   I179 @S9S_MB_2U_LIB.S9S_MB_2U(SCH_1):PAGE111
   192 M_G_CPU1_SA_DQ<30> @S9S_MB_2U_LIB.S9S_MB_2U(SCH_1):M_G_CPU1_SA_DQ(30)   I179 @S9S_MB_2U_LIB.S9S_MB_2U(SCH_1):PAGE111
   229 M_G_CPU1_SB_CS_N<3> @S9S_MB_2U_LIB.S9S_MB_2U(SCH_1):M_G_CPU1_SB_CS_N(3)   I179 @S9S_MB_2U_LIB.S9S_MB_2U(SCH_1):PAGE111
   209 M_G_CPU1_SA_CS_N<3> @S9S_MB_2U_LIB.S9S_MB_2U(SCH_1):M_G_CPU1_SA_CS_N(3)   I179 @S9S_MB_2U_LIB.S9S_MB_2U(SCH_1):PAGE111
    84 M_G_CPU1_SB_CS_N<2> @S9S_MB_2U_LIB.S9S_MB_2U(SCH_1):M_G_CPU1_SB_CS_N(2)   I179 @S9S_MB_2U_LIB.S9S_MB_2U(SCH_1):PAGE111
    64 M_G_CPU1_SA_CS_N<2> @S9S_MB_2U_LIB.S9S_MB_2U(SCH_1):M_G_CPU1_SA_CS_N(2)   I179 @S9S_MB_2U_LIB.S9S_MB_2U(SCH_1):PAGE111
   217 M_G_CPU1_CLK_DP<1> @S9S_MB_2U_LIB.S9S_MB_2U(SCH_1):M_G_CPU1_CLK_DP(1)   I179 @S9S_MB_2U_LIB.S9S_MB_2U(SCH_1):PAGE111
   218 M_G_CPU1_CLK_DN<1> @S9S_MB_2U_LIB.S9S_MB_2U(SCH_1):M_G_CPU1_CLK_DN(1)   I179 @S9S_MB_2U_LIB.S9S_MB_2U(SCH_1):PAGE111
    96 M_G_CPU1_SB_CB<0> @S9S_MB_2U_LIB.S9S_MB_2U(SCH_1):M_G_CPU1_SB_CB(0)   I179 @S9S_MB_2U_LIB.S9S_MB_2U(SCH_1):PAGE111
    98 M_G_CPU1_SB_CB<1> @S9S_MB_2U_LIB.S9S_MB_2U(SCH_1):M_G_CPU1_SB_CB(1)   I179 @S9S_MB_2U_LIB.S9S_MB_2U(SCH_1):PAGE111
   241 M_G_CPU1_SB_CB<2> @S9S_MB_2U_LIB.S9S_MB_2U(SCH_1):M_G_CPU1_SB_CB(2)   I179 @S9S_MB_2U_LIB.S9S_MB_2U(SCH_1):PAGE111
   243 M_G_CPU1_SB_CB<3> @S9S_MB_2U_LIB.S9S_MB_2U(SCH_1):M_G_CPU1_SB_CB(3)   I179 @S9S_MB_2U_LIB.S9S_MB_2U(SCH_1):PAGE111
    89 M_G_CPU1_SB_CB<4> @S9S_MB_2U_LIB.S9S_MB_2U(SCH_1):M_G_CPU1_SB_CB(4)   I179 @S9S_MB_2U_LIB.S9S_MB_2U(SCH_1):PAGE111
    91 M_G_CPU1_SB_CB<5> @S9S_MB_2U_LIB.S9S_MB_2U(SCH_1):M_G_CPU1_SB_CB(5)   I179 @S9S_MB_2U_LIB.S9S_MB_2U(SCH_1):PAGE111
   234 M_G_CPU1_SB_CB<6> @S9S_MB_2U_LIB.S9S_MB_2U(SCH_1):M_G_CPU1_SB_CB(6)   I179 @S9S_MB_2U_LIB.S9S_MB_2U(SCH_1):PAGE111
    51 M_G_CPU1_SA_CB<0> @S9S_MB_2U_LIB.S9S_MB_2U(SCH_1):M_G_CPU1_SA_CB(0)   I179 @S9S_MB_2U_LIB.S9S_MB_2U(SCH_1):PAGE111
   196 M_G_CPU1_SA_CB<2> @S9S_MB_2U_LIB.S9S_MB_2U(SCH_1):M_G_CPU1_SA_CB(2)   I179 @S9S_MB_2U_LIB.S9S_MB_2U(SCH_1):PAGE111
   198 M_G_CPU1_SA_CB<3> @S9S_MB_2U_LIB.S9S_MB_2U(SCH_1):M_G_CPU1_SA_CB(3)   I179 @S9S_MB_2U_LIB.S9S_MB_2U(SCH_1):PAGE111
    60 M_G_CPU1_SA_CB<5> @S9S_MB_2U_LIB.S9S_MB_2U(SCH_1):M_G_CPU1_SA_CB(5)   I179 @S9S_MB_2U_LIB.S9S_MB_2U(SCH_1):PAGE111
   203 M_G_CPU1_SA_CB<6> @S9S_MB_2U_LIB.S9S_MB_2U(SCH_1):M_G_CPU1_SA_CB(6)   I179 @S9S_MB_2U_LIB.S9S_MB_2U(SCH_1):PAGE111
    82 M_G_CPU1_SB_CA<6> @S9S_MB_2U_LIB.S9S_MB_2U(SCH_1):M_G_CPU1_SB_CA(6)   I179 @S9S_MB_2U_LIB.S9S_MB_2U(SCH_1):PAGE111
    72 M_G_CPU1_SA_CA<6> @S9S_MB_2U_LIB.S9S_MB_2U(SCH_1):M_G_CPU1_SA_CA(6)   I179 @S9S_MB_2U_LIB.S9S_MB_2U(SCH_1):PAGE111
   225 M_G_CPU1_SB_CA<5> @S9S_MB_2U_LIB.S9S_MB_2U(SCH_1):M_G_CPU1_SB_CA(5)   I179 @S9S_MB_2U_LIB.S9S_MB_2U(SCH_1):PAGE111
   215 M_G_CPU1_SA_CA<5> @S9S_MB_2U_LIB.S9S_MB_2U(SCH_1):M_G_CPU1_SA_CA(5)   I179 @S9S_MB_2U_LIB.S9S_MB_2U(SCH_1):PAGE111
    80 M_G_CPU1_SB_CA<4> @S9S_MB_2U_LIB.S9S_MB_2U(SCH_1):M_G_CPU1_SB_CA(4)   I179 @S9S_MB_2U_LIB.S9S_MB_2U(SCH_1):PAGE111
    70 M_G_CPU1_SA_CA<4> @S9S_MB_2U_LIB.S9S_MB_2U(SCH_1):M_G_CPU1_SA_CA(4)   I179 @S9S_MB_2U_LIB.S9S_MB_2U(SCH_1):PAGE111
   223 M_G_CPU1_SB_CA<3> @S9S_MB_2U_LIB.S9S_MB_2U(SCH_1):M_G_CPU1_SB_CA(3)   I179 @S9S_MB_2U_LIB.S9S_MB_2U(SCH_1):PAGE111
   213 M_G_CPU1_SA_CA<3> @S9S_MB_2U_LIB.S9S_MB_2U(SCH_1):M_G_CPU1_SA_CA(3)   I179 @S9S_MB_2U_LIB.S9S_MB_2U(SCH_1):PAGE111
    78 M_G_CPU1_SB_CA<2> @S9S_MB_2U_LIB.S9S_MB_2U(SCH_1):M_G_CPU1_SB_CA(2)   I179 @S9S_MB_2U_LIB.S9S_MB_2U(SCH_1):PAGE111
    68 M_G_CPU1_SA_CA<2> @S9S_MB_2U_LIB.S9S_MB_2U(SCH_1):M_G_CPU1_SA_CA(2)   I179 @S9S_MB_2U_LIB.S9S_MB_2U(SCH_1):PAGE111
   221 M_G_CPU1_SB_CA<1> @S9S_MB_2U_LIB.S9S_MB_2U(SCH_1):M_G_CPU1_SB_CA(1)   I179 @S9S_MB_2U_LIB.S9S_MB_2U(SCH_1):PAGE111
   211 M_G_CPU1_SA_CA<1> @S9S_MB_2U_LIB.S9S_MB_2U(SCH_1):M_G_CPU1_SA_CA(1)   I179 @S9S_MB_2U_LIB.S9S_MB_2U(SCH_1):PAGE111
    76 M_G_CPU1_SB_CA<0> @S9S_MB_2U_LIB.S9S_MB_2U(SCH_1):M_G_CPU1_SB_CA(0)   I179 @S9S_MB_2U_LIB.S9S_MB_2U(SCH_1):PAGE111
    66 M_G_CPU1_SA_CA<0> @S9S_MB_2U_LIB.S9S_MB_2U(SCH_1):M_G_CPU1_SA_CA(0)   I179 @S9S_MB_2U_LIB.S9S_MB_2U(SCH_1):PAGE111
    62 M_G_CPU1_ALERT_N @S9S_MB_2U_LIB.S9S_MB_2U(SCH_1):M_G_CPU1_ALERT_N   I179 @S9S_MB_2U_LIB.S9S_MB_2U(SCH_1):PAGE111
   236 M_G_CPU1_SB_CB<7> @S9S_MB_2U_LIB.S9S_MB_2U(SCH_1):M_G_CPU1_SB_CB(7)   I179 @S9S_MB_2U_LIB.S9S_MB_2U(SCH_1):PAGE111
    53 M_G_CPU1_SA_CB<1> @S9S_MB_2U_LIB.S9S_MB_2U(SCH_1):M_G_CPU1_SA_CB(1)   I179 @S9S_MB_2U_LIB.S9S_MB_2U(SCH_1):PAGE111
    58 M_G_CPU1_SA_CB<4> @S9S_MB_2U_LIB.S9S_MB_2U(SCH_1):M_G_CPU1_SA_CB(4)   I179 @S9S_MB_2U_LIB.S9S_MB_2U(SCH_1):PAGE111
   205 M_G_CPU1_SA_CB<7> @S9S_MB_2U_LIB.S9S_MB_2U(SCH_1):M_G_CPU1_SA_CB(7)   I179 @S9S_MB_2U_LIB.S9S_MB_2U(SCH_1):PAGE111
   194 M_G_CPU1_SA_DQ<31> @S9S_MB_2U_LIB.S9S_MB_2U(SCH_1):M_G_CPU1_SA_DQ(31)   I179 @S9S_MB_2U_LIB.S9S_MB_2U(SCH_1):PAGE111
    93 M_G_CPU1_SB_DQS_DP<9> @S9S_MB_2U_LIB.S9S_MB_2U(SCH_1):M_G_CPU1_SB_DQS_DP(9)   I180 @S9S_MB_2U_LIB.S9S_MB_2U(SCH_1):PAGE111
    94 M_G_CPU1_SB_DQS_DN<9> @S9S_MB_2U_LIB.S9S_MB_2U(SCH_1):M_G_CPU1_SB_DQS_DN(9)   I180 @S9S_MB_2U_LIB.S9S_MB_2U(SCH_1):PAGE111
   201 M_G_CPU1_SA_DQS_DP<9> @S9S_MB_2U_LIB.S9S_MB_2U(SCH_1):M_G_CPU1_SA_DQS_DP(9)   I180 @S9S_MB_2U_LIB.S9S_MB_2U(SCH_1):PAGE111
   200 M_G_CPU1_SA_DQS_DN<9> @S9S_MB_2U_LIB.S9S_MB_2U(SCH_1):M_G_CPU1_SA_DQS_DN(9)   I180 @S9S_MB_2U_LIB.S9S_MB_2U(SCH_1):PAGE111
   190 M_G_CPU1_SA_DQS_DP<8> @S9S_MB_2U_LIB.S9S_MB_2U(SCH_1):M_G_CPU1_SA_DQS_DP(8)   I180 @S9S_MB_2U_LIB.S9S_MB_2U(SCH_1):PAGE111
   189 M_G_CPU1_SA_DQS_DN<8> @S9S_MB_2U_LIB.S9S_MB_2U(SCH_1):M_G_CPU1_SA_DQS_DN(8)   I180 @S9S_MB_2U_LIB.S9S_MB_2U(SCH_1):PAGE111
   271 M_G_CPU1_SB_DQS_DN<7> @S9S_MB_2U_LIB.S9S_MB_2U(SCH_1):M_G_CPU1_SB_DQS_DN(7)   I180 @S9S_MB_2U_LIB.S9S_MB_2U(SCH_1):PAGE111
   179 M_G_CPU1_SA_DQS_DP<7> @S9S_MB_2U_LIB.S9S_MB_2U(SCH_1):M_G_CPU1_SA_DQS_DP(7)   I180 @S9S_MB_2U_LIB.S9S_MB_2U(SCH_1):PAGE111
   261 M_G_CPU1_SB_DQS_DP<6> @S9S_MB_2U_LIB.S9S_MB_2U(SCH_1):M_G_CPU1_SB_DQS_DP(6)   I180 @S9S_MB_2U_LIB.S9S_MB_2U(SCH_1):PAGE111
   260 M_G_CPU1_SB_DQS_DN<6> @S9S_MB_2U_LIB.S9S_MB_2U(SCH_1):M_G_CPU1_SB_DQS_DN(6)   I180 @S9S_MB_2U_LIB.S9S_MB_2U(SCH_1):PAGE111
   167 M_G_CPU1_SA_DQS_DN<6> @S9S_MB_2U_LIB.S9S_MB_2U(SCH_1):M_G_CPU1_SA_DQS_DN(6)   I180 @S9S_MB_2U_LIB.S9S_MB_2U(SCH_1):PAGE111
   250 M_G_CPU1_SB_DQS_DP<5> @S9S_MB_2U_LIB.S9S_MB_2U(SCH_1):M_G_CPU1_SB_DQS_DP(5)   I180 @S9S_MB_2U_LIB.S9S_MB_2U(SCH_1):PAGE111
   249 M_G_CPU1_SB_DQS_DN<5> @S9S_MB_2U_LIB.S9S_MB_2U(SCH_1):M_G_CPU1_SB_DQS_DN(5)   I180 @S9S_MB_2U_LIB.S9S_MB_2U(SCH_1):PAGE111
   157 M_G_CPU1_SA_DQS_DP<5> @S9S_MB_2U_LIB.S9S_MB_2U(SCH_1):M_G_CPU1_SA_DQS_DP(5)   I180 @S9S_MB_2U_LIB.S9S_MB_2U(SCH_1):PAGE111
   156 M_G_CPU1_SA_DQS_DN<5> @S9S_MB_2U_LIB.S9S_MB_2U(SCH_1):M_G_CPU1_SA_DQS_DN(5)   I180 @S9S_MB_2U_LIB.S9S_MB_2U(SCH_1):PAGE111
   239 M_G_CPU1_SB_DQS_DP<4> @S9S_MB_2U_LIB.S9S_MB_2U(SCH_1):M_G_CPU1_SB_DQS_DP(4)   I180 @S9S_MB_2U_LIB.S9S_MB_2U(SCH_1):PAGE111
   238 M_G_CPU1_SB_DQS_DN<4> @S9S_MB_2U_LIB.S9S_MB_2U(SCH_1):M_G_CPU1_SB_DQS_DN(4)   I180 @S9S_MB_2U_LIB.S9S_MB_2U(SCH_1):PAGE111
    55 M_G_CPU1_SA_DQS_DP<4> @S9S_MB_2U_LIB.S9S_MB_2U(SCH_1):M_G_CPU1_SA_DQS_DP(4)   I180 @S9S_MB_2U_LIB.S9S_MB_2U(SCH_1):PAGE111
    56 M_G_CPU1_SA_DQS_DN<4> @S9S_MB_2U_LIB.S9S_MB_2U(SCH_1):M_G_CPU1_SA_DQS_DN(4)   I180 @S9S_MB_2U_LIB.S9S_MB_2U(SCH_1):PAGE111
   137 M_G_CPU1_SB_DQS_DP<3> @S9S_MB_2U_LIB.S9S_MB_2U(SCH_1):M_G_CPU1_SB_DQS_DP(3)   I180 @S9S_MB_2U_LIB.S9S_MB_2U(SCH_1):PAGE111
   138 M_G_CPU1_SB_DQS_DN<3> @S9S_MB_2U_LIB.S9S_MB_2U(SCH_1):M_G_CPU1_SB_DQS_DN(3)   I180 @S9S_MB_2U_LIB.S9S_MB_2U(SCH_1):PAGE111
    44 M_G_CPU1_SA_DQS_DP<3> @S9S_MB_2U_LIB.S9S_MB_2U(SCH_1):M_G_CPU1_SA_DQS_DP(3)   I180 @S9S_MB_2U_LIB.S9S_MB_2U(SCH_1):PAGE111
    45 M_G_CPU1_SA_DQS_DN<3> @S9S_MB_2U_LIB.S9S_MB_2U(SCH_1):M_G_CPU1_SA_DQS_DN(3)   I180 @S9S_MB_2U_LIB.S9S_MB_2U(SCH_1):PAGE111
   126 M_G_CPU1_SB_DQS_DP<2> @S9S_MB_2U_LIB.S9S_MB_2U(SCH_1):M_G_CPU1_SB_DQS_DP(2)   I180 @S9S_MB_2U_LIB.S9S_MB_2U(SCH_1):PAGE111
   127 M_G_CPU1_SB_DQS_DN<2> @S9S_MB_2U_LIB.S9S_MB_2U(SCH_1):M_G_CPU1_SB_DQS_DN(2)   I180 @S9S_MB_2U_LIB.S9S_MB_2U(SCH_1):PAGE111
    33 M_G_CPU1_SA_DQS_DP<2> @S9S_MB_2U_LIB.S9S_MB_2U(SCH_1):M_G_CPU1_SA_DQS_DP(2)   I180 @S9S_MB_2U_LIB.S9S_MB_2U(SCH_1):PAGE111
    34 M_G_CPU1_SA_DQS_DN<2> @S9S_MB_2U_LIB.S9S_MB_2U(SCH_1):M_G_CPU1_SA_DQS_DN(2)   I180 @S9S_MB_2U_LIB.S9S_MB_2U(SCH_1):PAGE111
   115 M_G_CPU1_SB_DQS_DP<1> @S9S_MB_2U_LIB.S9S_MB_2U(SCH_1):M_G_CPU1_SB_DQS_DP(1)   I180 @S9S_MB_2U_LIB.S9S_MB_2U(SCH_1):PAGE111
   116 M_G_CPU1_SB_DQS_DN<1> @S9S_MB_2U_LIB.S9S_MB_2U(SCH_1):M_G_CPU1_SB_DQS_DN(1)   I180 @S9S_MB_2U_LIB.S9S_MB_2U(SCH_1):PAGE111
    22 M_G_CPU1_SA_DQS_DP<1> @S9S_MB_2U_LIB.S9S_MB_2U(SCH_1):M_G_CPU1_SA_DQS_DP(1)   I180 @S9S_MB_2U_LIB.S9S_MB_2U(SCH_1):PAGE111
    23 M_G_CPU1_SA_DQS_DN<1> @S9S_MB_2U_LIB.S9S_MB_2U(SCH_1):M_G_CPU1_SA_DQS_DN(1)   I180 @S9S_MB_2U_LIB.S9S_MB_2U(SCH_1):PAGE111
   104 M_G_CPU1_SB_DQS_DP<0> @S9S_MB_2U_LIB.S9S_MB_2U(SCH_1):M_G_CPU1_SB_DQS_DP(0)   I180 @S9S_MB_2U_LIB.S9S_MB_2U(SCH_1):PAGE111
   105 M_G_CPU1_SB_DQS_DN<0> @S9S_MB_2U_LIB.S9S_MB_2U(SCH_1):M_G_CPU1_SB_DQS_DN(0)   I180 @S9S_MB_2U_LIB.S9S_MB_2U(SCH_1):PAGE111
    11 M_G_CPU1_SA_DQS_DP<0> @S9S_MB_2U_LIB.S9S_MB_2U(SCH_1):M_G_CPU1_SA_DQS_DP(0)   I180 @S9S_MB_2U_LIB.S9S_MB_2U(SCH_1):PAGE111
    12 M_G_CPU1_SA_DQS_DN<0> @S9S_MB_2U_LIB.S9S_MB_2U(SCH_1):M_G_CPU1_SA_DQS_DN(0)   I180 @S9S_MB_2U_LIB.S9S_MB_2U(SCH_1):PAGE111
   272 M_G_CPU1_SB_DQS_DP<7> @S9S_MB_2U_LIB.S9S_MB_2U(SCH_1):M_G_CPU1_SB_DQS_DP(7)   I180 @S9S_MB_2U_LIB.S9S_MB_2U(SCH_1):PAGE111
   282 M_G_CPU1_SB_DQS_DN<8> @S9S_MB_2U_LIB.S9S_MB_2U(SCH_1):M_G_CPU1_SB_DQS_DN(8)   I180 @S9S_MB_2U_LIB.S9S_MB_2U(SCH_1):PAGE111
   283 M_G_CPU1_SB_DQS_DP<8> @S9S_MB_2U_LIB.S9S_MB_2U(SCH_1):M_G_CPU1_SB_DQS_DP(8)   I180 @S9S_MB_2U_LIB.S9S_MB_2U(SCH_1):PAGE111
   168 M_G_CPU1_SA_DQS_DP<6> @S9S_MB_2U_LIB.S9S_MB_2U(SCH_1):M_G_CPU1_SA_DQS_DP(6)   I180 @S9S_MB_2U_LIB.S9S_MB_2U(SCH_1):PAGE111
   178 M_G_CPU1_SA_DQS_DN<7> @S9S_MB_2U_LIB.S9S_MB_2U(SCH_1):M_G_CPU1_SA_DQS_DN(7)   I180 @S9S_MB_2U_LIB.S9S_MB_2U(SCH_1):PAGE111
     6    GND @S9S_MB_2U_LIB.S9S_MB_2U(SCH_1):GND   I178 @S9S_MB_2U_LIB.S9S_MB_2U(SCH_1):PAGE111
     8    GND @S9S_MB_2U_LIB.S9S_MB_2U(SCH_1):GND   I178 @S9S_MB_2U_LIB.S9S_MB_2U(SCH_1):PAGE111
    10    GND @S9S_MB_2U_LIB.S9S_MB_2U(SCH_1):GND   I178 @S9S_MB_2U_LIB.S9S_MB_2U(SCH_1):PAGE111
    13    GND @S9S_MB_2U_LIB.S9S_MB_2U(SCH_1):GND   I178 @S9S_MB_2U_LIB.S9S_MB_2U(SCH_1):PAGE111
    15    GND @S9S_MB_2U_LIB.S9S_MB_2U(SCH_1):GND   I178 @S9S_MB_2U_LIB.S9S_MB_2U(SCH_1):PAGE111
    17    GND @S9S_MB_2U_LIB.S9S_MB_2U(SCH_1):GND   I178 @S9S_MB_2U_LIB.S9S_MB_2U(SCH_1):PAGE111
    19    GND @S9S_MB_2U_LIB.S9S_MB_2U(SCH_1):GND   I178 @S9S_MB_2U_LIB.S9S_MB_2U(SCH_1):PAGE111
    21    GND @S9S_MB_2U_LIB.S9S_MB_2U(SCH_1):GND   I178 @S9S_MB_2U_LIB.S9S_MB_2U(SCH_1):PAGE111
    24    GND @S9S_MB_2U_LIB.S9S_MB_2U(SCH_1):GND   I178 @S9S_MB_2U_LIB.S9S_MB_2U(SCH_1):PAGE111
    26    GND @S9S_MB_2U_LIB.S9S_MB_2U(SCH_1):GND   I178 @S9S_MB_2U_LIB.S9S_MB_2U(SCH_1):PAGE111
    28    GND @S9S_MB_2U_LIB.S9S_MB_2U(SCH_1):GND   I178 @S9S_MB_2U_LIB.S9S_MB_2U(SCH_1):PAGE111
    30    GND @S9S_MB_2U_LIB.S9S_MB_2U(SCH_1):GND   I178 @S9S_MB_2U_LIB.S9S_MB_2U(SCH_1):PAGE111
    32    GND @S9S_MB_2U_LIB.S9S_MB_2U(SCH_1):GND   I178 @S9S_MB_2U_LIB.S9S_MB_2U(SCH_1):PAGE111
    35    GND @S9S_MB_2U_LIB.S9S_MB_2U(SCH_1):GND   I178 @S9S_MB_2U_LIB.S9S_MB_2U(SCH_1):PAGE111
    37    GND @S9S_MB_2U_LIB.S9S_MB_2U(SCH_1):GND   I178 @S9S_MB_2U_LIB.S9S_MB_2U(SCH_1):PAGE111
    39    GND @S9S_MB_2U_LIB.S9S_MB_2U(SCH_1):GND   I178 @S9S_MB_2U_LIB.S9S_MB_2U(SCH_1):PAGE111
    41    GND @S9S_MB_2U_LIB.S9S_MB_2U(SCH_1):GND   I178 @S9S_MB_2U_LIB.S9S_MB_2U(SCH_1):PAGE111
    43    GND @S9S_MB_2U_LIB.S9S_MB_2U(SCH_1):GND   I178 @S9S_MB_2U_LIB.S9S_MB_2U(SCH_1):PAGE111
    46    GND @S9S_MB_2U_LIB.S9S_MB_2U(SCH_1):GND   I178 @S9S_MB_2U_LIB.S9S_MB_2U(SCH_1):PAGE111
    48    GND @S9S_MB_2U_LIB.S9S_MB_2U(SCH_1):GND   I178 @S9S_MB_2U_LIB.S9S_MB_2U(SCH_1):PAGE111
    50    GND @S9S_MB_2U_LIB.S9S_MB_2U(SCH_1):GND   I178 @S9S_MB_2U_LIB.S9S_MB_2U(SCH_1):PAGE111
    52    GND @S9S_MB_2U_LIB.S9S_MB_2U(SCH_1):GND   I178 @S9S_MB_2U_LIB.S9S_MB_2U(SCH_1):PAGE111
    54    GND @S9S_MB_2U_LIB.S9S_MB_2U(SCH_1):GND   I178 @S9S_MB_2U_LIB.S9S_MB_2U(SCH_1):PAGE111
    57    GND @S9S_MB_2U_LIB.S9S_MB_2U(SCH_1):GND   I178 @S9S_MB_2U_LIB.S9S_MB_2U(SCH_1):PAGE111
    59    GND @S9S_MB_2U_LIB.S9S_MB_2U(SCH_1):GND   I178 @S9S_MB_2U_LIB.S9S_MB_2U(SCH_1):PAGE111
    61    GND @S9S_MB_2U_LIB.S9S_MB_2U(SCH_1):GND   I178 @S9S_MB_2U_LIB.S9S_MB_2U(SCH_1):PAGE111
    63    GND @S9S_MB_2U_LIB.S9S_MB_2U(SCH_1):GND   I178 @S9S_MB_2U_LIB.S9S_MB_2U(SCH_1):PAGE111
    65    GND @S9S_MB_2U_LIB.S9S_MB_2U(SCH_1):GND   I178 @S9S_MB_2U_LIB.S9S_MB_2U(SCH_1):PAGE111
    67    GND @S9S_MB_2U_LIB.S9S_MB_2U(SCH_1):GND   I178 @S9S_MB_2U_LIB.S9S_MB_2U(SCH_1):PAGE111
    69    GND @S9S_MB_2U_LIB.S9S_MB_2U(SCH_1):GND   I178 @S9S_MB_2U_LIB.S9S_MB_2U(SCH_1):PAGE111
    71    GND @S9S_MB_2U_LIB.S9S_MB_2U(SCH_1):GND   I178 @S9S_MB_2U_LIB.S9S_MB_2U(SCH_1):PAGE111
    73    GND @S9S_MB_2U_LIB.S9S_MB_2U(SCH_1):GND   I178 @S9S_MB_2U_LIB.S9S_MB_2U(SCH_1):PAGE111
    75    GND @S9S_MB_2U_LIB.S9S_MB_2U(SCH_1):GND   I178 @S9S_MB_2U_LIB.S9S_MB_2U(SCH_1):PAGE111
    77    GND @S9S_MB_2U_LIB.S9S_MB_2U(SCH_1):GND   I178 @S9S_MB_2U_LIB.S9S_MB_2U(SCH_1):PAGE111
    79    GND @S9S_MB_2U_LIB.S9S_MB_2U(SCH_1):GND   I178 @S9S_MB_2U_LIB.S9S_MB_2U(SCH_1):PAGE111
    81    GND @S9S_MB_2U_LIB.S9S_MB_2U(SCH_1):GND   I178 @S9S_MB_2U_LIB.S9S_MB_2U(SCH_1):PAGE111
    83    GND @S9S_MB_2U_LIB.S9S_MB_2U(SCH_1):GND   I178 @S9S_MB_2U_LIB.S9S_MB_2U(SCH_1):PAGE111
    85    GND @S9S_MB_2U_LIB.S9S_MB_2U(SCH_1):GND   I178 @S9S_MB_2U_LIB.S9S_MB_2U(SCH_1):PAGE111
    88    GND @S9S_MB_2U_LIB.S9S_MB_2U(SCH_1):GND   I178 @S9S_MB_2U_LIB.S9S_MB_2U(SCH_1):PAGE111
    90    GND @S9S_MB_2U_LIB.S9S_MB_2U(SCH_1):GND   I178 @S9S_MB_2U_LIB.S9S_MB_2U(SCH_1):PAGE111
    92    GND @S9S_MB_2U_LIB.S9S_MB_2U(SCH_1):GND   I178 @S9S_MB_2U_LIB.S9S_MB_2U(SCH_1):PAGE111
    95    GND @S9S_MB_2U_LIB.S9S_MB_2U(SCH_1):GND   I178 @S9S_MB_2U_LIB.S9S_MB_2U(SCH_1):PAGE111
    97    GND @S9S_MB_2U_LIB.S9S_MB_2U(SCH_1):GND   I178 @S9S_MB_2U_LIB.S9S_MB_2U(SCH_1):PAGE111
    99    GND @S9S_MB_2U_LIB.S9S_MB_2U(SCH_1):GND   I178 @S9S_MB_2U_LIB.S9S_MB_2U(SCH_1):PAGE111
   101    GND @S9S_MB_2U_LIB.S9S_MB_2U(SCH_1):GND   I178 @S9S_MB_2U_LIB.S9S_MB_2U(SCH_1):PAGE111
   103    GND @S9S_MB_2U_LIB.S9S_MB_2U(SCH_1):GND   I178 @S9S_MB_2U_LIB.S9S_MB_2U(SCH_1):PAGE111
   106    GND @S9S_MB_2U_LIB.S9S_MB_2U(SCH_1):GND   I178 @S9S_MB_2U_LIB.S9S_MB_2U(SCH_1):PAGE111
   108    GND @S9S_MB_2U_LIB.S9S_MB_2U(SCH_1):GND   I178 @S9S_MB_2U_LIB.S9S_MB_2U(SCH_1):PAGE111
   110    GND @S9S_MB_2U_LIB.S9S_MB_2U(SCH_1):GND   I178 @S9S_MB_2U_LIB.S9S_MB_2U(SCH_1):PAGE111
   112    GND @S9S_MB_2U_LIB.S9S_MB_2U(SCH_1):GND   I178 @S9S_MB_2U_LIB.S9S_MB_2U(SCH_1):PAGE111
   114    GND @S9S_MB_2U_LIB.S9S_MB_2U(SCH_1):GND   I178 @S9S_MB_2U_LIB.S9S_MB_2U(SCH_1):PAGE111
   117    GND @S9S_MB_2U_LIB.S9S_MB_2U(SCH_1):GND   I178 @S9S_MB_2U_LIB.S9S_MB_2U(SCH_1):PAGE111
   119    GND @S9S_MB_2U_LIB.S9S_MB_2U(SCH_1):GND   I178 @S9S_MB_2U_LIB.S9S_MB_2U(SCH_1):PAGE111
   121    GND @S9S_MB_2U_LIB.S9S_MB_2U(SCH_1):GND   I178 @S9S_MB_2U_LIB.S9S_MB_2U(SCH_1):PAGE111
   123    GND @S9S_MB_2U_LIB.S9S_MB_2U(SCH_1):GND   I178 @S9S_MB_2U_LIB.S9S_MB_2U(SCH_1):PAGE111
   125    GND @S9S_MB_2U_LIB.S9S_MB_2U(SCH_1):GND   I178 @S9S_MB_2U_LIB.S9S_MB_2U(SCH_1):PAGE111
   128    GND @S9S_MB_2U_LIB.S9S_MB_2U(SCH_1):GND   I178 @S9S_MB_2U_LIB.S9S_MB_2U(SCH_1):PAGE111
   130    GND @S9S_MB_2U_LIB.S9S_MB_2U(SCH_1):GND   I178 @S9S_MB_2U_LIB.S9S_MB_2U(SCH_1):PAGE111
   134    GND @S9S_MB_2U_LIB.S9S_MB_2U(SCH_1):GND   I178 @S9S_MB_2U_LIB.S9S_MB_2U(SCH_1):PAGE111
   143    GND @S9S_MB_2U_LIB.S9S_MB_2U(SCH_1):GND   I178 @S9S_MB_2U_LIB.S9S_MB_2U(SCH_1):PAGE111
   151    GND @S9S_MB_2U_LIB.S9S_MB_2U(SCH_1):GND   I178 @S9S_MB_2U_LIB.S9S_MB_2U(SCH_1):PAGE111
   153    GND @S9S_MB_2U_LIB.S9S_MB_2U(SCH_1):GND   I178 @S9S_MB_2U_LIB.S9S_MB_2U(SCH_1):PAGE111
   155    GND @S9S_MB_2U_LIB.S9S_MB_2U(SCH_1):GND   I178 @S9S_MB_2U_LIB.S9S_MB_2U(SCH_1):PAGE111
   158    GND @S9S_MB_2U_LIB.S9S_MB_2U(SCH_1):GND   I178 @S9S_MB_2U_LIB.S9S_MB_2U(SCH_1):PAGE111
   160    GND @S9S_MB_2U_LIB.S9S_MB_2U(SCH_1):GND   I178 @S9S_MB_2U_LIB.S9S_MB_2U(SCH_1):PAGE111
   162    GND @S9S_MB_2U_LIB.S9S_MB_2U(SCH_1):GND   I178 @S9S_MB_2U_LIB.S9S_MB_2U(SCH_1):PAGE111
   164    GND @S9S_MB_2U_LIB.S9S_MB_2U(SCH_1):GND   I178 @S9S_MB_2U_LIB.S9S_MB_2U(SCH_1):PAGE111
   166    GND @S9S_MB_2U_LIB.S9S_MB_2U(SCH_1):GND   I178 @S9S_MB_2U_LIB.S9S_MB_2U(SCH_1):PAGE111
   169    GND @S9S_MB_2U_LIB.S9S_MB_2U(SCH_1):GND   I178 @S9S_MB_2U_LIB.S9S_MB_2U(SCH_1):PAGE111
   171    GND @S9S_MB_2U_LIB.S9S_MB_2U(SCH_1):GND   I178 @S9S_MB_2U_LIB.S9S_MB_2U(SCH_1):PAGE111
   173    GND @S9S_MB_2U_LIB.S9S_MB_2U(SCH_1):GND   I178 @S9S_MB_2U_LIB.S9S_MB_2U(SCH_1):PAGE111
   175    GND @S9S_MB_2U_LIB.S9S_MB_2U(SCH_1):GND   I178 @S9S_MB_2U_LIB.S9S_MB_2U(SCH_1):PAGE111
   177    GND @S9S_MB_2U_LIB.S9S_MB_2U(SCH_1):GND   I178 @S9S_MB_2U_LIB.S9S_MB_2U(SCH_1):PAGE111
   180    GND @S9S_MB_2U_LIB.S9S_MB_2U(SCH_1):GND   I178 @S9S_MB_2U_LIB.S9S_MB_2U(SCH_1):PAGE111
   182    GND @S9S_MB_2U_LIB.S9S_MB_2U(SCH_1):GND   I178 @S9S_MB_2U_LIB.S9S_MB_2U(SCH_1):PAGE111
   184    GND @S9S_MB_2U_LIB.S9S_MB_2U(SCH_1):GND   I178 @S9S_MB_2U_LIB.S9S_MB_2U(SCH_1):PAGE111
   186    GND @S9S_MB_2U_LIB.S9S_MB_2U(SCH_1):GND   I178 @S9S_MB_2U_LIB.S9S_MB_2U(SCH_1):PAGE111
   188    GND @S9S_MB_2U_LIB.S9S_MB_2U(SCH_1):GND   I178 @S9S_MB_2U_LIB.S9S_MB_2U(SCH_1):PAGE111
   191    GND @S9S_MB_2U_LIB.S9S_MB_2U(SCH_1):GND   I178 @S9S_MB_2U_LIB.S9S_MB_2U(SCH_1):PAGE111
   193    GND @S9S_MB_2U_LIB.S9S_MB_2U(SCH_1):GND   I178 @S9S_MB_2U_LIB.S9S_MB_2U(SCH_1):PAGE111
   195    GND @S9S_MB_2U_LIB.S9S_MB_2U(SCH_1):GND   I178 @S9S_MB_2U_LIB.S9S_MB_2U(SCH_1):PAGE111
   197    GND @S9S_MB_2U_LIB.S9S_MB_2U(SCH_1):GND   I178 @S9S_MB_2U_LIB.S9S_MB_2U(SCH_1):PAGE111
   199    GND @S9S_MB_2U_LIB.S9S_MB_2U(SCH_1):GND   I178 @S9S_MB_2U_LIB.S9S_MB_2U(SCH_1):PAGE111
   202    GND @S9S_MB_2U_LIB.S9S_MB_2U(SCH_1):GND   I178 @S9S_MB_2U_LIB.S9S_MB_2U(SCH_1):PAGE111
   204    GND @S9S_MB_2U_LIB.S9S_MB_2U(SCH_1):GND   I178 @S9S_MB_2U_LIB.S9S_MB_2U(SCH_1):PAGE111
   206    GND @S9S_MB_2U_LIB.S9S_MB_2U(SCH_1):GND   I178 @S9S_MB_2U_LIB.S9S_MB_2U(SCH_1):PAGE111
   208    GND @S9S_MB_2U_LIB.S9S_MB_2U(SCH_1):GND   I178 @S9S_MB_2U_LIB.S9S_MB_2U(SCH_1):PAGE111
   210    GND @S9S_MB_2U_LIB.S9S_MB_2U(SCH_1):GND   I178 @S9S_MB_2U_LIB.S9S_MB_2U(SCH_1):PAGE111
   212    GND @S9S_MB_2U_LIB.S9S_MB_2U(SCH_1):GND   I178 @S9S_MB_2U_LIB.S9S_MB_2U(SCH_1):PAGE111
   214    GND @S9S_MB_2U_LIB.S9S_MB_2U(SCH_1):GND   I178 @S9S_MB_2U_LIB.S9S_MB_2U(SCH_1):PAGE111
   216    GND @S9S_MB_2U_LIB.S9S_MB_2U(SCH_1):GND   I178 @S9S_MB_2U_LIB.S9S_MB_2U(SCH_1):PAGE111
   219    GND @S9S_MB_2U_LIB.S9S_MB_2U(SCH_1):GND   I178 @S9S_MB_2U_LIB.S9S_MB_2U(SCH_1):PAGE111
   222    GND @S9S_MB_2U_LIB.S9S_MB_2U(SCH_1):GND   I178 @S9S_MB_2U_LIB.S9S_MB_2U(SCH_1):PAGE111
   224    GND @S9S_MB_2U_LIB.S9S_MB_2U(SCH_1):GND   I178 @S9S_MB_2U_LIB.S9S_MB_2U(SCH_1):PAGE111
   226    GND @S9S_MB_2U_LIB.S9S_MB_2U(SCH_1):GND   I178 @S9S_MB_2U_LIB.S9S_MB_2U(SCH_1):PAGE111
   228    GND @S9S_MB_2U_LIB.S9S_MB_2U(SCH_1):GND   I178 @S9S_MB_2U_LIB.S9S_MB_2U(SCH_1):PAGE111
   233    GND @S9S_MB_2U_LIB.S9S_MB_2U(SCH_1):GND   I178 @S9S_MB_2U_LIB.S9S_MB_2U(SCH_1):PAGE111
   237    GND @S9S_MB_2U_LIB.S9S_MB_2U(SCH_1):GND   I178 @S9S_MB_2U_LIB.S9S_MB_2U(SCH_1):PAGE111
   242    GND @S9S_MB_2U_LIB.S9S_MB_2U(SCH_1):GND   I178 @S9S_MB_2U_LIB.S9S_MB_2U(SCH_1):PAGE111
   244    GND @S9S_MB_2U_LIB.S9S_MB_2U(SCH_1):GND   I178 @S9S_MB_2U_LIB.S9S_MB_2U(SCH_1):PAGE111
   246    GND @S9S_MB_2U_LIB.S9S_MB_2U(SCH_1):GND   I178 @S9S_MB_2U_LIB.S9S_MB_2U(SCH_1):PAGE111
   248    GND @S9S_MB_2U_LIB.S9S_MB_2U(SCH_1):GND   I178 @S9S_MB_2U_LIB.S9S_MB_2U(SCH_1):PAGE111
   251    GND @S9S_MB_2U_LIB.S9S_MB_2U(SCH_1):GND   I178 @S9S_MB_2U_LIB.S9S_MB_2U(SCH_1):PAGE111
   253    GND @S9S_MB_2U_LIB.S9S_MB_2U(SCH_1):GND   I178 @S9S_MB_2U_LIB.S9S_MB_2U(SCH_1):PAGE111
   255    GND @S9S_MB_2U_LIB.S9S_MB_2U(SCH_1):GND   I178 @S9S_MB_2U_LIB.S9S_MB_2U(SCH_1):PAGE111
   257    GND @S9S_MB_2U_LIB.S9S_MB_2U(SCH_1):GND   I178 @S9S_MB_2U_LIB.S9S_MB_2U(SCH_1):PAGE111
   259    GND @S9S_MB_2U_LIB.S9S_MB_2U(SCH_1):GND   I178 @S9S_MB_2U_LIB.S9S_MB_2U(SCH_1):PAGE111
   262    GND @S9S_MB_2U_LIB.S9S_MB_2U(SCH_1):GND   I178 @S9S_MB_2U_LIB.S9S_MB_2U(SCH_1):PAGE111
   264    GND @S9S_MB_2U_LIB.S9S_MB_2U(SCH_1):GND   I178 @S9S_MB_2U_LIB.S9S_MB_2U(SCH_1):PAGE111
   266    GND @S9S_MB_2U_LIB.S9S_MB_2U(SCH_1):GND   I178 @S9S_MB_2U_LIB.S9S_MB_2U(SCH_1):PAGE111
   268    GND @S9S_MB_2U_LIB.S9S_MB_2U(SCH_1):GND   I178 @S9S_MB_2U_LIB.S9S_MB_2U(SCH_1):PAGE111
   270    GND @S9S_MB_2U_LIB.S9S_MB_2U(SCH_1):GND   I178 @S9S_MB_2U_LIB.S9S_MB_2U(SCH_1):PAGE111
   273    GND @S9S_MB_2U_LIB.S9S_MB_2U(SCH_1):GND   I178 @S9S_MB_2U_LIB.S9S_MB_2U(SCH_1):PAGE111
   275    GND @S9S_MB_2U_LIB.S9S_MB_2U(SCH_1):GND   I178 @S9S_MB_2U_LIB.S9S_MB_2U(SCH_1):PAGE111
   277    GND @S9S_MB_2U_LIB.S9S_MB_2U(SCH_1):GND   I178 @S9S_MB_2U_LIB.S9S_MB_2U(SCH_1):PAGE111
   279    GND @S9S_MB_2U_LIB.S9S_MB_2U(SCH_1):GND   I178 @S9S_MB_2U_LIB.S9S_MB_2U(SCH_1):PAGE111
   281    GND @S9S_MB_2U_LIB.S9S_MB_2U(SCH_1):GND   I178 @S9S_MB_2U_LIB.S9S_MB_2U(SCH_1):PAGE111
   284    GND @S9S_MB_2U_LIB.S9S_MB_2U(SCH_1):GND   I178 @S9S_MB_2U_LIB.S9S_MB_2U(SCH_1):PAGE111
   286    GND @S9S_MB_2U_LIB.S9S_MB_2U(SCH_1):GND   I178 @S9S_MB_2U_LIB.S9S_MB_2U(SCH_1):PAGE111
   288    GND @S9S_MB_2U_LIB.S9S_MB_2U(SCH_1):GND   I178 @S9S_MB_2U_LIB.S9S_MB_2U(SCH_1):PAGE111
     1 P12V_S3_AUX_CPU1_NVDIMM @S9S_MB_2U_LIB.S9S_MB_2U(SCH_1):P12V_S3_AUX_CPU1_NVDIMM   I178 @S9S_MB_2U_LIB.S9S_MB_2U(SCH_1):PAGE111
   145 P12V_S3_AUX_CPU1_NVDIMM @S9S_MB_2U_LIB.S9S_MB_2U(SCH_1):P12V_S3_AUX_CPU1_NVDIMM   I178 @S9S_MB_2U_LIB.S9S_MB_2U(SCH_1):PAGE111
   146 P12V_S3_AUX_CPU1_NVDIMM @S9S_MB_2U_LIB.S9S_MB_2U(SCH_1):P12V_S3_AUX_CPU1_NVDIMM   I178 @S9S_MB_2U_LIB.S9S_MB_2U(SCH_1):PAGE111
   230    GND @S9S_MB_2U_LIB.S9S_MB_2U(SCH_1):GND   I178 @S9S_MB_2U_LIB.S9S_MB_2U(SCH_1):PAGE111
   235    GND @S9S_MB_2U_LIB.S9S_MB_2U(SCH_1):GND   I178 @S9S_MB_2U_LIB.S9S_MB_2U(SCH_1):PAGE111
   240    GND @S9S_MB_2U_LIB.S9S_MB_2U(SCH_1):GND   I178 @S9S_MB_2U_LIB.S9S_MB_2U(SCH_1):PAGE111
   132    GND @S9S_MB_2U_LIB.S9S_MB_2U(SCH_1):GND   I178 @S9S_MB_2U_LIB.S9S_MB_2U(SCH_1):PAGE111
   136    GND @S9S_MB_2U_LIB.S9S_MB_2U(SCH_1):GND   I178 @S9S_MB_2U_LIB.S9S_MB_2U(SCH_1):PAGE111
   139    GND @S9S_MB_2U_LIB.S9S_MB_2U(SCH_1):GND   I178 @S9S_MB_2U_LIB.S9S_MB_2U(SCH_1):PAGE111
   141    GND @S9S_MB_2U_LIB.S9S_MB_2U(SCH_1):GND   I178 @S9S_MB_2U_LIB.S9S_MB_2U(SCH_1):PAGE111
    G1    GND @S9S_MB_2U_LIB.S9S_MB_2U(SCH_1):GND   I178 @S9S_MB_2U_LIB.S9S_MB_2U(SCH_1):PAGE111
    G2    GND @S9S_MB_2U_LIB.S9S_MB_2U(SCH_1):GND   I178 @S9S_MB_2U_LIB.S9S_MB_2U(SCH_1):PAGE111
    G3    GND @S9S_MB_2U_LIB.S9S_MB_2U(SCH_1):GND   I178 @S9S_MB_2U_LIB.S9S_MB_2U(SCH_1):PAGE111

 J31 SCONN288_ADR50017P130CC-SCONN2A
     3 P3V3_AUX @S9S_MB_2U_LIB.S9S_MB_2U(SCH_1):P3V3_AUX   I180 @S9S_MB_2U_LIB.S9S_MB_2U(SCH_1):PAGE112
     2 TP_CHH_CPU1_DIMM1_FRU_0 @S9S_MB_2U_LIB.S9S_MB_2U(SCH_1):TP_CHH_CPU1_DIMM1_FRU_0   I180 @S9S_MB_2U_LIB.S9S_MB_2U(SCH_1):PAGE112
   144 TP_CHH_CPU1_DIMM1_FRU_1 @S9S_MB_2U_LIB.S9S_MB_2U(SCH_1):TP_CHH_CPU1_DIMM1_FRU_1   I180 @S9S_MB_2U_LIB.S9S_MB_2U(SCH_1):PAGE112
   149 TP_CHH_CPU1_DIMM1_FRU_2 @S9S_MB_2U_LIB.S9S_MB_2U(SCH_1):TP_CHH_CPU1_DIMM1_FRU_2   I180 @S9S_MB_2U_LIB.S9S_MB_2U(SCH_1):PAGE112
   150 TP_CHH_CPU1_DIMM1_FRU_3 @S9S_MB_2U_LIB.S9S_MB_2U(SCH_1):TP_CHH_CPU1_DIMM1_FRU_3   I180 @S9S_MB_2U_LIB.S9S_MB_2U(SCH_1):PAGE112
   220 TP_CHH_CPU1_DIMM1_FRU_4 @S9S_MB_2U_LIB.S9S_MB_2U(SCH_1):TP_CHH_CPU1_DIMM1_FRU_4   I180 @S9S_MB_2U_LIB.S9S_MB_2U(SCH_1):PAGE112
   231 TP_CHH_CPU1_DIMM1_FRU_5 @S9S_MB_2U_LIB.S9S_MB_2U(SCH_1):TP_CHH_CPU1_DIMM1_FRU_5   I180 @S9S_MB_2U_LIB.S9S_MB_2U(SCH_1):PAGE112
   232 TP_CHH_CPU1_DIMM1_FRU_6 @S9S_MB_2U_LIB.S9S_MB_2U(SCH_1):TP_CHH_CPU1_DIMM1_FRU_6   I180 @S9S_MB_2U_LIB.S9S_MB_2U(SCH_1):PAGE112
   207 RST_M_GH_CPU1_FPGA_N @S9S_MB_2U_LIB.S9S_MB_2U(SCH_1):RST_M_GH_CPU1_FPGA_N   I180 @S9S_MB_2U_LIB.S9S_MB_2U(SCH_1):PAGE112
   147 PWRGD_CHH_CPU1_DIMM1 @S9S_MB_2U_LIB.S9S_MB_2U(SCH_1):PWRGD_CHH_CPU1_DIMM1   I180 @S9S_MB_2U_LIB.S9S_MB_2U(SCH_1):PAGE112
   227 M_H_CPU1_SB_PAR @S9S_MB_2U_LIB.S9S_MB_2U(SCH_1):M_H_CPU1_SB_PAR   I180 @S9S_MB_2U_LIB.S9S_MB_2U(SCH_1):PAGE112
    74 M_H_CPU1_SA_PAR @S9S_MB_2U_LIB.S9S_MB_2U(SCH_1):M_H_CPU1_SA_PAR   I180 @S9S_MB_2U_LIB.S9S_MB_2U(SCH_1):PAGE112
    87 M_H_CPU1_SB_RSP<0> @S9S_MB_2U_LIB.S9S_MB_2U(SCH_1):M_H_CPU1_SB_RSP(0)   I180 @S9S_MB_2U_LIB.S9S_MB_2U(SCH_1):PAGE112
    86 M_H_CPU1_SA_RSP<0> @S9S_MB_2U_LIB.S9S_MB_2U(SCH_1):M_H_CPU1_SA_RSP(0)   I180 @S9S_MB_2U_LIB.S9S_MB_2U(SCH_1):PAGE112
     5 I3C_SPD_DDREFGH_CPU1_LVC1_SDA @S9S_MB_2U_LIB.S9S_MB_2U(SCH_1):I3C_SPD_DDREFGH_CPU1_LVC1_SDA   I180 @S9S_MB_2U_LIB.S9S_MB_2U(SCH_1):PAGE112
     4 I3C_SPD_DDREFGH_CPU1_LVC1_SCL_6 @S9S_MB_2U_LIB.S9S_MB_2U(SCH_1):I3C_SPD_DDREFGH_CPU1_LVC1_SCL_R7   I180 @S9S_MB_2U_LIB.S9S_MB_2U(SCH_1):PAGE112
   148 PD_CHH_CPU1_DIMM1_SAA @S9S_MB_2U_LIB.S9S_MB_2U(SCH_1):PD_CHH_CPU1_DIMM1_SAA   I180 @S9S_MB_2U_LIB.S9S_MB_2U(SCH_1):PAGE112
   100 M_H_CPU1_SB_DQ<0> @S9S_MB_2U_LIB.S9S_MB_2U(SCH_1):M_H_CPU1_SB_DQ(0)   I180 @S9S_MB_2U_LIB.S9S_MB_2U(SCH_1):PAGE112
   102 M_H_CPU1_SB_DQ<1> @S9S_MB_2U_LIB.S9S_MB_2U(SCH_1):M_H_CPU1_SB_DQ(1)   I180 @S9S_MB_2U_LIB.S9S_MB_2U(SCH_1):PAGE112
   245 M_H_CPU1_SB_DQ<2> @S9S_MB_2U_LIB.S9S_MB_2U(SCH_1):M_H_CPU1_SB_DQ(2)   I180 @S9S_MB_2U_LIB.S9S_MB_2U(SCH_1):PAGE112
   247 M_H_CPU1_SB_DQ<3> @S9S_MB_2U_LIB.S9S_MB_2U(SCH_1):M_H_CPU1_SB_DQ(3)   I180 @S9S_MB_2U_LIB.S9S_MB_2U(SCH_1):PAGE112
   107 M_H_CPU1_SB_DQ<4> @S9S_MB_2U_LIB.S9S_MB_2U(SCH_1):M_H_CPU1_SB_DQ(4)   I180 @S9S_MB_2U_LIB.S9S_MB_2U(SCH_1):PAGE112
   109 M_H_CPU1_SB_DQ<5> @S9S_MB_2U_LIB.S9S_MB_2U(SCH_1):M_H_CPU1_SB_DQ(5)   I180 @S9S_MB_2U_LIB.S9S_MB_2U(SCH_1):PAGE112
   252 M_H_CPU1_SB_DQ<6> @S9S_MB_2U_LIB.S9S_MB_2U(SCH_1):M_H_CPU1_SB_DQ(6)   I180 @S9S_MB_2U_LIB.S9S_MB_2U(SCH_1):PAGE112
   254 M_H_CPU1_SB_DQ<7> @S9S_MB_2U_LIB.S9S_MB_2U(SCH_1):M_H_CPU1_SB_DQ(7)   I180 @S9S_MB_2U_LIB.S9S_MB_2U(SCH_1):PAGE112
   111 M_H_CPU1_SB_DQ<8> @S9S_MB_2U_LIB.S9S_MB_2U(SCH_1):M_H_CPU1_SB_DQ(8)   I180 @S9S_MB_2U_LIB.S9S_MB_2U(SCH_1):PAGE112
   113 M_H_CPU1_SB_DQ<9> @S9S_MB_2U_LIB.S9S_MB_2U(SCH_1):M_H_CPU1_SB_DQ(9)   I180 @S9S_MB_2U_LIB.S9S_MB_2U(SCH_1):PAGE112
   256 M_H_CPU1_SB_DQ<10> @S9S_MB_2U_LIB.S9S_MB_2U(SCH_1):M_H_CPU1_SB_DQ(10)   I180 @S9S_MB_2U_LIB.S9S_MB_2U(SCH_1):PAGE112
   258 M_H_CPU1_SB_DQ<11> @S9S_MB_2U_LIB.S9S_MB_2U(SCH_1):M_H_CPU1_SB_DQ(11)   I180 @S9S_MB_2U_LIB.S9S_MB_2U(SCH_1):PAGE112
   118 M_H_CPU1_SB_DQ<12> @S9S_MB_2U_LIB.S9S_MB_2U(SCH_1):M_H_CPU1_SB_DQ(12)   I180 @S9S_MB_2U_LIB.S9S_MB_2U(SCH_1):PAGE112
   120 M_H_CPU1_SB_DQ<13> @S9S_MB_2U_LIB.S9S_MB_2U(SCH_1):M_H_CPU1_SB_DQ(13)   I180 @S9S_MB_2U_LIB.S9S_MB_2U(SCH_1):PAGE112
   263 M_H_CPU1_SB_DQ<14> @S9S_MB_2U_LIB.S9S_MB_2U(SCH_1):M_H_CPU1_SB_DQ(14)   I180 @S9S_MB_2U_LIB.S9S_MB_2U(SCH_1):PAGE112
   265 M_H_CPU1_SB_DQ<15> @S9S_MB_2U_LIB.S9S_MB_2U(SCH_1):M_H_CPU1_SB_DQ(15)   I180 @S9S_MB_2U_LIB.S9S_MB_2U(SCH_1):PAGE112
   122 M_H_CPU1_SB_DQ<16> @S9S_MB_2U_LIB.S9S_MB_2U(SCH_1):M_H_CPU1_SB_DQ(16)   I180 @S9S_MB_2U_LIB.S9S_MB_2U(SCH_1):PAGE112
   124 M_H_CPU1_SB_DQ<17> @S9S_MB_2U_LIB.S9S_MB_2U(SCH_1):M_H_CPU1_SB_DQ(17)   I180 @S9S_MB_2U_LIB.S9S_MB_2U(SCH_1):PAGE112
   267 M_H_CPU1_SB_DQ<18> @S9S_MB_2U_LIB.S9S_MB_2U(SCH_1):M_H_CPU1_SB_DQ(18)   I180 @S9S_MB_2U_LIB.S9S_MB_2U(SCH_1):PAGE112
   269 M_H_CPU1_SB_DQ<19> @S9S_MB_2U_LIB.S9S_MB_2U(SCH_1):M_H_CPU1_SB_DQ(19)   I180 @S9S_MB_2U_LIB.S9S_MB_2U(SCH_1):PAGE112
   129 M_H_CPU1_SB_DQ<20> @S9S_MB_2U_LIB.S9S_MB_2U(SCH_1):M_H_CPU1_SB_DQ(20)   I180 @S9S_MB_2U_LIB.S9S_MB_2U(SCH_1):PAGE112
   131 M_H_CPU1_SB_DQ<21> @S9S_MB_2U_LIB.S9S_MB_2U(SCH_1):M_H_CPU1_SB_DQ(21)   I180 @S9S_MB_2U_LIB.S9S_MB_2U(SCH_1):PAGE112
   274 M_H_CPU1_SB_DQ<22> @S9S_MB_2U_LIB.S9S_MB_2U(SCH_1):M_H_CPU1_SB_DQ(22)   I180 @S9S_MB_2U_LIB.S9S_MB_2U(SCH_1):PAGE112
   276 M_H_CPU1_SB_DQ<23> @S9S_MB_2U_LIB.S9S_MB_2U(SCH_1):M_H_CPU1_SB_DQ(23)   I180 @S9S_MB_2U_LIB.S9S_MB_2U(SCH_1):PAGE112
   133 M_H_CPU1_SB_DQ<24> @S9S_MB_2U_LIB.S9S_MB_2U(SCH_1):M_H_CPU1_SB_DQ(24)   I180 @S9S_MB_2U_LIB.S9S_MB_2U(SCH_1):PAGE112
   135 M_H_CPU1_SB_DQ<25> @S9S_MB_2U_LIB.S9S_MB_2U(SCH_1):M_H_CPU1_SB_DQ(25)   I180 @S9S_MB_2U_LIB.S9S_MB_2U(SCH_1):PAGE112
   278 M_H_CPU1_SB_DQ<26> @S9S_MB_2U_LIB.S9S_MB_2U(SCH_1):M_H_CPU1_SB_DQ(26)   I180 @S9S_MB_2U_LIB.S9S_MB_2U(SCH_1):PAGE112
   280 M_H_CPU1_SB_DQ<27> @S9S_MB_2U_LIB.S9S_MB_2U(SCH_1):M_H_CPU1_SB_DQ(27)   I180 @S9S_MB_2U_LIB.S9S_MB_2U(SCH_1):PAGE112
   140 M_H_CPU1_SB_DQ<28> @S9S_MB_2U_LIB.S9S_MB_2U(SCH_1):M_H_CPU1_SB_DQ(28)   I180 @S9S_MB_2U_LIB.S9S_MB_2U(SCH_1):PAGE112
   142 M_H_CPU1_SB_DQ<29> @S9S_MB_2U_LIB.S9S_MB_2U(SCH_1):M_H_CPU1_SB_DQ(29)   I180 @S9S_MB_2U_LIB.S9S_MB_2U(SCH_1):PAGE112
   285 M_H_CPU1_SB_DQ<30> @S9S_MB_2U_LIB.S9S_MB_2U(SCH_1):M_H_CPU1_SB_DQ(30)   I180 @S9S_MB_2U_LIB.S9S_MB_2U(SCH_1):PAGE112
   287 M_H_CPU1_SB_DQ<31> @S9S_MB_2U_LIB.S9S_MB_2U(SCH_1):M_H_CPU1_SB_DQ(31)   I180 @S9S_MB_2U_LIB.S9S_MB_2U(SCH_1):PAGE112
     7 M_H_CPU1_SA_DQ<0> @S9S_MB_2U_LIB.S9S_MB_2U(SCH_1):M_H_CPU1_SA_DQ(0)   I180 @S9S_MB_2U_LIB.S9S_MB_2U(SCH_1):PAGE112
     9 M_H_CPU1_SA_DQ<1> @S9S_MB_2U_LIB.S9S_MB_2U(SCH_1):M_H_CPU1_SA_DQ(1)   I180 @S9S_MB_2U_LIB.S9S_MB_2U(SCH_1):PAGE112
   152 M_H_CPU1_SA_DQ<2> @S9S_MB_2U_LIB.S9S_MB_2U(SCH_1):M_H_CPU1_SA_DQ(2)   I180 @S9S_MB_2U_LIB.S9S_MB_2U(SCH_1):PAGE112
   154 M_H_CPU1_SA_DQ<3> @S9S_MB_2U_LIB.S9S_MB_2U(SCH_1):M_H_CPU1_SA_DQ(3)   I180 @S9S_MB_2U_LIB.S9S_MB_2U(SCH_1):PAGE112
    14 M_H_CPU1_SA_DQ<4> @S9S_MB_2U_LIB.S9S_MB_2U(SCH_1):M_H_CPU1_SA_DQ(4)   I180 @S9S_MB_2U_LIB.S9S_MB_2U(SCH_1):PAGE112
    16 M_H_CPU1_SA_DQ<5> @S9S_MB_2U_LIB.S9S_MB_2U(SCH_1):M_H_CPU1_SA_DQ(5)   I180 @S9S_MB_2U_LIB.S9S_MB_2U(SCH_1):PAGE112
   159 M_H_CPU1_SA_DQ<6> @S9S_MB_2U_LIB.S9S_MB_2U(SCH_1):M_H_CPU1_SA_DQ(6)   I180 @S9S_MB_2U_LIB.S9S_MB_2U(SCH_1):PAGE112
   161 M_H_CPU1_SA_DQ<7> @S9S_MB_2U_LIB.S9S_MB_2U(SCH_1):M_H_CPU1_SA_DQ(7)   I180 @S9S_MB_2U_LIB.S9S_MB_2U(SCH_1):PAGE112
    18 M_H_CPU1_SA_DQ<8> @S9S_MB_2U_LIB.S9S_MB_2U(SCH_1):M_H_CPU1_SA_DQ(8)   I180 @S9S_MB_2U_LIB.S9S_MB_2U(SCH_1):PAGE112
    20 M_H_CPU1_SA_DQ<9> @S9S_MB_2U_LIB.S9S_MB_2U(SCH_1):M_H_CPU1_SA_DQ(9)   I180 @S9S_MB_2U_LIB.S9S_MB_2U(SCH_1):PAGE112
   163 M_H_CPU1_SA_DQ<10> @S9S_MB_2U_LIB.S9S_MB_2U(SCH_1):M_H_CPU1_SA_DQ(10)   I180 @S9S_MB_2U_LIB.S9S_MB_2U(SCH_1):PAGE112
   165 M_H_CPU1_SA_DQ<11> @S9S_MB_2U_LIB.S9S_MB_2U(SCH_1):M_H_CPU1_SA_DQ(11)   I180 @S9S_MB_2U_LIB.S9S_MB_2U(SCH_1):PAGE112
    25 M_H_CPU1_SA_DQ<12> @S9S_MB_2U_LIB.S9S_MB_2U(SCH_1):M_H_CPU1_SA_DQ(12)   I180 @S9S_MB_2U_LIB.S9S_MB_2U(SCH_1):PAGE112
    27 M_H_CPU1_SA_DQ<13> @S9S_MB_2U_LIB.S9S_MB_2U(SCH_1):M_H_CPU1_SA_DQ(13)   I180 @S9S_MB_2U_LIB.S9S_MB_2U(SCH_1):PAGE112
   170 M_H_CPU1_SA_DQ<14> @S9S_MB_2U_LIB.S9S_MB_2U(SCH_1):M_H_CPU1_SA_DQ(14)   I180 @S9S_MB_2U_LIB.S9S_MB_2U(SCH_1):PAGE112
   172 M_H_CPU1_SA_DQ<15> @S9S_MB_2U_LIB.S9S_MB_2U(SCH_1):M_H_CPU1_SA_DQ(15)   I180 @S9S_MB_2U_LIB.S9S_MB_2U(SCH_1):PAGE112
    29 M_H_CPU1_SA_DQ<16> @S9S_MB_2U_LIB.S9S_MB_2U(SCH_1):M_H_CPU1_SA_DQ(16)   I180 @S9S_MB_2U_LIB.S9S_MB_2U(SCH_1):PAGE112
    31 M_H_CPU1_SA_DQ<17> @S9S_MB_2U_LIB.S9S_MB_2U(SCH_1):M_H_CPU1_SA_DQ(17)   I180 @S9S_MB_2U_LIB.S9S_MB_2U(SCH_1):PAGE112
   174 M_H_CPU1_SA_DQ<18> @S9S_MB_2U_LIB.S9S_MB_2U(SCH_1):M_H_CPU1_SA_DQ(18)   I180 @S9S_MB_2U_LIB.S9S_MB_2U(SCH_1):PAGE112
   176 M_H_CPU1_SA_DQ<19> @S9S_MB_2U_LIB.S9S_MB_2U(SCH_1):M_H_CPU1_SA_DQ(19)   I180 @S9S_MB_2U_LIB.S9S_MB_2U(SCH_1):PAGE112
    36 M_H_CPU1_SA_DQ<20> @S9S_MB_2U_LIB.S9S_MB_2U(SCH_1):M_H_CPU1_SA_DQ(20)   I180 @S9S_MB_2U_LIB.S9S_MB_2U(SCH_1):PAGE112
    38 M_H_CPU1_SA_DQ<21> @S9S_MB_2U_LIB.S9S_MB_2U(SCH_1):M_H_CPU1_SA_DQ(21)   I180 @S9S_MB_2U_LIB.S9S_MB_2U(SCH_1):PAGE112
   181 M_H_CPU1_SA_DQ<22> @S9S_MB_2U_LIB.S9S_MB_2U(SCH_1):M_H_CPU1_SA_DQ(22)   I180 @S9S_MB_2U_LIB.S9S_MB_2U(SCH_1):PAGE112
   183 M_H_CPU1_SA_DQ<23> @S9S_MB_2U_LIB.S9S_MB_2U(SCH_1):M_H_CPU1_SA_DQ(23)   I180 @S9S_MB_2U_LIB.S9S_MB_2U(SCH_1):PAGE112
    40 M_H_CPU1_SA_DQ<24> @S9S_MB_2U_LIB.S9S_MB_2U(SCH_1):M_H_CPU1_SA_DQ(24)   I180 @S9S_MB_2U_LIB.S9S_MB_2U(SCH_1):PAGE112
    42 M_H_CPU1_SA_DQ<25> @S9S_MB_2U_LIB.S9S_MB_2U(SCH_1):M_H_CPU1_SA_DQ(25)   I180 @S9S_MB_2U_LIB.S9S_MB_2U(SCH_1):PAGE112
   185 M_H_CPU1_SA_DQ<26> @S9S_MB_2U_LIB.S9S_MB_2U(SCH_1):M_H_CPU1_SA_DQ(26)   I180 @S9S_MB_2U_LIB.S9S_MB_2U(SCH_1):PAGE112
   187 M_H_CPU1_SA_DQ<27> @S9S_MB_2U_LIB.S9S_MB_2U(SCH_1):M_H_CPU1_SA_DQ(27)   I180 @S9S_MB_2U_LIB.S9S_MB_2U(SCH_1):PAGE112
    47 M_H_CPU1_SA_DQ<28> @S9S_MB_2U_LIB.S9S_MB_2U(SCH_1):M_H_CPU1_SA_DQ(28)   I180 @S9S_MB_2U_LIB.S9S_MB_2U(SCH_1):PAGE112
    49 M_H_CPU1_SA_DQ<29> @S9S_MB_2U_LIB.S9S_MB_2U(SCH_1):M_H_CPU1_SA_DQ(29)   I180 @S9S_MB_2U_LIB.S9S_MB_2U(SCH_1):PAGE112
   192 M_H_CPU1_SA_DQ<30> @S9S_MB_2U_LIB.S9S_MB_2U(SCH_1):M_H_CPU1_SA_DQ(30)   I180 @S9S_MB_2U_LIB.S9S_MB_2U(SCH_1):PAGE112
   229 M_H_CPU1_SB_CS_N<1> @S9S_MB_2U_LIB.S9S_MB_2U(SCH_1):M_H_CPU1_SB_CS_N(1)   I180 @S9S_MB_2U_LIB.S9S_MB_2U(SCH_1):PAGE112
   209 M_H_CPU1_SA_CS_N<1> @S9S_MB_2U_LIB.S9S_MB_2U(SCH_1):M_H_CPU1_SA_CS_N(1)   I180 @S9S_MB_2U_LIB.S9S_MB_2U(SCH_1):PAGE112
    84 M_H_CPU1_SB_CS_N<0> @S9S_MB_2U_LIB.S9S_MB_2U(SCH_1):M_H_CPU1_SB_CS_N(0)   I180 @S9S_MB_2U_LIB.S9S_MB_2U(SCH_1):PAGE112
    64 M_H_CPU1_SA_CS_N<0> @S9S_MB_2U_LIB.S9S_MB_2U(SCH_1):M_H_CPU1_SA_CS_N(0)   I180 @S9S_MB_2U_LIB.S9S_MB_2U(SCH_1):PAGE112
   217 M_H_CPU1_CLK_DP<0> @S9S_MB_2U_LIB.S9S_MB_2U(SCH_1):M_H_CPU1_CLK_DP(0)   I180 @S9S_MB_2U_LIB.S9S_MB_2U(SCH_1):PAGE112
   218 M_H_CPU1_CLK_DN<0> @S9S_MB_2U_LIB.S9S_MB_2U(SCH_1):M_H_CPU1_CLK_DN(0)   I180 @S9S_MB_2U_LIB.S9S_MB_2U(SCH_1):PAGE112
    96 M_H_CPU1_SB_CB<0> @S9S_MB_2U_LIB.S9S_MB_2U(SCH_1):M_H_CPU1_SB_CB(0)   I180 @S9S_MB_2U_LIB.S9S_MB_2U(SCH_1):PAGE112
    98 M_H_CPU1_SB_CB<1> @S9S_MB_2U_LIB.S9S_MB_2U(SCH_1):M_H_CPU1_SB_CB(1)   I180 @S9S_MB_2U_LIB.S9S_MB_2U(SCH_1):PAGE112
   241 M_H_CPU1_SB_CB<2> @S9S_MB_2U_LIB.S9S_MB_2U(SCH_1):M_H_CPU1_SB_CB(2)   I180 @S9S_MB_2U_LIB.S9S_MB_2U(SCH_1):PAGE112
   243 M_H_CPU1_SB_CB<3> @S9S_MB_2U_LIB.S9S_MB_2U(SCH_1):M_H_CPU1_SB_CB(3)   I180 @S9S_MB_2U_LIB.S9S_MB_2U(SCH_1):PAGE112
    89 M_H_CPU1_SB_CB<4> @S9S_MB_2U_LIB.S9S_MB_2U(SCH_1):M_H_CPU1_SB_CB(4)   I180 @S9S_MB_2U_LIB.S9S_MB_2U(SCH_1):PAGE112
    91 M_H_CPU1_SB_CB<5> @S9S_MB_2U_LIB.S9S_MB_2U(SCH_1):M_H_CPU1_SB_CB(5)   I180 @S9S_MB_2U_LIB.S9S_MB_2U(SCH_1):PAGE112
   234 M_H_CPU1_SB_CB<6> @S9S_MB_2U_LIB.S9S_MB_2U(SCH_1):M_H_CPU1_SB_CB(6)   I180 @S9S_MB_2U_LIB.S9S_MB_2U(SCH_1):PAGE112
    51 M_H_CPU1_SA_CB<0> @S9S_MB_2U_LIB.S9S_MB_2U(SCH_1):M_H_CPU1_SA_CB(0)   I180 @S9S_MB_2U_LIB.S9S_MB_2U(SCH_1):PAGE112
   196 M_H_CPU1_SA_CB<2> @S9S_MB_2U_LIB.S9S_MB_2U(SCH_1):M_H_CPU1_SA_CB(2)   I180 @S9S_MB_2U_LIB.S9S_MB_2U(SCH_1):PAGE112
   198 M_H_CPU1_SA_CB<3> @S9S_MB_2U_LIB.S9S_MB_2U(SCH_1):M_H_CPU1_SA_CB(3)   I180 @S9S_MB_2U_LIB.S9S_MB_2U(SCH_1):PAGE112
    60 M_H_CPU1_SA_CB<5> @S9S_MB_2U_LIB.S9S_MB_2U(SCH_1):M_H_CPU1_SA_CB(5)   I180 @S9S_MB_2U_LIB.S9S_MB_2U(SCH_1):PAGE112
   203 M_H_CPU1_SA_CB<6> @S9S_MB_2U_LIB.S9S_MB_2U(SCH_1):M_H_CPU1_SA_CB(6)   I180 @S9S_MB_2U_LIB.S9S_MB_2U(SCH_1):PAGE112
    82 M_H_CPU1_SB_CA<6> @S9S_MB_2U_LIB.S9S_MB_2U(SCH_1):M_H_CPU1_SB_CA(6)   I180 @S9S_MB_2U_LIB.S9S_MB_2U(SCH_1):PAGE112
    72 M_H_CPU1_SA_CA<6> @S9S_MB_2U_LIB.S9S_MB_2U(SCH_1):M_H_CPU1_SA_CA(6)   I180 @S9S_MB_2U_LIB.S9S_MB_2U(SCH_1):PAGE112
   225 M_H_CPU1_SB_CA<5> @S9S_MB_2U_LIB.S9S_MB_2U(SCH_1):M_H_CPU1_SB_CA(5)   I180 @S9S_MB_2U_LIB.S9S_MB_2U(SCH_1):PAGE112
   215 M_H_CPU1_SA_CA<5> @S9S_MB_2U_LIB.S9S_MB_2U(SCH_1):M_H_CPU1_SA_CA(5)   I180 @S9S_MB_2U_LIB.S9S_MB_2U(SCH_1):PAGE112
    80 M_H_CPU1_SB_CA<4> @S9S_MB_2U_LIB.S9S_MB_2U(SCH_1):M_H_CPU1_SB_CA(4)   I180 @S9S_MB_2U_LIB.S9S_MB_2U(SCH_1):PAGE112
    70 M_H_CPU1_SA_CA<4> @S9S_MB_2U_LIB.S9S_MB_2U(SCH_1):M_H_CPU1_SA_CA(4)   I180 @S9S_MB_2U_LIB.S9S_MB_2U(SCH_1):PAGE112
   223 M_H_CPU1_SB_CA<3> @S9S_MB_2U_LIB.S9S_MB_2U(SCH_1):M_H_CPU1_SB_CA(3)   I180 @S9S_MB_2U_LIB.S9S_MB_2U(SCH_1):PAGE112
   213 M_H_CPU1_SA_CA<3> @S9S_MB_2U_LIB.S9S_MB_2U(SCH_1):M_H_CPU1_SA_CA(3)   I180 @S9S_MB_2U_LIB.S9S_MB_2U(SCH_1):PAGE112
    78 M_H_CPU1_SB_CA<2> @S9S_MB_2U_LIB.S9S_MB_2U(SCH_1):M_H_CPU1_SB_CA(2)   I180 @S9S_MB_2U_LIB.S9S_MB_2U(SCH_1):PAGE112
    68 M_H_CPU1_SA_CA<2> @S9S_MB_2U_LIB.S9S_MB_2U(SCH_1):M_H_CPU1_SA_CA(2)   I180 @S9S_MB_2U_LIB.S9S_MB_2U(SCH_1):PAGE112
   221 M_H_CPU1_SB_CA<1> @S9S_MB_2U_LIB.S9S_MB_2U(SCH_1):M_H_CPU1_SB_CA(1)   I180 @S9S_MB_2U_LIB.S9S_MB_2U(SCH_1):PAGE112
   211 M_H_CPU1_SA_CA<1> @S9S_MB_2U_LIB.S9S_MB_2U(SCH_1):M_H_CPU1_SA_CA(1)   I180 @S9S_MB_2U_LIB.S9S_MB_2U(SCH_1):PAGE112
    76 M_H_CPU1_SB_CA<0> @S9S_MB_2U_LIB.S9S_MB_2U(SCH_1):M_H_CPU1_SB_CA(0)   I180 @S9S_MB_2U_LIB.S9S_MB_2U(SCH_1):PAGE112
    66 M_H_CPU1_SA_CA<0> @S9S_MB_2U_LIB.S9S_MB_2U(SCH_1):M_H_CPU1_SA_CA(0)   I180 @S9S_MB_2U_LIB.S9S_MB_2U(SCH_1):PAGE112
    62 M_H_CPU1_ALERT_N @S9S_MB_2U_LIB.S9S_MB_2U(SCH_1):M_H_CPU1_ALERT_N   I180 @S9S_MB_2U_LIB.S9S_MB_2U(SCH_1):PAGE112
   236 M_H_CPU1_SB_CB<7> @S9S_MB_2U_LIB.S9S_MB_2U(SCH_1):M_H_CPU1_SB_CB(7)   I180 @S9S_MB_2U_LIB.S9S_MB_2U(SCH_1):PAGE112
    53 M_H_CPU1_SA_CB<1> @S9S_MB_2U_LIB.S9S_MB_2U(SCH_1):M_H_CPU1_SA_CB(1)   I180 @S9S_MB_2U_LIB.S9S_MB_2U(SCH_1):PAGE112
    58 M_H_CPU1_SA_CB<4> @S9S_MB_2U_LIB.S9S_MB_2U(SCH_1):M_H_CPU1_SA_CB(4)   I180 @S9S_MB_2U_LIB.S9S_MB_2U(SCH_1):PAGE112
   205 M_H_CPU1_SA_CB<7> @S9S_MB_2U_LIB.S9S_MB_2U(SCH_1):M_H_CPU1_SA_CB(7)   I180 @S9S_MB_2U_LIB.S9S_MB_2U(SCH_1):PAGE112
   194 M_H_CPU1_SA_DQ<31> @S9S_MB_2U_LIB.S9S_MB_2U(SCH_1):M_H_CPU1_SA_DQ(31)   I180 @S9S_MB_2U_LIB.S9S_MB_2U(SCH_1):PAGE112
    93 M_H_CPU1_SB_DQS_DP<9> @S9S_MB_2U_LIB.S9S_MB_2U(SCH_1):M_H_CPU1_SB_DQS_DP(9)   I181 @S9S_MB_2U_LIB.S9S_MB_2U(SCH_1):PAGE112
    94 M_H_CPU1_SB_DQS_DN<9> @S9S_MB_2U_LIB.S9S_MB_2U(SCH_1):M_H_CPU1_SB_DQS_DN(9)   I181 @S9S_MB_2U_LIB.S9S_MB_2U(SCH_1):PAGE112
   201 M_H_CPU1_SA_DQS_DP<9> @S9S_MB_2U_LIB.S9S_MB_2U(SCH_1):M_H_CPU1_SA_DQS_DP(9)   I181 @S9S_MB_2U_LIB.S9S_MB_2U(SCH_1):PAGE112
   200 M_H_CPU1_SA_DQS_DN<9> @S9S_MB_2U_LIB.S9S_MB_2U(SCH_1):M_H_CPU1_SA_DQS_DN(9)   I181 @S9S_MB_2U_LIB.S9S_MB_2U(SCH_1):PAGE112
   190 M_H_CPU1_SA_DQS_DP<8> @S9S_MB_2U_LIB.S9S_MB_2U(SCH_1):M_H_CPU1_SA_DQS_DP(8)   I181 @S9S_MB_2U_LIB.S9S_MB_2U(SCH_1):PAGE112
   189 M_H_CPU1_SA_DQS_DN<8> @S9S_MB_2U_LIB.S9S_MB_2U(SCH_1):M_H_CPU1_SA_DQS_DN(8)   I181 @S9S_MB_2U_LIB.S9S_MB_2U(SCH_1):PAGE112
   271 M_H_CPU1_SB_DQS_DN<7> @S9S_MB_2U_LIB.S9S_MB_2U(SCH_1):M_H_CPU1_SB_DQS_DN(7)   I181 @S9S_MB_2U_LIB.S9S_MB_2U(SCH_1):PAGE112
   179 M_H_CPU1_SA_DQS_DP<7> @S9S_MB_2U_LIB.S9S_MB_2U(SCH_1):M_H_CPU1_SA_DQS_DP(7)   I181 @S9S_MB_2U_LIB.S9S_MB_2U(SCH_1):PAGE112
   261 M_H_CPU1_SB_DQS_DP<6> @S9S_MB_2U_LIB.S9S_MB_2U(SCH_1):M_H_CPU1_SB_DQS_DP(6)   I181 @S9S_MB_2U_LIB.S9S_MB_2U(SCH_1):PAGE112
   260 M_H_CPU1_SB_DQS_DN<6> @S9S_MB_2U_LIB.S9S_MB_2U(SCH_1):M_H_CPU1_SB_DQS_DN(6)   I181 @S9S_MB_2U_LIB.S9S_MB_2U(SCH_1):PAGE112
   167 M_H_CPU1_SA_DQS_DN<6> @S9S_MB_2U_LIB.S9S_MB_2U(SCH_1):M_H_CPU1_SA_DQS_DN(6)   I181 @S9S_MB_2U_LIB.S9S_MB_2U(SCH_1):PAGE112
   250 M_H_CPU1_SB_DQS_DP<5> @S9S_MB_2U_LIB.S9S_MB_2U(SCH_1):M_H_CPU1_SB_DQS_DP(5)   I181 @S9S_MB_2U_LIB.S9S_MB_2U(SCH_1):PAGE112
   249 M_H_CPU1_SB_DQS_DN<5> @S9S_MB_2U_LIB.S9S_MB_2U(SCH_1):M_H_CPU1_SB_DQS_DN(5)   I181 @S9S_MB_2U_LIB.S9S_MB_2U(SCH_1):PAGE112
   157 M_H_CPU1_SA_DQS_DP<5> @S9S_MB_2U_LIB.S9S_MB_2U(SCH_1):M_H_CPU1_SA_DQS_DP(5)   I181 @S9S_MB_2U_LIB.S9S_MB_2U(SCH_1):PAGE112
   156 M_H_CPU1_SA_DQS_DN<5> @S9S_MB_2U_LIB.S9S_MB_2U(SCH_1):M_H_CPU1_SA_DQS_DN(5)   I181 @S9S_MB_2U_LIB.S9S_MB_2U(SCH_1):PAGE112
   239 M_H_CPU1_SB_DQS_DP<4> @S9S_MB_2U_LIB.S9S_MB_2U(SCH_1):M_H_CPU1_SB_DQS_DP(4)   I181 @S9S_MB_2U_LIB.S9S_MB_2U(SCH_1):PAGE112
   238 M_H_CPU1_SB_DQS_DN<4> @S9S_MB_2U_LIB.S9S_MB_2U(SCH_1):M_H_CPU1_SB_DQS_DN(4)   I181 @S9S_MB_2U_LIB.S9S_MB_2U(SCH_1):PAGE112
    55 M_H_CPU1_SA_DQS_DP<4> @S9S_MB_2U_LIB.S9S_MB_2U(SCH_1):M_H_CPU1_SA_DQS_DP(4)   I181 @S9S_MB_2U_LIB.S9S_MB_2U(SCH_1):PAGE112
    56 M_H_CPU1_SA_DQS_DN<4> @S9S_MB_2U_LIB.S9S_MB_2U(SCH_1):M_H_CPU1_SA_DQS_DN(4)   I181 @S9S_MB_2U_LIB.S9S_MB_2U(SCH_1):PAGE112
   137 M_H_CPU1_SB_DQS_DP<3> @S9S_MB_2U_LIB.S9S_MB_2U(SCH_1):M_H_CPU1_SB_DQS_DP(3)   I181 @S9S_MB_2U_LIB.S9S_MB_2U(SCH_1):PAGE112
   138 M_H_CPU1_SB_DQS_DN<3> @S9S_MB_2U_LIB.S9S_MB_2U(SCH_1):M_H_CPU1_SB_DQS_DN(3)   I181 @S9S_MB_2U_LIB.S9S_MB_2U(SCH_1):PAGE112
    44 M_H_CPU1_SA_DQS_DP<3> @S9S_MB_2U_LIB.S9S_MB_2U(SCH_1):M_H_CPU1_SA_DQS_DP(3)   I181 @S9S_MB_2U_LIB.S9S_MB_2U(SCH_1):PAGE112
    45 M_H_CPU1_SA_DQS_DN<3> @S9S_MB_2U_LIB.S9S_MB_2U(SCH_1):M_H_CPU1_SA_DQS_DN(3)   I181 @S9S_MB_2U_LIB.S9S_MB_2U(SCH_1):PAGE112
   126 M_H_CPU1_SB_DQS_DP<2> @S9S_MB_2U_LIB.S9S_MB_2U(SCH_1):M_H_CPU1_SB_DQS_DP(2)   I181 @S9S_MB_2U_LIB.S9S_MB_2U(SCH_1):PAGE112
   127 M_H_CPU1_SB_DQS_DN<2> @S9S_MB_2U_LIB.S9S_MB_2U(SCH_1):M_H_CPU1_SB_DQS_DN(2)   I181 @S9S_MB_2U_LIB.S9S_MB_2U(SCH_1):PAGE112
    33 M_H_CPU1_SA_DQS_DP<2> @S9S_MB_2U_LIB.S9S_MB_2U(SCH_1):M_H_CPU1_SA_DQS_DP(2)   I181 @S9S_MB_2U_LIB.S9S_MB_2U(SCH_1):PAGE112
    34 M_H_CPU1_SA_DQS_DN<2> @S9S_MB_2U_LIB.S9S_MB_2U(SCH_1):M_H_CPU1_SA_DQS_DN(2)   I181 @S9S_MB_2U_LIB.S9S_MB_2U(SCH_1):PAGE112
   115 M_H_CPU1_SB_DQS_DP<1> @S9S_MB_2U_LIB.S9S_MB_2U(SCH_1):M_H_CPU1_SB_DQS_DP(1)   I181 @S9S_MB_2U_LIB.S9S_MB_2U(SCH_1):PAGE112
   116 M_H_CPU1_SB_DQS_DN<1> @S9S_MB_2U_LIB.S9S_MB_2U(SCH_1):M_H_CPU1_SB_DQS_DN(1)   I181 @S9S_MB_2U_LIB.S9S_MB_2U(SCH_1):PAGE112
    22 M_H_CPU1_SA_DQS_DP<1> @S9S_MB_2U_LIB.S9S_MB_2U(SCH_1):M_H_CPU1_SA_DQS_DP(1)   I181 @S9S_MB_2U_LIB.S9S_MB_2U(SCH_1):PAGE112
    23 M_H_CPU1_SA_DQS_DN<1> @S9S_MB_2U_LIB.S9S_MB_2U(SCH_1):M_H_CPU1_SA_DQS_DN(1)   I181 @S9S_MB_2U_LIB.S9S_MB_2U(SCH_1):PAGE112
   104 M_H_CPU1_SB_DQS_DP<0> @S9S_MB_2U_LIB.S9S_MB_2U(SCH_1):M_H_CPU1_SB_DQS_DP(0)   I181 @S9S_MB_2U_LIB.S9S_MB_2U(SCH_1):PAGE112
   105 M_H_CPU1_SB_DQS_DN<0> @S9S_MB_2U_LIB.S9S_MB_2U(SCH_1):M_H_CPU1_SB_DQS_DN(0)   I181 @S9S_MB_2U_LIB.S9S_MB_2U(SCH_1):PAGE112
    11 M_H_CPU1_SA_DQS_DP<0> @S9S_MB_2U_LIB.S9S_MB_2U(SCH_1):M_H_CPU1_SA_DQS_DP(0)   I181 @S9S_MB_2U_LIB.S9S_MB_2U(SCH_1):PAGE112
    12 M_H_CPU1_SA_DQS_DN<0> @S9S_MB_2U_LIB.S9S_MB_2U(SCH_1):M_H_CPU1_SA_DQS_DN(0)   I181 @S9S_MB_2U_LIB.S9S_MB_2U(SCH_1):PAGE112
   272 M_H_CPU1_SB_DQS_DP<7> @S9S_MB_2U_LIB.S9S_MB_2U(SCH_1):M_H_CPU1_SB_DQS_DP(7)   I181 @S9S_MB_2U_LIB.S9S_MB_2U(SCH_1):PAGE112
   282 M_H_CPU1_SB_DQS_DN<8> @S9S_MB_2U_LIB.S9S_MB_2U(SCH_1):M_H_CPU1_SB_DQS_DN(8)   I181 @S9S_MB_2U_LIB.S9S_MB_2U(SCH_1):PAGE112
   283 M_H_CPU1_SB_DQS_DP<8> @S9S_MB_2U_LIB.S9S_MB_2U(SCH_1):M_H_CPU1_SB_DQS_DP(8)   I181 @S9S_MB_2U_LIB.S9S_MB_2U(SCH_1):PAGE112
   168 M_H_CPU1_SA_DQS_DP<6> @S9S_MB_2U_LIB.S9S_MB_2U(SCH_1):M_H_CPU1_SA_DQS_DP(6)   I181 @S9S_MB_2U_LIB.S9S_MB_2U(SCH_1):PAGE112
   178 M_H_CPU1_SA_DQS_DN<7> @S9S_MB_2U_LIB.S9S_MB_2U(SCH_1):M_H_CPU1_SA_DQS_DN(7)   I181 @S9S_MB_2U_LIB.S9S_MB_2U(SCH_1):PAGE112
     6    GND @S9S_MB_2U_LIB.S9S_MB_2U(SCH_1):GND   I178 @S9S_MB_2U_LIB.S9S_MB_2U(SCH_1):PAGE112
     8    GND @S9S_MB_2U_LIB.S9S_MB_2U(SCH_1):GND   I178 @S9S_MB_2U_LIB.S9S_MB_2U(SCH_1):PAGE112
    10    GND @S9S_MB_2U_LIB.S9S_MB_2U(SCH_1):GND   I178 @S9S_MB_2U_LIB.S9S_MB_2U(SCH_1):PAGE112
    13    GND @S9S_MB_2U_LIB.S9S_MB_2U(SCH_1):GND   I178 @S9S_MB_2U_LIB.S9S_MB_2U(SCH_1):PAGE112
    15    GND @S9S_MB_2U_LIB.S9S_MB_2U(SCH_1):GND   I178 @S9S_MB_2U_LIB.S9S_MB_2U(SCH_1):PAGE112
    17    GND @S9S_MB_2U_LIB.S9S_MB_2U(SCH_1):GND   I178 @S9S_MB_2U_LIB.S9S_MB_2U(SCH_1):PAGE112
    19    GND @S9S_MB_2U_LIB.S9S_MB_2U(SCH_1):GND   I178 @S9S_MB_2U_LIB.S9S_MB_2U(SCH_1):PAGE112
    21    GND @S9S_MB_2U_LIB.S9S_MB_2U(SCH_1):GND   I178 @S9S_MB_2U_LIB.S9S_MB_2U(SCH_1):PAGE112
    24    GND @S9S_MB_2U_LIB.S9S_MB_2U(SCH_1):GND   I178 @S9S_MB_2U_LIB.S9S_MB_2U(SCH_1):PAGE112
    26    GND @S9S_MB_2U_LIB.S9S_MB_2U(SCH_1):GND   I178 @S9S_MB_2U_LIB.S9S_MB_2U(SCH_1):PAGE112
    28    GND @S9S_MB_2U_LIB.S9S_MB_2U(SCH_1):GND   I178 @S9S_MB_2U_LIB.S9S_MB_2U(SCH_1):PAGE112
    30    GND @S9S_MB_2U_LIB.S9S_MB_2U(SCH_1):GND   I178 @S9S_MB_2U_LIB.S9S_MB_2U(SCH_1):PAGE112
    32    GND @S9S_MB_2U_LIB.S9S_MB_2U(SCH_1):GND   I178 @S9S_MB_2U_LIB.S9S_MB_2U(SCH_1):PAGE112
    35    GND @S9S_MB_2U_LIB.S9S_MB_2U(SCH_1):GND   I178 @S9S_MB_2U_LIB.S9S_MB_2U(SCH_1):PAGE112
    37    GND @S9S_MB_2U_LIB.S9S_MB_2U(SCH_1):GND   I178 @S9S_MB_2U_LIB.S9S_MB_2U(SCH_1):PAGE112
    39    GND @S9S_MB_2U_LIB.S9S_MB_2U(SCH_1):GND   I178 @S9S_MB_2U_LIB.S9S_MB_2U(SCH_1):PAGE112
    41    GND @S9S_MB_2U_LIB.S9S_MB_2U(SCH_1):GND   I178 @S9S_MB_2U_LIB.S9S_MB_2U(SCH_1):PAGE112
    43    GND @S9S_MB_2U_LIB.S9S_MB_2U(SCH_1):GND   I178 @S9S_MB_2U_LIB.S9S_MB_2U(SCH_1):PAGE112
    46    GND @S9S_MB_2U_LIB.S9S_MB_2U(SCH_1):GND   I178 @S9S_MB_2U_LIB.S9S_MB_2U(SCH_1):PAGE112
    48    GND @S9S_MB_2U_LIB.S9S_MB_2U(SCH_1):GND   I178 @S9S_MB_2U_LIB.S9S_MB_2U(SCH_1):PAGE112
    50    GND @S9S_MB_2U_LIB.S9S_MB_2U(SCH_1):GND   I178 @S9S_MB_2U_LIB.S9S_MB_2U(SCH_1):PAGE112
    52    GND @S9S_MB_2U_LIB.S9S_MB_2U(SCH_1):GND   I178 @S9S_MB_2U_LIB.S9S_MB_2U(SCH_1):PAGE112
    54    GND @S9S_MB_2U_LIB.S9S_MB_2U(SCH_1):GND   I178 @S9S_MB_2U_LIB.S9S_MB_2U(SCH_1):PAGE112
    57    GND @S9S_MB_2U_LIB.S9S_MB_2U(SCH_1):GND   I178 @S9S_MB_2U_LIB.S9S_MB_2U(SCH_1):PAGE112
    59    GND @S9S_MB_2U_LIB.S9S_MB_2U(SCH_1):GND   I178 @S9S_MB_2U_LIB.S9S_MB_2U(SCH_1):PAGE112
    61    GND @S9S_MB_2U_LIB.S9S_MB_2U(SCH_1):GND   I178 @S9S_MB_2U_LIB.S9S_MB_2U(SCH_1):PAGE112
    63    GND @S9S_MB_2U_LIB.S9S_MB_2U(SCH_1):GND   I178 @S9S_MB_2U_LIB.S9S_MB_2U(SCH_1):PAGE112
    65    GND @S9S_MB_2U_LIB.S9S_MB_2U(SCH_1):GND   I178 @S9S_MB_2U_LIB.S9S_MB_2U(SCH_1):PAGE112
    67    GND @S9S_MB_2U_LIB.S9S_MB_2U(SCH_1):GND   I178 @S9S_MB_2U_LIB.S9S_MB_2U(SCH_1):PAGE112
    69    GND @S9S_MB_2U_LIB.S9S_MB_2U(SCH_1):GND   I178 @S9S_MB_2U_LIB.S9S_MB_2U(SCH_1):PAGE112
    71    GND @S9S_MB_2U_LIB.S9S_MB_2U(SCH_1):GND   I178 @S9S_MB_2U_LIB.S9S_MB_2U(SCH_1):PAGE112
    73    GND @S9S_MB_2U_LIB.S9S_MB_2U(SCH_1):GND   I178 @S9S_MB_2U_LIB.S9S_MB_2U(SCH_1):PAGE112
    75    GND @S9S_MB_2U_LIB.S9S_MB_2U(SCH_1):GND   I178 @S9S_MB_2U_LIB.S9S_MB_2U(SCH_1):PAGE112
    77    GND @S9S_MB_2U_LIB.S9S_MB_2U(SCH_1):GND   I178 @S9S_MB_2U_LIB.S9S_MB_2U(SCH_1):PAGE112
    79    GND @S9S_MB_2U_LIB.S9S_MB_2U(SCH_1):GND   I178 @S9S_MB_2U_LIB.S9S_MB_2U(SCH_1):PAGE112
    81    GND @S9S_MB_2U_LIB.S9S_MB_2U(SCH_1):GND   I178 @S9S_MB_2U_LIB.S9S_MB_2U(SCH_1):PAGE112
    83    GND @S9S_MB_2U_LIB.S9S_MB_2U(SCH_1):GND   I178 @S9S_MB_2U_LIB.S9S_MB_2U(SCH_1):PAGE112
    85    GND @S9S_MB_2U_LIB.S9S_MB_2U(SCH_1):GND   I178 @S9S_MB_2U_LIB.S9S_MB_2U(SCH_1):PAGE112
    88    GND @S9S_MB_2U_LIB.S9S_MB_2U(SCH_1):GND   I178 @S9S_MB_2U_LIB.S9S_MB_2U(SCH_1):PAGE112
    90    GND @S9S_MB_2U_LIB.S9S_MB_2U(SCH_1):GND   I178 @S9S_MB_2U_LIB.S9S_MB_2U(SCH_1):PAGE112
    92    GND @S9S_MB_2U_LIB.S9S_MB_2U(SCH_1):GND   I178 @S9S_MB_2U_LIB.S9S_MB_2U(SCH_1):PAGE112
    95    GND @S9S_MB_2U_LIB.S9S_MB_2U(SCH_1):GND   I178 @S9S_MB_2U_LIB.S9S_MB_2U(SCH_1):PAGE112
    97    GND @S9S_MB_2U_LIB.S9S_MB_2U(SCH_1):GND   I178 @S9S_MB_2U_LIB.S9S_MB_2U(SCH_1):PAGE112
    99    GND @S9S_MB_2U_LIB.S9S_MB_2U(SCH_1):GND   I178 @S9S_MB_2U_LIB.S9S_MB_2U(SCH_1):PAGE112
   101    GND @S9S_MB_2U_LIB.S9S_MB_2U(SCH_1):GND   I178 @S9S_MB_2U_LIB.S9S_MB_2U(SCH_1):PAGE112
   103    GND @S9S_MB_2U_LIB.S9S_MB_2U(SCH_1):GND   I178 @S9S_MB_2U_LIB.S9S_MB_2U(SCH_1):PAGE112
   106    GND @S9S_MB_2U_LIB.S9S_MB_2U(SCH_1):GND   I178 @S9S_MB_2U_LIB.S9S_MB_2U(SCH_1):PAGE112
   108    GND @S9S_MB_2U_LIB.S9S_MB_2U(SCH_1):GND   I178 @S9S_MB_2U_LIB.S9S_MB_2U(SCH_1):PAGE112
   110    GND @S9S_MB_2U_LIB.S9S_MB_2U(SCH_1):GND   I178 @S9S_MB_2U_LIB.S9S_MB_2U(SCH_1):PAGE112
   112    GND @S9S_MB_2U_LIB.S9S_MB_2U(SCH_1):GND   I178 @S9S_MB_2U_LIB.S9S_MB_2U(SCH_1):PAGE112
   114    GND @S9S_MB_2U_LIB.S9S_MB_2U(SCH_1):GND   I178 @S9S_MB_2U_LIB.S9S_MB_2U(SCH_1):PAGE112
   117    GND @S9S_MB_2U_LIB.S9S_MB_2U(SCH_1):GND   I178 @S9S_MB_2U_LIB.S9S_MB_2U(SCH_1):PAGE112
   119    GND @S9S_MB_2U_LIB.S9S_MB_2U(SCH_1):GND   I178 @S9S_MB_2U_LIB.S9S_MB_2U(SCH_1):PAGE112
   121    GND @S9S_MB_2U_LIB.S9S_MB_2U(SCH_1):GND   I178 @S9S_MB_2U_LIB.S9S_MB_2U(SCH_1):PAGE112
   123    GND @S9S_MB_2U_LIB.S9S_MB_2U(SCH_1):GND   I178 @S9S_MB_2U_LIB.S9S_MB_2U(SCH_1):PAGE112
   125    GND @S9S_MB_2U_LIB.S9S_MB_2U(SCH_1):GND   I178 @S9S_MB_2U_LIB.S9S_MB_2U(SCH_1):PAGE112
   128    GND @S9S_MB_2U_LIB.S9S_MB_2U(SCH_1):GND   I178 @S9S_MB_2U_LIB.S9S_MB_2U(SCH_1):PAGE112
   130    GND @S9S_MB_2U_LIB.S9S_MB_2U(SCH_1):GND   I178 @S9S_MB_2U_LIB.S9S_MB_2U(SCH_1):PAGE112
   134    GND @S9S_MB_2U_LIB.S9S_MB_2U(SCH_1):GND   I178 @S9S_MB_2U_LIB.S9S_MB_2U(SCH_1):PAGE112
   143    GND @S9S_MB_2U_LIB.S9S_MB_2U(SCH_1):GND   I178 @S9S_MB_2U_LIB.S9S_MB_2U(SCH_1):PAGE112
   151    GND @S9S_MB_2U_LIB.S9S_MB_2U(SCH_1):GND   I178 @S9S_MB_2U_LIB.S9S_MB_2U(SCH_1):PAGE112
   153    GND @S9S_MB_2U_LIB.S9S_MB_2U(SCH_1):GND   I178 @S9S_MB_2U_LIB.S9S_MB_2U(SCH_1):PAGE112
   155    GND @S9S_MB_2U_LIB.S9S_MB_2U(SCH_1):GND   I178 @S9S_MB_2U_LIB.S9S_MB_2U(SCH_1):PAGE112
   158    GND @S9S_MB_2U_LIB.S9S_MB_2U(SCH_1):GND   I178 @S9S_MB_2U_LIB.S9S_MB_2U(SCH_1):PAGE112
   160    GND @S9S_MB_2U_LIB.S9S_MB_2U(SCH_1):GND   I178 @S9S_MB_2U_LIB.S9S_MB_2U(SCH_1):PAGE112
   162    GND @S9S_MB_2U_LIB.S9S_MB_2U(SCH_1):GND   I178 @S9S_MB_2U_LIB.S9S_MB_2U(SCH_1):PAGE112
   164    GND @S9S_MB_2U_LIB.S9S_MB_2U(SCH_1):GND   I178 @S9S_MB_2U_LIB.S9S_MB_2U(SCH_1):PAGE112
   166    GND @S9S_MB_2U_LIB.S9S_MB_2U(SCH_1):GND   I178 @S9S_MB_2U_LIB.S9S_MB_2U(SCH_1):PAGE112
   169    GND @S9S_MB_2U_LIB.S9S_MB_2U(SCH_1):GND   I178 @S9S_MB_2U_LIB.S9S_MB_2U(SCH_1):PAGE112
   171    GND @S9S_MB_2U_LIB.S9S_MB_2U(SCH_1):GND   I178 @S9S_MB_2U_LIB.S9S_MB_2U(SCH_1):PAGE112
   173    GND @S9S_MB_2U_LIB.S9S_MB_2U(SCH_1):GND   I178 @S9S_MB_2U_LIB.S9S_MB_2U(SCH_1):PAGE112
   175    GND @S9S_MB_2U_LIB.S9S_MB_2U(SCH_1):GND   I178 @S9S_MB_2U_LIB.S9S_MB_2U(SCH_1):PAGE112
   177    GND @S9S_MB_2U_LIB.S9S_MB_2U(SCH_1):GND   I178 @S9S_MB_2U_LIB.S9S_MB_2U(SCH_1):PAGE112
   180    GND @S9S_MB_2U_LIB.S9S_MB_2U(SCH_1):GND   I178 @S9S_MB_2U_LIB.S9S_MB_2U(SCH_1):PAGE112
   182    GND @S9S_MB_2U_LIB.S9S_MB_2U(SCH_1):GND   I178 @S9S_MB_2U_LIB.S9S_MB_2U(SCH_1):PAGE112
   184    GND @S9S_MB_2U_LIB.S9S_MB_2U(SCH_1):GND   I178 @S9S_MB_2U_LIB.S9S_MB_2U(SCH_1):PAGE112
   186    GND @S9S_MB_2U_LIB.S9S_MB_2U(SCH_1):GND   I178 @S9S_MB_2U_LIB.S9S_MB_2U(SCH_1):PAGE112
   188    GND @S9S_MB_2U_LIB.S9S_MB_2U(SCH_1):GND   I178 @S9S_MB_2U_LIB.S9S_MB_2U(SCH_1):PAGE112
   191    GND @S9S_MB_2U_LIB.S9S_MB_2U(SCH_1):GND   I178 @S9S_MB_2U_LIB.S9S_MB_2U(SCH_1):PAGE112
   193    GND @S9S_MB_2U_LIB.S9S_MB_2U(SCH_1):GND   I178 @S9S_MB_2U_LIB.S9S_MB_2U(SCH_1):PAGE112
   195    GND @S9S_MB_2U_LIB.S9S_MB_2U(SCH_1):GND   I178 @S9S_MB_2U_LIB.S9S_MB_2U(SCH_1):PAGE112
   197    GND @S9S_MB_2U_LIB.S9S_MB_2U(SCH_1):GND   I178 @S9S_MB_2U_LIB.S9S_MB_2U(SCH_1):PAGE112
   199    GND @S9S_MB_2U_LIB.S9S_MB_2U(SCH_1):GND   I178 @S9S_MB_2U_LIB.S9S_MB_2U(SCH_1):PAGE112
   202    GND @S9S_MB_2U_LIB.S9S_MB_2U(SCH_1):GND   I178 @S9S_MB_2U_LIB.S9S_MB_2U(SCH_1):PAGE112
   204    GND @S9S_MB_2U_LIB.S9S_MB_2U(SCH_1):GND   I178 @S9S_MB_2U_LIB.S9S_MB_2U(SCH_1):PAGE112
   206    GND @S9S_MB_2U_LIB.S9S_MB_2U(SCH_1):GND   I178 @S9S_MB_2U_LIB.S9S_MB_2U(SCH_1):PAGE112
   208    GND @S9S_MB_2U_LIB.S9S_MB_2U(SCH_1):GND   I178 @S9S_MB_2U_LIB.S9S_MB_2U(SCH_1):PAGE112
   210    GND @S9S_MB_2U_LIB.S9S_MB_2U(SCH_1):GND   I178 @S9S_MB_2U_LIB.S9S_MB_2U(SCH_1):PAGE112
   212    GND @S9S_MB_2U_LIB.S9S_MB_2U(SCH_1):GND   I178 @S9S_MB_2U_LIB.S9S_MB_2U(SCH_1):PAGE112
   214    GND @S9S_MB_2U_LIB.S9S_MB_2U(SCH_1):GND   I178 @S9S_MB_2U_LIB.S9S_MB_2U(SCH_1):PAGE112
   216    GND @S9S_MB_2U_LIB.S9S_MB_2U(SCH_1):GND   I178 @S9S_MB_2U_LIB.S9S_MB_2U(SCH_1):PAGE112
   219    GND @S9S_MB_2U_LIB.S9S_MB_2U(SCH_1):GND   I178 @S9S_MB_2U_LIB.S9S_MB_2U(SCH_1):PAGE112
   222    GND @S9S_MB_2U_LIB.S9S_MB_2U(SCH_1):GND   I178 @S9S_MB_2U_LIB.S9S_MB_2U(SCH_1):PAGE112
   224    GND @S9S_MB_2U_LIB.S9S_MB_2U(SCH_1):GND   I178 @S9S_MB_2U_LIB.S9S_MB_2U(SCH_1):PAGE112
   226    GND @S9S_MB_2U_LIB.S9S_MB_2U(SCH_1):GND   I178 @S9S_MB_2U_LIB.S9S_MB_2U(SCH_1):PAGE112
   228    GND @S9S_MB_2U_LIB.S9S_MB_2U(SCH_1):GND   I178 @S9S_MB_2U_LIB.S9S_MB_2U(SCH_1):PAGE112
   233    GND @S9S_MB_2U_LIB.S9S_MB_2U(SCH_1):GND   I178 @S9S_MB_2U_LIB.S9S_MB_2U(SCH_1):PAGE112
   237    GND @S9S_MB_2U_LIB.S9S_MB_2U(SCH_1):GND   I178 @S9S_MB_2U_LIB.S9S_MB_2U(SCH_1):PAGE112
   242    GND @S9S_MB_2U_LIB.S9S_MB_2U(SCH_1):GND   I178 @S9S_MB_2U_LIB.S9S_MB_2U(SCH_1):PAGE112
   244    GND @S9S_MB_2U_LIB.S9S_MB_2U(SCH_1):GND   I178 @S9S_MB_2U_LIB.S9S_MB_2U(SCH_1):PAGE112
   246    GND @S9S_MB_2U_LIB.S9S_MB_2U(SCH_1):GND   I178 @S9S_MB_2U_LIB.S9S_MB_2U(SCH_1):PAGE112
   248    GND @S9S_MB_2U_LIB.S9S_MB_2U(SCH_1):GND   I178 @S9S_MB_2U_LIB.S9S_MB_2U(SCH_1):PAGE112
   251    GND @S9S_MB_2U_LIB.S9S_MB_2U(SCH_1):GND   I178 @S9S_MB_2U_LIB.S9S_MB_2U(SCH_1):PAGE112
   253    GND @S9S_MB_2U_LIB.S9S_MB_2U(SCH_1):GND   I178 @S9S_MB_2U_LIB.S9S_MB_2U(SCH_1):PAGE112
   255    GND @S9S_MB_2U_LIB.S9S_MB_2U(SCH_1):GND   I178 @S9S_MB_2U_LIB.S9S_MB_2U(SCH_1):PAGE112
   257    GND @S9S_MB_2U_LIB.S9S_MB_2U(SCH_1):GND   I178 @S9S_MB_2U_LIB.S9S_MB_2U(SCH_1):PAGE112
   259    GND @S9S_MB_2U_LIB.S9S_MB_2U(SCH_1):GND   I178 @S9S_MB_2U_LIB.S9S_MB_2U(SCH_1):PAGE112
   262    GND @S9S_MB_2U_LIB.S9S_MB_2U(SCH_1):GND   I178 @S9S_MB_2U_LIB.S9S_MB_2U(SCH_1):PAGE112
   264    GND @S9S_MB_2U_LIB.S9S_MB_2U(SCH_1):GND   I178 @S9S_MB_2U_LIB.S9S_MB_2U(SCH_1):PAGE112
   266    GND @S9S_MB_2U_LIB.S9S_MB_2U(SCH_1):GND   I178 @S9S_MB_2U_LIB.S9S_MB_2U(SCH_1):PAGE112
   268    GND @S9S_MB_2U_LIB.S9S_MB_2U(SCH_1):GND   I178 @S9S_MB_2U_LIB.S9S_MB_2U(SCH_1):PAGE112
   270    GND @S9S_MB_2U_LIB.S9S_MB_2U(SCH_1):GND   I178 @S9S_MB_2U_LIB.S9S_MB_2U(SCH_1):PAGE112
   273    GND @S9S_MB_2U_LIB.S9S_MB_2U(SCH_1):GND   I178 @S9S_MB_2U_LIB.S9S_MB_2U(SCH_1):PAGE112
   275    GND @S9S_MB_2U_LIB.S9S_MB_2U(SCH_1):GND   I178 @S9S_MB_2U_LIB.S9S_MB_2U(SCH_1):PAGE112
   277    GND @S9S_MB_2U_LIB.S9S_MB_2U(SCH_1):GND   I178 @S9S_MB_2U_LIB.S9S_MB_2U(SCH_1):PAGE112
   279    GND @S9S_MB_2U_LIB.S9S_MB_2U(SCH_1):GND   I178 @S9S_MB_2U_LIB.S9S_MB_2U(SCH_1):PAGE112
   281    GND @S9S_MB_2U_LIB.S9S_MB_2U(SCH_1):GND   I178 @S9S_MB_2U_LIB.S9S_MB_2U(SCH_1):PAGE112
   284    GND @S9S_MB_2U_LIB.S9S_MB_2U(SCH_1):GND   I178 @S9S_MB_2U_LIB.S9S_MB_2U(SCH_1):PAGE112
   286    GND @S9S_MB_2U_LIB.S9S_MB_2U(SCH_1):GND   I178 @S9S_MB_2U_LIB.S9S_MB_2U(SCH_1):PAGE112
   288    GND @S9S_MB_2U_LIB.S9S_MB_2U(SCH_1):GND   I178 @S9S_MB_2U_LIB.S9S_MB_2U(SCH_1):PAGE112
     1 P12V_S3_AUX_CPU1_NVDIMM @S9S_MB_2U_LIB.S9S_MB_2U(SCH_1):P12V_S3_AUX_CPU1_NVDIMM   I178 @S9S_MB_2U_LIB.S9S_MB_2U(SCH_1):PAGE112
   145 P12V_S3_AUX_CPU1_NVDIMM @S9S_MB_2U_LIB.S9S_MB_2U(SCH_1):P12V_S3_AUX_CPU1_NVDIMM   I178 @S9S_MB_2U_LIB.S9S_MB_2U(SCH_1):PAGE112
   146 P12V_S3_AUX_CPU1_NVDIMM @S9S_MB_2U_LIB.S9S_MB_2U(SCH_1):P12V_S3_AUX_CPU1_NVDIMM   I178 @S9S_MB_2U_LIB.S9S_MB_2U(SCH_1):PAGE112
   230    GND @S9S_MB_2U_LIB.S9S_MB_2U(SCH_1):GND   I178 @S9S_MB_2U_LIB.S9S_MB_2U(SCH_1):PAGE112
   235    GND @S9S_MB_2U_LIB.S9S_MB_2U(SCH_1):GND   I178 @S9S_MB_2U_LIB.S9S_MB_2U(SCH_1):PAGE112
   240    GND @S9S_MB_2U_LIB.S9S_MB_2U(SCH_1):GND   I178 @S9S_MB_2U_LIB.S9S_MB_2U(SCH_1):PAGE112
   132    GND @S9S_MB_2U_LIB.S9S_MB_2U(SCH_1):GND   I178 @S9S_MB_2U_LIB.S9S_MB_2U(SCH_1):PAGE112
   136    GND @S9S_MB_2U_LIB.S9S_MB_2U(SCH_1):GND   I178 @S9S_MB_2U_LIB.S9S_MB_2U(SCH_1):PAGE112
   139    GND @S9S_MB_2U_LIB.S9S_MB_2U(SCH_1):GND   I178 @S9S_MB_2U_LIB.S9S_MB_2U(SCH_1):PAGE112
   141    GND @S9S_MB_2U_LIB.S9S_MB_2U(SCH_1):GND   I178 @S9S_MB_2U_LIB.S9S_MB_2U(SCH_1):PAGE112
    G1    GND @S9S_MB_2U_LIB.S9S_MB_2U(SCH_1):GND   I178 @S9S_MB_2U_LIB.S9S_MB_2U(SCH_1):PAGE112
    G2    GND @S9S_MB_2U_LIB.S9S_MB_2U(SCH_1):GND   I178 @S9S_MB_2U_LIB.S9S_MB_2U(SCH_1):PAGE112
    G3    GND @S9S_MB_2U_LIB.S9S_MB_2U(SCH_1):GND   I178 @S9S_MB_2U_LIB.S9S_MB_2U(SCH_1):PAGE112

 J32 SCONN288_ADR50017P087CC-SCONN2A
     3 P3V3_AUX @S9S_MB_2U_LIB.S9S_MB_2U(SCH_1):P3V3_AUX   I179 @S9S_MB_2U_LIB.S9S_MB_2U(SCH_1):PAGE113
     2 TP_CHH_CPU1_DIMM2_FRU_0 @S9S_MB_2U_LIB.S9S_MB_2U(SCH_1):TP_CHH_CPU1_DIMM2_FRU_0   I179 @S9S_MB_2U_LIB.S9S_MB_2U(SCH_1):PAGE113
   144 TP_CHH_CPU1_DIMM2_FRU_1 @S9S_MB_2U_LIB.S9S_MB_2U(SCH_1):TP_CHH_CPU1_DIMM2_FRU_1   I179 @S9S_MB_2U_LIB.S9S_MB_2U(SCH_1):PAGE113
   149 TP_CHH_CPU1_DIMM2_FRU_2 @S9S_MB_2U_LIB.S9S_MB_2U(SCH_1):TP_CHH_CPU1_DIMM2_FRU_2   I179 @S9S_MB_2U_LIB.S9S_MB_2U(SCH_1):PAGE113
   150 TP_CHH_CPU1_DIMM2_FRU_3 @S9S_MB_2U_LIB.S9S_MB_2U(SCH_1):TP_CHH_CPU1_DIMM2_FRU_3   I179 @S9S_MB_2U_LIB.S9S_MB_2U(SCH_1):PAGE113
   220 TP_CHH_CPU1_DIMM2_FRU_4 @S9S_MB_2U_LIB.S9S_MB_2U(SCH_1):TP_CHH_CPU1_DIMM2_FRU_4   I179 @S9S_MB_2U_LIB.S9S_MB_2U(SCH_1):PAGE113
   231 TP_CHH_CPU1_DIMM2_FRU_5 @S9S_MB_2U_LIB.S9S_MB_2U(SCH_1):TP_CHH_CPU1_DIMM2_FRU_5   I179 @S9S_MB_2U_LIB.S9S_MB_2U(SCH_1):PAGE113
   232 TP_CHH_CPU1_DIMM2_FRU_6 @S9S_MB_2U_LIB.S9S_MB_2U(SCH_1):TP_CHH_CPU1_DIMM2_FRU_6   I179 @S9S_MB_2U_LIB.S9S_MB_2U(SCH_1):PAGE113
   207 RST_M_GH_CPU1_FPGA_N @S9S_MB_2U_LIB.S9S_MB_2U(SCH_1):RST_M_GH_CPU1_FPGA_N   I179 @S9S_MB_2U_LIB.S9S_MB_2U(SCH_1):PAGE113
   147 PWRGD_CHH_CPU1_DIMM2 @S9S_MB_2U_LIB.S9S_MB_2U(SCH_1):PWRGD_CHH_CPU1_DIMM2   I179 @S9S_MB_2U_LIB.S9S_MB_2U(SCH_1):PAGE113
   227 M_H_CPU1_SB_PAR @S9S_MB_2U_LIB.S9S_MB_2U(SCH_1):M_H_CPU1_SB_PAR   I179 @S9S_MB_2U_LIB.S9S_MB_2U(SCH_1):PAGE113
    74 M_H_CPU1_SA_PAR @S9S_MB_2U_LIB.S9S_MB_2U(SCH_1):M_H_CPU1_SA_PAR   I179 @S9S_MB_2U_LIB.S9S_MB_2U(SCH_1):PAGE113
    87 M_H_CPU1_SB_RSP<1> @S9S_MB_2U_LIB.S9S_MB_2U(SCH_1):M_H_CPU1_SB_RSP(1)   I179 @S9S_MB_2U_LIB.S9S_MB_2U(SCH_1):PAGE113
    86 M_H_CPU1_SA_RSP<1> @S9S_MB_2U_LIB.S9S_MB_2U(SCH_1):M_H_CPU1_SA_RSP(1)   I179 @S9S_MB_2U_LIB.S9S_MB_2U(SCH_1):PAGE113
     5 I3C_SPD_DDREFGH_CPU1_LVC1_SDA @S9S_MB_2U_LIB.S9S_MB_2U(SCH_1):I3C_SPD_DDREFGH_CPU1_LVC1_SDA   I179 @S9S_MB_2U_LIB.S9S_MB_2U(SCH_1):PAGE113
     4 I3C_SPD_DDREFGH_CPU1_LVC1_SCL_7 @S9S_MB_2U_LIB.S9S_MB_2U(SCH_1):I3C_SPD_DDREFGH_CPU1_LVC1_SCL_R8   I179 @S9S_MB_2U_LIB.S9S_MB_2U(SCH_1):PAGE113
   148 PD_CHH_CPU1_DIMM2_SAA @S9S_MB_2U_LIB.S9S_MB_2U(SCH_1):PD_CHH_CPU1_DIMM2_SAA   I179 @S9S_MB_2U_LIB.S9S_MB_2U(SCH_1):PAGE113
   100 M_H_CPU1_SB_DQ<0> @S9S_MB_2U_LIB.S9S_MB_2U(SCH_1):M_H_CPU1_SB_DQ(0)   I179 @S9S_MB_2U_LIB.S9S_MB_2U(SCH_1):PAGE113
   102 M_H_CPU1_SB_DQ<1> @S9S_MB_2U_LIB.S9S_MB_2U(SCH_1):M_H_CPU1_SB_DQ(1)   I179 @S9S_MB_2U_LIB.S9S_MB_2U(SCH_1):PAGE113
   245 M_H_CPU1_SB_DQ<2> @S9S_MB_2U_LIB.S9S_MB_2U(SCH_1):M_H_CPU1_SB_DQ(2)   I179 @S9S_MB_2U_LIB.S9S_MB_2U(SCH_1):PAGE113
   247 M_H_CPU1_SB_DQ<3> @S9S_MB_2U_LIB.S9S_MB_2U(SCH_1):M_H_CPU1_SB_DQ(3)   I179 @S9S_MB_2U_LIB.S9S_MB_2U(SCH_1):PAGE113
   107 M_H_CPU1_SB_DQ<4> @S9S_MB_2U_LIB.S9S_MB_2U(SCH_1):M_H_CPU1_SB_DQ(4)   I179 @S9S_MB_2U_LIB.S9S_MB_2U(SCH_1):PAGE113
   109 M_H_CPU1_SB_DQ<5> @S9S_MB_2U_LIB.S9S_MB_2U(SCH_1):M_H_CPU1_SB_DQ(5)   I179 @S9S_MB_2U_LIB.S9S_MB_2U(SCH_1):PAGE113
   252 M_H_CPU1_SB_DQ<6> @S9S_MB_2U_LIB.S9S_MB_2U(SCH_1):M_H_CPU1_SB_DQ(6)   I179 @S9S_MB_2U_LIB.S9S_MB_2U(SCH_1):PAGE113
   254 M_H_CPU1_SB_DQ<7> @S9S_MB_2U_LIB.S9S_MB_2U(SCH_1):M_H_CPU1_SB_DQ(7)   I179 @S9S_MB_2U_LIB.S9S_MB_2U(SCH_1):PAGE113
   111 M_H_CPU1_SB_DQ<8> @S9S_MB_2U_LIB.S9S_MB_2U(SCH_1):M_H_CPU1_SB_DQ(8)   I179 @S9S_MB_2U_LIB.S9S_MB_2U(SCH_1):PAGE113
   113 M_H_CPU1_SB_DQ<9> @S9S_MB_2U_LIB.S9S_MB_2U(SCH_1):M_H_CPU1_SB_DQ(9)   I179 @S9S_MB_2U_LIB.S9S_MB_2U(SCH_1):PAGE113
   256 M_H_CPU1_SB_DQ<10> @S9S_MB_2U_LIB.S9S_MB_2U(SCH_1):M_H_CPU1_SB_DQ(10)   I179 @S9S_MB_2U_LIB.S9S_MB_2U(SCH_1):PAGE113
   258 M_H_CPU1_SB_DQ<11> @S9S_MB_2U_LIB.S9S_MB_2U(SCH_1):M_H_CPU1_SB_DQ(11)   I179 @S9S_MB_2U_LIB.S9S_MB_2U(SCH_1):PAGE113
   118 M_H_CPU1_SB_DQ<12> @S9S_MB_2U_LIB.S9S_MB_2U(SCH_1):M_H_CPU1_SB_DQ(12)   I179 @S9S_MB_2U_LIB.S9S_MB_2U(SCH_1):PAGE113
   120 M_H_CPU1_SB_DQ<13> @S9S_MB_2U_LIB.S9S_MB_2U(SCH_1):M_H_CPU1_SB_DQ(13)   I179 @S9S_MB_2U_LIB.S9S_MB_2U(SCH_1):PAGE113
   263 M_H_CPU1_SB_DQ<14> @S9S_MB_2U_LIB.S9S_MB_2U(SCH_1):M_H_CPU1_SB_DQ(14)   I179 @S9S_MB_2U_LIB.S9S_MB_2U(SCH_1):PAGE113
   265 M_H_CPU1_SB_DQ<15> @S9S_MB_2U_LIB.S9S_MB_2U(SCH_1):M_H_CPU1_SB_DQ(15)   I179 @S9S_MB_2U_LIB.S9S_MB_2U(SCH_1):PAGE113
   122 M_H_CPU1_SB_DQ<16> @S9S_MB_2U_LIB.S9S_MB_2U(SCH_1):M_H_CPU1_SB_DQ(16)   I179 @S9S_MB_2U_LIB.S9S_MB_2U(SCH_1):PAGE113
   124 M_H_CPU1_SB_DQ<17> @S9S_MB_2U_LIB.S9S_MB_2U(SCH_1):M_H_CPU1_SB_DQ(17)   I179 @S9S_MB_2U_LIB.S9S_MB_2U(SCH_1):PAGE113
   267 M_H_CPU1_SB_DQ<18> @S9S_MB_2U_LIB.S9S_MB_2U(SCH_1):M_H_CPU1_SB_DQ(18)   I179 @S9S_MB_2U_LIB.S9S_MB_2U(SCH_1):PAGE113
   269 M_H_CPU1_SB_DQ<19> @S9S_MB_2U_LIB.S9S_MB_2U(SCH_1):M_H_CPU1_SB_DQ(19)   I179 @S9S_MB_2U_LIB.S9S_MB_2U(SCH_1):PAGE113
   129 M_H_CPU1_SB_DQ<20> @S9S_MB_2U_LIB.S9S_MB_2U(SCH_1):M_H_CPU1_SB_DQ(20)   I179 @S9S_MB_2U_LIB.S9S_MB_2U(SCH_1):PAGE113
   131 M_H_CPU1_SB_DQ<21> @S9S_MB_2U_LIB.S9S_MB_2U(SCH_1):M_H_CPU1_SB_DQ(21)   I179 @S9S_MB_2U_LIB.S9S_MB_2U(SCH_1):PAGE113
   274 M_H_CPU1_SB_DQ<22> @S9S_MB_2U_LIB.S9S_MB_2U(SCH_1):M_H_CPU1_SB_DQ(22)   I179 @S9S_MB_2U_LIB.S9S_MB_2U(SCH_1):PAGE113
   276 M_H_CPU1_SB_DQ<23> @S9S_MB_2U_LIB.S9S_MB_2U(SCH_1):M_H_CPU1_SB_DQ(23)   I179 @S9S_MB_2U_LIB.S9S_MB_2U(SCH_1):PAGE113
   133 M_H_CPU1_SB_DQ<24> @S9S_MB_2U_LIB.S9S_MB_2U(SCH_1):M_H_CPU1_SB_DQ(24)   I179 @S9S_MB_2U_LIB.S9S_MB_2U(SCH_1):PAGE113
   135 M_H_CPU1_SB_DQ<25> @S9S_MB_2U_LIB.S9S_MB_2U(SCH_1):M_H_CPU1_SB_DQ(25)   I179 @S9S_MB_2U_LIB.S9S_MB_2U(SCH_1):PAGE113
   278 M_H_CPU1_SB_DQ<26> @S9S_MB_2U_LIB.S9S_MB_2U(SCH_1):M_H_CPU1_SB_DQ(26)   I179 @S9S_MB_2U_LIB.S9S_MB_2U(SCH_1):PAGE113
   280 M_H_CPU1_SB_DQ<27> @S9S_MB_2U_LIB.S9S_MB_2U(SCH_1):M_H_CPU1_SB_DQ(27)   I179 @S9S_MB_2U_LIB.S9S_MB_2U(SCH_1):PAGE113
   140 M_H_CPU1_SB_DQ<28> @S9S_MB_2U_LIB.S9S_MB_2U(SCH_1):M_H_CPU1_SB_DQ(28)   I179 @S9S_MB_2U_LIB.S9S_MB_2U(SCH_1):PAGE113
   142 M_H_CPU1_SB_DQ<29> @S9S_MB_2U_LIB.S9S_MB_2U(SCH_1):M_H_CPU1_SB_DQ(29)   I179 @S9S_MB_2U_LIB.S9S_MB_2U(SCH_1):PAGE113
   285 M_H_CPU1_SB_DQ<30> @S9S_MB_2U_LIB.S9S_MB_2U(SCH_1):M_H_CPU1_SB_DQ(30)   I179 @S9S_MB_2U_LIB.S9S_MB_2U(SCH_1):PAGE113
   287 M_H_CPU1_SB_DQ<31> @S9S_MB_2U_LIB.S9S_MB_2U(SCH_1):M_H_CPU1_SB_DQ(31)   I179 @S9S_MB_2U_LIB.S9S_MB_2U(SCH_1):PAGE113
     7 M_H_CPU1_SA_DQ<0> @S9S_MB_2U_LIB.S9S_MB_2U(SCH_1):M_H_CPU1_SA_DQ(0)   I179 @S9S_MB_2U_LIB.S9S_MB_2U(SCH_1):PAGE113
     9 M_H_CPU1_SA_DQ<1> @S9S_MB_2U_LIB.S9S_MB_2U(SCH_1):M_H_CPU1_SA_DQ(1)   I179 @S9S_MB_2U_LIB.S9S_MB_2U(SCH_1):PAGE113
   152 M_H_CPU1_SA_DQ<2> @S9S_MB_2U_LIB.S9S_MB_2U(SCH_1):M_H_CPU1_SA_DQ(2)   I179 @S9S_MB_2U_LIB.S9S_MB_2U(SCH_1):PAGE113
   154 M_H_CPU1_SA_DQ<3> @S9S_MB_2U_LIB.S9S_MB_2U(SCH_1):M_H_CPU1_SA_DQ(3)   I179 @S9S_MB_2U_LIB.S9S_MB_2U(SCH_1):PAGE113
    14 M_H_CPU1_SA_DQ<4> @S9S_MB_2U_LIB.S9S_MB_2U(SCH_1):M_H_CPU1_SA_DQ(4)   I179 @S9S_MB_2U_LIB.S9S_MB_2U(SCH_1):PAGE113
    16 M_H_CPU1_SA_DQ<5> @S9S_MB_2U_LIB.S9S_MB_2U(SCH_1):M_H_CPU1_SA_DQ(5)   I179 @S9S_MB_2U_LIB.S9S_MB_2U(SCH_1):PAGE113
   159 M_H_CPU1_SA_DQ<6> @S9S_MB_2U_LIB.S9S_MB_2U(SCH_1):M_H_CPU1_SA_DQ(6)   I179 @S9S_MB_2U_LIB.S9S_MB_2U(SCH_1):PAGE113
   161 M_H_CPU1_SA_DQ<7> @S9S_MB_2U_LIB.S9S_MB_2U(SCH_1):M_H_CPU1_SA_DQ(7)   I179 @S9S_MB_2U_LIB.S9S_MB_2U(SCH_1):PAGE113
    18 M_H_CPU1_SA_DQ<8> @S9S_MB_2U_LIB.S9S_MB_2U(SCH_1):M_H_CPU1_SA_DQ(8)   I179 @S9S_MB_2U_LIB.S9S_MB_2U(SCH_1):PAGE113
    20 M_H_CPU1_SA_DQ<9> @S9S_MB_2U_LIB.S9S_MB_2U(SCH_1):M_H_CPU1_SA_DQ(9)   I179 @S9S_MB_2U_LIB.S9S_MB_2U(SCH_1):PAGE113
   163 M_H_CPU1_SA_DQ<10> @S9S_MB_2U_LIB.S9S_MB_2U(SCH_1):M_H_CPU1_SA_DQ(10)   I179 @S9S_MB_2U_LIB.S9S_MB_2U(SCH_1):PAGE113
   165 M_H_CPU1_SA_DQ<11> @S9S_MB_2U_LIB.S9S_MB_2U(SCH_1):M_H_CPU1_SA_DQ(11)   I179 @S9S_MB_2U_LIB.S9S_MB_2U(SCH_1):PAGE113
    25 M_H_CPU1_SA_DQ<12> @S9S_MB_2U_LIB.S9S_MB_2U(SCH_1):M_H_CPU1_SA_DQ(12)   I179 @S9S_MB_2U_LIB.S9S_MB_2U(SCH_1):PAGE113
    27 M_H_CPU1_SA_DQ<13> @S9S_MB_2U_LIB.S9S_MB_2U(SCH_1):M_H_CPU1_SA_DQ(13)   I179 @S9S_MB_2U_LIB.S9S_MB_2U(SCH_1):PAGE113
   170 M_H_CPU1_SA_DQ<14> @S9S_MB_2U_LIB.S9S_MB_2U(SCH_1):M_H_CPU1_SA_DQ(14)   I179 @S9S_MB_2U_LIB.S9S_MB_2U(SCH_1):PAGE113
   172 M_H_CPU1_SA_DQ<15> @S9S_MB_2U_LIB.S9S_MB_2U(SCH_1):M_H_CPU1_SA_DQ(15)   I179 @S9S_MB_2U_LIB.S9S_MB_2U(SCH_1):PAGE113
    29 M_H_CPU1_SA_DQ<16> @S9S_MB_2U_LIB.S9S_MB_2U(SCH_1):M_H_CPU1_SA_DQ(16)   I179 @S9S_MB_2U_LIB.S9S_MB_2U(SCH_1):PAGE113
    31 M_H_CPU1_SA_DQ<17> @S9S_MB_2U_LIB.S9S_MB_2U(SCH_1):M_H_CPU1_SA_DQ(17)   I179 @S9S_MB_2U_LIB.S9S_MB_2U(SCH_1):PAGE113
   174 M_H_CPU1_SA_DQ<18> @S9S_MB_2U_LIB.S9S_MB_2U(SCH_1):M_H_CPU1_SA_DQ(18)   I179 @S9S_MB_2U_LIB.S9S_MB_2U(SCH_1):PAGE113
   176 M_H_CPU1_SA_DQ<19> @S9S_MB_2U_LIB.S9S_MB_2U(SCH_1):M_H_CPU1_SA_DQ(19)   I179 @S9S_MB_2U_LIB.S9S_MB_2U(SCH_1):PAGE113
    36 M_H_CPU1_SA_DQ<20> @S9S_MB_2U_LIB.S9S_MB_2U(SCH_1):M_H_CPU1_SA_DQ(20)   I179 @S9S_MB_2U_LIB.S9S_MB_2U(SCH_1):PAGE113
    38 M_H_CPU1_SA_DQ<21> @S9S_MB_2U_LIB.S9S_MB_2U(SCH_1):M_H_CPU1_SA_DQ(21)   I179 @S9S_MB_2U_LIB.S9S_MB_2U(SCH_1):PAGE113
   181 M_H_CPU1_SA_DQ<22> @S9S_MB_2U_LIB.S9S_MB_2U(SCH_1):M_H_CPU1_SA_DQ(22)   I179 @S9S_MB_2U_LIB.S9S_MB_2U(SCH_1):PAGE113
   183 M_H_CPU1_SA_DQ<23> @S9S_MB_2U_LIB.S9S_MB_2U(SCH_1):M_H_CPU1_SA_DQ(23)   I179 @S9S_MB_2U_LIB.S9S_MB_2U(SCH_1):PAGE113
    40 M_H_CPU1_SA_DQ<24> @S9S_MB_2U_LIB.S9S_MB_2U(SCH_1):M_H_CPU1_SA_DQ(24)   I179 @S9S_MB_2U_LIB.S9S_MB_2U(SCH_1):PAGE113
    42 M_H_CPU1_SA_DQ<25> @S9S_MB_2U_LIB.S9S_MB_2U(SCH_1):M_H_CPU1_SA_DQ(25)   I179 @S9S_MB_2U_LIB.S9S_MB_2U(SCH_1):PAGE113
   185 M_H_CPU1_SA_DQ<26> @S9S_MB_2U_LIB.S9S_MB_2U(SCH_1):M_H_CPU1_SA_DQ(26)   I179 @S9S_MB_2U_LIB.S9S_MB_2U(SCH_1):PAGE113
   187 M_H_CPU1_SA_DQ<27> @S9S_MB_2U_LIB.S9S_MB_2U(SCH_1):M_H_CPU1_SA_DQ(27)   I179 @S9S_MB_2U_LIB.S9S_MB_2U(SCH_1):PAGE113
    47 M_H_CPU1_SA_DQ<28> @S9S_MB_2U_LIB.S9S_MB_2U(SCH_1):M_H_CPU1_SA_DQ(28)   I179 @S9S_MB_2U_LIB.S9S_MB_2U(SCH_1):PAGE113
    49 M_H_CPU1_SA_DQ<29> @S9S_MB_2U_LIB.S9S_MB_2U(SCH_1):M_H_CPU1_SA_DQ(29)   I179 @S9S_MB_2U_LIB.S9S_MB_2U(SCH_1):PAGE113
   192 M_H_CPU1_SA_DQ<30> @S9S_MB_2U_LIB.S9S_MB_2U(SCH_1):M_H_CPU1_SA_DQ(30)   I179 @S9S_MB_2U_LIB.S9S_MB_2U(SCH_1):PAGE113
   229 M_H_CPU1_SB_CS_N<3> @S9S_MB_2U_LIB.S9S_MB_2U(SCH_1):M_H_CPU1_SB_CS_N(3)   I179 @S9S_MB_2U_LIB.S9S_MB_2U(SCH_1):PAGE113
   209 M_H_CPU1_SA_CS_N<3> @S9S_MB_2U_LIB.S9S_MB_2U(SCH_1):M_H_CPU1_SA_CS_N(3)   I179 @S9S_MB_2U_LIB.S9S_MB_2U(SCH_1):PAGE113
    84 M_H_CPU1_SB_CS_N<2> @S9S_MB_2U_LIB.S9S_MB_2U(SCH_1):M_H_CPU1_SB_CS_N(2)   I179 @S9S_MB_2U_LIB.S9S_MB_2U(SCH_1):PAGE113
    64 M_H_CPU1_SA_CS_N<2> @S9S_MB_2U_LIB.S9S_MB_2U(SCH_1):M_H_CPU1_SA_CS_N(2)   I179 @S9S_MB_2U_LIB.S9S_MB_2U(SCH_1):PAGE113
   217 M_H_CPU1_CLK_DP<1> @S9S_MB_2U_LIB.S9S_MB_2U(SCH_1):M_H_CPU1_CLK_DP(1)   I179 @S9S_MB_2U_LIB.S9S_MB_2U(SCH_1):PAGE113
   218 M_H_CPU1_CLK_DN<1> @S9S_MB_2U_LIB.S9S_MB_2U(SCH_1):M_H_CPU1_CLK_DN(1)   I179 @S9S_MB_2U_LIB.S9S_MB_2U(SCH_1):PAGE113
    96 M_H_CPU1_SB_CB<0> @S9S_MB_2U_LIB.S9S_MB_2U(SCH_1):M_H_CPU1_SB_CB(0)   I179 @S9S_MB_2U_LIB.S9S_MB_2U(SCH_1):PAGE113
    98 M_H_CPU1_SB_CB<1> @S9S_MB_2U_LIB.S9S_MB_2U(SCH_1):M_H_CPU1_SB_CB(1)   I179 @S9S_MB_2U_LIB.S9S_MB_2U(SCH_1):PAGE113
   241 M_H_CPU1_SB_CB<2> @S9S_MB_2U_LIB.S9S_MB_2U(SCH_1):M_H_CPU1_SB_CB(2)   I179 @S9S_MB_2U_LIB.S9S_MB_2U(SCH_1):PAGE113
   243 M_H_CPU1_SB_CB<3> @S9S_MB_2U_LIB.S9S_MB_2U(SCH_1):M_H_CPU1_SB_CB(3)   I179 @S9S_MB_2U_LIB.S9S_MB_2U(SCH_1):PAGE113
    89 M_H_CPU1_SB_CB<4> @S9S_MB_2U_LIB.S9S_MB_2U(SCH_1):M_H_CPU1_SB_CB(4)   I179 @S9S_MB_2U_LIB.S9S_MB_2U(SCH_1):PAGE113
    91 M_H_CPU1_SB_CB<5> @S9S_MB_2U_LIB.S9S_MB_2U(SCH_1):M_H_CPU1_SB_CB(5)   I179 @S9S_MB_2U_LIB.S9S_MB_2U(SCH_1):PAGE113
   234 M_H_CPU1_SB_CB<6> @S9S_MB_2U_LIB.S9S_MB_2U(SCH_1):M_H_CPU1_SB_CB(6)   I179 @S9S_MB_2U_LIB.S9S_MB_2U(SCH_1):PAGE113
    51 M_H_CPU1_SA_CB<0> @S9S_MB_2U_LIB.S9S_MB_2U(SCH_1):M_H_CPU1_SA_CB(0)   I179 @S9S_MB_2U_LIB.S9S_MB_2U(SCH_1):PAGE113
   196 M_H_CPU1_SA_CB<2> @S9S_MB_2U_LIB.S9S_MB_2U(SCH_1):M_H_CPU1_SA_CB(2)   I179 @S9S_MB_2U_LIB.S9S_MB_2U(SCH_1):PAGE113
   198 M_H_CPU1_SA_CB<3> @S9S_MB_2U_LIB.S9S_MB_2U(SCH_1):M_H_CPU1_SA_CB(3)   I179 @S9S_MB_2U_LIB.S9S_MB_2U(SCH_1):PAGE113
    60 M_H_CPU1_SA_CB<5> @S9S_MB_2U_LIB.S9S_MB_2U(SCH_1):M_H_CPU1_SA_CB(5)   I179 @S9S_MB_2U_LIB.S9S_MB_2U(SCH_1):PAGE113
   203 M_H_CPU1_SA_CB<6> @S9S_MB_2U_LIB.S9S_MB_2U(SCH_1):M_H_CPU1_SA_CB(6)   I179 @S9S_MB_2U_LIB.S9S_MB_2U(SCH_1):PAGE113
    82 M_H_CPU1_SB_CA<6> @S9S_MB_2U_LIB.S9S_MB_2U(SCH_1):M_H_CPU1_SB_CA(6)   I179 @S9S_MB_2U_LIB.S9S_MB_2U(SCH_1):PAGE113
    72 M_H_CPU1_SA_CA<6> @S9S_MB_2U_LIB.S9S_MB_2U(SCH_1):M_H_CPU1_SA_CA(6)   I179 @S9S_MB_2U_LIB.S9S_MB_2U(SCH_1):PAGE113
   225 M_H_CPU1_SB_CA<5> @S9S_MB_2U_LIB.S9S_MB_2U(SCH_1):M_H_CPU1_SB_CA(5)   I179 @S9S_MB_2U_LIB.S9S_MB_2U(SCH_1):PAGE113
   215 M_H_CPU1_SA_CA<5> @S9S_MB_2U_LIB.S9S_MB_2U(SCH_1):M_H_CPU1_SA_CA(5)   I179 @S9S_MB_2U_LIB.S9S_MB_2U(SCH_1):PAGE113
    80 M_H_CPU1_SB_CA<4> @S9S_MB_2U_LIB.S9S_MB_2U(SCH_1):M_H_CPU1_SB_CA(4)   I179 @S9S_MB_2U_LIB.S9S_MB_2U(SCH_1):PAGE113
    70 M_H_CPU1_SA_CA<4> @S9S_MB_2U_LIB.S9S_MB_2U(SCH_1):M_H_CPU1_SA_CA(4)   I179 @S9S_MB_2U_LIB.S9S_MB_2U(SCH_1):PAGE113
   223 M_H_CPU1_SB_CA<3> @S9S_MB_2U_LIB.S9S_MB_2U(SCH_1):M_H_CPU1_SB_CA(3)   I179 @S9S_MB_2U_LIB.S9S_MB_2U(SCH_1):PAGE113
   213 M_H_CPU1_SA_CA<3> @S9S_MB_2U_LIB.S9S_MB_2U(SCH_1):M_H_CPU1_SA_CA(3)   I179 @S9S_MB_2U_LIB.S9S_MB_2U(SCH_1):PAGE113
    78 M_H_CPU1_SB_CA<2> @S9S_MB_2U_LIB.S9S_MB_2U(SCH_1):M_H_CPU1_SB_CA(2)   I179 @S9S_MB_2U_LIB.S9S_MB_2U(SCH_1):PAGE113
    68 M_H_CPU1_SA_CA<2> @S9S_MB_2U_LIB.S9S_MB_2U(SCH_1):M_H_CPU1_SA_CA(2)   I179 @S9S_MB_2U_LIB.S9S_MB_2U(SCH_1):PAGE113
   221 M_H_CPU1_SB_CA<1> @S9S_MB_2U_LIB.S9S_MB_2U(SCH_1):M_H_CPU1_SB_CA(1)   I179 @S9S_MB_2U_LIB.S9S_MB_2U(SCH_1):PAGE113
   211 M_H_CPU1_SA_CA<1> @S9S_MB_2U_LIB.S9S_MB_2U(SCH_1):M_H_CPU1_SA_CA(1)   I179 @S9S_MB_2U_LIB.S9S_MB_2U(SCH_1):PAGE113
    76 M_H_CPU1_SB_CA<0> @S9S_MB_2U_LIB.S9S_MB_2U(SCH_1):M_H_CPU1_SB_CA(0)   I179 @S9S_MB_2U_LIB.S9S_MB_2U(SCH_1):PAGE113
    66 M_H_CPU1_SA_CA<0> @S9S_MB_2U_LIB.S9S_MB_2U(SCH_1):M_H_CPU1_SA_CA(0)   I179 @S9S_MB_2U_LIB.S9S_MB_2U(SCH_1):PAGE113
    62 M_H_CPU1_ALERT_N @S9S_MB_2U_LIB.S9S_MB_2U(SCH_1):M_H_CPU1_ALERT_N   I179 @S9S_MB_2U_LIB.S9S_MB_2U(SCH_1):PAGE113
   236 M_H_CPU1_SB_CB<7> @S9S_MB_2U_LIB.S9S_MB_2U(SCH_1):M_H_CPU1_SB_CB(7)   I179 @S9S_MB_2U_LIB.S9S_MB_2U(SCH_1):PAGE113
    53 M_H_CPU1_SA_CB<1> @S9S_MB_2U_LIB.S9S_MB_2U(SCH_1):M_H_CPU1_SA_CB(1)   I179 @S9S_MB_2U_LIB.S9S_MB_2U(SCH_1):PAGE113
    58 M_H_CPU1_SA_CB<4> @S9S_MB_2U_LIB.S9S_MB_2U(SCH_1):M_H_CPU1_SA_CB(4)   I179 @S9S_MB_2U_LIB.S9S_MB_2U(SCH_1):PAGE113
   205 M_H_CPU1_SA_CB<7> @S9S_MB_2U_LIB.S9S_MB_2U(SCH_1):M_H_CPU1_SA_CB(7)   I179 @S9S_MB_2U_LIB.S9S_MB_2U(SCH_1):PAGE113
   194 M_H_CPU1_SA_DQ<31> @S9S_MB_2U_LIB.S9S_MB_2U(SCH_1):M_H_CPU1_SA_DQ(31)   I179 @S9S_MB_2U_LIB.S9S_MB_2U(SCH_1):PAGE113
    93 M_H_CPU1_SB_DQS_DP<9> @S9S_MB_2U_LIB.S9S_MB_2U(SCH_1):M_H_CPU1_SB_DQS_DP(9)   I180 @S9S_MB_2U_LIB.S9S_MB_2U(SCH_1):PAGE113
    94 M_H_CPU1_SB_DQS_DN<9> @S9S_MB_2U_LIB.S9S_MB_2U(SCH_1):M_H_CPU1_SB_DQS_DN(9)   I180 @S9S_MB_2U_LIB.S9S_MB_2U(SCH_1):PAGE113
   201 M_H_CPU1_SA_DQS_DP<9> @S9S_MB_2U_LIB.S9S_MB_2U(SCH_1):M_H_CPU1_SA_DQS_DP(9)   I180 @S9S_MB_2U_LIB.S9S_MB_2U(SCH_1):PAGE113
   200 M_H_CPU1_SA_DQS_DN<9> @S9S_MB_2U_LIB.S9S_MB_2U(SCH_1):M_H_CPU1_SA_DQS_DN(9)   I180 @S9S_MB_2U_LIB.S9S_MB_2U(SCH_1):PAGE113
   190 M_H_CPU1_SA_DQS_DP<8> @S9S_MB_2U_LIB.S9S_MB_2U(SCH_1):M_H_CPU1_SA_DQS_DP(8)   I180 @S9S_MB_2U_LIB.S9S_MB_2U(SCH_1):PAGE113
   189 M_H_CPU1_SA_DQS_DN<8> @S9S_MB_2U_LIB.S9S_MB_2U(SCH_1):M_H_CPU1_SA_DQS_DN(8)   I180 @S9S_MB_2U_LIB.S9S_MB_2U(SCH_1):PAGE113
   271 M_H_CPU1_SB_DQS_DN<7> @S9S_MB_2U_LIB.S9S_MB_2U(SCH_1):M_H_CPU1_SB_DQS_DN(7)   I180 @S9S_MB_2U_LIB.S9S_MB_2U(SCH_1):PAGE113
   179 M_H_CPU1_SA_DQS_DP<7> @S9S_MB_2U_LIB.S9S_MB_2U(SCH_1):M_H_CPU1_SA_DQS_DP(7)   I180 @S9S_MB_2U_LIB.S9S_MB_2U(SCH_1):PAGE113
   261 M_H_CPU1_SB_DQS_DP<6> @S9S_MB_2U_LIB.S9S_MB_2U(SCH_1):M_H_CPU1_SB_DQS_DP(6)   I180 @S9S_MB_2U_LIB.S9S_MB_2U(SCH_1):PAGE113
   260 M_H_CPU1_SB_DQS_DN<6> @S9S_MB_2U_LIB.S9S_MB_2U(SCH_1):M_H_CPU1_SB_DQS_DN(6)   I180 @S9S_MB_2U_LIB.S9S_MB_2U(SCH_1):PAGE113
   167 M_H_CPU1_SA_DQS_DN<6> @S9S_MB_2U_LIB.S9S_MB_2U(SCH_1):M_H_CPU1_SA_DQS_DN(6)   I180 @S9S_MB_2U_LIB.S9S_MB_2U(SCH_1):PAGE113
   250 M_H_CPU1_SB_DQS_DP<5> @S9S_MB_2U_LIB.S9S_MB_2U(SCH_1):M_H_CPU1_SB_DQS_DP(5)   I180 @S9S_MB_2U_LIB.S9S_MB_2U(SCH_1):PAGE113
   249 M_H_CPU1_SB_DQS_DN<5> @S9S_MB_2U_LIB.S9S_MB_2U(SCH_1):M_H_CPU1_SB_DQS_DN(5)   I180 @S9S_MB_2U_LIB.S9S_MB_2U(SCH_1):PAGE113
   157 M_H_CPU1_SA_DQS_DP<5> @S9S_MB_2U_LIB.S9S_MB_2U(SCH_1):M_H_CPU1_SA_DQS_DP(5)   I180 @S9S_MB_2U_LIB.S9S_MB_2U(SCH_1):PAGE113
   156 M_H_CPU1_SA_DQS_DN<5> @S9S_MB_2U_LIB.S9S_MB_2U(SCH_1):M_H_CPU1_SA_DQS_DN(5)   I180 @S9S_MB_2U_LIB.S9S_MB_2U(SCH_1):PAGE113
   239 M_H_CPU1_SB_DQS_DP<4> @S9S_MB_2U_LIB.S9S_MB_2U(SCH_1):M_H_CPU1_SB_DQS_DP(4)   I180 @S9S_MB_2U_LIB.S9S_MB_2U(SCH_1):PAGE113
   238 M_H_CPU1_SB_DQS_DN<4> @S9S_MB_2U_LIB.S9S_MB_2U(SCH_1):M_H_CPU1_SB_DQS_DN(4)   I180 @S9S_MB_2U_LIB.S9S_MB_2U(SCH_1):PAGE113
    55 M_H_CPU1_SA_DQS_DP<4> @S9S_MB_2U_LIB.S9S_MB_2U(SCH_1):M_H_CPU1_SA_DQS_DP(4)   I180 @S9S_MB_2U_LIB.S9S_MB_2U(SCH_1):PAGE113
    56 M_H_CPU1_SA_DQS_DN<4> @S9S_MB_2U_LIB.S9S_MB_2U(SCH_1):M_H_CPU1_SA_DQS_DN(4)   I180 @S9S_MB_2U_LIB.S9S_MB_2U(SCH_1):PAGE113
   137 M_H_CPU1_SB_DQS_DP<3> @S9S_MB_2U_LIB.S9S_MB_2U(SCH_1):M_H_CPU1_SB_DQS_DP(3)   I180 @S9S_MB_2U_LIB.S9S_MB_2U(SCH_1):PAGE113
   138 M_H_CPU1_SB_DQS_DN<3> @S9S_MB_2U_LIB.S9S_MB_2U(SCH_1):M_H_CPU1_SB_DQS_DN(3)   I180 @S9S_MB_2U_LIB.S9S_MB_2U(SCH_1):PAGE113
    44 M_H_CPU1_SA_DQS_DP<3> @S9S_MB_2U_LIB.S9S_MB_2U(SCH_1):M_H_CPU1_SA_DQS_DP(3)   I180 @S9S_MB_2U_LIB.S9S_MB_2U(SCH_1):PAGE113
    45 M_H_CPU1_SA_DQS_DN<3> @S9S_MB_2U_LIB.S9S_MB_2U(SCH_1):M_H_CPU1_SA_DQS_DN(3)   I180 @S9S_MB_2U_LIB.S9S_MB_2U(SCH_1):PAGE113
   126 M_H_CPU1_SB_DQS_DP<2> @S9S_MB_2U_LIB.S9S_MB_2U(SCH_1):M_H_CPU1_SB_DQS_DP(2)   I180 @S9S_MB_2U_LIB.S9S_MB_2U(SCH_1):PAGE113
   127 M_H_CPU1_SB_DQS_DN<2> @S9S_MB_2U_LIB.S9S_MB_2U(SCH_1):M_H_CPU1_SB_DQS_DN(2)   I180 @S9S_MB_2U_LIB.S9S_MB_2U(SCH_1):PAGE113
    33 M_H_CPU1_SA_DQS_DP<2> @S9S_MB_2U_LIB.S9S_MB_2U(SCH_1):M_H_CPU1_SA_DQS_DP(2)   I180 @S9S_MB_2U_LIB.S9S_MB_2U(SCH_1):PAGE113
    34 M_H_CPU1_SA_DQS_DN<2> @S9S_MB_2U_LIB.S9S_MB_2U(SCH_1):M_H_CPU1_SA_DQS_DN(2)   I180 @S9S_MB_2U_LIB.S9S_MB_2U(SCH_1):PAGE113
   115 M_H_CPU1_SB_DQS_DP<1> @S9S_MB_2U_LIB.S9S_MB_2U(SCH_1):M_H_CPU1_SB_DQS_DP(1)   I180 @S9S_MB_2U_LIB.S9S_MB_2U(SCH_1):PAGE113
   116 M_H_CPU1_SB_DQS_DN<1> @S9S_MB_2U_LIB.S9S_MB_2U(SCH_1):M_H_CPU1_SB_DQS_DN(1)   I180 @S9S_MB_2U_LIB.S9S_MB_2U(SCH_1):PAGE113
    22 M_H_CPU1_SA_DQS_DP<1> @S9S_MB_2U_LIB.S9S_MB_2U(SCH_1):M_H_CPU1_SA_DQS_DP(1)   I180 @S9S_MB_2U_LIB.S9S_MB_2U(SCH_1):PAGE113
    23 M_H_CPU1_SA_DQS_DN<1> @S9S_MB_2U_LIB.S9S_MB_2U(SCH_1):M_H_CPU1_SA_DQS_DN(1)   I180 @S9S_MB_2U_LIB.S9S_MB_2U(SCH_1):PAGE113
   104 M_H_CPU1_SB_DQS_DP<0> @S9S_MB_2U_LIB.S9S_MB_2U(SCH_1):M_H_CPU1_SB_DQS_DP(0)   I180 @S9S_MB_2U_LIB.S9S_MB_2U(SCH_1):PAGE113
   105 M_H_CPU1_SB_DQS_DN<0> @S9S_MB_2U_LIB.S9S_MB_2U(SCH_1):M_H_CPU1_SB_DQS_DN(0)   I180 @S9S_MB_2U_LIB.S9S_MB_2U(SCH_1):PAGE113
    11 M_H_CPU1_SA_DQS_DP<0> @S9S_MB_2U_LIB.S9S_MB_2U(SCH_1):M_H_CPU1_SA_DQS_DP(0)   I180 @S9S_MB_2U_LIB.S9S_MB_2U(SCH_1):PAGE113
    12 M_H_CPU1_SA_DQS_DN<0> @S9S_MB_2U_LIB.S9S_MB_2U(SCH_1):M_H_CPU1_SA_DQS_DN(0)   I180 @S9S_MB_2U_LIB.S9S_MB_2U(SCH_1):PAGE113
   272 M_H_CPU1_SB_DQS_DP<7> @S9S_MB_2U_LIB.S9S_MB_2U(SCH_1):M_H_CPU1_SB_DQS_DP(7)   I180 @S9S_MB_2U_LIB.S9S_MB_2U(SCH_1):PAGE113
   282 M_H_CPU1_SB_DQS_DN<8> @S9S_MB_2U_LIB.S9S_MB_2U(SCH_1):M_H_CPU1_SB_DQS_DN(8)   I180 @S9S_MB_2U_LIB.S9S_MB_2U(SCH_1):PAGE113
   283 M_H_CPU1_SB_DQS_DP<8> @S9S_MB_2U_LIB.S9S_MB_2U(SCH_1):M_H_CPU1_SB_DQS_DP(8)   I180 @S9S_MB_2U_LIB.S9S_MB_2U(SCH_1):PAGE113
   168 M_H_CPU1_SA_DQS_DP<6> @S9S_MB_2U_LIB.S9S_MB_2U(SCH_1):M_H_CPU1_SA_DQS_DP(6)   I180 @S9S_MB_2U_LIB.S9S_MB_2U(SCH_1):PAGE113
   178 M_H_CPU1_SA_DQS_DN<7> @S9S_MB_2U_LIB.S9S_MB_2U(SCH_1):M_H_CPU1_SA_DQS_DN(7)   I180 @S9S_MB_2U_LIB.S9S_MB_2U(SCH_1):PAGE113
     6    GND @S9S_MB_2U_LIB.S9S_MB_2U(SCH_1):GND   I177 @S9S_MB_2U_LIB.S9S_MB_2U(SCH_1):PAGE113
     8    GND @S9S_MB_2U_LIB.S9S_MB_2U(SCH_1):GND   I177 @S9S_MB_2U_LIB.S9S_MB_2U(SCH_1):PAGE113
    10    GND @S9S_MB_2U_LIB.S9S_MB_2U(SCH_1):GND   I177 @S9S_MB_2U_LIB.S9S_MB_2U(SCH_1):PAGE113
    13    GND @S9S_MB_2U_LIB.S9S_MB_2U(SCH_1):GND   I177 @S9S_MB_2U_LIB.S9S_MB_2U(SCH_1):PAGE113
    15    GND @S9S_MB_2U_LIB.S9S_MB_2U(SCH_1):GND   I177 @S9S_MB_2U_LIB.S9S_MB_2U(SCH_1):PAGE113
    17    GND @S9S_MB_2U_LIB.S9S_MB_2U(SCH_1):GND   I177 @S9S_MB_2U_LIB.S9S_MB_2U(SCH_1):PAGE113
    19    GND @S9S_MB_2U_LIB.S9S_MB_2U(SCH_1):GND   I177 @S9S_MB_2U_LIB.S9S_MB_2U(SCH_1):PAGE113
    21    GND @S9S_MB_2U_LIB.S9S_MB_2U(SCH_1):GND   I177 @S9S_MB_2U_LIB.S9S_MB_2U(SCH_1):PAGE113
    24    GND @S9S_MB_2U_LIB.S9S_MB_2U(SCH_1):GND   I177 @S9S_MB_2U_LIB.S9S_MB_2U(SCH_1):PAGE113
    26    GND @S9S_MB_2U_LIB.S9S_MB_2U(SCH_1):GND   I177 @S9S_MB_2U_LIB.S9S_MB_2U(SCH_1):PAGE113
    28    GND @S9S_MB_2U_LIB.S9S_MB_2U(SCH_1):GND   I177 @S9S_MB_2U_LIB.S9S_MB_2U(SCH_1):PAGE113
    30    GND @S9S_MB_2U_LIB.S9S_MB_2U(SCH_1):GND   I177 @S9S_MB_2U_LIB.S9S_MB_2U(SCH_1):PAGE113
    32    GND @S9S_MB_2U_LIB.S9S_MB_2U(SCH_1):GND   I177 @S9S_MB_2U_LIB.S9S_MB_2U(SCH_1):PAGE113
    35    GND @S9S_MB_2U_LIB.S9S_MB_2U(SCH_1):GND   I177 @S9S_MB_2U_LIB.S9S_MB_2U(SCH_1):PAGE113
    37    GND @S9S_MB_2U_LIB.S9S_MB_2U(SCH_1):GND   I177 @S9S_MB_2U_LIB.S9S_MB_2U(SCH_1):PAGE113
    39    GND @S9S_MB_2U_LIB.S9S_MB_2U(SCH_1):GND   I177 @S9S_MB_2U_LIB.S9S_MB_2U(SCH_1):PAGE113
    41    GND @S9S_MB_2U_LIB.S9S_MB_2U(SCH_1):GND   I177 @S9S_MB_2U_LIB.S9S_MB_2U(SCH_1):PAGE113
    43    GND @S9S_MB_2U_LIB.S9S_MB_2U(SCH_1):GND   I177 @S9S_MB_2U_LIB.S9S_MB_2U(SCH_1):PAGE113
    46    GND @S9S_MB_2U_LIB.S9S_MB_2U(SCH_1):GND   I177 @S9S_MB_2U_LIB.S9S_MB_2U(SCH_1):PAGE113
    48    GND @S9S_MB_2U_LIB.S9S_MB_2U(SCH_1):GND   I177 @S9S_MB_2U_LIB.S9S_MB_2U(SCH_1):PAGE113
    50    GND @S9S_MB_2U_LIB.S9S_MB_2U(SCH_1):GND   I177 @S9S_MB_2U_LIB.S9S_MB_2U(SCH_1):PAGE113
    52    GND @S9S_MB_2U_LIB.S9S_MB_2U(SCH_1):GND   I177 @S9S_MB_2U_LIB.S9S_MB_2U(SCH_1):PAGE113
    54    GND @S9S_MB_2U_LIB.S9S_MB_2U(SCH_1):GND   I177 @S9S_MB_2U_LIB.S9S_MB_2U(SCH_1):PAGE113
    57    GND @S9S_MB_2U_LIB.S9S_MB_2U(SCH_1):GND   I177 @S9S_MB_2U_LIB.S9S_MB_2U(SCH_1):PAGE113
    59    GND @S9S_MB_2U_LIB.S9S_MB_2U(SCH_1):GND   I177 @S9S_MB_2U_LIB.S9S_MB_2U(SCH_1):PAGE113
    61    GND @S9S_MB_2U_LIB.S9S_MB_2U(SCH_1):GND   I177 @S9S_MB_2U_LIB.S9S_MB_2U(SCH_1):PAGE113
    63    GND @S9S_MB_2U_LIB.S9S_MB_2U(SCH_1):GND   I177 @S9S_MB_2U_LIB.S9S_MB_2U(SCH_1):PAGE113
    65    GND @S9S_MB_2U_LIB.S9S_MB_2U(SCH_1):GND   I177 @S9S_MB_2U_LIB.S9S_MB_2U(SCH_1):PAGE113
    67    GND @S9S_MB_2U_LIB.S9S_MB_2U(SCH_1):GND   I177 @S9S_MB_2U_LIB.S9S_MB_2U(SCH_1):PAGE113
    69    GND @S9S_MB_2U_LIB.S9S_MB_2U(SCH_1):GND   I177 @S9S_MB_2U_LIB.S9S_MB_2U(SCH_1):PAGE113
    71    GND @S9S_MB_2U_LIB.S9S_MB_2U(SCH_1):GND   I177 @S9S_MB_2U_LIB.S9S_MB_2U(SCH_1):PAGE113
    73    GND @S9S_MB_2U_LIB.S9S_MB_2U(SCH_1):GND   I177 @S9S_MB_2U_LIB.S9S_MB_2U(SCH_1):PAGE113
    75    GND @S9S_MB_2U_LIB.S9S_MB_2U(SCH_1):GND   I177 @S9S_MB_2U_LIB.S9S_MB_2U(SCH_1):PAGE113
    77    GND @S9S_MB_2U_LIB.S9S_MB_2U(SCH_1):GND   I177 @S9S_MB_2U_LIB.S9S_MB_2U(SCH_1):PAGE113
    79    GND @S9S_MB_2U_LIB.S9S_MB_2U(SCH_1):GND   I177 @S9S_MB_2U_LIB.S9S_MB_2U(SCH_1):PAGE113
    81    GND @S9S_MB_2U_LIB.S9S_MB_2U(SCH_1):GND   I177 @S9S_MB_2U_LIB.S9S_MB_2U(SCH_1):PAGE113
    83    GND @S9S_MB_2U_LIB.S9S_MB_2U(SCH_1):GND   I177 @S9S_MB_2U_LIB.S9S_MB_2U(SCH_1):PAGE113
    85    GND @S9S_MB_2U_LIB.S9S_MB_2U(SCH_1):GND   I177 @S9S_MB_2U_LIB.S9S_MB_2U(SCH_1):PAGE113
    88    GND @S9S_MB_2U_LIB.S9S_MB_2U(SCH_1):GND   I177 @S9S_MB_2U_LIB.S9S_MB_2U(SCH_1):PAGE113
    90    GND @S9S_MB_2U_LIB.S9S_MB_2U(SCH_1):GND   I177 @S9S_MB_2U_LIB.S9S_MB_2U(SCH_1):PAGE113
    92    GND @S9S_MB_2U_LIB.S9S_MB_2U(SCH_1):GND   I177 @S9S_MB_2U_LIB.S9S_MB_2U(SCH_1):PAGE113
    95    GND @S9S_MB_2U_LIB.S9S_MB_2U(SCH_1):GND   I177 @S9S_MB_2U_LIB.S9S_MB_2U(SCH_1):PAGE113
    97    GND @S9S_MB_2U_LIB.S9S_MB_2U(SCH_1):GND   I177 @S9S_MB_2U_LIB.S9S_MB_2U(SCH_1):PAGE113
    99    GND @S9S_MB_2U_LIB.S9S_MB_2U(SCH_1):GND   I177 @S9S_MB_2U_LIB.S9S_MB_2U(SCH_1):PAGE113
   101    GND @S9S_MB_2U_LIB.S9S_MB_2U(SCH_1):GND   I177 @S9S_MB_2U_LIB.S9S_MB_2U(SCH_1):PAGE113
   103    GND @S9S_MB_2U_LIB.S9S_MB_2U(SCH_1):GND   I177 @S9S_MB_2U_LIB.S9S_MB_2U(SCH_1):PAGE113
   106    GND @S9S_MB_2U_LIB.S9S_MB_2U(SCH_1):GND   I177 @S9S_MB_2U_LIB.S9S_MB_2U(SCH_1):PAGE113
   108    GND @S9S_MB_2U_LIB.S9S_MB_2U(SCH_1):GND   I177 @S9S_MB_2U_LIB.S9S_MB_2U(SCH_1):PAGE113
   110    GND @S9S_MB_2U_LIB.S9S_MB_2U(SCH_1):GND   I177 @S9S_MB_2U_LIB.S9S_MB_2U(SCH_1):PAGE113
   112    GND @S9S_MB_2U_LIB.S9S_MB_2U(SCH_1):GND   I177 @S9S_MB_2U_LIB.S9S_MB_2U(SCH_1):PAGE113
   114    GND @S9S_MB_2U_LIB.S9S_MB_2U(SCH_1):GND   I177 @S9S_MB_2U_LIB.S9S_MB_2U(SCH_1):PAGE113
   117    GND @S9S_MB_2U_LIB.S9S_MB_2U(SCH_1):GND   I177 @S9S_MB_2U_LIB.S9S_MB_2U(SCH_1):PAGE113
   119    GND @S9S_MB_2U_LIB.S9S_MB_2U(SCH_1):GND   I177 @S9S_MB_2U_LIB.S9S_MB_2U(SCH_1):PAGE113
   121    GND @S9S_MB_2U_LIB.S9S_MB_2U(SCH_1):GND   I177 @S9S_MB_2U_LIB.S9S_MB_2U(SCH_1):PAGE113
   123    GND @S9S_MB_2U_LIB.S9S_MB_2U(SCH_1):GND   I177 @S9S_MB_2U_LIB.S9S_MB_2U(SCH_1):PAGE113
   125    GND @S9S_MB_2U_LIB.S9S_MB_2U(SCH_1):GND   I177 @S9S_MB_2U_LIB.S9S_MB_2U(SCH_1):PAGE113
   128    GND @S9S_MB_2U_LIB.S9S_MB_2U(SCH_1):GND   I177 @S9S_MB_2U_LIB.S9S_MB_2U(SCH_1):PAGE113
   130    GND @S9S_MB_2U_LIB.S9S_MB_2U(SCH_1):GND   I177 @S9S_MB_2U_LIB.S9S_MB_2U(SCH_1):PAGE113
   134    GND @S9S_MB_2U_LIB.S9S_MB_2U(SCH_1):GND   I177 @S9S_MB_2U_LIB.S9S_MB_2U(SCH_1):PAGE113
   143    GND @S9S_MB_2U_LIB.S9S_MB_2U(SCH_1):GND   I177 @S9S_MB_2U_LIB.S9S_MB_2U(SCH_1):PAGE113
   151    GND @S9S_MB_2U_LIB.S9S_MB_2U(SCH_1):GND   I177 @S9S_MB_2U_LIB.S9S_MB_2U(SCH_1):PAGE113
   153    GND @S9S_MB_2U_LIB.S9S_MB_2U(SCH_1):GND   I177 @S9S_MB_2U_LIB.S9S_MB_2U(SCH_1):PAGE113
   155    GND @S9S_MB_2U_LIB.S9S_MB_2U(SCH_1):GND   I177 @S9S_MB_2U_LIB.S9S_MB_2U(SCH_1):PAGE113
   158    GND @S9S_MB_2U_LIB.S9S_MB_2U(SCH_1):GND   I177 @S9S_MB_2U_LIB.S9S_MB_2U(SCH_1):PAGE113
   160    GND @S9S_MB_2U_LIB.S9S_MB_2U(SCH_1):GND   I177 @S9S_MB_2U_LIB.S9S_MB_2U(SCH_1):PAGE113
   162    GND @S9S_MB_2U_LIB.S9S_MB_2U(SCH_1):GND   I177 @S9S_MB_2U_LIB.S9S_MB_2U(SCH_1):PAGE113
   164    GND @S9S_MB_2U_LIB.S9S_MB_2U(SCH_1):GND   I177 @S9S_MB_2U_LIB.S9S_MB_2U(SCH_1):PAGE113
   166    GND @S9S_MB_2U_LIB.S9S_MB_2U(SCH_1):GND   I177 @S9S_MB_2U_LIB.S9S_MB_2U(SCH_1):PAGE113
   169    GND @S9S_MB_2U_LIB.S9S_MB_2U(SCH_1):GND   I177 @S9S_MB_2U_LIB.S9S_MB_2U(SCH_1):PAGE113
   171    GND @S9S_MB_2U_LIB.S9S_MB_2U(SCH_1):GND   I177 @S9S_MB_2U_LIB.S9S_MB_2U(SCH_1):PAGE113
   173    GND @S9S_MB_2U_LIB.S9S_MB_2U(SCH_1):GND   I177 @S9S_MB_2U_LIB.S9S_MB_2U(SCH_1):PAGE113
   175    GND @S9S_MB_2U_LIB.S9S_MB_2U(SCH_1):GND   I177 @S9S_MB_2U_LIB.S9S_MB_2U(SCH_1):PAGE113
   177    GND @S9S_MB_2U_LIB.S9S_MB_2U(SCH_1):GND   I177 @S9S_MB_2U_LIB.S9S_MB_2U(SCH_1):PAGE113
   180    GND @S9S_MB_2U_LIB.S9S_MB_2U(SCH_1):GND   I177 @S9S_MB_2U_LIB.S9S_MB_2U(SCH_1):PAGE113
   182    GND @S9S_MB_2U_LIB.S9S_MB_2U(SCH_1):GND   I177 @S9S_MB_2U_LIB.S9S_MB_2U(SCH_1):PAGE113
   184    GND @S9S_MB_2U_LIB.S9S_MB_2U(SCH_1):GND   I177 @S9S_MB_2U_LIB.S9S_MB_2U(SCH_1):PAGE113
   186    GND @S9S_MB_2U_LIB.S9S_MB_2U(SCH_1):GND   I177 @S9S_MB_2U_LIB.S9S_MB_2U(SCH_1):PAGE113
   188    GND @S9S_MB_2U_LIB.S9S_MB_2U(SCH_1):GND   I177 @S9S_MB_2U_LIB.S9S_MB_2U(SCH_1):PAGE113
   191    GND @S9S_MB_2U_LIB.S9S_MB_2U(SCH_1):GND   I177 @S9S_MB_2U_LIB.S9S_MB_2U(SCH_1):PAGE113
   193    GND @S9S_MB_2U_LIB.S9S_MB_2U(SCH_1):GND   I177 @S9S_MB_2U_LIB.S9S_MB_2U(SCH_1):PAGE113
   195    GND @S9S_MB_2U_LIB.S9S_MB_2U(SCH_1):GND   I177 @S9S_MB_2U_LIB.S9S_MB_2U(SCH_1):PAGE113
   197    GND @S9S_MB_2U_LIB.S9S_MB_2U(SCH_1):GND   I177 @S9S_MB_2U_LIB.S9S_MB_2U(SCH_1):PAGE113
   199    GND @S9S_MB_2U_LIB.S9S_MB_2U(SCH_1):GND   I177 @S9S_MB_2U_LIB.S9S_MB_2U(SCH_1):PAGE113
   202    GND @S9S_MB_2U_LIB.S9S_MB_2U(SCH_1):GND   I177 @S9S_MB_2U_LIB.S9S_MB_2U(SCH_1):PAGE113
   204    GND @S9S_MB_2U_LIB.S9S_MB_2U(SCH_1):GND   I177 @S9S_MB_2U_LIB.S9S_MB_2U(SCH_1):PAGE113
   206    GND @S9S_MB_2U_LIB.S9S_MB_2U(SCH_1):GND   I177 @S9S_MB_2U_LIB.S9S_MB_2U(SCH_1):PAGE113
   208    GND @S9S_MB_2U_LIB.S9S_MB_2U(SCH_1):GND   I177 @S9S_MB_2U_LIB.S9S_MB_2U(SCH_1):PAGE113
   210    GND @S9S_MB_2U_LIB.S9S_MB_2U(SCH_1):GND   I177 @S9S_MB_2U_LIB.S9S_MB_2U(SCH_1):PAGE113
   212    GND @S9S_MB_2U_LIB.S9S_MB_2U(SCH_1):GND   I177 @S9S_MB_2U_LIB.S9S_MB_2U(SCH_1):PAGE113
   214    GND @S9S_MB_2U_LIB.S9S_MB_2U(SCH_1):GND   I177 @S9S_MB_2U_LIB.S9S_MB_2U(SCH_1):PAGE113
   216    GND @S9S_MB_2U_LIB.S9S_MB_2U(SCH_1):GND   I177 @S9S_MB_2U_LIB.S9S_MB_2U(SCH_1):PAGE113
   219    GND @S9S_MB_2U_LIB.S9S_MB_2U(SCH_1):GND   I177 @S9S_MB_2U_LIB.S9S_MB_2U(SCH_1):PAGE113
   222    GND @S9S_MB_2U_LIB.S9S_MB_2U(SCH_1):GND   I177 @S9S_MB_2U_LIB.S9S_MB_2U(SCH_1):PAGE113
   224    GND @S9S_MB_2U_LIB.S9S_MB_2U(SCH_1):GND   I177 @S9S_MB_2U_LIB.S9S_MB_2U(SCH_1):PAGE113
   226    GND @S9S_MB_2U_LIB.S9S_MB_2U(SCH_1):GND   I177 @S9S_MB_2U_LIB.S9S_MB_2U(SCH_1):PAGE113
   228    GND @S9S_MB_2U_LIB.S9S_MB_2U(SCH_1):GND   I177 @S9S_MB_2U_LIB.S9S_MB_2U(SCH_1):PAGE113
   233    GND @S9S_MB_2U_LIB.S9S_MB_2U(SCH_1):GND   I177 @S9S_MB_2U_LIB.S9S_MB_2U(SCH_1):PAGE113
   237    GND @S9S_MB_2U_LIB.S9S_MB_2U(SCH_1):GND   I177 @S9S_MB_2U_LIB.S9S_MB_2U(SCH_1):PAGE113
   242    GND @S9S_MB_2U_LIB.S9S_MB_2U(SCH_1):GND   I177 @S9S_MB_2U_LIB.S9S_MB_2U(SCH_1):PAGE113
   244    GND @S9S_MB_2U_LIB.S9S_MB_2U(SCH_1):GND   I177 @S9S_MB_2U_LIB.S9S_MB_2U(SCH_1):PAGE113
   246    GND @S9S_MB_2U_LIB.S9S_MB_2U(SCH_1):GND   I177 @S9S_MB_2U_LIB.S9S_MB_2U(SCH_1):PAGE113
   248    GND @S9S_MB_2U_LIB.S9S_MB_2U(SCH_1):GND   I177 @S9S_MB_2U_LIB.S9S_MB_2U(SCH_1):PAGE113
   251    GND @S9S_MB_2U_LIB.S9S_MB_2U(SCH_1):GND   I177 @S9S_MB_2U_LIB.S9S_MB_2U(SCH_1):PAGE113
   253    GND @S9S_MB_2U_LIB.S9S_MB_2U(SCH_1):GND   I177 @S9S_MB_2U_LIB.S9S_MB_2U(SCH_1):PAGE113
   255    GND @S9S_MB_2U_LIB.S9S_MB_2U(SCH_1):GND   I177 @S9S_MB_2U_LIB.S9S_MB_2U(SCH_1):PAGE113
   257    GND @S9S_MB_2U_LIB.S9S_MB_2U(SCH_1):GND   I177 @S9S_MB_2U_LIB.S9S_MB_2U(SCH_1):PAGE113
   259    GND @S9S_MB_2U_LIB.S9S_MB_2U(SCH_1):GND   I177 @S9S_MB_2U_LIB.S9S_MB_2U(SCH_1):PAGE113
   262    GND @S9S_MB_2U_LIB.S9S_MB_2U(SCH_1):GND   I177 @S9S_MB_2U_LIB.S9S_MB_2U(SCH_1):PAGE113
   264    GND @S9S_MB_2U_LIB.S9S_MB_2U(SCH_1):GND   I177 @S9S_MB_2U_LIB.S9S_MB_2U(SCH_1):PAGE113
   266    GND @S9S_MB_2U_LIB.S9S_MB_2U(SCH_1):GND   I177 @S9S_MB_2U_LIB.S9S_MB_2U(SCH_1):PAGE113
   268    GND @S9S_MB_2U_LIB.S9S_MB_2U(SCH_1):GND   I177 @S9S_MB_2U_LIB.S9S_MB_2U(SCH_1):PAGE113
   270    GND @S9S_MB_2U_LIB.S9S_MB_2U(SCH_1):GND   I177 @S9S_MB_2U_LIB.S9S_MB_2U(SCH_1):PAGE113
   273    GND @S9S_MB_2U_LIB.S9S_MB_2U(SCH_1):GND   I177 @S9S_MB_2U_LIB.S9S_MB_2U(SCH_1):PAGE113
   275    GND @S9S_MB_2U_LIB.S9S_MB_2U(SCH_1):GND   I177 @S9S_MB_2U_LIB.S9S_MB_2U(SCH_1):PAGE113
   277    GND @S9S_MB_2U_LIB.S9S_MB_2U(SCH_1):GND   I177 @S9S_MB_2U_LIB.S9S_MB_2U(SCH_1):PAGE113
   279    GND @S9S_MB_2U_LIB.S9S_MB_2U(SCH_1):GND   I177 @S9S_MB_2U_LIB.S9S_MB_2U(SCH_1):PAGE113
   281    GND @S9S_MB_2U_LIB.S9S_MB_2U(SCH_1):GND   I177 @S9S_MB_2U_LIB.S9S_MB_2U(SCH_1):PAGE113
   284    GND @S9S_MB_2U_LIB.S9S_MB_2U(SCH_1):GND   I177 @S9S_MB_2U_LIB.S9S_MB_2U(SCH_1):PAGE113
   286    GND @S9S_MB_2U_LIB.S9S_MB_2U(SCH_1):GND   I177 @S9S_MB_2U_LIB.S9S_MB_2U(SCH_1):PAGE113
   288    GND @S9S_MB_2U_LIB.S9S_MB_2U(SCH_1):GND   I177 @S9S_MB_2U_LIB.S9S_MB_2U(SCH_1):PAGE113
     1 P12V_S3_AUX_CPU1_NVDIMM @S9S_MB_2U_LIB.S9S_MB_2U(SCH_1):P12V_S3_AUX_CPU1_NVDIMM   I177 @S9S_MB_2U_LIB.S9S_MB_2U(SCH_1):PAGE113
   145 P12V_S3_AUX_CPU1_NVDIMM @S9S_MB_2U_LIB.S9S_MB_2U(SCH_1):P12V_S3_AUX_CPU1_NVDIMM   I177 @S9S_MB_2U_LIB.S9S_MB_2U(SCH_1):PAGE113
   146 P12V_S3_AUX_CPU1_NVDIMM @S9S_MB_2U_LIB.S9S_MB_2U(SCH_1):P12V_S3_AUX_CPU1_NVDIMM   I177 @S9S_MB_2U_LIB.S9S_MB_2U(SCH_1):PAGE113
   230    GND @S9S_MB_2U_LIB.S9S_MB_2U(SCH_1):GND   I177 @S9S_MB_2U_LIB.S9S_MB_2U(SCH_1):PAGE113
   235    GND @S9S_MB_2U_LIB.S9S_MB_2U(SCH_1):GND   I177 @S9S_MB_2U_LIB.S9S_MB_2U(SCH_1):PAGE113
   240    GND @S9S_MB_2U_LIB.S9S_MB_2U(SCH_1):GND   I177 @S9S_MB_2U_LIB.S9S_MB_2U(SCH_1):PAGE113
   132    GND @S9S_MB_2U_LIB.S9S_MB_2U(SCH_1):GND   I177 @S9S_MB_2U_LIB.S9S_MB_2U(SCH_1):PAGE113
   136    GND @S9S_MB_2U_LIB.S9S_MB_2U(SCH_1):GND   I177 @S9S_MB_2U_LIB.S9S_MB_2U(SCH_1):PAGE113
   139    GND @S9S_MB_2U_LIB.S9S_MB_2U(SCH_1):GND   I177 @S9S_MB_2U_LIB.S9S_MB_2U(SCH_1):PAGE113
   141    GND @S9S_MB_2U_LIB.S9S_MB_2U(SCH_1):GND   I177 @S9S_MB_2U_LIB.S9S_MB_2U(SCH_1):PAGE113
    G1    GND @S9S_MB_2U_LIB.S9S_MB_2U(SCH_1):GND   I177 @S9S_MB_2U_LIB.S9S_MB_2U(SCH_1):PAGE113
    G2    GND @S9S_MB_2U_LIB.S9S_MB_2U(SCH_1):GND   I177 @S9S_MB_2U_LIB.S9S_MB_2U(SCH_1):PAGE113
    G3    GND @S9S_MB_2U_LIB.S9S_MB_2U(SCH_1):GND   I177 @S9S_MB_2U_LIB.S9S_MB_2U(SCH_1):PAGE113

 J35 SCONN168_ME1016810202011-SCONNA
   OB1 FM_OCP_V3_2_PWR_GOOD @S9S_MB_2U_LIB.S9S_MB_2U(SCH_1):FM_OCP_V3_2_PWR_GOOD   I303 @S9S_MB_2U_LIB.S9S_MB_2U(SCH_1):PAGE146
   OB2 OCP_V3_2_MAIN_PWR_EN_R @S9S_MB_2U_LIB.S9S_MB_2U(SCH_1):OCP_V3_2_MAIN_PWR_EN_R   I303 @S9S_MB_2U_LIB.S9S_MB_2U(SCH_1):PAGE146
   OB3 SGPIO_OCP_V3_2_LD_N @S9S_MB_2U_LIB.S9S_MB_2U(SCH_1):SGPIO_OCP_V3_2_LD_N   I303 @S9S_MB_2U_LIB.S9S_MB_2U(SCH_1):PAGE146
   OB4 SGPIO_OCP_V3_2_DATAIN @S9S_MB_2U_LIB.S9S_MB_2U(SCH_1):SGPIO_OCP_V3_2_DATAIN   I303 @S9S_MB_2U_LIB.S9S_MB_2U(SCH_1):PAGE146
   OB5 SGPIO_OCP_V3_2_DATAOUT @S9S_MB_2U_LIB.S9S_MB_2U(SCH_1):SGPIO_OCP_V3_2_DATAOUT   I303 @S9S_MB_2U_LIB.S9S_MB_2U(SCH_1):PAGE146
   OB6 SGPIO_OCP_V3_2_CLK @S9S_MB_2U_LIB.S9S_MB_2U(SCH_1):SGPIO_OCP_V3_2_CLK   I303 @S9S_MB_2U_LIB.S9S_MB_2U(SCH_1):PAGE146
   OB7 OCP_V3_2_ID0 @S9S_MB_2U_LIB.S9S_MB_2U(SCH_1):OCP_V3_2_ID0   I303 @S9S_MB_2U_LIB.S9S_MB_2U(SCH_1):PAGE146
   OB8 NCSI_OCP_V3_2_RXD1 @S9S_MB_2U_LIB.S9S_MB_2U(SCH_1):NCSI_OCP_V3_2_RXD1   I303 @S9S_MB_2U_LIB.S9S_MB_2U(SCH_1):PAGE146
   OB9 NCSI_OCP_V3_2_RXD0 @S9S_MB_2U_LIB.S9S_MB_2U(SCH_1):NCSI_OCP_V3_2_RXD0   I303 @S9S_MB_2U_LIB.S9S_MB_2U(SCH_1):PAGE146
  OB10    GND @S9S_MB_2U_LIB.S9S_MB_2U(SCH_1):GND   I303 @S9S_MB_2U_LIB.S9S_MB_2U(SCH_1):PAGE146
  OB11 CLK_100M_OCP_V3_2_C_DN @S9S_MB_2U_LIB.S9S_MB_2U(SCH_1):CLK_100M_OCP_V3_2_C_DN   I303 @S9S_MB_2U_LIB.S9S_MB_2U(SCH_1):PAGE146
  OB12 CLK_100M_OCP_V3_2_C_DP @S9S_MB_2U_LIB.S9S_MB_2U(SCH_1):CLK_100M_OCP_V3_2_C_DP   I303 @S9S_MB_2U_LIB.S9S_MB_2U(SCH_1):PAGE146
  OB13    GND @S9S_MB_2U_LIB.S9S_MB_2U(SCH_1):GND   I303 @S9S_MB_2U_LIB.S9S_MB_2U(SCH_1):PAGE146
  OB14 NCSI_OCP_V3_2_CRS_DV @S9S_MB_2U_LIB.S9S_MB_2U(SCH_1):NCSI_OCP_V3_2_CRS_DV   I303 @S9S_MB_2U_LIB.S9S_MB_2U(SCH_1):PAGE146
    B1 P12V_OCP_V3_2 @S9S_MB_2U_LIB.S9S_MB_2U(SCH_1):P12V_OCP_V3_2   I303 @S9S_MB_2U_LIB.S9S_MB_2U(SCH_1):PAGE146
    B2 P12V_OCP_V3_2 @S9S_MB_2U_LIB.S9S_MB_2U(SCH_1):P12V_OCP_V3_2   I303 @S9S_MB_2U_LIB.S9S_MB_2U(SCH_1):PAGE146
    B3 P12V_OCP_V3_2 @S9S_MB_2U_LIB.S9S_MB_2U(SCH_1):P12V_OCP_V3_2   I303 @S9S_MB_2U_LIB.S9S_MB_2U(SCH_1):PAGE146
    B4 P12V_OCP_V3_2 @S9S_MB_2U_LIB.S9S_MB_2U(SCH_1):P12V_OCP_V3_2   I303 @S9S_MB_2U_LIB.S9S_MB_2U(SCH_1):PAGE146
    B5 P12V_OCP_V3_2 @S9S_MB_2U_LIB.S9S_MB_2U(SCH_1):P12V_OCP_V3_2   I303 @S9S_MB_2U_LIB.S9S_MB_2U(SCH_1):PAGE146
    B6 P12V_OCP_V3_2 @S9S_MB_2U_LIB.S9S_MB_2U(SCH_1):P12V_OCP_V3_2   I303 @S9S_MB_2U_LIB.S9S_MB_2U(SCH_1):PAGE146
    B7 OCP_V3_2_BIF0_R_N @S9S_MB_2U_LIB.S9S_MB_2U(SCH_1):OCP_V3_2_BIF0_R_N   I303 @S9S_MB_2U_LIB.S9S_MB_2U(SCH_1):PAGE146
    B8 OCP_V3_2_BIF1_R_N @S9S_MB_2U_LIB.S9S_MB_2U(SCH_1):OCP_V3_2_BIF1_R_N   I303 @S9S_MB_2U_LIB.S9S_MB_2U(SCH_1):PAGE146
    B9 OCP_V3_2_BIF2_R_N @S9S_MB_2U_LIB.S9S_MB_2U(SCH_1):OCP_V3_2_BIF2_R_N   I303 @S9S_MB_2U_LIB.S9S_MB_2U(SCH_1):PAGE146
   B10 RST_PERST0_OCP_V3_2_N @S9S_MB_2U_LIB.S9S_MB_2U(SCH_1):RST_PERST0_OCP_V3_2_N   I303 @S9S_MB_2U_LIB.S9S_MB_2U(SCH_1):PAGE146
   B11 P3V3_OCP_V3_2 @S9S_MB_2U_LIB.S9S_MB_2U(SCH_1):P3V3_OCP_V3_2   I303 @S9S_MB_2U_LIB.S9S_MB_2U(SCH_1):PAGE146
   B12 OCP_V3_2_AUX_PWR_EN_R @S9S_MB_2U_LIB.S9S_MB_2U(SCH_1):OCP_V3_2_AUX_PWR_EN_R   I303 @S9S_MB_2U_LIB.S9S_MB_2U(SCH_1):PAGE146
   B13    GND @S9S_MB_2U_LIB.S9S_MB_2U(SCH_1):GND   I303 @S9S_MB_2U_LIB.S9S_MB_2U(SCH_1):PAGE146
   B14 CLK_100M_OCP_V3_2_A_DN @S9S_MB_2U_LIB.S9S_MB_2U(SCH_1):CLK_100M_OCP_V3_2_A_DN   I303 @S9S_MB_2U_LIB.S9S_MB_2U(SCH_1):PAGE146
   B15 CLK_100M_OCP_V3_2_A_DP @S9S_MB_2U_LIB.S9S_MB_2U(SCH_1):CLK_100M_OCP_V3_2_A_DP   I303 @S9S_MB_2U_LIB.S9S_MB_2U(SCH_1):PAGE146
   B16    GND @S9S_MB_2U_LIB.S9S_MB_2U(SCH_1):GND   I303 @S9S_MB_2U_LIB.S9S_MB_2U(SCH_1):PAGE146
   B17 P5E_CPU1_PE1_TX_C_DP<0> @S9S_MB_2U_LIB.S9S_MB_2U(SCH_1):P5E_CPU1_PE1_TX_C_DP(0)   I303 @S9S_MB_2U_LIB.S9S_MB_2U(SCH_1):PAGE146
   B18 P5E_CPU1_PE1_TX_C_DN<0> @S9S_MB_2U_LIB.S9S_MB_2U(SCH_1):P5E_CPU1_PE1_TX_C_DN(0)   I303 @S9S_MB_2U_LIB.S9S_MB_2U(SCH_1):PAGE146
   B19    GND @S9S_MB_2U_LIB.S9S_MB_2U(SCH_1):GND   I303 @S9S_MB_2U_LIB.S9S_MB_2U(SCH_1):PAGE146
   B20 P5E_CPU1_PE1_TX_C_DN<1> @S9S_MB_2U_LIB.S9S_MB_2U(SCH_1):P5E_CPU1_PE1_TX_C_DN(1)   I303 @S9S_MB_2U_LIB.S9S_MB_2U(SCH_1):PAGE146
   B21 P5E_CPU1_PE1_TX_C_DP<1> @S9S_MB_2U_LIB.S9S_MB_2U(SCH_1):P5E_CPU1_PE1_TX_C_DP(1)   I303 @S9S_MB_2U_LIB.S9S_MB_2U(SCH_1):PAGE146
   B22    GND @S9S_MB_2U_LIB.S9S_MB_2U(SCH_1):GND   I303 @S9S_MB_2U_LIB.S9S_MB_2U(SCH_1):PAGE146
   B23 P5E_CPU1_PE1_TX_C_DP<2> @S9S_MB_2U_LIB.S9S_MB_2U(SCH_1):P5E_CPU1_PE1_TX_C_DP(2)   I303 @S9S_MB_2U_LIB.S9S_MB_2U(SCH_1):PAGE146
   B24 P5E_CPU1_PE1_TX_C_DN<2> @S9S_MB_2U_LIB.S9S_MB_2U(SCH_1):P5E_CPU1_PE1_TX_C_DN(2)   I303 @S9S_MB_2U_LIB.S9S_MB_2U(SCH_1):PAGE146
   B25    GND @S9S_MB_2U_LIB.S9S_MB_2U(SCH_1):GND   I303 @S9S_MB_2U_LIB.S9S_MB_2U(SCH_1):PAGE146
   B26 P5E_CPU1_PE1_TX_C_DN<3> @S9S_MB_2U_LIB.S9S_MB_2U(SCH_1):P5E_CPU1_PE1_TX_C_DN(3)   I303 @S9S_MB_2U_LIB.S9S_MB_2U(SCH_1):PAGE146
   B27 P5E_CPU1_PE1_TX_C_DP<3> @S9S_MB_2U_LIB.S9S_MB_2U(SCH_1):P5E_CPU1_PE1_TX_C_DP(3)   I303 @S9S_MB_2U_LIB.S9S_MB_2U(SCH_1):PAGE146
   B28    GND @S9S_MB_2U_LIB.S9S_MB_2U(SCH_1):GND   I303 @S9S_MB_2U_LIB.S9S_MB_2U(SCH_1):PAGE146
   B29    GND @S9S_MB_2U_LIB.S9S_MB_2U(SCH_1):GND   I303 @S9S_MB_2U_LIB.S9S_MB_2U(SCH_1):PAGE146
   B30 P5E_CPU1_PE1_TX_C_DP<4> @S9S_MB_2U_LIB.S9S_MB_2U(SCH_1):P5E_CPU1_PE1_TX_C_DP(4)   I303 @S9S_MB_2U_LIB.S9S_MB_2U(SCH_1):PAGE146
   B31 P5E_CPU1_PE1_TX_C_DN<4> @S9S_MB_2U_LIB.S9S_MB_2U(SCH_1):P5E_CPU1_PE1_TX_C_DN(4)   I303 @S9S_MB_2U_LIB.S9S_MB_2U(SCH_1):PAGE146
   B32    GND @S9S_MB_2U_LIB.S9S_MB_2U(SCH_1):GND   I303 @S9S_MB_2U_LIB.S9S_MB_2U(SCH_1):PAGE146
   B33 P5E_CPU1_PE1_TX_C_DN<5> @S9S_MB_2U_LIB.S9S_MB_2U(SCH_1):P5E_CPU1_PE1_TX_C_DN(5)   I303 @S9S_MB_2U_LIB.S9S_MB_2U(SCH_1):PAGE146
   B34 P5E_CPU1_PE1_TX_C_DP<5> @S9S_MB_2U_LIB.S9S_MB_2U(SCH_1):P5E_CPU1_PE1_TX_C_DP(5)   I303 @S9S_MB_2U_LIB.S9S_MB_2U(SCH_1):PAGE146
   B35    GND @S9S_MB_2U_LIB.S9S_MB_2U(SCH_1):GND   I303 @S9S_MB_2U_LIB.S9S_MB_2U(SCH_1):PAGE146
   B36 P5E_CPU1_PE1_TX_C_DP<6> @S9S_MB_2U_LIB.S9S_MB_2U(SCH_1):P5E_CPU1_PE1_TX_C_DP(6)   I303 @S9S_MB_2U_LIB.S9S_MB_2U(SCH_1):PAGE146
   B37 P5E_CPU1_PE1_TX_C_DN<6> @S9S_MB_2U_LIB.S9S_MB_2U(SCH_1):P5E_CPU1_PE1_TX_C_DN(6)   I303 @S9S_MB_2U_LIB.S9S_MB_2U(SCH_1):PAGE146
   B38    GND @S9S_MB_2U_LIB.S9S_MB_2U(SCH_1):GND   I303 @S9S_MB_2U_LIB.S9S_MB_2U(SCH_1):PAGE146
   B39 P5E_CPU1_PE1_TX_C_DN<7> @S9S_MB_2U_LIB.S9S_MB_2U(SCH_1):P5E_CPU1_PE1_TX_C_DN(7)   I303 @S9S_MB_2U_LIB.S9S_MB_2U(SCH_1):PAGE146
   B40 P5E_CPU1_PE1_TX_C_DP<7> @S9S_MB_2U_LIB.S9S_MB_2U(SCH_1):P5E_CPU1_PE1_TX_C_DP(7)   I303 @S9S_MB_2U_LIB.S9S_MB_2U(SCH_1):PAGE146
   B41    GND @S9S_MB_2U_LIB.S9S_MB_2U(SCH_1):GND   I303 @S9S_MB_2U_LIB.S9S_MB_2U(SCH_1):PAGE146
   B42 OCP_V3_2_PRSNT0_R_N @S9S_MB_2U_LIB.S9S_MB_2U(SCH_1):OCP_V3_2_PRSNT0_R_N   I303 @S9S_MB_2U_LIB.S9S_MB_2U(SCH_1):PAGE146
   B43    GND @S9S_MB_2U_LIB.S9S_MB_2U(SCH_1):GND   I303 @S9S_MB_2U_LIB.S9S_MB_2U(SCH_1):PAGE146
   B44 P5E_CPU1_PE1_TX_C_DP<8> @S9S_MB_2U_LIB.S9S_MB_2U(SCH_1):P5E_CPU1_PE1_TX_C_DP(8)   I303 @S9S_MB_2U_LIB.S9S_MB_2U(SCH_1):PAGE146
   B45 P5E_CPU1_PE1_TX_C_DN<8> @S9S_MB_2U_LIB.S9S_MB_2U(SCH_1):P5E_CPU1_PE1_TX_C_DN(8)   I303 @S9S_MB_2U_LIB.S9S_MB_2U(SCH_1):PAGE146
   B46    GND @S9S_MB_2U_LIB.S9S_MB_2U(SCH_1):GND   I303 @S9S_MB_2U_LIB.S9S_MB_2U(SCH_1):PAGE146
   B47 P5E_CPU1_PE1_TX_C_DN<9> @S9S_MB_2U_LIB.S9S_MB_2U(SCH_1):P5E_CPU1_PE1_TX_C_DN(9)   I303 @S9S_MB_2U_LIB.S9S_MB_2U(SCH_1):PAGE146
   B48 P5E_CPU1_PE1_TX_C_DP<9> @S9S_MB_2U_LIB.S9S_MB_2U(SCH_1):P5E_CPU1_PE1_TX_C_DP(9)   I303 @S9S_MB_2U_LIB.S9S_MB_2U(SCH_1):PAGE146
   B49    GND @S9S_MB_2U_LIB.S9S_MB_2U(SCH_1):GND   I303 @S9S_MB_2U_LIB.S9S_MB_2U(SCH_1):PAGE146
   B50 P5E_CPU1_PE1_TX_C_DP<10> @S9S_MB_2U_LIB.S9S_MB_2U(SCH_1):P5E_CPU1_PE1_TX_C_DP(10)   I303 @S9S_MB_2U_LIB.S9S_MB_2U(SCH_1):PAGE146
   B51 P5E_CPU1_PE1_TX_C_DN<10> @S9S_MB_2U_LIB.S9S_MB_2U(SCH_1):P5E_CPU1_PE1_TX_C_DN(10)   I303 @S9S_MB_2U_LIB.S9S_MB_2U(SCH_1):PAGE146
   B52    GND @S9S_MB_2U_LIB.S9S_MB_2U(SCH_1):GND   I303 @S9S_MB_2U_LIB.S9S_MB_2U(SCH_1):PAGE146
   B53 P5E_CPU1_PE1_TX_C_DN<11> @S9S_MB_2U_LIB.S9S_MB_2U(SCH_1):P5E_CPU1_PE1_TX_C_DN(11)   I303 @S9S_MB_2U_LIB.S9S_MB_2U(SCH_1):PAGE146
   B54 P5E_CPU1_PE1_TX_C_DP<11> @S9S_MB_2U_LIB.S9S_MB_2U(SCH_1):P5E_CPU1_PE1_TX_C_DP(11)   I303 @S9S_MB_2U_LIB.S9S_MB_2U(SCH_1):PAGE146
   B55    GND @S9S_MB_2U_LIB.S9S_MB_2U(SCH_1):GND   I303 @S9S_MB_2U_LIB.S9S_MB_2U(SCH_1):PAGE146
   B56 P5E_CPU1_PE1_TX_C_DP<12> @S9S_MB_2U_LIB.S9S_MB_2U(SCH_1):P5E_CPU1_PE1_TX_C_DP(12)   I303 @S9S_MB_2U_LIB.S9S_MB_2U(SCH_1):PAGE146
   OA1 RST_PERST2_OCP_V3_2_N @S9S_MB_2U_LIB.S9S_MB_2U(SCH_1):RST_PERST2_OCP_V3_2_N   I303 @S9S_MB_2U_LIB.S9S_MB_2U(SCH_1):PAGE146
   OA2 RST_PERST3_OCP_V3_2_N @S9S_MB_2U_LIB.S9S_MB_2U(SCH_1):RST_PERST3_OCP_V3_2_N   I303 @S9S_MB_2U_LIB.S9S_MB_2U(SCH_1):PAGE146
   OA3 IRQ_LVC3_OCP_V3_2_WAKE_N @S9S_MB_2U_LIB.S9S_MB_2U(SCH_1):IRQ_LVC3_OCP_V3_2_WAKE_N   I303 @S9S_MB_2U_LIB.S9S_MB_2U(SCH_1):PAGE146
   OA4 OCP_V3_2_ISO1_RBT_ARB_IN @S9S_MB_2U_LIB.S9S_MB_2U(SCH_1):OCP_V3_2_ISO1_RBT_ARB_IN   I303 @S9S_MB_2U_LIB.S9S_MB_2U(SCH_1):PAGE146
   OA5 OCP_V3_2_ISO2_RBT_ARB_OUT @S9S_MB_2U_LIB.S9S_MB_2U(SCH_1):OCP_V3_2_ISO2_RBT_ARB_OUT   I303 @S9S_MB_2U_LIB.S9S_MB_2U(SCH_1):PAGE146
   OA6 OCP_V3_2_ID1 @S9S_MB_2U_LIB.S9S_MB_2U(SCH_1):OCP_V3_2_ID1   I303 @S9S_MB_2U_LIB.S9S_MB_2U(SCH_1):PAGE146
   OA7 NCSI_OCP_V3_2_TX_EN @S9S_MB_2U_LIB.S9S_MB_2U(SCH_1):NCSI_OCP_V3_2_TX_EN   I303 @S9S_MB_2U_LIB.S9S_MB_2U(SCH_1):PAGE146
   OA8 NCSI_OCP_V3_2_TXD1 @S9S_MB_2U_LIB.S9S_MB_2U(SCH_1):NCSI_OCP_V3_2_TXD1   I303 @S9S_MB_2U_LIB.S9S_MB_2U(SCH_1):PAGE146
   OA9 NCSI_OCP_V3_2_TXD0 @S9S_MB_2U_LIB.S9S_MB_2U(SCH_1):NCSI_OCP_V3_2_TXD0   I303 @S9S_MB_2U_LIB.S9S_MB_2U(SCH_1):PAGE146
  OA10    GND @S9S_MB_2U_LIB.S9S_MB_2U(SCH_1):GND   I303 @S9S_MB_2U_LIB.S9S_MB_2U(SCH_1):PAGE146
  OA11 CLK_100M_OCP_V3_2_D_DN @S9S_MB_2U_LIB.S9S_MB_2U(SCH_1):CLK_100M_OCP_V3_2_D_DN   I303 @S9S_MB_2U_LIB.S9S_MB_2U(SCH_1):PAGE146
  OA12 CLK_100M_OCP_V3_2_D_DP @S9S_MB_2U_LIB.S9S_MB_2U(SCH_1):CLK_100M_OCP_V3_2_D_DP   I303 @S9S_MB_2U_LIB.S9S_MB_2U(SCH_1):PAGE146
  OA13    GND @S9S_MB_2U_LIB.S9S_MB_2U(SCH_1):GND   I303 @S9S_MB_2U_LIB.S9S_MB_2U(SCH_1):PAGE146
  OA14 CLK_50M_NCSI_OCP_V3_2_ISO @S9S_MB_2U_LIB.S9S_MB_2U(SCH_1):CLK_50M_NCSI_OCP_V3_2_ISO   I303 @S9S_MB_2U_LIB.S9S_MB_2U(SCH_1):PAGE146
    A1    GND @S9S_MB_2U_LIB.S9S_MB_2U(SCH_1):GND   I303 @S9S_MB_2U_LIB.S9S_MB_2U(SCH_1):PAGE146
    A2    GND @S9S_MB_2U_LIB.S9S_MB_2U(SCH_1):GND   I303 @S9S_MB_2U_LIB.S9S_MB_2U(SCH_1):PAGE146
    A3    GND @S9S_MB_2U_LIB.S9S_MB_2U(SCH_1):GND   I303 @S9S_MB_2U_LIB.S9S_MB_2U(SCH_1):PAGE146
    A4    GND @S9S_MB_2U_LIB.S9S_MB_2U(SCH_1):GND   I303 @S9S_MB_2U_LIB.S9S_MB_2U(SCH_1):PAGE146
    A5    GND @S9S_MB_2U_LIB.S9S_MB_2U(SCH_1):GND   I303 @S9S_MB_2U_LIB.S9S_MB_2U(SCH_1):PAGE146
    A6    GND @S9S_MB_2U_LIB.S9S_MB_2U(SCH_1):GND   I303 @S9S_MB_2U_LIB.S9S_MB_2U(SCH_1):PAGE146
    A7 SMB_OCP_V3_2_3V3AUX_BUF_R_SCL @S9S_MB_2U_LIB.S9S_MB_2U(SCH_1):SMB_OCP_V3_2_3V3AUX_BUF_R_SCL   I303 @S9S_MB_2U_LIB.S9S_MB_2U(SCH_1):PAGE146
    A8 SMB_OCP_V3_2_3V3AUX_BUF_R_SDA @S9S_MB_2U_LIB.S9S_MB_2U(SCH_1):SMB_OCP_V3_2_3V3AUX_BUF_R_SDA   I303 @S9S_MB_2U_LIB.S9S_MB_2U(SCH_1):PAGE146
    A9 RST_SMB_OCP_V3_2_N @S9S_MB_2U_LIB.S9S_MB_2U(SCH_1):RST_SMB_OCP_V3_2_N   I303 @S9S_MB_2U_LIB.S9S_MB_2U(SCH_1):PAGE146
   A10 OCP_V3_1_PRSNTA_R_N @S9S_MB_2U_LIB.S9S_MB_2U(SCH_1):OCP_V3_1_PRSNTA_R_N   I303 @S9S_MB_2U_LIB.S9S_MB_2U(SCH_1):PAGE146
   A11 RST_PERST1_OCP_V3_2_N @S9S_MB_2U_LIB.S9S_MB_2U(SCH_1):RST_PERST1_OCP_V3_2_N   I303 @S9S_MB_2U_LIB.S9S_MB_2U(SCH_1):PAGE146
   A12 OCP_V3_2_PRSNT2_R_N @S9S_MB_2U_LIB.S9S_MB_2U(SCH_1):OCP_V3_2_PRSNT2_R_N   I303 @S9S_MB_2U_LIB.S9S_MB_2U(SCH_1):PAGE146
   A13    GND @S9S_MB_2U_LIB.S9S_MB_2U(SCH_1):GND   I303 @S9S_MB_2U_LIB.S9S_MB_2U(SCH_1):PAGE146
   A14 CLK_100M_OCP_V3_2_B_DN @S9S_MB_2U_LIB.S9S_MB_2U(SCH_1):CLK_100M_OCP_V3_2_B_DN   I303 @S9S_MB_2U_LIB.S9S_MB_2U(SCH_1):PAGE146
   A15 CLK_100M_OCP_V3_2_B_DP @S9S_MB_2U_LIB.S9S_MB_2U(SCH_1):CLK_100M_OCP_V3_2_B_DP   I303 @S9S_MB_2U_LIB.S9S_MB_2U(SCH_1):PAGE146
   A16    GND @S9S_MB_2U_LIB.S9S_MB_2U(SCH_1):GND   I303 @S9S_MB_2U_LIB.S9S_MB_2U(SCH_1):PAGE146
   A17 P5E_CPU1_PE1_RX_DN<0> @S9S_MB_2U_LIB.S9S_MB_2U(SCH_1):P5E_CPU1_PE1_RX_DN(0)   I303 @S9S_MB_2U_LIB.S9S_MB_2U(SCH_1):PAGE146
   A18 P5E_CPU1_PE1_RX_DP<0> @S9S_MB_2U_LIB.S9S_MB_2U(SCH_1):P5E_CPU1_PE1_RX_DP(0)   I303 @S9S_MB_2U_LIB.S9S_MB_2U(SCH_1):PAGE146
   A19    GND @S9S_MB_2U_LIB.S9S_MB_2U(SCH_1):GND   I303 @S9S_MB_2U_LIB.S9S_MB_2U(SCH_1):PAGE146
   A20 P5E_CPU1_PE1_RX_DN<1> @S9S_MB_2U_LIB.S9S_MB_2U(SCH_1):P5E_CPU1_PE1_RX_DN(1)   I303 @S9S_MB_2U_LIB.S9S_MB_2U(SCH_1):PAGE146
   A21 P5E_CPU1_PE1_RX_DP<1> @S9S_MB_2U_LIB.S9S_MB_2U(SCH_1):P5E_CPU1_PE1_RX_DP(1)   I303 @S9S_MB_2U_LIB.S9S_MB_2U(SCH_1):PAGE146
   A22    GND @S9S_MB_2U_LIB.S9S_MB_2U(SCH_1):GND   I303 @S9S_MB_2U_LIB.S9S_MB_2U(SCH_1):PAGE146
   A23 P5E_CPU1_PE1_RX_DN<2> @S9S_MB_2U_LIB.S9S_MB_2U(SCH_1):P5E_CPU1_PE1_RX_DN(2)   I303 @S9S_MB_2U_LIB.S9S_MB_2U(SCH_1):PAGE146
   A24 P5E_CPU1_PE1_RX_DP<2> @S9S_MB_2U_LIB.S9S_MB_2U(SCH_1):P5E_CPU1_PE1_RX_DP(2)   I303 @S9S_MB_2U_LIB.S9S_MB_2U(SCH_1):PAGE146
   A25    GND @S9S_MB_2U_LIB.S9S_MB_2U(SCH_1):GND   I303 @S9S_MB_2U_LIB.S9S_MB_2U(SCH_1):PAGE146
   A26 P5E_CPU1_PE1_RX_DN<3> @S9S_MB_2U_LIB.S9S_MB_2U(SCH_1):P5E_CPU1_PE1_RX_DN(3)   I303 @S9S_MB_2U_LIB.S9S_MB_2U(SCH_1):PAGE146
   A27 P5E_CPU1_PE1_RX_DP<3> @S9S_MB_2U_LIB.S9S_MB_2U(SCH_1):P5E_CPU1_PE1_RX_DP(3)   I303 @S9S_MB_2U_LIB.S9S_MB_2U(SCH_1):PAGE146
   A28    GND @S9S_MB_2U_LIB.S9S_MB_2U(SCH_1):GND   I303 @S9S_MB_2U_LIB.S9S_MB_2U(SCH_1):PAGE146
   A29    GND @S9S_MB_2U_LIB.S9S_MB_2U(SCH_1):GND   I303 @S9S_MB_2U_LIB.S9S_MB_2U(SCH_1):PAGE146
   A30 P5E_CPU1_PE1_RX_DN<4> @S9S_MB_2U_LIB.S9S_MB_2U(SCH_1):P5E_CPU1_PE1_RX_DN(4)   I303 @S9S_MB_2U_LIB.S9S_MB_2U(SCH_1):PAGE146
   A31 P5E_CPU1_PE1_RX_DP<4> @S9S_MB_2U_LIB.S9S_MB_2U(SCH_1):P5E_CPU1_PE1_RX_DP(4)   I303 @S9S_MB_2U_LIB.S9S_MB_2U(SCH_1):PAGE146
   A32    GND @S9S_MB_2U_LIB.S9S_MB_2U(SCH_1):GND   I303 @S9S_MB_2U_LIB.S9S_MB_2U(SCH_1):PAGE146
   A33 P5E_CPU1_PE1_RX_DN<5> @S9S_MB_2U_LIB.S9S_MB_2U(SCH_1):P5E_CPU1_PE1_RX_DN(5)   I303 @S9S_MB_2U_LIB.S9S_MB_2U(SCH_1):PAGE146
   A34 P5E_CPU1_PE1_RX_DP<5> @S9S_MB_2U_LIB.S9S_MB_2U(SCH_1):P5E_CPU1_PE1_RX_DP(5)   I303 @S9S_MB_2U_LIB.S9S_MB_2U(SCH_1):PAGE146
   A35    GND @S9S_MB_2U_LIB.S9S_MB_2U(SCH_1):GND   I303 @S9S_MB_2U_LIB.S9S_MB_2U(SCH_1):PAGE146
   A36 P5E_CPU1_PE1_RX_DN<6> @S9S_MB_2U_LIB.S9S_MB_2U(SCH_1):P5E_CPU1_PE1_RX_DN(6)   I303 @S9S_MB_2U_LIB.S9S_MB_2U(SCH_1):PAGE146
   A37 P5E_CPU1_PE1_RX_DP<6> @S9S_MB_2U_LIB.S9S_MB_2U(SCH_1):P5E_CPU1_PE1_RX_DP(6)   I303 @S9S_MB_2U_LIB.S9S_MB_2U(SCH_1):PAGE146
   A38    GND @S9S_MB_2U_LIB.S9S_MB_2U(SCH_1):GND   I303 @S9S_MB_2U_LIB.S9S_MB_2U(SCH_1):PAGE146
   A39 P5E_CPU1_PE1_RX_DN<7> @S9S_MB_2U_LIB.S9S_MB_2U(SCH_1):P5E_CPU1_PE1_RX_DN(7)   I303 @S9S_MB_2U_LIB.S9S_MB_2U(SCH_1):PAGE146
   A40 P5E_CPU1_PE1_RX_DP<7> @S9S_MB_2U_LIB.S9S_MB_2U(SCH_1):P5E_CPU1_PE1_RX_DP(7)   I303 @S9S_MB_2U_LIB.S9S_MB_2U(SCH_1):PAGE146
   A41    GND @S9S_MB_2U_LIB.S9S_MB_2U(SCH_1):GND   I303 @S9S_MB_2U_LIB.S9S_MB_2U(SCH_1):PAGE146
   A42 OCP_V3_2_PRSNT1_R_N @S9S_MB_2U_LIB.S9S_MB_2U(SCH_1):OCP_V3_2_PRSNT1_R_N   I303 @S9S_MB_2U_LIB.S9S_MB_2U(SCH_1):PAGE146
   A43    GND @S9S_MB_2U_LIB.S9S_MB_2U(SCH_1):GND   I303 @S9S_MB_2U_LIB.S9S_MB_2U(SCH_1):PAGE146
   A44 P5E_CPU1_PE1_RX_DN<8> @S9S_MB_2U_LIB.S9S_MB_2U(SCH_1):P5E_CPU1_PE1_RX_DN(8)   I303 @S9S_MB_2U_LIB.S9S_MB_2U(SCH_1):PAGE146
   A45 P5E_CPU1_PE1_RX_DP<8> @S9S_MB_2U_LIB.S9S_MB_2U(SCH_1):P5E_CPU1_PE1_RX_DP(8)   I303 @S9S_MB_2U_LIB.S9S_MB_2U(SCH_1):PAGE146
   A46    GND @S9S_MB_2U_LIB.S9S_MB_2U(SCH_1):GND   I303 @S9S_MB_2U_LIB.S9S_MB_2U(SCH_1):PAGE146
   A47 P5E_CPU1_PE1_RX_DN<9> @S9S_MB_2U_LIB.S9S_MB_2U(SCH_1):P5E_CPU1_PE1_RX_DN(9)   I303 @S9S_MB_2U_LIB.S9S_MB_2U(SCH_1):PAGE146
   A48 P5E_CPU1_PE1_RX_DP<9> @S9S_MB_2U_LIB.S9S_MB_2U(SCH_1):P5E_CPU1_PE1_RX_DP(9)   I303 @S9S_MB_2U_LIB.S9S_MB_2U(SCH_1):PAGE146
   A49    GND @S9S_MB_2U_LIB.S9S_MB_2U(SCH_1):GND   I303 @S9S_MB_2U_LIB.S9S_MB_2U(SCH_1):PAGE146
   A50 P5E_CPU1_PE1_RX_DN<10> @S9S_MB_2U_LIB.S9S_MB_2U(SCH_1):P5E_CPU1_PE1_RX_DN(10)   I303 @S9S_MB_2U_LIB.S9S_MB_2U(SCH_1):PAGE146
   A51 P5E_CPU1_PE1_RX_DP<10> @S9S_MB_2U_LIB.S9S_MB_2U(SCH_1):P5E_CPU1_PE1_RX_DP(10)   I303 @S9S_MB_2U_LIB.S9S_MB_2U(SCH_1):PAGE146
   A52    GND @S9S_MB_2U_LIB.S9S_MB_2U(SCH_1):GND   I303 @S9S_MB_2U_LIB.S9S_MB_2U(SCH_1):PAGE146
   A53 P5E_CPU1_PE1_RX_DN<11> @S9S_MB_2U_LIB.S9S_MB_2U(SCH_1):P5E_CPU1_PE1_RX_DN(11)   I303 @S9S_MB_2U_LIB.S9S_MB_2U(SCH_1):PAGE146
   A54 P5E_CPU1_PE1_RX_DP<11> @S9S_MB_2U_LIB.S9S_MB_2U(SCH_1):P5E_CPU1_PE1_RX_DP(11)   I303 @S9S_MB_2U_LIB.S9S_MB_2U(SCH_1):PAGE146
   A55    GND @S9S_MB_2U_LIB.S9S_MB_2U(SCH_1):GND   I303 @S9S_MB_2U_LIB.S9S_MB_2U(SCH_1):PAGE146
   A56 P5E_CPU1_PE1_RX_DN<12> @S9S_MB_2U_LIB.S9S_MB_2U(SCH_1):P5E_CPU1_PE1_RX_DN(12)   I303 @S9S_MB_2U_LIB.S9S_MB_2U(SCH_1):PAGE146
   A57 P5E_CPU1_PE1_RX_DP<12> @S9S_MB_2U_LIB.S9S_MB_2U(SCH_1):P5E_CPU1_PE1_RX_DP(12)   I303 @S9S_MB_2U_LIB.S9S_MB_2U(SCH_1):PAGE146
   A58    GND @S9S_MB_2U_LIB.S9S_MB_2U(SCH_1):GND   I303 @S9S_MB_2U_LIB.S9S_MB_2U(SCH_1):PAGE146
   A59 P5E_CPU1_PE1_RX_DN<13> @S9S_MB_2U_LIB.S9S_MB_2U(SCH_1):P5E_CPU1_PE1_RX_DN(13)   I303 @S9S_MB_2U_LIB.S9S_MB_2U(SCH_1):PAGE146
   A60 P5E_CPU1_PE1_RX_DP<13> @S9S_MB_2U_LIB.S9S_MB_2U(SCH_1):P5E_CPU1_PE1_RX_DP(13)   I303 @S9S_MB_2U_LIB.S9S_MB_2U(SCH_1):PAGE146
   A61    GND @S9S_MB_2U_LIB.S9S_MB_2U(SCH_1):GND   I303 @S9S_MB_2U_LIB.S9S_MB_2U(SCH_1):PAGE146
   A62 P5E_CPU1_PE1_RX_DN<14> @S9S_MB_2U_LIB.S9S_MB_2U(SCH_1):P5E_CPU1_PE1_RX_DN(14)   I303 @S9S_MB_2U_LIB.S9S_MB_2U(SCH_1):PAGE146
   A63 P5E_CPU1_PE1_RX_DP<14> @S9S_MB_2U_LIB.S9S_MB_2U(SCH_1):P5E_CPU1_PE1_RX_DP(14)   I303 @S9S_MB_2U_LIB.S9S_MB_2U(SCH_1):PAGE146
   A64    GND @S9S_MB_2U_LIB.S9S_MB_2U(SCH_1):GND   I303 @S9S_MB_2U_LIB.S9S_MB_2U(SCH_1):PAGE146
   A65 P5E_CPU1_PE1_RX_DN<15> @S9S_MB_2U_LIB.S9S_MB_2U(SCH_1):P5E_CPU1_PE1_RX_DN(15)   I303 @S9S_MB_2U_LIB.S9S_MB_2U(SCH_1):PAGE146
   A66 P5E_CPU1_PE1_RX_DP<15> @S9S_MB_2U_LIB.S9S_MB_2U(SCH_1):P5E_CPU1_PE1_RX_DP(15)   I303 @S9S_MB_2U_LIB.S9S_MB_2U(SCH_1):PAGE146
   A67    GND @S9S_MB_2U_LIB.S9S_MB_2U(SCH_1):GND   I303 @S9S_MB_2U_LIB.S9S_MB_2U(SCH_1):PAGE146
   A68 USB2_5_R1_DN @S9S_MB_2U_LIB.S9S_MB_2U(SCH_1):USB2_5_R1_DN   I303 @S9S_MB_2U_LIB.S9S_MB_2U(SCH_1):PAGE146
   A69 USB2_5_R1_DP @S9S_MB_2U_LIB.S9S_MB_2U(SCH_1):USB2_5_R1_DP   I303 @S9S_MB_2U_LIB.S9S_MB_2U(SCH_1):PAGE146
   A70 OCP_V3_2_PWRBRK_N @S9S_MB_2U_LIB.S9S_MB_2U(SCH_1):OCP_V3_2_PWRBRK_N   I303 @S9S_MB_2U_LIB.S9S_MB_2U(SCH_1):PAGE146
   B57 P5E_CPU1_PE1_TX_C_DN<12> @S9S_MB_2U_LIB.S9S_MB_2U(SCH_1):P5E_CPU1_PE1_TX_C_DN(12)   I303 @S9S_MB_2U_LIB.S9S_MB_2U(SCH_1):PAGE146
   B58    GND @S9S_MB_2U_LIB.S9S_MB_2U(SCH_1):GND   I303 @S9S_MB_2U_LIB.S9S_MB_2U(SCH_1):PAGE146
   B59 P5E_CPU1_PE1_TX_C_DN<13> @S9S_MB_2U_LIB.S9S_MB_2U(SCH_1):P5E_CPU1_PE1_TX_C_DN(13)   I303 @S9S_MB_2U_LIB.S9S_MB_2U(SCH_1):PAGE146
   B60 P5E_CPU1_PE1_TX_C_DP<13> @S9S_MB_2U_LIB.S9S_MB_2U(SCH_1):P5E_CPU1_PE1_TX_C_DP(13)   I303 @S9S_MB_2U_LIB.S9S_MB_2U(SCH_1):PAGE146
   B61    GND @S9S_MB_2U_LIB.S9S_MB_2U(SCH_1):GND   I303 @S9S_MB_2U_LIB.S9S_MB_2U(SCH_1):PAGE146
   B62 P5E_CPU1_PE1_TX_C_DP<14> @S9S_MB_2U_LIB.S9S_MB_2U(SCH_1):P5E_CPU1_PE1_TX_C_DP(14)   I303 @S9S_MB_2U_LIB.S9S_MB_2U(SCH_1):PAGE146
   B63 P5E_CPU1_PE1_TX_C_DN<14> @S9S_MB_2U_LIB.S9S_MB_2U(SCH_1):P5E_CPU1_PE1_TX_C_DN(14)   I303 @S9S_MB_2U_LIB.S9S_MB_2U(SCH_1):PAGE146
   B64    GND @S9S_MB_2U_LIB.S9S_MB_2U(SCH_1):GND   I303 @S9S_MB_2U_LIB.S9S_MB_2U(SCH_1):PAGE146
   B65 P5E_CPU1_PE1_TX_C_DN<15> @S9S_MB_2U_LIB.S9S_MB_2U(SCH_1):P5E_CPU1_PE1_TX_C_DN(15)   I303 @S9S_MB_2U_LIB.S9S_MB_2U(SCH_1):PAGE146
   B66 P5E_CPU1_PE1_TX_C_DP<15> @S9S_MB_2U_LIB.S9S_MB_2U(SCH_1):P5E_CPU1_PE1_TX_C_DP(15)   I303 @S9S_MB_2U_LIB.S9S_MB_2U(SCH_1):PAGE146
   B67    GND @S9S_MB_2U_LIB.S9S_MB_2U(SCH_1):GND   I303 @S9S_MB_2U_LIB.S9S_MB_2U(SCH_1):PAGE146
   B68 TP_OCP_V3_2_B68 @S9S_MB_2U_LIB.S9S_MB_2U(SCH_1):TP_OCP_V3_2_B68   I303 @S9S_MB_2U_LIB.S9S_MB_2U(SCH_1):PAGE146
   B69 TP_OCP_V3_2_B69 @S9S_MB_2U_LIB.S9S_MB_2U(SCH_1):TP_OCP_V3_2_B69   I303 @S9S_MB_2U_LIB.S9S_MB_2U(SCH_1):PAGE146
   B70 OCP_V3_2_PRSNT3_R_N @S9S_MB_2U_LIB.S9S_MB_2U(SCH_1):OCP_V3_2_PRSNT3_R_N   I303 @S9S_MB_2U_LIB.S9S_MB_2U(SCH_1):PAGE146
    G1    GND @S9S_MB_2U_LIB.S9S_MB_2U(SCH_1):GND   I303 @S9S_MB_2U_LIB.S9S_MB_2U(SCH_1):PAGE146
    G2    GND @S9S_MB_2U_LIB.S9S_MB_2U(SCH_1):GND   I303 @S9S_MB_2U_LIB.S9S_MB_2U(SCH_1):PAGE146
    G3    GND @S9S_MB_2U_LIB.S9S_MB_2U(SCH_1):GND   I303 @S9S_MB_2U_LIB.S9S_MB_2U(SCH_1):PAGE146
    G4    GND @S9S_MB_2U_LIB.S9S_MB_2U(SCH_1):GND   I303 @S9S_MB_2U_LIB.S9S_MB_2U(SCH_1):PAGE146
    G5    GND @S9S_MB_2U_LIB.S9S_MB_2U(SCH_1):GND   I303 @S9S_MB_2U_LIB.S9S_MB_2U(SCH_1):PAGE146

 J37 SCONN168_ME1016810202011-SCONNA
   OB1 FM_OCP_SFF_PWR_GOOD @S9S_MB_2U_LIB.S9S_MB_2U(SCH_1):FM_OCP_SFF_PWR_GOOD   I199 @S9S_MB_2U_LIB.S9S_MB_2U(SCH_1):PAGE150
   OB2 OCP_SFF_MAIN_PWR_EN_R @S9S_MB_2U_LIB.S9S_MB_2U(SCH_1):OCP_SFF_MAIN_PWR_EN_R   I199 @S9S_MB_2U_LIB.S9S_MB_2U(SCH_1):PAGE150
   OB3 SGPIO_OCP_SFF_LD_N @S9S_MB_2U_LIB.S9S_MB_2U(SCH_1):SGPIO_OCP_SFF_LD_N   I199 @S9S_MB_2U_LIB.S9S_MB_2U(SCH_1):PAGE150
   OB4 SGPIO_OCP_SFF_DATAIN @S9S_MB_2U_LIB.S9S_MB_2U(SCH_1):SGPIO_OCP_SFF_DATAIN   I199 @S9S_MB_2U_LIB.S9S_MB_2U(SCH_1):PAGE150
   OB5 SGPIO_OCP_SFF_DATAOUT @S9S_MB_2U_LIB.S9S_MB_2U(SCH_1):SGPIO_OCP_SFF_DATAOUT   I199 @S9S_MB_2U_LIB.S9S_MB_2U(SCH_1):PAGE150
   OB6 SGPIO_OCP_SFF_CLK @S9S_MB_2U_LIB.S9S_MB_2U(SCH_1):SGPIO_OCP_SFF_CLK   I199 @S9S_MB_2U_LIB.S9S_MB_2U(SCH_1):PAGE150
   OB7 OCP_SFF_ID0 @S9S_MB_2U_LIB.S9S_MB_2U(SCH_1):OCP_SFF_ID0   I199 @S9S_MB_2U_LIB.S9S_MB_2U(SCH_1):PAGE150
   OB8 NCSI_OCP_SFF_RXD1 @S9S_MB_2U_LIB.S9S_MB_2U(SCH_1):NCSI_OCP_SFF_RXD1   I199 @S9S_MB_2U_LIB.S9S_MB_2U(SCH_1):PAGE150
   OB9 NCSI_OCP_SFF_RXD0 @S9S_MB_2U_LIB.S9S_MB_2U(SCH_1):NCSI_OCP_SFF_RXD0   I199 @S9S_MB_2U_LIB.S9S_MB_2U(SCH_1):PAGE150
  OB10    GND @S9S_MB_2U_LIB.S9S_MB_2U(SCH_1):GND   I199 @S9S_MB_2U_LIB.S9S_MB_2U(SCH_1):PAGE150
  OB11 CLK_100M_OCP_SFF_2_DN @S9S_MB_2U_LIB.S9S_MB_2U(SCH_1):CLK_100M_OCP_SFF_2_DN   I199 @S9S_MB_2U_LIB.S9S_MB_2U(SCH_1):PAGE150
  OB12 CLK_100M_OCP_SFF_2_DP @S9S_MB_2U_LIB.S9S_MB_2U(SCH_1):CLK_100M_OCP_SFF_2_DP   I199 @S9S_MB_2U_LIB.S9S_MB_2U(SCH_1):PAGE150
  OB13    GND @S9S_MB_2U_LIB.S9S_MB_2U(SCH_1):GND   I199 @S9S_MB_2U_LIB.S9S_MB_2U(SCH_1):PAGE150
  OB14 NCSI_OCP_SFF_CRS_DV @S9S_MB_2U_LIB.S9S_MB_2U(SCH_1):NCSI_OCP_SFF_CRS_DV   I199 @S9S_MB_2U_LIB.S9S_MB_2U(SCH_1):PAGE150
    B1 P12V_OCP_SFF @S9S_MB_2U_LIB.S9S_MB_2U(SCH_1):P12V_OCP_SFF   I199 @S9S_MB_2U_LIB.S9S_MB_2U(SCH_1):PAGE150
    B2 P12V_OCP_SFF @S9S_MB_2U_LIB.S9S_MB_2U(SCH_1):P12V_OCP_SFF   I199 @S9S_MB_2U_LIB.S9S_MB_2U(SCH_1):PAGE150
    B3 P12V_OCP_SFF @S9S_MB_2U_LIB.S9S_MB_2U(SCH_1):P12V_OCP_SFF   I199 @S9S_MB_2U_LIB.S9S_MB_2U(SCH_1):PAGE150
    B4 P12V_OCP_SFF @S9S_MB_2U_LIB.S9S_MB_2U(SCH_1):P12V_OCP_SFF   I199 @S9S_MB_2U_LIB.S9S_MB_2U(SCH_1):PAGE150
    B5 P12V_OCP_SFF @S9S_MB_2U_LIB.S9S_MB_2U(SCH_1):P12V_OCP_SFF   I199 @S9S_MB_2U_LIB.S9S_MB_2U(SCH_1):PAGE150
    B6 P12V_OCP_SFF @S9S_MB_2U_LIB.S9S_MB_2U(SCH_1):P12V_OCP_SFF   I199 @S9S_MB_2U_LIB.S9S_MB_2U(SCH_1):PAGE150
    B7 OCP_SFF_BIF0_R_N @S9S_MB_2U_LIB.S9S_MB_2U(SCH_1):OCP_SFF_BIF0_R_N   I199 @S9S_MB_2U_LIB.S9S_MB_2U(SCH_1):PAGE150
    B8 OCP_SFF_BIF1_R_N @S9S_MB_2U_LIB.S9S_MB_2U(SCH_1):OCP_SFF_BIF1_R_N   I199 @S9S_MB_2U_LIB.S9S_MB_2U(SCH_1):PAGE150
    B9 OCP_SFF_BIF2_R_N @S9S_MB_2U_LIB.S9S_MB_2U(SCH_1):OCP_SFF_BIF2_R_N   I199 @S9S_MB_2U_LIB.S9S_MB_2U(SCH_1):PAGE150
   B10 RST_PERST0_OCP_SFF_N @S9S_MB_2U_LIB.S9S_MB_2U(SCH_1):RST_PERST0_OCP_SFF_N   I199 @S9S_MB_2U_LIB.S9S_MB_2U(SCH_1):PAGE150
   B11 P3V3_OCP_SFF @S9S_MB_2U_LIB.S9S_MB_2U(SCH_1):P3V3_OCP_SFF   I199 @S9S_MB_2U_LIB.S9S_MB_2U(SCH_1):PAGE150
   B12 OCP_SFF_AUX_PWR_EN_R @S9S_MB_2U_LIB.S9S_MB_2U(SCH_1):OCP_SFF_AUX_PWR_EN_R   I199 @S9S_MB_2U_LIB.S9S_MB_2U(SCH_1):PAGE150
   B13    GND @S9S_MB_2U_LIB.S9S_MB_2U(SCH_1):GND   I199 @S9S_MB_2U_LIB.S9S_MB_2U(SCH_1):PAGE150
   B14 CLK_100M_OCP_SFF_0_DN @S9S_MB_2U_LIB.S9S_MB_2U(SCH_1):CLK_100M_OCP_SFF_0_DN   I199 @S9S_MB_2U_LIB.S9S_MB_2U(SCH_1):PAGE150
   B15 CLK_100M_OCP_SFF_0_DP @S9S_MB_2U_LIB.S9S_MB_2U(SCH_1):CLK_100M_OCP_SFF_0_DP   I199 @S9S_MB_2U_LIB.S9S_MB_2U(SCH_1):PAGE150
   B16    GND @S9S_MB_2U_LIB.S9S_MB_2U(SCH_1):GND   I199 @S9S_MB_2U_LIB.S9S_MB_2U(SCH_1):PAGE150
   B17 P5E_CPU0_PE1_TX_C_DN<0> @S9S_MB_2U_LIB.S9S_MB_2U(SCH_1):P5E_CPU0_PE1_TX_C_DN(0)   I199 @S9S_MB_2U_LIB.S9S_MB_2U(SCH_1):PAGE150
   B18 P5E_CPU0_PE1_TX_C_DP<0> @S9S_MB_2U_LIB.S9S_MB_2U(SCH_1):P5E_CPU0_PE1_TX_C_DP(0)   I199 @S9S_MB_2U_LIB.S9S_MB_2U(SCH_1):PAGE150
   B19    GND @S9S_MB_2U_LIB.S9S_MB_2U(SCH_1):GND   I199 @S9S_MB_2U_LIB.S9S_MB_2U(SCH_1):PAGE150
   B20 P5E_CPU0_PE1_TX_C_DN<1> @S9S_MB_2U_LIB.S9S_MB_2U(SCH_1):P5E_CPU0_PE1_TX_C_DN(1)   I199 @S9S_MB_2U_LIB.S9S_MB_2U(SCH_1):PAGE150
   B21 P5E_CPU0_PE1_TX_C_DP<1> @S9S_MB_2U_LIB.S9S_MB_2U(SCH_1):P5E_CPU0_PE1_TX_C_DP(1)   I199 @S9S_MB_2U_LIB.S9S_MB_2U(SCH_1):PAGE150
   B22    GND @S9S_MB_2U_LIB.S9S_MB_2U(SCH_1):GND   I199 @S9S_MB_2U_LIB.S9S_MB_2U(SCH_1):PAGE150
   B23 P5E_CPU0_PE1_TX_C_DP<2> @S9S_MB_2U_LIB.S9S_MB_2U(SCH_1):P5E_CPU0_PE1_TX_C_DP(2)   I199 @S9S_MB_2U_LIB.S9S_MB_2U(SCH_1):PAGE150
   B24 P5E_CPU0_PE1_TX_C_DN<2> @S9S_MB_2U_LIB.S9S_MB_2U(SCH_1):P5E_CPU0_PE1_TX_C_DN(2)   I199 @S9S_MB_2U_LIB.S9S_MB_2U(SCH_1):PAGE150
   B25    GND @S9S_MB_2U_LIB.S9S_MB_2U(SCH_1):GND   I199 @S9S_MB_2U_LIB.S9S_MB_2U(SCH_1):PAGE150
   B26 P5E_CPU0_PE1_TX_C_DN<3> @S9S_MB_2U_LIB.S9S_MB_2U(SCH_1):P5E_CPU0_PE1_TX_C_DN(3)   I199 @S9S_MB_2U_LIB.S9S_MB_2U(SCH_1):PAGE150
   B27 P5E_CPU0_PE1_TX_C_DP<3> @S9S_MB_2U_LIB.S9S_MB_2U(SCH_1):P5E_CPU0_PE1_TX_C_DP(3)   I199 @S9S_MB_2U_LIB.S9S_MB_2U(SCH_1):PAGE150
   B28    GND @S9S_MB_2U_LIB.S9S_MB_2U(SCH_1):GND   I199 @S9S_MB_2U_LIB.S9S_MB_2U(SCH_1):PAGE150
   B29    GND @S9S_MB_2U_LIB.S9S_MB_2U(SCH_1):GND   I199 @S9S_MB_2U_LIB.S9S_MB_2U(SCH_1):PAGE150
   B30 P5E_CPU0_PE1_TX_C_DP<4> @S9S_MB_2U_LIB.S9S_MB_2U(SCH_1):P5E_CPU0_PE1_TX_C_DP(4)   I199 @S9S_MB_2U_LIB.S9S_MB_2U(SCH_1):PAGE150
   B31 P5E_CPU0_PE1_TX_C_DN<4> @S9S_MB_2U_LIB.S9S_MB_2U(SCH_1):P5E_CPU0_PE1_TX_C_DN(4)   I199 @S9S_MB_2U_LIB.S9S_MB_2U(SCH_1):PAGE150
   B32    GND @S9S_MB_2U_LIB.S9S_MB_2U(SCH_1):GND   I199 @S9S_MB_2U_LIB.S9S_MB_2U(SCH_1):PAGE150
   B33 P5E_CPU0_PE1_TX_C_DN<5> @S9S_MB_2U_LIB.S9S_MB_2U(SCH_1):P5E_CPU0_PE1_TX_C_DN(5)   I199 @S9S_MB_2U_LIB.S9S_MB_2U(SCH_1):PAGE150
   B34 P5E_CPU0_PE1_TX_C_DP<5> @S9S_MB_2U_LIB.S9S_MB_2U(SCH_1):P5E_CPU0_PE1_TX_C_DP(5)   I199 @S9S_MB_2U_LIB.S9S_MB_2U(SCH_1):PAGE150
   B35    GND @S9S_MB_2U_LIB.S9S_MB_2U(SCH_1):GND   I199 @S9S_MB_2U_LIB.S9S_MB_2U(SCH_1):PAGE150
   B36 P5E_CPU0_PE1_TX_C_DP<6> @S9S_MB_2U_LIB.S9S_MB_2U(SCH_1):P5E_CPU0_PE1_TX_C_DP(6)   I199 @S9S_MB_2U_LIB.S9S_MB_2U(SCH_1):PAGE150
   B37 P5E_CPU0_PE1_TX_C_DN<6> @S9S_MB_2U_LIB.S9S_MB_2U(SCH_1):P5E_CPU0_PE1_TX_C_DN(6)   I199 @S9S_MB_2U_LIB.S9S_MB_2U(SCH_1):PAGE150
   B38    GND @S9S_MB_2U_LIB.S9S_MB_2U(SCH_1):GND   I199 @S9S_MB_2U_LIB.S9S_MB_2U(SCH_1):PAGE150
   B39 P5E_CPU0_PE1_TX_C_DN<7> @S9S_MB_2U_LIB.S9S_MB_2U(SCH_1):P5E_CPU0_PE1_TX_C_DN(7)   I199 @S9S_MB_2U_LIB.S9S_MB_2U(SCH_1):PAGE150
   B40 P5E_CPU0_PE1_TX_C_DP<7> @S9S_MB_2U_LIB.S9S_MB_2U(SCH_1):P5E_CPU0_PE1_TX_C_DP(7)   I199 @S9S_MB_2U_LIB.S9S_MB_2U(SCH_1):PAGE150
   B41    GND @S9S_MB_2U_LIB.S9S_MB_2U(SCH_1):GND   I199 @S9S_MB_2U_LIB.S9S_MB_2U(SCH_1):PAGE150
   B42 OCP_SFF_PRSNT0_R_N @S9S_MB_2U_LIB.S9S_MB_2U(SCH_1):OCP_SFF_PRSNT0_R_N   I199 @S9S_MB_2U_LIB.S9S_MB_2U(SCH_1):PAGE150
   B43    GND @S9S_MB_2U_LIB.S9S_MB_2U(SCH_1):GND   I199 @S9S_MB_2U_LIB.S9S_MB_2U(SCH_1):PAGE150
   B44 P5E_CPU0_PE1_TX_C_DP<8> @S9S_MB_2U_LIB.S9S_MB_2U(SCH_1):P5E_CPU0_PE1_TX_C_DP(8)   I199 @S9S_MB_2U_LIB.S9S_MB_2U(SCH_1):PAGE150
   B45 P5E_CPU0_PE1_TX_C_DN<8> @S9S_MB_2U_LIB.S9S_MB_2U(SCH_1):P5E_CPU0_PE1_TX_C_DN(8)   I199 @S9S_MB_2U_LIB.S9S_MB_2U(SCH_1):PAGE150
   B46    GND @S9S_MB_2U_LIB.S9S_MB_2U(SCH_1):GND   I199 @S9S_MB_2U_LIB.S9S_MB_2U(SCH_1):PAGE150
   B47 P5E_CPU0_PE1_TX_C_DN<9> @S9S_MB_2U_LIB.S9S_MB_2U(SCH_1):P5E_CPU0_PE1_TX_C_DN(9)   I199 @S9S_MB_2U_LIB.S9S_MB_2U(SCH_1):PAGE150
   B48 P5E_CPU0_PE1_TX_C_DP<9> @S9S_MB_2U_LIB.S9S_MB_2U(SCH_1):P5E_CPU0_PE1_TX_C_DP(9)   I199 @S9S_MB_2U_LIB.S9S_MB_2U(SCH_1):PAGE150
   B49    GND @S9S_MB_2U_LIB.S9S_MB_2U(SCH_1):GND   I199 @S9S_MB_2U_LIB.S9S_MB_2U(SCH_1):PAGE150
   B50 P5E_CPU0_PE1_TX_C_DP<10> @S9S_MB_2U_LIB.S9S_MB_2U(SCH_1):P5E_CPU0_PE1_TX_C_DP(10)   I199 @S9S_MB_2U_LIB.S9S_MB_2U(SCH_1):PAGE150
   B51 P5E_CPU0_PE1_TX_C_DN<10> @S9S_MB_2U_LIB.S9S_MB_2U(SCH_1):P5E_CPU0_PE1_TX_C_DN(10)   I199 @S9S_MB_2U_LIB.S9S_MB_2U(SCH_1):PAGE150
   B52    GND @S9S_MB_2U_LIB.S9S_MB_2U(SCH_1):GND   I199 @S9S_MB_2U_LIB.S9S_MB_2U(SCH_1):PAGE150
   B53 P5E_CPU0_PE1_TX_C_DN<11> @S9S_MB_2U_LIB.S9S_MB_2U(SCH_1):P5E_CPU0_PE1_TX_C_DN(11)   I199 @S9S_MB_2U_LIB.S9S_MB_2U(SCH_1):PAGE150
   B54 P5E_CPU0_PE1_TX_C_DP<11> @S9S_MB_2U_LIB.S9S_MB_2U(SCH_1):P5E_CPU0_PE1_TX_C_DP(11)   I199 @S9S_MB_2U_LIB.S9S_MB_2U(SCH_1):PAGE150
   B55    GND @S9S_MB_2U_LIB.S9S_MB_2U(SCH_1):GND   I199 @S9S_MB_2U_LIB.S9S_MB_2U(SCH_1):PAGE150
   B56 P5E_CPU0_PE1_TX_C_DP<12> @S9S_MB_2U_LIB.S9S_MB_2U(SCH_1):P5E_CPU0_PE1_TX_C_DP(12)   I199 @S9S_MB_2U_LIB.S9S_MB_2U(SCH_1):PAGE150
   OA1 RST_PERST2_OCP_SFF_N @S9S_MB_2U_LIB.S9S_MB_2U(SCH_1):RST_PERST2_OCP_SFF_N   I199 @S9S_MB_2U_LIB.S9S_MB_2U(SCH_1):PAGE150
   OA2 RST_PERST3_OCP_SFF_N @S9S_MB_2U_LIB.S9S_MB_2U(SCH_1):RST_PERST3_OCP_SFF_N   I199 @S9S_MB_2U_LIB.S9S_MB_2U(SCH_1):PAGE150
   OA3 IRQ_LVC3_OCP_SFF_WAKE_N @S9S_MB_2U_LIB.S9S_MB_2U(SCH_1):IRQ_LVC3_OCP_SFF_WAKE_N   I199 @S9S_MB_2U_LIB.S9S_MB_2U(SCH_1):PAGE150
   OA4 OCP_SFF_ISO1_RBT_ARB_IN @S9S_MB_2U_LIB.S9S_MB_2U(SCH_1):OCP_SFF_ISO1_RBT_ARB_IN   I199 @S9S_MB_2U_LIB.S9S_MB_2U(SCH_1):PAGE150
   OA5 OCP_SFF_ISO2_RBT_ARB_OUT @S9S_MB_2U_LIB.S9S_MB_2U(SCH_1):OCP_SFF_ISO2_RBT_ARB_OUT   I199 @S9S_MB_2U_LIB.S9S_MB_2U(SCH_1):PAGE150
   OA6 OCP_SFF_ID1 @S9S_MB_2U_LIB.S9S_MB_2U(SCH_1):OCP_SFF_ID1   I199 @S9S_MB_2U_LIB.S9S_MB_2U(SCH_1):PAGE150
   OA7 NCSI_OCP_SFF_TX_EN @S9S_MB_2U_LIB.S9S_MB_2U(SCH_1):NCSI_OCP_SFF_TX_EN   I199 @S9S_MB_2U_LIB.S9S_MB_2U(SCH_1):PAGE150
   OA8 NCSI_OCP_SFF_TXD1 @S9S_MB_2U_LIB.S9S_MB_2U(SCH_1):NCSI_OCP_SFF_TXD1   I199 @S9S_MB_2U_LIB.S9S_MB_2U(SCH_1):PAGE150
   OA9 NCSI_OCP_SFF_TXD0 @S9S_MB_2U_LIB.S9S_MB_2U(SCH_1):NCSI_OCP_SFF_TXD0   I199 @S9S_MB_2U_LIB.S9S_MB_2U(SCH_1):PAGE150
  OA10    GND @S9S_MB_2U_LIB.S9S_MB_2U(SCH_1):GND   I199 @S9S_MB_2U_LIB.S9S_MB_2U(SCH_1):PAGE150
  OA11 CLK_100M_OCP_SFF_3_DN @S9S_MB_2U_LIB.S9S_MB_2U(SCH_1):CLK_100M_OCP_SFF_3_DN   I199 @S9S_MB_2U_LIB.S9S_MB_2U(SCH_1):PAGE150
  OA12 CLK_100M_OCP_SFF_3_DP @S9S_MB_2U_LIB.S9S_MB_2U(SCH_1):CLK_100M_OCP_SFF_3_DP   I199 @S9S_MB_2U_LIB.S9S_MB_2U(SCH_1):PAGE150
  OA13    GND @S9S_MB_2U_LIB.S9S_MB_2U(SCH_1):GND   I199 @S9S_MB_2U_LIB.S9S_MB_2U(SCH_1):PAGE150
  OA14 CLK_50M_NCSI_OCP_SFF_ISO @S9S_MB_2U_LIB.S9S_MB_2U(SCH_1):CLK_50M_NCSI_OCP_SFF_ISO   I199 @S9S_MB_2U_LIB.S9S_MB_2U(SCH_1):PAGE150
    A1    GND @S9S_MB_2U_LIB.S9S_MB_2U(SCH_1):GND   I199 @S9S_MB_2U_LIB.S9S_MB_2U(SCH_1):PAGE150
    A2    GND @S9S_MB_2U_LIB.S9S_MB_2U(SCH_1):GND   I199 @S9S_MB_2U_LIB.S9S_MB_2U(SCH_1):PAGE150
    A3    GND @S9S_MB_2U_LIB.S9S_MB_2U(SCH_1):GND   I199 @S9S_MB_2U_LIB.S9S_MB_2U(SCH_1):PAGE150
    A4    GND @S9S_MB_2U_LIB.S9S_MB_2U(SCH_1):GND   I199 @S9S_MB_2U_LIB.S9S_MB_2U(SCH_1):PAGE150
    A5    GND @S9S_MB_2U_LIB.S9S_MB_2U(SCH_1):GND   I199 @S9S_MB_2U_LIB.S9S_MB_2U(SCH_1):PAGE150
    A6    GND @S9S_MB_2U_LIB.S9S_MB_2U(SCH_1):GND   I199 @S9S_MB_2U_LIB.S9S_MB_2U(SCH_1):PAGE150
    A7 SMB_OCP_SFF_3V3AUX_BUF_R_SCL @S9S_MB_2U_LIB.S9S_MB_2U(SCH_1):SMB_OCP_SFF_3V3AUX_BUF_R_SCL   I199 @S9S_MB_2U_LIB.S9S_MB_2U(SCH_1):PAGE150
    A8 SMB_OCP_SFF_3V3AUX_BUF_R_SDA @S9S_MB_2U_LIB.S9S_MB_2U(SCH_1):SMB_OCP_SFF_3V3AUX_BUF_R_SDA   I199 @S9S_MB_2U_LIB.S9S_MB_2U(SCH_1):PAGE150
    A9 RST_SMB_OCP_SFF_N @S9S_MB_2U_LIB.S9S_MB_2U(SCH_1):RST_SMB_OCP_SFF_N   I199 @S9S_MB_2U_LIB.S9S_MB_2U(SCH_1):PAGE150
   A10 OCP_SFF_PRSNTA_R_N @S9S_MB_2U_LIB.S9S_MB_2U(SCH_1):OCP_SFF_PRSNTA_R_N   I199 @S9S_MB_2U_LIB.S9S_MB_2U(SCH_1):PAGE150
   A11 RST_PERST1_OCP_SFF_N @S9S_MB_2U_LIB.S9S_MB_2U(SCH_1):RST_PERST1_OCP_SFF_N   I199 @S9S_MB_2U_LIB.S9S_MB_2U(SCH_1):PAGE150
   A12 OCP_SFF_PRSNT2_R_N @S9S_MB_2U_LIB.S9S_MB_2U(SCH_1):OCP_SFF_PRSNT2_R_N   I199 @S9S_MB_2U_LIB.S9S_MB_2U(SCH_1):PAGE150
   A13    GND @S9S_MB_2U_LIB.S9S_MB_2U(SCH_1):GND   I199 @S9S_MB_2U_LIB.S9S_MB_2U(SCH_1):PAGE150
   A14 CLK_100M_OCP_SFF_1_DN @S9S_MB_2U_LIB.S9S_MB_2U(SCH_1):CLK_100M_OCP_SFF_1_DN   I199 @S9S_MB_2U_LIB.S9S_MB_2U(SCH_1):PAGE150
   A15 CLK_100M_OCP_SFF_1_DP @S9S_MB_2U_LIB.S9S_MB_2U(SCH_1):CLK_100M_OCP_SFF_1_DP   I199 @S9S_MB_2U_LIB.S9S_MB_2U(SCH_1):PAGE150
   A16    GND @S9S_MB_2U_LIB.S9S_MB_2U(SCH_1):GND   I199 @S9S_MB_2U_LIB.S9S_MB_2U(SCH_1):PAGE150
   A17 P5E_CPU0_PE1_RX_DN<0> @S9S_MB_2U_LIB.S9S_MB_2U(SCH_1):P5E_CPU0_PE1_RX_DN(0)   I199 @S9S_MB_2U_LIB.S9S_MB_2U(SCH_1):PAGE150
   A18 P5E_CPU0_PE1_RX_DP<0> @S9S_MB_2U_LIB.S9S_MB_2U(SCH_1):P5E_CPU0_PE1_RX_DP(0)   I199 @S9S_MB_2U_LIB.S9S_MB_2U(SCH_1):PAGE150
   A19    GND @S9S_MB_2U_LIB.S9S_MB_2U(SCH_1):GND   I199 @S9S_MB_2U_LIB.S9S_MB_2U(SCH_1):PAGE150
   A20 P5E_CPU0_PE1_RX_DP<1> @S9S_MB_2U_LIB.S9S_MB_2U(SCH_1):P5E_CPU0_PE1_RX_DP(1)   I199 @S9S_MB_2U_LIB.S9S_MB_2U(SCH_1):PAGE150
   A21 P5E_CPU0_PE1_RX_DN<1> @S9S_MB_2U_LIB.S9S_MB_2U(SCH_1):P5E_CPU0_PE1_RX_DN(1)   I199 @S9S_MB_2U_LIB.S9S_MB_2U(SCH_1):PAGE150
   A22    GND @S9S_MB_2U_LIB.S9S_MB_2U(SCH_1):GND   I199 @S9S_MB_2U_LIB.S9S_MB_2U(SCH_1):PAGE150
   A23 P5E_CPU0_PE1_RX_DP<2> @S9S_MB_2U_LIB.S9S_MB_2U(SCH_1):P5E_CPU0_PE1_RX_DP(2)   I199 @S9S_MB_2U_LIB.S9S_MB_2U(SCH_1):PAGE150
   A24 P5E_CPU0_PE1_RX_DN<2> @S9S_MB_2U_LIB.S9S_MB_2U(SCH_1):P5E_CPU0_PE1_RX_DN(2)   I199 @S9S_MB_2U_LIB.S9S_MB_2U(SCH_1):PAGE150
   A25    GND @S9S_MB_2U_LIB.S9S_MB_2U(SCH_1):GND   I199 @S9S_MB_2U_LIB.S9S_MB_2U(SCH_1):PAGE150
   A26 P5E_CPU0_PE1_RX_DP<3> @S9S_MB_2U_LIB.S9S_MB_2U(SCH_1):P5E_CPU0_PE1_RX_DP(3)   I199 @S9S_MB_2U_LIB.S9S_MB_2U(SCH_1):PAGE150
   A27 P5E_CPU0_PE1_RX_DN<3> @S9S_MB_2U_LIB.S9S_MB_2U(SCH_1):P5E_CPU0_PE1_RX_DN(3)   I199 @S9S_MB_2U_LIB.S9S_MB_2U(SCH_1):PAGE150
   A28    GND @S9S_MB_2U_LIB.S9S_MB_2U(SCH_1):GND   I199 @S9S_MB_2U_LIB.S9S_MB_2U(SCH_1):PAGE150
   A29    GND @S9S_MB_2U_LIB.S9S_MB_2U(SCH_1):GND   I199 @S9S_MB_2U_LIB.S9S_MB_2U(SCH_1):PAGE150
   A30 P5E_CPU0_PE1_RX_DP<4> @S9S_MB_2U_LIB.S9S_MB_2U(SCH_1):P5E_CPU0_PE1_RX_DP(4)   I199 @S9S_MB_2U_LIB.S9S_MB_2U(SCH_1):PAGE150
   A31 P5E_CPU0_PE1_RX_DN<4> @S9S_MB_2U_LIB.S9S_MB_2U(SCH_1):P5E_CPU0_PE1_RX_DN(4)   I199 @S9S_MB_2U_LIB.S9S_MB_2U(SCH_1):PAGE150
   A32    GND @S9S_MB_2U_LIB.S9S_MB_2U(SCH_1):GND   I199 @S9S_MB_2U_LIB.S9S_MB_2U(SCH_1):PAGE150
   A33 P5E_CPU0_PE1_RX_DP<5> @S9S_MB_2U_LIB.S9S_MB_2U(SCH_1):P5E_CPU0_PE1_RX_DP(5)   I199 @S9S_MB_2U_LIB.S9S_MB_2U(SCH_1):PAGE150
   A34 P5E_CPU0_PE1_RX_DN<5> @S9S_MB_2U_LIB.S9S_MB_2U(SCH_1):P5E_CPU0_PE1_RX_DN(5)   I199 @S9S_MB_2U_LIB.S9S_MB_2U(SCH_1):PAGE150
   A35    GND @S9S_MB_2U_LIB.S9S_MB_2U(SCH_1):GND   I199 @S9S_MB_2U_LIB.S9S_MB_2U(SCH_1):PAGE150
   A36 P5E_CPU0_PE1_RX_DP<6> @S9S_MB_2U_LIB.S9S_MB_2U(SCH_1):P5E_CPU0_PE1_RX_DP(6)   I199 @S9S_MB_2U_LIB.S9S_MB_2U(SCH_1):PAGE150
   A37 P5E_CPU0_PE1_RX_DN<6> @S9S_MB_2U_LIB.S9S_MB_2U(SCH_1):P5E_CPU0_PE1_RX_DN(6)   I199 @S9S_MB_2U_LIB.S9S_MB_2U(SCH_1):PAGE150
   A38    GND @S9S_MB_2U_LIB.S9S_MB_2U(SCH_1):GND   I199 @S9S_MB_2U_LIB.S9S_MB_2U(SCH_1):PAGE150
   A39 P5E_CPU0_PE1_RX_DP<7> @S9S_MB_2U_LIB.S9S_MB_2U(SCH_1):P5E_CPU0_PE1_RX_DP(7)   I199 @S9S_MB_2U_LIB.S9S_MB_2U(SCH_1):PAGE150
   A40 P5E_CPU0_PE1_RX_DN<7> @S9S_MB_2U_LIB.S9S_MB_2U(SCH_1):P5E_CPU0_PE1_RX_DN(7)   I199 @S9S_MB_2U_LIB.S9S_MB_2U(SCH_1):PAGE150
   A41    GND @S9S_MB_2U_LIB.S9S_MB_2U(SCH_1):GND   I199 @S9S_MB_2U_LIB.S9S_MB_2U(SCH_1):PAGE150
   A42 OCP_SFF_PRSNT1_R_N @S9S_MB_2U_LIB.S9S_MB_2U(SCH_1):OCP_SFF_PRSNT1_R_N   I199 @S9S_MB_2U_LIB.S9S_MB_2U(SCH_1):PAGE150
   A43    GND @S9S_MB_2U_LIB.S9S_MB_2U(SCH_1):GND   I199 @S9S_MB_2U_LIB.S9S_MB_2U(SCH_1):PAGE150
   A44 P5E_CPU0_PE1_RX_DP<8> @S9S_MB_2U_LIB.S9S_MB_2U(SCH_1):P5E_CPU0_PE1_RX_DP(8)   I199 @S9S_MB_2U_LIB.S9S_MB_2U(SCH_1):PAGE150
   A45 P5E_CPU0_PE1_RX_DN<8> @S9S_MB_2U_LIB.S9S_MB_2U(SCH_1):P5E_CPU0_PE1_RX_DN(8)   I199 @S9S_MB_2U_LIB.S9S_MB_2U(SCH_1):PAGE150
   A46    GND @S9S_MB_2U_LIB.S9S_MB_2U(SCH_1):GND   I199 @S9S_MB_2U_LIB.S9S_MB_2U(SCH_1):PAGE150
   A47 P5E_CPU0_PE1_RX_DP<9> @S9S_MB_2U_LIB.S9S_MB_2U(SCH_1):P5E_CPU0_PE1_RX_DP(9)   I199 @S9S_MB_2U_LIB.S9S_MB_2U(SCH_1):PAGE150
   A48 P5E_CPU0_PE1_RX_DN<9> @S9S_MB_2U_LIB.S9S_MB_2U(SCH_1):P5E_CPU0_PE1_RX_DN(9)   I199 @S9S_MB_2U_LIB.S9S_MB_2U(SCH_1):PAGE150
   A49    GND @S9S_MB_2U_LIB.S9S_MB_2U(SCH_1):GND   I199 @S9S_MB_2U_LIB.S9S_MB_2U(SCH_1):PAGE150
   A50 P5E_CPU0_PE1_RX_DP<10> @S9S_MB_2U_LIB.S9S_MB_2U(SCH_1):P5E_CPU0_PE1_RX_DP(10)   I199 @S9S_MB_2U_LIB.S9S_MB_2U(SCH_1):PAGE150
   A51 P5E_CPU0_PE1_RX_DN<10> @S9S_MB_2U_LIB.S9S_MB_2U(SCH_1):P5E_CPU0_PE1_RX_DN(10)   I199 @S9S_MB_2U_LIB.S9S_MB_2U(SCH_1):PAGE150
   A52    GND @S9S_MB_2U_LIB.S9S_MB_2U(SCH_1):GND   I199 @S9S_MB_2U_LIB.S9S_MB_2U(SCH_1):PAGE150
   A53 P5E_CPU0_PE1_RX_DP<11> @S9S_MB_2U_LIB.S9S_MB_2U(SCH_1):P5E_CPU0_PE1_RX_DP(11)   I199 @S9S_MB_2U_LIB.S9S_MB_2U(SCH_1):PAGE150
   A54 P5E_CPU0_PE1_RX_DN<11> @S9S_MB_2U_LIB.S9S_MB_2U(SCH_1):P5E_CPU0_PE1_RX_DN(11)   I199 @S9S_MB_2U_LIB.S9S_MB_2U(SCH_1):PAGE150
   A55    GND @S9S_MB_2U_LIB.S9S_MB_2U(SCH_1):GND   I199 @S9S_MB_2U_LIB.S9S_MB_2U(SCH_1):PAGE150
   A56 P5E_CPU0_PE1_RX_DP<12> @S9S_MB_2U_LIB.S9S_MB_2U(SCH_1):P5E_CPU0_PE1_RX_DP(12)   I199 @S9S_MB_2U_LIB.S9S_MB_2U(SCH_1):PAGE150
   A57 P5E_CPU0_PE1_RX_DN<12> @S9S_MB_2U_LIB.S9S_MB_2U(SCH_1):P5E_CPU0_PE1_RX_DN(12)   I199 @S9S_MB_2U_LIB.S9S_MB_2U(SCH_1):PAGE150
   A58    GND @S9S_MB_2U_LIB.S9S_MB_2U(SCH_1):GND   I199 @S9S_MB_2U_LIB.S9S_MB_2U(SCH_1):PAGE150
   A59 P5E_CPU0_PE1_RX_DP<13> @S9S_MB_2U_LIB.S9S_MB_2U(SCH_1):P5E_CPU0_PE1_RX_DP(13)   I199 @S9S_MB_2U_LIB.S9S_MB_2U(SCH_1):PAGE150
   A60 P5E_CPU0_PE1_RX_DN<13> @S9S_MB_2U_LIB.S9S_MB_2U(SCH_1):P5E_CPU0_PE1_RX_DN(13)   I199 @S9S_MB_2U_LIB.S9S_MB_2U(SCH_1):PAGE150
   A61    GND @S9S_MB_2U_LIB.S9S_MB_2U(SCH_1):GND   I199 @S9S_MB_2U_LIB.S9S_MB_2U(SCH_1):PAGE150
   A62 P5E_CPU0_PE1_RX_DP<14> @S9S_MB_2U_LIB.S9S_MB_2U(SCH_1):P5E_CPU0_PE1_RX_DP(14)   I199 @S9S_MB_2U_LIB.S9S_MB_2U(SCH_1):PAGE150
   A63 P5E_CPU0_PE1_RX_DN<14> @S9S_MB_2U_LIB.S9S_MB_2U(SCH_1):P5E_CPU0_PE1_RX_DN(14)   I199 @S9S_MB_2U_LIB.S9S_MB_2U(SCH_1):PAGE150
   A64    GND @S9S_MB_2U_LIB.S9S_MB_2U(SCH_1):GND   I199 @S9S_MB_2U_LIB.S9S_MB_2U(SCH_1):PAGE150
   A65 P5E_CPU0_PE1_RX_DP<15> @S9S_MB_2U_LIB.S9S_MB_2U(SCH_1):P5E_CPU0_PE1_RX_DP(15)   I199 @S9S_MB_2U_LIB.S9S_MB_2U(SCH_1):PAGE150
   A66 P5E_CPU0_PE1_RX_DN<15> @S9S_MB_2U_LIB.S9S_MB_2U(SCH_1):P5E_CPU0_PE1_RX_DN(15)   I199 @S9S_MB_2U_LIB.S9S_MB_2U(SCH_1):PAGE150
   A67    GND @S9S_MB_2U_LIB.S9S_MB_2U(SCH_1):GND   I199 @S9S_MB_2U_LIB.S9S_MB_2U(SCH_1):PAGE150
   A68 OCP_SFF_USB2_3_DN @S9S_MB_2U_LIB.S9S_MB_2U(SCH_1):OCP_SFF_USB2_3_DN   I199 @S9S_MB_2U_LIB.S9S_MB_2U(SCH_1):PAGE150
   A69 OCP_SFF_USB2_3_DP @S9S_MB_2U_LIB.S9S_MB_2U(SCH_1):OCP_SFF_USB2_3_DP   I199 @S9S_MB_2U_LIB.S9S_MB_2U(SCH_1):PAGE150
   A70 OCP_SFF_PWRBRK_N @S9S_MB_2U_LIB.S9S_MB_2U(SCH_1):OCP_SFF_PWRBRK_N   I199 @S9S_MB_2U_LIB.S9S_MB_2U(SCH_1):PAGE150
   B57 P5E_CPU0_PE1_TX_C_DN<12> @S9S_MB_2U_LIB.S9S_MB_2U(SCH_1):P5E_CPU0_PE1_TX_C_DN(12)   I199 @S9S_MB_2U_LIB.S9S_MB_2U(SCH_1):PAGE150
   B58    GND @S9S_MB_2U_LIB.S9S_MB_2U(SCH_1):GND   I199 @S9S_MB_2U_LIB.S9S_MB_2U(SCH_1):PAGE150
   B59 P5E_CPU0_PE1_TX_C_DN<13> @S9S_MB_2U_LIB.S9S_MB_2U(SCH_1):P5E_CPU0_PE1_TX_C_DN(13)   I199 @S9S_MB_2U_LIB.S9S_MB_2U(SCH_1):PAGE150
   B60 P5E_CPU0_PE1_TX_C_DP<13> @S9S_MB_2U_LIB.S9S_MB_2U(SCH_1):P5E_CPU0_PE1_TX_C_DP(13)   I199 @S9S_MB_2U_LIB.S9S_MB_2U(SCH_1):PAGE150
   B61    GND @S9S_MB_2U_LIB.S9S_MB_2U(SCH_1):GND   I199 @S9S_MB_2U_LIB.S9S_MB_2U(SCH_1):PAGE150
   B62 P5E_CPU0_PE1_TX_C_DP<14> @S9S_MB_2U_LIB.S9S_MB_2U(SCH_1):P5E_CPU0_PE1_TX_C_DP(14)   I199 @S9S_MB_2U_LIB.S9S_MB_2U(SCH_1):PAGE150
   B63 P5E_CPU0_PE1_TX_C_DN<14> @S9S_MB_2U_LIB.S9S_MB_2U(SCH_1):P5E_CPU0_PE1_TX_C_DN(14)   I199 @S9S_MB_2U_LIB.S9S_MB_2U(SCH_1):PAGE150
   B64    GND @S9S_MB_2U_LIB.S9S_MB_2U(SCH_1):GND   I199 @S9S_MB_2U_LIB.S9S_MB_2U(SCH_1):PAGE150
   B65 P5E_CPU0_PE1_TX_C_DN<15> @S9S_MB_2U_LIB.S9S_MB_2U(SCH_1):P5E_CPU0_PE1_TX_C_DN(15)   I199 @S9S_MB_2U_LIB.S9S_MB_2U(SCH_1):PAGE150
   B66 P5E_CPU0_PE1_TX_C_DP<15> @S9S_MB_2U_LIB.S9S_MB_2U(SCH_1):P5E_CPU0_PE1_TX_C_DP(15)   I199 @S9S_MB_2U_LIB.S9S_MB_2U(SCH_1):PAGE150
   B67    GND @S9S_MB_2U_LIB.S9S_MB_2U(SCH_1):GND   I199 @S9S_MB_2U_LIB.S9S_MB_2U(SCH_1):PAGE150
   B68 TP_OCP_SFF_B68 @S9S_MB_2U_LIB.S9S_MB_2U(SCH_1):TP_OCP_SFF_B68   I199 @S9S_MB_2U_LIB.S9S_MB_2U(SCH_1):PAGE150
   B69 TP_OCP_SFF_B69 @S9S_MB_2U_LIB.S9S_MB_2U(SCH_1):TP_OCP_SFF_B69   I199 @S9S_MB_2U_LIB.S9S_MB_2U(SCH_1):PAGE150
   B70 OCP_SFF_PRSNT3_R_N @S9S_MB_2U_LIB.S9S_MB_2U(SCH_1):OCP_SFF_PRSNT3_R_N   I199 @S9S_MB_2U_LIB.S9S_MB_2U(SCH_1):PAGE150
    G1    GND @S9S_MB_2U_LIB.S9S_MB_2U(SCH_1):GND   I199 @S9S_MB_2U_LIB.S9S_MB_2U(SCH_1):PAGE150
    G2    GND @S9S_MB_2U_LIB.S9S_MB_2U(SCH_1):GND   I199 @S9S_MB_2U_LIB.S9S_MB_2U(SCH_1):PAGE150
    G3    GND @S9S_MB_2U_LIB.S9S_MB_2U(SCH_1):GND   I199 @S9S_MB_2U_LIB.S9S_MB_2U(SCH_1):PAGE150
    G4    GND @S9S_MB_2U_LIB.S9S_MB_2U(SCH_1):GND   I199 @S9S_MB_2U_LIB.S9S_MB_2U(SCH_1):PAGE150
    G5    GND @S9S_MB_2U_LIB.S9S_MB_2U(SCH_1):GND   I199 @S9S_MB_2U_LIB.S9S_MB_2U(SCH_1):PAGE150

 J41 SCONN168_ME1016810202011-SCONNA
   OB1 P12V_SCM @S9S_MB_2U_LIB.S9S_MB_2U(SCH_1):P12V_SCM   I173 @S9S_MB_2U_LIB.S9S_MB_2U(SCH_1):PAGE227
   OB2 P12V_SCM @S9S_MB_2U_LIB.S9S_MB_2U(SCH_1):P12V_SCM   I173 @S9S_MB_2U_LIB.S9S_MB_2U(SCH_1):PAGE227
   OB3 PRSNT0_N @S9S_MB_2U_LIB.S9S_MB_2U(SCH_1):PRSNT0_N   I173 @S9S_MB_2U_LIB.S9S_MB_2U(SCH_1):PAGE227
   OB4    GND @S9S_MB_2U_LIB.S9S_MB_2U(SCH_1):GND   I173 @S9S_MB_2U_LIB.S9S_MB_2U(SCH_1):PAGE227
   OB5 UART_BMC_BIC_TX @S9S_MB_2U_LIB.S9S_MB_2U(SCH_1):UART_BMC_BIC_TX   I173 @S9S_MB_2U_LIB.S9S_MB_2U(SCH_1):PAGE227
   OB6 UART_BMC_BIC_BUF_RX @S9S_MB_2U_LIB.S9S_MB_2U(SCH_1):UART_BMC_BIC_BUF_RX   I173 @S9S_MB_2U_LIB.S9S_MB_2U(SCH_1):PAGE227
   OB7    GND @S9S_MB_2U_LIB.S9S_MB_2U(SCH_1):GND   I173 @S9S_MB_2U_LIB.S9S_MB_2U(SCH_1):PAGE227
   OB8 USB2_7_R_DP @S9S_MB_2U_LIB.S9S_MB_2U(SCH_1):USB2_7_R_DP   I173 @S9S_MB_2U_LIB.S9S_MB_2U(SCH_1):PAGE227
   OB9 USB2_7_R_DN @S9S_MB_2U_LIB.S9S_MB_2U(SCH_1):USB2_7_R_DN   I173 @S9S_MB_2U_LIB.S9S_MB_2U(SCH_1):PAGE227
  OB10    GND @S9S_MB_2U_LIB.S9S_MB_2U(SCH_1):GND   I173 @S9S_MB_2U_LIB.S9S_MB_2U(SCH_1):PAGE227
  OB11 RST_SRST_PLD_BMC_N @S9S_MB_2U_LIB.S9S_MB_2U(SCH_1):RST_SRST_PLD_BMC_N   I173 @S9S_MB_2U_LIB.S9S_MB_2U(SCH_1):PAGE227
  OB12 SPI_TPM_CS_N @S9S_MB_2U_LIB.S9S_MB_2U(SCH_1):SPI_TPM_CS_N   I173 @S9S_MB_2U_LIB.S9S_MB_2U(SCH_1):PAGE227
  OB13 H_CPU_CATERR_LVC2_BMC_N @S9S_MB_2U_LIB.S9S_MB_2U(SCH_1):H_CPU_CATERR_LVC2_BMC_N   I173 @S9S_MB_2U_LIB.S9S_MB_2U(SCH_1):PAGE227
  OB14 FM_SOL_UART_CH_SEL_R @S9S_MB_2U_LIB.S9S_MB_2U(SCH_1):FM_SOL_UART_CH_SEL_R   I173 @S9S_MB_2U_LIB.S9S_MB_2U(SCH_1):PAGE227
    B1 ESPI_HOST_LPC_BMC_CLK @S9S_MB_2U_LIB.S9S_MB_2U(SCH_1):ESPI_HOST_LPC_BMC_CLK   I173 @S9S_MB_2U_LIB.S9S_MB_2U(SCH_1):PAGE227
    B2 ESPI_HOST_LPC_BMC_LFRAME_N @S9S_MB_2U_LIB.S9S_MB_2U(SCH_1):ESPI_HOST_LPC_BMC_LFRAME_N   I173 @S9S_MB_2U_LIB.S9S_MB_2U(SCH_1):PAGE227
    B3 IRQ_ESPI_LPC_SERIRQ_ALERT_R_N @S9S_MB_2U_LIB.S9S_MB_2U(SCH_1):IRQ_ESPI_LPC_SERIRQ_ALERT_R_N   I173 @S9S_MB_2U_LIB.S9S_MB_2U(SCH_1):PAGE227
    B4 ESPI_BMC_LPC_RST_N @S9S_MB_2U_LIB.S9S_MB_2U(SCH_1):ESPI_BMC_LPC_RST_N   I173 @S9S_MB_2U_LIB.S9S_MB_2U(SCH_1):PAGE227
    B5 ESPI_LPC_LAD0_IO0 @S9S_MB_2U_LIB.S9S_MB_2U(SCH_1):ESPI_LPC_LAD0_IO0   I173 @S9S_MB_2U_LIB.S9S_MB_2U(SCH_1):PAGE227
    B6 ESPI_LPC_LAD0_IO1 @S9S_MB_2U_LIB.S9S_MB_2U(SCH_1):ESPI_LPC_LAD0_IO1   I173 @S9S_MB_2U_LIB.S9S_MB_2U(SCH_1):PAGE227
    B7 ESPI_LPC_LAD0_IO2 @S9S_MB_2U_LIB.S9S_MB_2U(SCH_1):ESPI_LPC_LAD0_IO2   I173 @S9S_MB_2U_LIB.S9S_MB_2U(SCH_1):PAGE227
    B8 ESPI_LPC_LAD0_IO3 @S9S_MB_2U_LIB.S9S_MB_2U(SCH_1):ESPI_LPC_LAD0_IO3   I173 @S9S_MB_2U_LIB.S9S_MB_2U(SCH_1):PAGE227
    B9 FM_LPC_ESPI_SEL @S9S_MB_2U_LIB.S9S_MB_2U(SCH_1):FM_LPC_ESPI_SEL   I173 @S9S_MB_2U_LIB.S9S_MB_2U(SCH_1):PAGE227
   B10    GND @S9S_MB_2U_LIB.S9S_MB_2U(SCH_1):GND   I173 @S9S_MB_2U_LIB.S9S_MB_2U(SCH_1):PAGE227
   B11 SPI_SYS_CLK @S9S_MB_2U_LIB.S9S_MB_2U(SCH_1):SPI_SYS_CLK   I173 @S9S_MB_2U_LIB.S9S_MB_2U(SCH_1):PAGE227
   B12 SPI_SYS_CS0_N @S9S_MB_2U_LIB.S9S_MB_2U(SCH_1):SPI_SYS_CS0_N   I173 @S9S_MB_2U_LIB.S9S_MB_2U(SCH_1):PAGE227
   B13 SPI_SYS_MOSI @S9S_MB_2U_LIB.S9S_MB_2U(SCH_1):SPI_SYS_MOSI   I173 @S9S_MB_2U_LIB.S9S_MB_2U(SCH_1):PAGE227
   B14 SPI_SYS_MISO @S9S_MB_2U_LIB.S9S_MB_2U(SCH_1):SPI_SYS_MISO   I173 @S9S_MB_2U_LIB.S9S_MB_2U(SCH_1):PAGE227
   B15 SPI_SYS_WP_IO2 @S9S_MB_2U_LIB.S9S_MB_2U(SCH_1):SPI_SYS_WP_IO2   I173 @S9S_MB_2U_LIB.S9S_MB_2U(SCH_1):PAGE227
   B16 SPI_SYS_HOLD_IO3 @S9S_MB_2U_LIB.S9S_MB_2U(SCH_1):SPI_SYS_HOLD_IO3   I173 @S9S_MB_2U_LIB.S9S_MB_2U(SCH_1):PAGE227
   B17    GND @S9S_MB_2U_LIB.S9S_MB_2U(SCH_1):GND   I173 @S9S_MB_2U_LIB.S9S_MB_2U(SCH_1):PAGE227
   B18 CLK_50M_RMII_BMC_OCP @S9S_MB_2U_LIB.S9S_MB_2U(SCH_1):CLK_50M_RMII_BMC_OCP   I173 @S9S_MB_2U_LIB.S9S_MB_2U(SCH_1):PAGE227
   B19 RMII_OCP_BMC_CRSDV @S9S_MB_2U_LIB.S9S_MB_2U(SCH_1):RMII_OCP_BMC_CRSDV   I173 @S9S_MB_2U_LIB.S9S_MB_2U(SCH_1):PAGE227
   B20 RMII_BMC_OCP_TX_EN @S9S_MB_2U_LIB.S9S_MB_2U(SCH_1):RMII_BMC_OCP_TX_EN   I173 @S9S_MB_2U_LIB.S9S_MB_2U(SCH_1):PAGE227
   B21 RMII_BMC_OCP_TXD_0 @S9S_MB_2U_LIB.S9S_MB_2U(SCH_1):RMII_BMC_OCP_TXD_0   I173 @S9S_MB_2U_LIB.S9S_MB_2U(SCH_1):PAGE227
   B22 RMII_BMC_OCP_TXD_1 @S9S_MB_2U_LIB.S9S_MB_2U(SCH_1):RMII_BMC_OCP_TXD_1   I173 @S9S_MB_2U_LIB.S9S_MB_2U(SCH_1):PAGE227
   B23 RMII_BMC_OCP_RX_ER @S9S_MB_2U_LIB.S9S_MB_2U(SCH_1):RMII_BMC_OCP_RX_ER   I173 @S9S_MB_2U_LIB.S9S_MB_2U(SCH_1):PAGE227
   B24 RMII_OCP_BMC_RXD_0 @S9S_MB_2U_LIB.S9S_MB_2U(SCH_1):RMII_OCP_BMC_RXD_0   I173 @S9S_MB_2U_LIB.S9S_MB_2U(SCH_1):PAGE227
   B25 RMII_OCP_BMC_RXD_1 @S9S_MB_2U_LIB.S9S_MB_2U(SCH_1):RMII_OCP_BMC_RXD_1   I173 @S9S_MB_2U_LIB.S9S_MB_2U(SCH_1):PAGE227
   B26    GND @S9S_MB_2U_LIB.S9S_MB_2U(SCH_1):GND   I173 @S9S_MB_2U_LIB.S9S_MB_2U(SCH_1):PAGE227
   B27 PECI_BMC @S9S_MB_2U_LIB.S9S_MB_2U(SCH_1):PECI_BMC   I173 @S9S_MB_2U_LIB.S9S_MB_2U(SCH_1):PAGE227
   B28 PVCCIO_PECI_BMC @S9S_MB_2U_LIB.S9S_MB_2U(SCH_1):PVCCIO_PECI_BMC   I173 @S9S_MB_2U_LIB.S9S_MB_2U(SCH_1):PAGE227
   B29 SGPIO_DO_0 @S9S_MB_2U_LIB.S9S_MB_2U(SCH_1):SGPIO_DO_0   I173 @S9S_MB_2U_LIB.S9S_MB_2U(SCH_1):PAGE227
   B30 SGPIO_CLK_0 @S9S_MB_2U_LIB.S9S_MB_2U(SCH_1):SGPIO_CLK_0   I173 @S9S_MB_2U_LIB.S9S_MB_2U(SCH_1):PAGE227
   B31 SGPIO_DI_0 @S9S_MB_2U_LIB.S9S_MB_2U(SCH_1):SGPIO_DI_0   I173 @S9S_MB_2U_LIB.S9S_MB_2U(SCH_1):PAGE227
   B32 SGPIO_LD_0 @S9S_MB_2U_LIB.S9S_MB_2U(SCH_1):SGPIO_LD_0   I173 @S9S_MB_2U_LIB.S9S_MB_2U(SCH_1):PAGE227
   B33    GND @S9S_MB_2U_LIB.S9S_MB_2U(SCH_1):GND   I173 @S9S_MB_2U_LIB.S9S_MB_2U(SCH_1):PAGE227
   B34 SGPIO_DO_1 @S9S_MB_2U_LIB.S9S_MB_2U(SCH_1):SGPIO_DO_1   I173 @S9S_MB_2U_LIB.S9S_MB_2U(SCH_1):PAGE227
   B35 SGPIO_CLK_1 @S9S_MB_2U_LIB.S9S_MB_2U(SCH_1):SGPIO_CLK_1   I173 @S9S_MB_2U_LIB.S9S_MB_2U(SCH_1):PAGE227
   B36 SGPIO_DI_1 @S9S_MB_2U_LIB.S9S_MB_2U(SCH_1):SGPIO_DI_1   I173 @S9S_MB_2U_LIB.S9S_MB_2U(SCH_1):PAGE227
   B37 SGPIO_LD_1 @S9S_MB_2U_LIB.S9S_MB_2U(SCH_1):SGPIO_LD_1   I173 @S9S_MB_2U_LIB.S9S_MB_2U(SCH_1):PAGE227
   B38    GND @S9S_MB_2U_LIB.S9S_MB_2U(SCH_1):GND   I173 @S9S_MB_2U_LIB.S9S_MB_2U(SCH_1):PAGE227
   B39 RST_SGPIO_RESET_N @S9S_MB_2U_LIB.S9S_MB_2U(SCH_1):RST_SGPIO_RESET_N   I173 @S9S_MB_2U_LIB.S9S_MB_2U(SCH_1):PAGE227
   B40 IRQ_SGPIO_INTR_N @S9S_MB_2U_LIB.S9S_MB_2U(SCH_1):IRQ_SGPIO_INTR_N   I173 @S9S_MB_2U_LIB.S9S_MB_2U(SCH_1):PAGE227
   B41 P3V_BAT_R1 @S9S_MB_2U_LIB.S9S_MB_2U(SCH_1):P3V_BAT_R1   I173 @S9S_MB_2U_LIB.S9S_MB_2U(SCH_1):PAGE227
   B42 FM_AC_PWR_BTN_N @S9S_MB_2U_LIB.S9S_MB_2U(SCH_1):FM_AC_PWR_BTN_N   I173 @S9S_MB_2U_LIB.S9S_MB_2U(SCH_1):PAGE227
   B43 TP_SPI_2_PLD_CLK @S9S_MB_2U_LIB.S9S_MB_2U(SCH_1):TP_SPI_2_PLD_CLK   I173 @S9S_MB_2U_LIB.S9S_MB_2U(SCH_1):PAGE227
   B44 TP_SPI_2_PLD_CS_N @S9S_MB_2U_LIB.S9S_MB_2U(SCH_1):TP_SPI_2_PLD_CS_N   I173 @S9S_MB_2U_LIB.S9S_MB_2U(SCH_1):PAGE227
   B45 TP_SPI_2_PLD_IO0 @S9S_MB_2U_LIB.S9S_MB_2U(SCH_1):TP_SPI_2_PLD_IO0   I173 @S9S_MB_2U_LIB.S9S_MB_2U(SCH_1):PAGE227
   B46 TP_SPI_2_PLD_IO1 @S9S_MB_2U_LIB.S9S_MB_2U(SCH_1):TP_SPI_2_PLD_IO1   I173 @S9S_MB_2U_LIB.S9S_MB_2U(SCH_1):PAGE227
   B47 TP_SPI_2_PLD_IO2 @S9S_MB_2U_LIB.S9S_MB_2U(SCH_1):TP_SPI_2_PLD_IO2   I173 @S9S_MB_2U_LIB.S9S_MB_2U(SCH_1):PAGE227
   B48 TP_SPI_2_PLD_IO3 @S9S_MB_2U_LIB.S9S_MB_2U(SCH_1):TP_SPI_2_PLD_IO3   I173 @S9S_MB_2U_LIB.S9S_MB_2U(SCH_1):PAGE227
   B49    GND @S9S_MB_2U_LIB.S9S_MB_2U(SCH_1):GND   I173 @S9S_MB_2U_LIB.S9S_MB_2U(SCH_1):PAGE227
   B50 USB2_HOST_BMC_B_DP @S9S_MB_2U_LIB.S9S_MB_2U(SCH_1):USB2_HOST_BMC_B_DP   I173 @S9S_MB_2U_LIB.S9S_MB_2U(SCH_1):PAGE227
   B51 USB2_HOST_BMC_B_DN @S9S_MB_2U_LIB.S9S_MB_2U(SCH_1):USB2_HOST_BMC_B_DN   I173 @S9S_MB_2U_LIB.S9S_MB_2U(SCH_1):PAGE227
   B52    GND @S9S_MB_2U_LIB.S9S_MB_2U(SCH_1):GND   I173 @S9S_MB_2U_LIB.S9S_MB_2U(SCH_1):PAGE227
   B53 USB2_8_DP @S9S_MB_2U_LIB.S9S_MB_2U(SCH_1):USB2_8_DP   I173 @S9S_MB_2U_LIB.S9S_MB_2U(SCH_1):PAGE227
   B54 USB2_8_DN @S9S_MB_2U_LIB.S9S_MB_2U(SCH_1):USB2_8_DN   I173 @S9S_MB_2U_LIB.S9S_MB_2U(SCH_1):PAGE227
   B55    GND @S9S_MB_2U_LIB.S9S_MB_2U(SCH_1):GND   I173 @S9S_MB_2U_LIB.S9S_MB_2U(SCH_1):PAGE227
   B56 USB2_HUB_2_BUF_EXT_DP @S9S_MB_2U_LIB.S9S_MB_2U(SCH_1):USB2_HUB_2_BUF_EXT_DP   I173 @S9S_MB_2U_LIB.S9S_MB_2U(SCH_1):PAGE227
   OA1 P12V_SCM @S9S_MB_2U_LIB.S9S_MB_2U(SCH_1):P12V_SCM   I173 @S9S_MB_2U_LIB.S9S_MB_2U(SCH_1):PAGE227
   OA2 P12V_SCM @S9S_MB_2U_LIB.S9S_MB_2U(SCH_1):P12V_SCM   I173 @S9S_MB_2U_LIB.S9S_MB_2U(SCH_1):PAGE227
   OA3    GND @S9S_MB_2U_LIB.S9S_MB_2U(SCH_1):GND   I173 @S9S_MB_2U_LIB.S9S_MB_2U(SCH_1):PAGE227
   OA4    GND @S9S_MB_2U_LIB.S9S_MB_2U(SCH_1):GND   I173 @S9S_MB_2U_LIB.S9S_MB_2U(SCH_1):PAGE227
   OA5 I3C_SPD_DDRABCD_CPU0_BMC_R_SCL @S9S_MB_2U_LIB.S9S_MB_2U(SCH_1):I3C_SPD_DDRABCD_CPU0_BMC_R_SCL   I173 @S9S_MB_2U_LIB.S9S_MB_2U(SCH_1):PAGE227
   OA6 I3C_SPD_DDRABCD_CPU0_BMC_R_SDA @S9S_MB_2U_LIB.S9S_MB_2U(SCH_1):I3C_SPD_DDRABCD_CPU0_BMC_R_SDA   I173 @S9S_MB_2U_LIB.S9S_MB_2U(SCH_1):PAGE227
   OA7 I3C_SPD_DDREFGH_CPU0_BMC_R_SCL @S9S_MB_2U_LIB.S9S_MB_2U(SCH_1):I3C_SPD_DDREFGH_CPU0_BMC_R_SCL   I173 @S9S_MB_2U_LIB.S9S_MB_2U(SCH_1):PAGE227
   OA8 I3C_SPD_DDREFGH_CPU0_BMC_R_SDA @S9S_MB_2U_LIB.S9S_MB_2U(SCH_1):I3C_SPD_DDREFGH_CPU0_BMC_R_SDA   I173 @S9S_MB_2U_LIB.S9S_MB_2U(SCH_1):PAGE227
   OA9 I3C_SPD_DDRABCD_CPU1_BMC_R_SCL @S9S_MB_2U_LIB.S9S_MB_2U(SCH_1):I3C_SPD_DDRABCD_CPU1_BMC_R_SCL   I173 @S9S_MB_2U_LIB.S9S_MB_2U(SCH_1):PAGE227
  OA10 I3C_SPD_DDRABCD_CPU1_BMC_R_SDA @S9S_MB_2U_LIB.S9S_MB_2U(SCH_1):I3C_SPD_DDRABCD_CPU1_BMC_R_SDA   I173 @S9S_MB_2U_LIB.S9S_MB_2U(SCH_1):PAGE227
  OA11 I3C_SPD_DDREFGH_CPU1_BMC_R_SCL @S9S_MB_2U_LIB.S9S_MB_2U(SCH_1):I3C_SPD_DDREFGH_CPU1_BMC_R_SCL   I173 @S9S_MB_2U_LIB.S9S_MB_2U(SCH_1):PAGE227
  OA12 I3C_SPD_DDREFGH_CPU1_BMC_R_SDA @S9S_MB_2U_LIB.S9S_MB_2U(SCH_1):I3C_SPD_DDREFGH_CPU1_BMC_R_SDA   I173 @S9S_MB_2U_LIB.S9S_MB_2U(SCH_1):PAGE227
  OA13    GND @S9S_MB_2U_LIB.S9S_MB_2U(SCH_1):GND   I173 @S9S_MB_2U_LIB.S9S_MB_2U(SCH_1):PAGE227
  OA14 VIRTUAL_RESEAT @S9S_MB_2U_LIB.S9S_MB_2U(SCH_1):VIRTUAL_RESEAT   I173 @S9S_MB_2U_LIB.S9S_MB_2U(SCH_1):PAGE227
    A1 SMB_OCP_SFF_3V3AUX_SCL_R0 @S9S_MB_2U_LIB.S9S_MB_2U(SCH_1):SMB_OCP_SFF_3V3AUX_SCL_R0   I173 @S9S_MB_2U_LIB.S9S_MB_2U(SCH_1):PAGE227
    A2 SMB_OCP_SFF_3V3AUX_SDA_R0 @S9S_MB_2U_LIB.S9S_MB_2U(SCH_1):SMB_OCP_SFF_3V3AUX_SDA_R0   I173 @S9S_MB_2U_LIB.S9S_MB_2U(SCH_1):PAGE227
    A3 SMB_HOST_3V3AUX_SCL_R0 @S9S_MB_2U_LIB.S9S_MB_2U(SCH_1):SMB_HOST_3V3AUX_SCL_R0   I173 @S9S_MB_2U_LIB.S9S_MB_2U(SCH_1):PAGE227
    A4 SMB_HOST_3V3AUX_SDA_R0 @S9S_MB_2U_LIB.S9S_MB_2U(SCH_1):SMB_HOST_3V3AUX_SDA_R0   I173 @S9S_MB_2U_LIB.S9S_MB_2U(SCH_1):PAGE227
    A5 SMB_VR_3V3AUX_SCL_R0 @S9S_MB_2U_LIB.S9S_MB_2U(SCH_1):SMB_VR_3V3AUX_SCL_R0   I173 @S9S_MB_2U_LIB.S9S_MB_2U(SCH_1):PAGE227
    A6 SMB_VR_3V3AUX_SDA_R0 @S9S_MB_2U_LIB.S9S_MB_2U(SCH_1):SMB_VR_3V3AUX_SDA_R0   I173 @S9S_MB_2U_LIB.S9S_MB_2U(SCH_1):PAGE227
    A7 SMB_SML1_PMBUS_3V3AUX_PCH_SCL_R @S9S_MB_2U_LIB.S9S_MB_2U(SCH_1):SMB_SML1_PMBUS_3V3AUX_PCH_SCL_R0   I173 @S9S_MB_2U_LIB.S9S_MB_2U(SCH_1):PAGE227
    A8 SMB_SML1_PMBUS_3V3AUX_PCH_SDA_R @S9S_MB_2U_LIB.S9S_MB_2U(SCH_1):SMB_SML1_PMBUS_3V3AUX_PCH_SDA_R0   I173 @S9S_MB_2U_LIB.S9S_MB_2U(SCH_1):PAGE227
    A9 I3C_BMC_SWB_SCL @S9S_MB_2U_LIB.S9S_MB_2U(SCH_1):I3C_BMC_SWB_SCL   I173 @S9S_MB_2U_LIB.S9S_MB_2U(SCH_1):PAGE227
   A10 I3C_BMC_SWB_SDA @S9S_MB_2U_LIB.S9S_MB_2U(SCH_1):I3C_BMC_SWB_SDA   I173 @S9S_MB_2U_LIB.S9S_MB_2U(SCH_1):PAGE227
   A11 SMB_OCP_V3_2_3V3AUX_SCL_R0 @S9S_MB_2U_LIB.S9S_MB_2U(SCH_1):SMB_OCP_V3_2_3V3AUX_SCL_R0   I173 @S9S_MB_2U_LIB.S9S_MB_2U(SCH_1):PAGE227
   A12 SMB_OCP_V3_2_3V3AUX_SDA_R0 @S9S_MB_2U_LIB.S9S_MB_2U(SCH_1):SMB_OCP_V3_2_3V3AUX_SDA_R0   I173 @S9S_MB_2U_LIB.S9S_MB_2U(SCH_1):PAGE227
   A13    GND @S9S_MB_2U_LIB.S9S_MB_2U(SCH_1):GND   I173 @S9S_MB_2U_LIB.S9S_MB_2U(SCH_1):PAGE227
   A14 CLK_100M_BMC_P3E_DP_R @S9S_MB_2U_LIB.S9S_MB_2U(SCH_1):CLK_100M_BMC_P3E_DP_R   I173 @S9S_MB_2U_LIB.S9S_MB_2U(SCH_1):PAGE227
   A15 CLK_100M_BMC_P3E_DN_R @S9S_MB_2U_LIB.S9S_MB_2U(SCH_1):CLK_100M_BMC_P3E_DN_R   I173 @S9S_MB_2U_LIB.S9S_MB_2U(SCH_1):PAGE227
   A16    GND @S9S_MB_2U_LIB.S9S_MB_2U(SCH_1):GND   I173 @S9S_MB_2U_LIB.S9S_MB_2U(SCH_1):PAGE227
   A17 P3E_PCH_BMC_TX_C_DP @S9S_MB_2U_LIB.S9S_MB_2U(SCH_1):P3E_PCH_BMC_TX_C_DP   I173 @S9S_MB_2U_LIB.S9S_MB_2U(SCH_1):PAGE227
   A18 P3E_PCH_BMC_TX_C_DN @S9S_MB_2U_LIB.S9S_MB_2U(SCH_1):P3E_PCH_BMC_TX_C_DN   I173 @S9S_MB_2U_LIB.S9S_MB_2U(SCH_1):PAGE227
   A19    GND @S9S_MB_2U_LIB.S9S_MB_2U(SCH_1):GND   I173 @S9S_MB_2U_LIB.S9S_MB_2U(SCH_1):PAGE227
   A20 P3E_PCH_BMC_RX_DP @S9S_MB_2U_LIB.S9S_MB_2U(SCH_1):P3E_PCH_BMC_RX_DP   I173 @S9S_MB_2U_LIB.S9S_MB_2U(SCH_1):PAGE227
   A21 P3E_PCH_BMC_RX_DN @S9S_MB_2U_LIB.S9S_MB_2U(SCH_1):P3E_PCH_BMC_RX_DN   I173 @S9S_MB_2U_LIB.S9S_MB_2U(SCH_1):PAGE227
   A22    GND @S9S_MB_2U_LIB.S9S_MB_2U(SCH_1):GND   I173 @S9S_MB_2U_LIB.S9S_MB_2U(SCH_1):PAGE227
   A23 SMB_PCIE0_3V3AUX_SCL @S9S_MB_2U_LIB.S9S_MB_2U(SCH_1):SMB_PCIE0_3V3AUX_SCL   I173 @S9S_MB_2U_LIB.S9S_MB_2U(SCH_1):PAGE227
   A24 SMB_PCIE0_3V3AUX_SDA @S9S_MB_2U_LIB.S9S_MB_2U(SCH_1):SMB_PCIE0_3V3AUX_SDA   I173 @S9S_MB_2U_LIB.S9S_MB_2U(SCH_1):PAGE227
   A25 SMB_SML0_3V3AUX_SCL_R1 @S9S_MB_2U_LIB.S9S_MB_2U(SCH_1):SMB_SML0_3V3AUX_SCL_R1   I173 @S9S_MB_2U_LIB.S9S_MB_2U(SCH_1):PAGE227
   A26 SMB_SML0_3V3AUX_SDA_R1 @S9S_MB_2U_LIB.S9S_MB_2U(SCH_1):SMB_SML0_3V3AUX_SDA_R1   I173 @S9S_MB_2U_LIB.S9S_MB_2U(SCH_1):PAGE227
   A27 SMB_1_PLD_3V3AUX_SCL_R3 @S9S_MB_2U_LIB.S9S_MB_2U(SCH_1):SMB_1_PLD_3V3AUX_SCL_R3   I173 @S9S_MB_2U_LIB.S9S_MB_2U(SCH_1):PAGE227
   A28 SMB_1_PLD_3V3AUX_SDA_R3 @S9S_MB_2U_LIB.S9S_MB_2U(SCH_1):SMB_1_PLD_3V3AUX_SDA_R3   I173 @S9S_MB_2U_LIB.S9S_MB_2U(SCH_1):PAGE227
   A29 SMB_FAN_3V3AUX_SCL @S9S_MB_2U_LIB.S9S_MB_2U(SCH_1):SMB_FAN_3V3AUX_SCL   I173 @S9S_MB_2U_LIB.S9S_MB_2U(SCH_1):PAGE227
   A30 SMB_FAN_3V3AUX_SDA @S9S_MB_2U_LIB.S9S_MB_2U(SCH_1):SMB_FAN_3V3AUX_SDA   I173 @S9S_MB_2U_LIB.S9S_MB_2U(SCH_1):PAGE227
   A31 SMB_PCIE2_3V3AUX_SCL_R0 @S9S_MB_2U_LIB.S9S_MB_2U(SCH_1):SMB_PCIE2_3V3AUX_SCL_R0   I173 @S9S_MB_2U_LIB.S9S_MB_2U(SCH_1):PAGE227
   A32 SMB_PCIE2_3V3AUX_SDA_R0 @S9S_MB_2U_LIB.S9S_MB_2U(SCH_1):SMB_PCIE2_3V3AUX_SDA_R0   I173 @S9S_MB_2U_LIB.S9S_MB_2U(SCH_1):PAGE227
   A33    GND @S9S_MB_2U_LIB.S9S_MB_2U(SCH_1):GND   I173 @S9S_MB_2U_LIB.S9S_MB_2U(SCH_1):PAGE227
   A34 JTAG_BMC_TCK @S9S_MB_2U_LIB.S9S_MB_2U(SCH_1):JTAG_BMC_TCK   I173 @S9S_MB_2U_LIB.S9S_MB_2U(SCH_1):PAGE227
   A35 JTAG_BMC_TMS @S9S_MB_2U_LIB.S9S_MB_2U(SCH_1):JTAG_BMC_TMS   I173 @S9S_MB_2U_LIB.S9S_MB_2U(SCH_1):PAGE227
   A36 JTAG_BMC_TDI @S9S_MB_2U_LIB.S9S_MB_2U(SCH_1):JTAG_BMC_TDI   I173 @S9S_MB_2U_LIB.S9S_MB_2U(SCH_1):PAGE227
   A37 JTAG_BMC_TDO @S9S_MB_2U_LIB.S9S_MB_2U(SCH_1):JTAG_BMC_TDO   I173 @S9S_MB_2U_LIB.S9S_MB_2U(SCH_1):PAGE227
   A38 SMB_PCIE3_3V3AUX_SCL_R @S9S_MB_2U_LIB.S9S_MB_2U(SCH_1):SMB_PCIE3_3V3AUX_SCL_R   I173 @S9S_MB_2U_LIB.S9S_MB_2U(SCH_1):PAGE227
   A39 SMB_PCIE3_3V3AUX_SDA_R @S9S_MB_2U_LIB.S9S_MB_2U(SCH_1):SMB_PCIE3_3V3AUX_SDA_R   I173 @S9S_MB_2U_LIB.S9S_MB_2U(SCH_1):PAGE227
   A40 SMB_S3M_CPU_3V3AUX_SCL_R0 @S9S_MB_2U_LIB.S9S_MB_2U(SCH_1):SMB_S3M_CPU_3V3AUX_SCL_R0   I173 @S9S_MB_2U_LIB.S9S_MB_2U(SCH_1):PAGE227
   A41 SMB_S3M_CPU_3V3AUX_SDA_R0 @S9S_MB_2U_LIB.S9S_MB_2U(SCH_1):SMB_S3M_CPU_3V3AUX_SDA_R0   I173 @S9S_MB_2U_LIB.S9S_MB_2U(SCH_1):PAGE227
   A42    GND @S9S_MB_2U_LIB.S9S_MB_2U(SCH_1):GND   I173 @S9S_MB_2U_LIB.S9S_MB_2U(SCH_1):PAGE227
   A43 FM_JTAG_BMC_MUX_SEL_FROM_BMC_R2 @S9S_MB_2U_LIB.S9S_MB_2U(SCH_1):FM_JTAG_BMC_MUX_SEL_FROM_BMC_R2   I173 @S9S_MB_2U_LIB.S9S_MB_2U(SCH_1):PAGE227
   A44 PWRGD_PS_PWROK_R @S9S_MB_2U_LIB.S9S_MB_2U(SCH_1):PWRGD_PS_PWROK_R   I173 @S9S_MB_2U_LIB.S9S_MB_2U(SCH_1):PAGE227
   A45 TP_HPM_STBY_EN @S9S_MB_2U_LIB.S9S_MB_2U(SCH_1):TP_HPM_STBY_EN   I173 @S9S_MB_2U_LIB.S9S_MB_2U(SCH_1):PAGE227
   A46 RST_MB_STBY_N @S9S_MB_2U_LIB.S9S_MB_2U(SCH_1):RST_MB_STBY_N   I173 @S9S_MB_2U_LIB.S9S_MB_2U(SCH_1):PAGE227
   A47 FM_BMC_PWRBTN_OUT_R_N @S9S_MB_2U_LIB.S9S_MB_2U(SCH_1):FM_BMC_PWRBTN_OUT_R_N   I173 @S9S_MB_2U_LIB.S9S_MB_2U(SCH_1):PAGE227
   A48 PWRGD_SYS_PWROK @S9S_MB_2U_LIB.S9S_MB_2U(SCH_1):PWRGD_SYS_PWROK   I173 @S9S_MB_2U_LIB.S9S_MB_2U(SCH_1):PAGE227
   A49 JTAG_BMC_DBP_PREQ_N @S9S_MB_2U_LIB.S9S_MB_2U(SCH_1):JTAG_BMC_DBP_PREQ_N   I173 @S9S_MB_2U_LIB.S9S_MB_2U(SCH_1):PAGE227
   A50 JTAG_DBP_BMC_PRDY_N @S9S_MB_2U_LIB.S9S_MB_2U(SCH_1):JTAG_DBP_BMC_PRDY_N   I173 @S9S_MB_2U_LIB.S9S_MB_2U(SCH_1):PAGE227
   A51 RST_PLTRST_B_N @S9S_MB_2U_LIB.S9S_MB_2U(SCH_1):RST_PLTRST_B_N   I173 @S9S_MB_2U_LIB.S9S_MB_2U(SCH_1):PAGE227
   A52 FM_UARTSW_MSB_R @S9S_MB_2U_LIB.S9S_MB_2U(SCH_1):FM_UARTSW_MSB_R   I173 @S9S_MB_2U_LIB.S9S_MB_2U(SCH_1):PAGE227
   A53 ROT_P1_RST_IND_N @S9S_MB_2U_LIB.S9S_MB_2U(SCH_1):ROT_P1_RST_IND_N   I173 @S9S_MB_2U_LIB.S9S_MB_2U(SCH_1):PAGE227
   A54 FM_BMC_INTRUDER_N @S9S_MB_2U_LIB.S9S_MB_2U(SCH_1):FM_BMC_INTRUDER_N   I173 @S9S_MB_2U_LIB.S9S_MB_2U(SCH_1):PAGE227
   A55 FM_UARTSW_LSB_R @S9S_MB_2U_LIB.S9S_MB_2U(SCH_1):FM_UARTSW_LSB_R   I173 @S9S_MB_2U_LIB.S9S_MB_2U(SCH_1):PAGE227
   A56 IRQ0_A57 @S9S_MB_2U_LIB.S9S_MB_2U(SCH_1):IRQ0_A57   I173 @S9S_MB_2U_LIB.S9S_MB_2U(SCH_1):PAGE227
   A57 FM_SCM_PRSNT1_N @S9S_MB_2U_LIB.S9S_MB_2U(SCH_1):FM_SCM_PRSNT1_N   I173 @S9S_MB_2U_LIB.S9S_MB_2U(SCH_1):PAGE227
   A58    GND @S9S_MB_2U_LIB.S9S_MB_2U(SCH_1):GND   I173 @S9S_MB_2U_LIB.S9S_MB_2U(SCH_1):PAGE227
   A59 USB3_PCH_RX_DP<4> @S9S_MB_2U_LIB.S9S_MB_2U(SCH_1):USB3_PCH_RX_DP(4)   I173 @S9S_MB_2U_LIB.S9S_MB_2U(SCH_1):PAGE227
   A60 USB3_PCH_RX_DN<4> @S9S_MB_2U_LIB.S9S_MB_2U(SCH_1):USB3_PCH_RX_DN(4)   I173 @S9S_MB_2U_LIB.S9S_MB_2U(SCH_1):PAGE227
   A61    GND @S9S_MB_2U_LIB.S9S_MB_2U(SCH_1):GND   I173 @S9S_MB_2U_LIB.S9S_MB_2U(SCH_1):PAGE227
   A62 TP_PCIE_HPM_RXP<1> @S9S_MB_2U_LIB.S9S_MB_2U(SCH_1):TP_PCIE_HPM_RXP(1)   I173 @S9S_MB_2U_LIB.S9S_MB_2U(SCH_1):PAGE227
   A63 TP_PCIE_HPM_RXN<1> @S9S_MB_2U_LIB.S9S_MB_2U(SCH_1):TP_PCIE_HPM_RXN(1)   I173 @S9S_MB_2U_LIB.S9S_MB_2U(SCH_1):PAGE227
   A64    GND @S9S_MB_2U_LIB.S9S_MB_2U(SCH_1):GND   I173 @S9S_MB_2U_LIB.S9S_MB_2U(SCH_1):PAGE227
   A65 P2E_MB_BMC_RX_BUF_DP<0> @S9S_MB_2U_LIB.S9S_MB_2U(SCH_1):P2E_MB_BMC_RX_BUF_DP(0)   I173 @S9S_MB_2U_LIB.S9S_MB_2U(SCH_1):PAGE227
   A66 P2E_MB_BMC_RX_BUF_DN<0> @S9S_MB_2U_LIB.S9S_MB_2U(SCH_1):P2E_MB_BMC_RX_BUF_DN(0)   I173 @S9S_MB_2U_LIB.S9S_MB_2U(SCH_1):PAGE227
   A67    GND @S9S_MB_2U_LIB.S9S_MB_2U(SCH_1):GND   I173 @S9S_MB_2U_LIB.S9S_MB_2U(SCH_1):PAGE227
   A68 CLK_100M_BMC_RC_DP @S9S_MB_2U_LIB.S9S_MB_2U(SCH_1):CLK_100M_BMC_RC_DP   I173 @S9S_MB_2U_LIB.S9S_MB_2U(SCH_1):PAGE227
   A69 CLK_100M_BMC_RC_DN @S9S_MB_2U_LIB.S9S_MB_2U(SCH_1):CLK_100M_BMC_RC_DN   I173 @S9S_MB_2U_LIB.S9S_MB_2U(SCH_1):PAGE227
   A70    GND @S9S_MB_2U_LIB.S9S_MB_2U(SCH_1):GND   I173 @S9S_MB_2U_LIB.S9S_MB_2U(SCH_1):PAGE227
   B57 USB2_HUB_2_BUF_EXT_DN @S9S_MB_2U_LIB.S9S_MB_2U(SCH_1):USB2_HUB_2_BUF_EXT_DN   I173 @S9S_MB_2U_LIB.S9S_MB_2U(SCH_1):PAGE227
   B58    GND @S9S_MB_2U_LIB.S9S_MB_2U(SCH_1):GND   I173 @S9S_MB_2U_LIB.S9S_MB_2U(SCH_1):PAGE227
   B59 USB3_PCH_TX_BUF_C_DP<4> @S9S_MB_2U_LIB.S9S_MB_2U(SCH_1):USB3_PCH_TX_BUF_C_DP(4)   I173 @S9S_MB_2U_LIB.S9S_MB_2U(SCH_1):PAGE227
   B60 USB3_PCH_TX_BUF_C_DN<4> @S9S_MB_2U_LIB.S9S_MB_2U(SCH_1):USB3_PCH_TX_BUF_C_DN(4)   I173 @S9S_MB_2U_LIB.S9S_MB_2U(SCH_1):PAGE227
   B61    GND @S9S_MB_2U_LIB.S9S_MB_2U(SCH_1):GND   I173 @S9S_MB_2U_LIB.S9S_MB_2U(SCH_1):PAGE227
   B62 TP_PCIE_HPM_TXP<1> @S9S_MB_2U_LIB.S9S_MB_2U(SCH_1):TP_PCIE_HPM_TXP(1)   I173 @S9S_MB_2U_LIB.S9S_MB_2U(SCH_1):PAGE227
   B63 TP_PCIE_HPM_TXN<1> @S9S_MB_2U_LIB.S9S_MB_2U(SCH_1):TP_PCIE_HPM_TXN(1)   I173 @S9S_MB_2U_LIB.S9S_MB_2U(SCH_1):PAGE227
   B64    GND @S9S_MB_2U_LIB.S9S_MB_2U(SCH_1):GND   I173 @S9S_MB_2U_LIB.S9S_MB_2U(SCH_1):PAGE227
   B65 P2E_MB_BMC_TX_C_DP<0> @S9S_MB_2U_LIB.S9S_MB_2U(SCH_1):P2E_MB_BMC_TX_C_DP(0)   I173 @S9S_MB_2U_LIB.S9S_MB_2U(SCH_1):PAGE227
   B66 P2E_MB_BMC_TX_C_DN<0> @S9S_MB_2U_LIB.S9S_MB_2U(SCH_1):P2E_MB_BMC_TX_C_DN(0)   I173 @S9S_MB_2U_LIB.S9S_MB_2U(SCH_1):PAGE227
   B67    GND @S9S_MB_2U_LIB.S9S_MB_2U(SCH_1):GND   I173 @S9S_MB_2U_LIB.S9S_MB_2U(SCH_1):PAGE227
   B68 TP_PCIE_HPM_TXP<3> @S9S_MB_2U_LIB.S9S_MB_2U(SCH_1):TP_PCIE_HPM_TXP(3)   I173 @S9S_MB_2U_LIB.S9S_MB_2U(SCH_1):PAGE227
   B69 TP_PCIE_HPM_TXN<3> @S9S_MB_2U_LIB.S9S_MB_2U(SCH_1):TP_PCIE_HPM_TXN(3)   I173 @S9S_MB_2U_LIB.S9S_MB_2U(SCH_1):PAGE227
   B70    GND @S9S_MB_2U_LIB.S9S_MB_2U(SCH_1):GND   I173 @S9S_MB_2U_LIB.S9S_MB_2U(SCH_1):PAGE227
    G1    GND @S9S_MB_2U_LIB.S9S_MB_2U(SCH_1):GND   I173 @S9S_MB_2U_LIB.S9S_MB_2U(SCH_1):PAGE227
    G2    GND @S9S_MB_2U_LIB.S9S_MB_2U(SCH_1):GND   I173 @S9S_MB_2U_LIB.S9S_MB_2U(SCH_1):PAGE227
    G3    GND @S9S_MB_2U_LIB.S9S_MB_2U(SCH_1):GND   I173 @S9S_MB_2U_LIB.S9S_MB_2U(SCH_1):PAGE227
    G4    GND @S9S_MB_2U_LIB.S9S_MB_2U(SCH_1):GND   I173 @S9S_MB_2U_LIB.S9S_MB_2U(SCH_1):PAGE227
    G5    GND @S9S_MB_2U_LIB.S9S_MB_2U(SCH_1):GND   I173 @S9S_MB_2U_LIB.S9S_MB_2U(SCH_1):PAGE227

 J42 SCONN60_ASP21410801-SCONN60_ASA
     1 P1V05_PCH_AUX @S9S_MB_2U_LIB.S9S_MB_2U(SCH_1):P1V05_PCH_AUX    I44 @S9S_MB_2U_LIB.S9S_MB_2U(SCH_1):PAGE133
     2 JTAG_DBP_TMS_R @S9S_MB_2U_LIB.S9S_MB_2U(SCH_1):JTAG_DBP_TMS_R    I44 @S9S_MB_2U_LIB.S9S_MB_2U(SCH_1):PAGE133
     3 JTAG_DBP_CPU_GTL_TCK_R @S9S_MB_2U_LIB.S9S_MB_2U(SCH_1):JTAG_DBP_CPU_GTL_TCK_R    I44 @S9S_MB_2U_LIB.S9S_MB_2U(SCH_1):PAGE133
     4 JTAG_DBP_TDO_R @S9S_MB_2U_LIB.S9S_MB_2U(SCH_1):JTAG_DBP_TDO_R    I44 @S9S_MB_2U_LIB.S9S_MB_2U(SCH_1):PAGE133
     5 JTAG_DBP_TDI_R @S9S_MB_2U_LIB.S9S_MB_2U(SCH_1):JTAG_DBP_TDI_R    I44 @S9S_MB_2U_LIB.S9S_MB_2U(SCH_1):PAGE133
     6 JTAG_RST_DBP_RST_CO_N @S9S_MB_2U_LIB.S9S_MB_2U(SCH_1):JTAG_RST_DBP_RST_CO_N    I44 @S9S_MB_2U_LIB.S9S_MB_2U(SCH_1):PAGE133
     7 JTAG_DBP_PMODE @S9S_MB_2U_LIB.S9S_MB_2U(SCH_1):JTAG_DBP_PMODE    I44 @S9S_MB_2U_LIB.S9S_MB_2U(SCH_1):PAGE133
     8 PD_TRST_P3 @S9S_MB_2U_LIB.S9S_MB_2U(SCH_1):PD_TRST_P3    I44 @S9S_MB_2U_LIB.S9S_MB_2U(SCH_1):PAGE133
     9 NC_MIPI60_P9 @S9S_MB_2U_LIB.S9S_MB_2U(SCH_1):NC_MIPI60_P9    I44 @S9S_MB_2U_LIB.S9S_MB_2U(SCH_1):PAGE133
    10 JTAG_DBP_PREQ_N_R @S9S_MB_2U_LIB.S9S_MB_2U(SCH_1):JTAG_DBP_PREQ_N_R    I44 @S9S_MB_2U_LIB.S9S_MB_2U(SCH_1):PAGE133
    11 JTAG_DBP_PRDY_R1_N @S9S_MB_2U_LIB.S9S_MB_2U(SCH_1):JTAG_DBP_PRDY_R1_N    I44 @S9S_MB_2U_LIB.S9S_MB_2U(SCH_1):PAGE133
    12 P1V8_PCH_AUX @S9S_MB_2U_LIB.S9S_MB_2U(SCH_1):P1V8_PCH_AUX    I44 @S9S_MB_2U_LIB.S9S_MB_2U(SCH_1):PAGE133
    13 JTAG_TRC_PCH_PTI0_CLK @S9S_MB_2U_LIB.S9S_MB_2U(SCH_1):JTAG_TRC_PCH_PTI0_CLK    I44 @S9S_MB_2U_LIB.S9S_MB_2U(SCH_1):PAGE133
    14    GND @S9S_MB_2U_LIB.S9S_MB_2U(SCH_1):GND    I44 @S9S_MB_2U_LIB.S9S_MB_2U(SCH_1):PAGE133
    15 JTAG_DBP_PCH_DEBUG_CONSENT_N @S9S_MB_2U_LIB.S9S_MB_2U(SCH_1):JTAG_DBP_PCH_DEBUG_CONSENT_N    I44 @S9S_MB_2U_LIB.S9S_MB_2U(SCH_1):PAGE133
    16    GND @S9S_MB_2U_LIB.S9S_MB_2U(SCH_1):GND    I44 @S9S_MB_2U_LIB.S9S_MB_2U(SCH_1):PAGE133
    17 JTAG_DBP_PRESENT_R_N @S9S_MB_2U_LIB.S9S_MB_2U(SCH_1):JTAG_DBP_PRESENT_R_N    I44 @S9S_MB_2U_LIB.S9S_MB_2U(SCH_1):PAGE133
    18 NC_DBP_P18 @S9S_MB_2U_LIB.S9S_MB_2U(SCH_1):NC_DBP_P18    I44 @S9S_MB_2U_LIB.S9S_MB_2U(SCH_1):PAGE133
    19 JTAG_TRC_PCH_PTI<0> @S9S_MB_2U_LIB.S9S_MB_2U(SCH_1):JTAG_TRC_PCH_PTI(0)    I44 @S9S_MB_2U_LIB.S9S_MB_2U(SCH_1):PAGE133
    20 NC_DBP_P20 @S9S_MB_2U_LIB.S9S_MB_2U(SCH_1):NC_DBP_P20    I44 @S9S_MB_2U_LIB.S9S_MB_2U(SCH_1):PAGE133
    21 JTAG_TRC_PCH_PTI<1> @S9S_MB_2U_LIB.S9S_MB_2U(SCH_1):JTAG_TRC_PCH_PTI(1)    I44 @S9S_MB_2U_LIB.S9S_MB_2U(SCH_1):PAGE133
    22 NC_DBP_P22 @S9S_MB_2U_LIB.S9S_MB_2U(SCH_1):NC_DBP_P22    I44 @S9S_MB_2U_LIB.S9S_MB_2U(SCH_1):PAGE133
    23 JTAG_TRC_PCH_PTI<2> @S9S_MB_2U_LIB.S9S_MB_2U(SCH_1):JTAG_TRC_PCH_PTI(2)    I44 @S9S_MB_2U_LIB.S9S_MB_2U(SCH_1):PAGE133
    24 NC_DBP_P24 @S9S_MB_2U_LIB.S9S_MB_2U(SCH_1):NC_DBP_P24    I44 @S9S_MB_2U_LIB.S9S_MB_2U(SCH_1):PAGE133
    25 JTAG_TRC_PCH_PTI<3> @S9S_MB_2U_LIB.S9S_MB_2U(SCH_1):JTAG_TRC_PCH_PTI(3)    I44 @S9S_MB_2U_LIB.S9S_MB_2U(SCH_1):PAGE133
    26 NC_DBP_P26 @S9S_MB_2U_LIB.S9S_MB_2U(SCH_1):NC_DBP_P26    I44 @S9S_MB_2U_LIB.S9S_MB_2U(SCH_1):PAGE133
    27 JTAG_TRC_PCH_PTI<4> @S9S_MB_2U_LIB.S9S_MB_2U(SCH_1):JTAG_TRC_PCH_PTI(4)    I44 @S9S_MB_2U_LIB.S9S_MB_2U(SCH_1):PAGE133
    28 NC_DBP_P28 @S9S_MB_2U_LIB.S9S_MB_2U(SCH_1):NC_DBP_P28    I44 @S9S_MB_2U_LIB.S9S_MB_2U(SCH_1):PAGE133
    30 NC_DBP_P30 @S9S_MB_2U_LIB.S9S_MB_2U(SCH_1):NC_DBP_P30    I44 @S9S_MB_2U_LIB.S9S_MB_2U(SCH_1):PAGE133
    29 JTAG_TRC_PCH_PTI<5> @S9S_MB_2U_LIB.S9S_MB_2U(SCH_1):JTAG_TRC_PCH_PTI(5)    I44 @S9S_MB_2U_LIB.S9S_MB_2U(SCH_1):PAGE133
    31 JTAG_TRC_PCH_PTI<6> @S9S_MB_2U_LIB.S9S_MB_2U(SCH_1):JTAG_TRC_PCH_PTI(6)    I44 @S9S_MB_2U_LIB.S9S_MB_2U(SCH_1):PAGE133
    32 NC_DBP_P32 @S9S_MB_2U_LIB.S9S_MB_2U(SCH_1):NC_DBP_P32    I44 @S9S_MB_2U_LIB.S9S_MB_2U(SCH_1):PAGE133
    33 JTAG_TRC_PCH_PTI<7> @S9S_MB_2U_LIB.S9S_MB_2U(SCH_1):JTAG_TRC_PCH_PTI(7)    I44 @S9S_MB_2U_LIB.S9S_MB_2U(SCH_1):PAGE133
    34 NC_DBP_P34 @S9S_MB_2U_LIB.S9S_MB_2U(SCH_1):NC_DBP_P34    I44 @S9S_MB_2U_LIB.S9S_MB_2U(SCH_1):PAGE133
    35 JTAG_TRC_PCH_PTI<8> @S9S_MB_2U_LIB.S9S_MB_2U(SCH_1):JTAG_TRC_PCH_PTI(8)    I44 @S9S_MB_2U_LIB.S9S_MB_2U(SCH_1):PAGE133
    36 JTAG_DBP_BOOT_HALT_N @S9S_MB_2U_LIB.S9S_MB_2U(SCH_1):JTAG_DBP_BOOT_HALT_N    I44 @S9S_MB_2U_LIB.S9S_MB_2U(SCH_1):PAGE133
    37 JTAG_TRC_PCH_PTI<9> @S9S_MB_2U_LIB.S9S_MB_2U(SCH_1):JTAG_TRC_PCH_PTI(9)    I44 @S9S_MB_2U_LIB.S9S_MB_2U(SCH_1):PAGE133
    38 FM_CPU_FBRK_DEBUG_N @S9S_MB_2U_LIB.S9S_MB_2U(SCH_1):FM_CPU_FBRK_DEBUG_N    I44 @S9S_MB_2U_LIB.S9S_MB_2U(SCH_1):PAGE133
    39 JTAG_TRC_PCH_PTI<10> @S9S_MB_2U_LIB.S9S_MB_2U(SCH_1):JTAG_TRC_PCH_PTI(10)    I44 @S9S_MB_2U_LIB.S9S_MB_2U(SCH_1):PAGE133
    40 JTAG_DBP_POWER_BTN_N @S9S_MB_2U_LIB.S9S_MB_2U(SCH_1):JTAG_DBP_POWER_BTN_N    I44 @S9S_MB_2U_LIB.S9S_MB_2U(SCH_1):PAGE133
    41 JTAG_TRC_PCH_PTI<11> @S9S_MB_2U_LIB.S9S_MB_2U(SCH_1):JTAG_TRC_PCH_PTI(11)    I44 @S9S_MB_2U_LIB.S9S_MB_2U(SCH_1):PAGE133
    42 JTAG_RST_DBP_RSMRST_N @S9S_MB_2U_LIB.S9S_MB_2U(SCH_1):JTAG_RST_DBP_RSMRST_N    I44 @S9S_MB_2U_LIB.S9S_MB_2U(SCH_1):PAGE133
    43 JTAG_TRC_PCH_PTI<12> @S9S_MB_2U_LIB.S9S_MB_2U(SCH_1):JTAG_TRC_PCH_PTI(12)    I44 @S9S_MB_2U_LIB.S9S_MB_2U(SCH_1):PAGE133
    44 NC_DBP_P44 @S9S_MB_2U_LIB.S9S_MB_2U(SCH_1):NC_DBP_P44    I44 @S9S_MB_2U_LIB.S9S_MB_2U(SCH_1):PAGE133
    45 JTAG_TRC_PCH_PTI<13> @S9S_MB_2U_LIB.S9S_MB_2U(SCH_1):JTAG_TRC_PCH_PTI(13)    I44 @S9S_MB_2U_LIB.S9S_MB_2U(SCH_1):PAGE133
    46 NC_DBP_P46 @S9S_MB_2U_LIB.S9S_MB_2U(SCH_1):NC_DBP_P46    I44 @S9S_MB_2U_LIB.S9S_MB_2U(SCH_1):PAGE133
    47 JTAG_TRC_PCH_PTI<14> @S9S_MB_2U_LIB.S9S_MB_2U(SCH_1):JTAG_TRC_PCH_PTI(14)    I44 @S9S_MB_2U_LIB.S9S_MB_2U(SCH_1):PAGE133
    48 SMB_HOST_3V3AUX_XDP_R_SCL @S9S_MB_2U_LIB.S9S_MB_2U(SCH_1):SMB_HOST_3V3AUX_XDP_R_SCL    I44 @S9S_MB_2U_LIB.S9S_MB_2U(SCH_1):PAGE133
    49 JTAG_TRC_PCH_PTI<15> @S9S_MB_2U_LIB.S9S_MB_2U(SCH_1):JTAG_TRC_PCH_PTI(15)    I44 @S9S_MB_2U_LIB.S9S_MB_2U(SCH_1):PAGE133
    50 SMB_HOST_3V3AUX_XDP_R_SDA @S9S_MB_2U_LIB.S9S_MB_2U(SCH_1):SMB_HOST_3V3AUX_XDP_R_SDA    I44 @S9S_MB_2U_LIB.S9S_MB_2U(SCH_1):PAGE133
    51 JTAG_DBP_TCK_R_TCK @S9S_MB_2U_LIB.S9S_MB_2U(SCH_1):JTAG_DBP_TCK_R_TCK    I44 @S9S_MB_2U_LIB.S9S_MB_2U(SCH_1):PAGE133
    52 P3V3_AUX @S9S_MB_2U_LIB.S9S_MB_2U(SCH_1):P3V3_AUX    I44 @S9S_MB_2U_LIB.S9S_MB_2U(SCH_1):PAGE133
    53 JTAG_DBP_CPU_HOOK9_MBP3_GTL_N @S9S_MB_2U_LIB.S9S_MB_2U(SCH_1):JTAG_DBP_CPU_HOOK9_MBP3_GTL_N    I44 @S9S_MB_2U_LIB.S9S_MB_2U(SCH_1):PAGE133
    54 NC_DBP_P54 @S9S_MB_2U_LIB.S9S_MB_2U(SCH_1):NC_DBP_P54    I44 @S9S_MB_2U_LIB.S9S_MB_2U(SCH_1):PAGE133
    55 JTAG_DBP_CPU_HOOK8_MBP2_GTL_N @S9S_MB_2U_LIB.S9S_MB_2U(SCH_1):JTAG_DBP_CPU_HOOK8_MBP2_GTL_N    I44 @S9S_MB_2U_LIB.S9S_MB_2U(SCH_1):PAGE133
    56 NC_DBP_P56 @S9S_MB_2U_LIB.S9S_MB_2U(SCH_1):NC_DBP_P56    I44 @S9S_MB_2U_LIB.S9S_MB_2U(SCH_1):PAGE133
    57    GND @S9S_MB_2U_LIB.S9S_MB_2U(SCH_1):GND    I44 @S9S_MB_2U_LIB.S9S_MB_2U(SCH_1):PAGE133
    58    GND @S9S_MB_2U_LIB.S9S_MB_2U(SCH_1):GND    I44 @S9S_MB_2U_LIB.S9S_MB_2U(SCH_1):PAGE133
    59 JTAG_TRC_PCH_PTI1_CLK @S9S_MB_2U_LIB.S9S_MB_2U(SCH_1):JTAG_TRC_PCH_PTI1_CLK    I44 @S9S_MB_2U_LIB.S9S_MB_2U(SCH_1):PAGE133
    60    GND @S9S_MB_2U_LIB.S9S_MB_2U(SCH_1):GND    I44 @S9S_MB_2U_LIB.S9S_MB_2U(SCH_1):PAGE133
    G1    GND @S9S_MB_2U_LIB.S9S_MB_2U(SCH_1):GND    I44 @S9S_MB_2U_LIB.S9S_MB_2U(SCH_1):PAGE133
    G2    GND @S9S_MB_2U_LIB.S9S_MB_2U(SCH_1):GND    I44 @S9S_MB_2U_LIB.S9S_MB_2U(SCH_1):PAGE133
    G3    GND @S9S_MB_2U_LIB.S9S_MB_2U(SCH_1):GND    I44 @S9S_MB_2U_LIB.S9S_MB_2U(SCH_1):PAGE133
    G4    GND @S9S_MB_2U_LIB.S9S_MB_2U(SCH_1):GND    I44 @S9S_MB_2U_LIB.S9S_MB_2U(SCH_1):PAGE133

 J43 CONN8_210HP1080BR1-CONN8_210-HA
     1 P3V3_AUX_BMC_D @S9S_MB_2U_LIB.S9S_MB_2U(SCH_1):P3V3_AUX_BMC_D    I79 @S9S_MB_2U_LIB.S9S_MB_2U(SCH_1):PAGE210
     2 JTAG_BMC_PLD_TDO @S9S_MB_2U_LIB.S9S_MB_2U(SCH_1):JTAG_BMC_PLD_TDO    I79 @S9S_MB_2U_LIB.S9S_MB_2U(SCH_1):PAGE210
     3 JTAG_BMC_PLD_TDI @S9S_MB_2U_LIB.S9S_MB_2U(SCH_1):JTAG_BMC_PLD_TDI    I79 @S9S_MB_2U_LIB.S9S_MB_2U(SCH_1):PAGE210
     4 TP_PLD_CONN_P4 @S9S_MB_2U_LIB.S9S_MB_2U(SCH_1):TP_PLD_CONN_P4    I79 @S9S_MB_2U_LIB.S9S_MB_2U(SCH_1):PAGE210
     5 TP_PLD_CONN_P5 @S9S_MB_2U_LIB.S9S_MB_2U(SCH_1):TP_PLD_CONN_P5    I79 @S9S_MB_2U_LIB.S9S_MB_2U(SCH_1):PAGE210
     6 JTAG_BMC_PLD_TMS @S9S_MB_2U_LIB.S9S_MB_2U(SCH_1):JTAG_BMC_PLD_TMS    I79 @S9S_MB_2U_LIB.S9S_MB_2U(SCH_1):PAGE210
     7    GND @S9S_MB_2U_LIB.S9S_MB_2U(SCH_1):GND    I79 @S9S_MB_2U_LIB.S9S_MB_2U(SCH_1):PAGE210
     8 JTAG_BMC_PLD_TCK @S9S_MB_2U_LIB.S9S_MB_2U(SCH_1):JTAG_BMC_PLD_TCK    I79 @S9S_MB_2U_LIB.S9S_MB_2U(SCH_1):PAGE210

 J45 CONN60_101062636003K02LF-CONN6A
    A2 FM_AC_PWR_BTN_PDB_N @S9S_MB_2U_LIB.S9S_MB_2U(SCH_1):FM_AC_PWR_BTN_PDB_N    I12 @S9S_MB_2U_LIB.S9S_MB_2U(SCH_1):PAGE233
    B2 PWRGD_P3V3_AUX_PDB_BUF @S9S_MB_2U_LIB.S9S_MB_2U(SCH_1):PWRGD_P3V3_AUX_PDB_BUF    I12 @S9S_MB_2U_LIB.S9S_MB_2U(SCH_1):PAGE233
    C2 SMB_FAN_3V3AUX_BUF_R_SDA @S9S_MB_2U_LIB.S9S_MB_2U(SCH_1):SMB_FAN_3V3AUX_BUF_R_SDA    I12 @S9S_MB_2U_LIB.S9S_MB_2U(SCH_1):PAGE233
    D2 FM_GPU_HSC_EN_BUF_R1 @S9S_MB_2U_LIB.S9S_MB_2U(SCH_1):FM_GPU_HSC_EN_BUF_R1    I12 @S9S_MB_2U_LIB.S9S_MB_2U(SCH_1):PAGE233
  P1_1    GND @S9S_MB_2U_LIB.S9S_MB_2U(SCH_1):GND    I12 @S9S_MB_2U_LIB.S9S_MB_2U(SCH_1):PAGE233
  P1_2    GND @S9S_MB_2U_LIB.S9S_MB_2U(SCH_1):GND    I12 @S9S_MB_2U_LIB.S9S_MB_2U(SCH_1):PAGE233
  P1_3    GND @S9S_MB_2U_LIB.S9S_MB_2U(SCH_1):GND    I12 @S9S_MB_2U_LIB.S9S_MB_2U(SCH_1):PAGE233
  P1_4    GND @S9S_MB_2U_LIB.S9S_MB_2U(SCH_1):GND    I12 @S9S_MB_2U_LIB.S9S_MB_2U(SCH_1):PAGE233
  P1_5    GND @S9S_MB_2U_LIB.S9S_MB_2U(SCH_1):GND    I12 @S9S_MB_2U_LIB.S9S_MB_2U(SCH_1):PAGE233
  P1_6    GND @S9S_MB_2U_LIB.S9S_MB_2U(SCH_1):GND    I12 @S9S_MB_2U_LIB.S9S_MB_2U(SCH_1):PAGE233
  P1_7    GND @S9S_MB_2U_LIB.S9S_MB_2U(SCH_1):GND    I12 @S9S_MB_2U_LIB.S9S_MB_2U(SCH_1):PAGE233
  P1_8    GND @S9S_MB_2U_LIB.S9S_MB_2U(SCH_1):GND    I12 @S9S_MB_2U_LIB.S9S_MB_2U(SCH_1):PAGE233
  P2_1    GND @S9S_MB_2U_LIB.S9S_MB_2U(SCH_1):GND    I12 @S9S_MB_2U_LIB.S9S_MB_2U(SCH_1):PAGE233
  P2_2    GND @S9S_MB_2U_LIB.S9S_MB_2U(SCH_1):GND    I12 @S9S_MB_2U_LIB.S9S_MB_2U(SCH_1):PAGE233
  P2_3    GND @S9S_MB_2U_LIB.S9S_MB_2U(SCH_1):GND    I12 @S9S_MB_2U_LIB.S9S_MB_2U(SCH_1):PAGE233
  P2_4    GND @S9S_MB_2U_LIB.S9S_MB_2U(SCH_1):GND    I12 @S9S_MB_2U_LIB.S9S_MB_2U(SCH_1):PAGE233
  P2_5    GND @S9S_MB_2U_LIB.S9S_MB_2U(SCH_1):GND    I12 @S9S_MB_2U_LIB.S9S_MB_2U(SCH_1):PAGE233
  P2_6    GND @S9S_MB_2U_LIB.S9S_MB_2U(SCH_1):GND    I12 @S9S_MB_2U_LIB.S9S_MB_2U(SCH_1):PAGE233
  P2_7    GND @S9S_MB_2U_LIB.S9S_MB_2U(SCH_1):GND    I12 @S9S_MB_2U_LIB.S9S_MB_2U(SCH_1):PAGE233
  P2_8    GND @S9S_MB_2U_LIB.S9S_MB_2U(SCH_1):GND    I12 @S9S_MB_2U_LIB.S9S_MB_2U(SCH_1):PAGE233
  P4_1 P12V_PSU @S9S_MB_2U_LIB.S9S_MB_2U(SCH_1):P12V_PSU    I12 @S9S_MB_2U_LIB.S9S_MB_2U(SCH_1):PAGE233
  P4_2 P12V_PSU @S9S_MB_2U_LIB.S9S_MB_2U(SCH_1):P12V_PSU    I12 @S9S_MB_2U_LIB.S9S_MB_2U(SCH_1):PAGE233
  P4_3 P12V_PSU @S9S_MB_2U_LIB.S9S_MB_2U(SCH_1):P12V_PSU    I12 @S9S_MB_2U_LIB.S9S_MB_2U(SCH_1):PAGE233
  P4_4 P12V_PSU @S9S_MB_2U_LIB.S9S_MB_2U(SCH_1):P12V_PSU    I12 @S9S_MB_2U_LIB.S9S_MB_2U(SCH_1):PAGE233
  P4_5 P12V_PSU @S9S_MB_2U_LIB.S9S_MB_2U(SCH_1):P12V_PSU    I12 @S9S_MB_2U_LIB.S9S_MB_2U(SCH_1):PAGE233
  P4_6 P12V_PSU @S9S_MB_2U_LIB.S9S_MB_2U(SCH_1):P12V_PSU    I12 @S9S_MB_2U_LIB.S9S_MB_2U(SCH_1):PAGE233
  P4_7 P12V_PSU @S9S_MB_2U_LIB.S9S_MB_2U(SCH_1):P12V_PSU    I12 @S9S_MB_2U_LIB.S9S_MB_2U(SCH_1):PAGE233
  P4_8 P12V_PSU @S9S_MB_2U_LIB.S9S_MB_2U(SCH_1):P12V_PSU    I12 @S9S_MB_2U_LIB.S9S_MB_2U(SCH_1):PAGE233
    A1 TP_J45_A1 @S9S_MB_2U_LIB.S9S_MB_2U(SCH_1):TP_J45_A1    I12 @S9S_MB_2U_LIB.S9S_MB_2U(SCH_1):PAGE233
    B1 RST_SMB_SWITCH_R_N @S9S_MB_2U_LIB.S9S_MB_2U(SCH_1):RST_SMB_SWITCH_R_N    I12 @S9S_MB_2U_LIB.S9S_MB_2U(SCH_1):PAGE233
    C1 SMB_FAN_3V3AUX_BUF_R_SCL @S9S_MB_2U_LIB.S9S_MB_2U(SCH_1):SMB_FAN_3V3AUX_BUF_R_SCL    I12 @S9S_MB_2U_LIB.S9S_MB_2U(SCH_1):PAGE233
    D1 FM_FAN_PWR_EN_R @S9S_MB_2U_LIB.S9S_MB_2U(SCH_1):FM_FAN_PWR_EN_R    I12 @S9S_MB_2U_LIB.S9S_MB_2U(SCH_1):PAGE233
  P5_1 P12V_PSU @S9S_MB_2U_LIB.S9S_MB_2U(SCH_1):P12V_PSU    I12 @S9S_MB_2U_LIB.S9S_MB_2U(SCH_1):PAGE233
  P5_2 P12V_PSU @S9S_MB_2U_LIB.S9S_MB_2U(SCH_1):P12V_PSU    I12 @S9S_MB_2U_LIB.S9S_MB_2U(SCH_1):PAGE233
  P5_3 P12V_PSU @S9S_MB_2U_LIB.S9S_MB_2U(SCH_1):P12V_PSU    I12 @S9S_MB_2U_LIB.S9S_MB_2U(SCH_1):PAGE233
  P5_4 P12V_PSU @S9S_MB_2U_LIB.S9S_MB_2U(SCH_1):P12V_PSU    I12 @S9S_MB_2U_LIB.S9S_MB_2U(SCH_1):PAGE233
  P5_5 P12V_PSU @S9S_MB_2U_LIB.S9S_MB_2U(SCH_1):P12V_PSU    I12 @S9S_MB_2U_LIB.S9S_MB_2U(SCH_1):PAGE233
  P5_6 P12V_PSU @S9S_MB_2U_LIB.S9S_MB_2U(SCH_1):P12V_PSU    I12 @S9S_MB_2U_LIB.S9S_MB_2U(SCH_1):PAGE233
  P5_7 P12V_PSU @S9S_MB_2U_LIB.S9S_MB_2U(SCH_1):P12V_PSU    I12 @S9S_MB_2U_LIB.S9S_MB_2U(SCH_1):PAGE233
  P5_8 P12V_PSU @S9S_MB_2U_LIB.S9S_MB_2U(SCH_1):P12V_PSU    I12 @S9S_MB_2U_LIB.S9S_MB_2U(SCH_1):PAGE233
  P3_1    GND @S9S_MB_2U_LIB.S9S_MB_2U(SCH_1):GND    I12 @S9S_MB_2U_LIB.S9S_MB_2U(SCH_1):PAGE233
  P3_2    GND @S9S_MB_2U_LIB.S9S_MB_2U(SCH_1):GND    I12 @S9S_MB_2U_LIB.S9S_MB_2U(SCH_1):PAGE233
  P3_3    GND @S9S_MB_2U_LIB.S9S_MB_2U(SCH_1):GND    I12 @S9S_MB_2U_LIB.S9S_MB_2U(SCH_1):PAGE233
  P3_4    GND @S9S_MB_2U_LIB.S9S_MB_2U(SCH_1):GND    I12 @S9S_MB_2U_LIB.S9S_MB_2U(SCH_1):PAGE233
  P3_5    GND @S9S_MB_2U_LIB.S9S_MB_2U(SCH_1):GND    I12 @S9S_MB_2U_LIB.S9S_MB_2U(SCH_1):PAGE233
  P3_6    GND @S9S_MB_2U_LIB.S9S_MB_2U(SCH_1):GND    I12 @S9S_MB_2U_LIB.S9S_MB_2U(SCH_1):PAGE233
  P3_7    GND @S9S_MB_2U_LIB.S9S_MB_2U(SCH_1):GND    I12 @S9S_MB_2U_LIB.S9S_MB_2U(SCH_1):PAGE233
  P3_8    GND @S9S_MB_2U_LIB.S9S_MB_2U(SCH_1):GND    I12 @S9S_MB_2U_LIB.S9S_MB_2U(SCH_1):PAGE233
  P6_1 P12V_PSU @S9S_MB_2U_LIB.S9S_MB_2U(SCH_1):P12V_PSU    I12 @S9S_MB_2U_LIB.S9S_MB_2U(SCH_1):PAGE233
  P6_2 P12V_PSU @S9S_MB_2U_LIB.S9S_MB_2U(SCH_1):P12V_PSU    I12 @S9S_MB_2U_LIB.S9S_MB_2U(SCH_1):PAGE233
  P6_3 P12V_PSU @S9S_MB_2U_LIB.S9S_MB_2U(SCH_1):P12V_PSU    I12 @S9S_MB_2U_LIB.S9S_MB_2U(SCH_1):PAGE233
  P6_4 P12V_PSU @S9S_MB_2U_LIB.S9S_MB_2U(SCH_1):P12V_PSU    I12 @S9S_MB_2U_LIB.S9S_MB_2U(SCH_1):PAGE233
  P6_5 P12V_PSU @S9S_MB_2U_LIB.S9S_MB_2U(SCH_1):P12V_PSU    I12 @S9S_MB_2U_LIB.S9S_MB_2U(SCH_1):PAGE233
  P6_6 P12V_PSU @S9S_MB_2U_LIB.S9S_MB_2U(SCH_1):P12V_PSU    I12 @S9S_MB_2U_LIB.S9S_MB_2U(SCH_1):PAGE233
  P6_7 P12V_PSU @S9S_MB_2U_LIB.S9S_MB_2U(SCH_1):P12V_PSU    I12 @S9S_MB_2U_LIB.S9S_MB_2U(SCH_1):PAGE233
  P6_8 P12V_PSU @S9S_MB_2U_LIB.S9S_MB_2U(SCH_1):P12V_PSU    I12 @S9S_MB_2U_LIB.S9S_MB_2U(SCH_1):PAGE233
    A3 P3V3_PDB_AUX_ADC @S9S_MB_2U_LIB.S9S_MB_2U(SCH_1):P3V3_PDB_AUX_ADC    I12 @S9S_MB_2U_LIB.S9S_MB_2U(SCH_1):PAGE233
    B3    GND @S9S_MB_2U_LIB.S9S_MB_2U(SCH_1):GND    I12 @S9S_MB_2U_LIB.S9S_MB_2U(SCH_1):PAGE233
    C3 HPDB_HSC_PWRGD_R @S9S_MB_2U_LIB.S9S_MB_2U(SCH_1):HPDB_HSC_PWRGD_R    I12 @S9S_MB_2U_LIB.S9S_MB_2U(SCH_1):PAGE233
    D3 PDB_PRSNT_N @S9S_MB_2U_LIB.S9S_MB_2U(SCH_1):PDB_PRSNT_N    I12 @S9S_MB_2U_LIB.S9S_MB_2U(SCH_1):PAGE233

 J59 SCONN75K_APCI0155P004A-SCONN75A
     2 P3V3_M2_0 @S9S_MB_2U_LIB.S9S_MB_2U(SCH_1):P3V3_M2_0   I178 @S9S_MB_2U_LIB.S9S_MB_2U(SCH_1):PAGE182
     4 P3V3_M2_0 @S9S_MB_2U_LIB.S9S_MB_2U(SCH_1):P3V3_M2_0   I178 @S9S_MB_2U_LIB.S9S_MB_2U(SCH_1):PAGE182
    10 LED_M2_SSD_0_ACT_N @S9S_MB_2U_LIB.S9S_MB_2U(SCH_1):LED_M2_SSD_0_ACT_N   I178 @S9S_MB_2U_LIB.S9S_MB_2U(SCH_1):PAGE182
    12 P3V3_M2_0 @S9S_MB_2U_LIB.S9S_MB_2U(SCH_1):P3V3_M2_0   I178 @S9S_MB_2U_LIB.S9S_MB_2U(SCH_1):PAGE182
    14 P3V3_M2_0 @S9S_MB_2U_LIB.S9S_MB_2U(SCH_1):P3V3_M2_0   I178 @S9S_MB_2U_LIB.S9S_MB_2U(SCH_1):PAGE182
    16 P3V3_M2_0 @S9S_MB_2U_LIB.S9S_MB_2U(SCH_1):P3V3_M2_0   I178 @S9S_MB_2U_LIB.S9S_MB_2U(SCH_1):PAGE182
    18 P3V3_M2_0 @S9S_MB_2U_LIB.S9S_MB_2U(SCH_1):P3V3_M2_0   I178 @S9S_MB_2U_LIB.S9S_MB_2U(SCH_1):PAGE182
    38 PD_M2_0_DEVSLP @S9S_MB_2U_LIB.S9S_MB_2U(SCH_1):PD_M2_0_DEVSLP   I178 @S9S_MB_2U_LIB.S9S_MB_2U(SCH_1):PAGE182
    50 RST_PCIE_PCH_DEV_0_N @S9S_MB_2U_LIB.S9S_MB_2U(SCH_1):RST_PCIE_PCH_DEV_0_N   I178 @S9S_MB_2U_LIB.S9S_MB_2U(SCH_1):PAGE182
    52 M2_SSD0_CLKREQ_EN_N_BUF @S9S_MB_2U_LIB.S9S_MB_2U(SCH_1):M2_SSD0_CLKREQ_EN_N_BUF   I178 @S9S_MB_2U_LIB.S9S_MB_2U(SCH_1):PAGE182
    54 M2_0_PEWAKE_N @S9S_MB_2U_LIB.S9S_MB_2U(SCH_1):M2_0_PEWAKE_N   I178 @S9S_MB_2U_LIB.S9S_MB_2U(SCH_1):PAGE182
    58 NC_M2_0_NC18 @S9S_MB_2U_LIB.S9S_MB_2U(SCH_1):NC_M2_0_NC18   I178 @S9S_MB_2U_LIB.S9S_MB_2U(SCH_1):PAGE182
    68 NC_M2_0_SUSCLK @S9S_MB_2U_LIB.S9S_MB_2U(SCH_1):NC_M2_0_SUSCLK   I178 @S9S_MB_2U_LIB.S9S_MB_2U(SCH_1):PAGE182
    70 P3V3_M2_0 @S9S_MB_2U_LIB.S9S_MB_2U(SCH_1):P3V3_M2_0   I178 @S9S_MB_2U_LIB.S9S_MB_2U(SCH_1):PAGE182
    72 P3V3_M2_0 @S9S_MB_2U_LIB.S9S_MB_2U(SCH_1):P3V3_M2_0   I178 @S9S_MB_2U_LIB.S9S_MB_2U(SCH_1):PAGE182
    74 P3V3_M2_0 @S9S_MB_2U_LIB.S9S_MB_2U(SCH_1):P3V3_M2_0   I178 @S9S_MB_2U_LIB.S9S_MB_2U(SCH_1):PAGE182
    41 P3E_PCH_M2_RX_DN<3> @S9S_MB_2U_LIB.S9S_MB_2U(SCH_1):P3E_PCH_M2_RX_DN(3)   I178 @S9S_MB_2U_LIB.S9S_MB_2U(SCH_1):PAGE182
    43 P3E_PCH_M2_RX_DP<3> @S9S_MB_2U_LIB.S9S_MB_2U(SCH_1):P3E_PCH_M2_RX_DP(3)   I178 @S9S_MB_2U_LIB.S9S_MB_2U(SCH_1):PAGE182
    47 P3E_PCH_M2_TX_C_DP<3> @S9S_MB_2U_LIB.S9S_MB_2U(SCH_1):P3E_PCH_M2_TX_C_DP(3)   I178 @S9S_MB_2U_LIB.S9S_MB_2U(SCH_1):PAGE182
    49 P3E_PCH_M2_TX_C_DN<3> @S9S_MB_2U_LIB.S9S_MB_2U(SCH_1):P3E_PCH_M2_TX_C_DN(3)   I178 @S9S_MB_2U_LIB.S9S_MB_2U(SCH_1):PAGE182
    57    GND @S9S_MB_2U_LIB.S9S_MB_2U(SCH_1):GND   I178 @S9S_MB_2U_LIB.S9S_MB_2U(SCH_1):PAGE182
    67 NC_M2_0_NC19 @S9S_MB_2U_LIB.S9S_MB_2U(SCH_1):NC_M2_0_NC19   I178 @S9S_MB_2U_LIB.S9S_MB_2U(SCH_1):PAGE182
    69 FM_M2_SSD_0_PEDET @S9S_MB_2U_LIB.S9S_MB_2U(SCH_1):FM_M2_SSD_0_PEDET   I178 @S9S_MB_2U_LIB.S9S_MB_2U(SCH_1):PAGE182
    71    GND @S9S_MB_2U_LIB.S9S_MB_2U(SCH_1):GND   I178 @S9S_MB_2U_LIB.S9S_MB_2U(SCH_1):PAGE182
    73    GND @S9S_MB_2U_LIB.S9S_MB_2U(SCH_1):GND   I178 @S9S_MB_2U_LIB.S9S_MB_2U(SCH_1):PAGE182
    75    GND @S9S_MB_2U_LIB.S9S_MB_2U(SCH_1):GND   I178 @S9S_MB_2U_LIB.S9S_MB_2U(SCH_1):PAGE182
    G1    GND @S9S_MB_2U_LIB.S9S_MB_2U(SCH_1):GND   I178 @S9S_MB_2U_LIB.S9S_MB_2U(SCH_1):PAGE182
    G2    GND @S9S_MB_2U_LIB.S9S_MB_2U(SCH_1):GND   I178 @S9S_MB_2U_LIB.S9S_MB_2U(SCH_1):PAGE182
     6 NC_M2_0_NC1 @S9S_MB_2U_LIB.S9S_MB_2U(SCH_1):NC_M2_0_NC1   I178 @S9S_MB_2U_LIB.S9S_MB_2U(SCH_1):PAGE182
     8 NC_M2_0_NC2 @S9S_MB_2U_LIB.S9S_MB_2U(SCH_1):NC_M2_0_NC2   I178 @S9S_MB_2U_LIB.S9S_MB_2U(SCH_1):PAGE182
    20 NC_M2_0_NC3 @S9S_MB_2U_LIB.S9S_MB_2U(SCH_1):NC_M2_0_NC3   I178 @S9S_MB_2U_LIB.S9S_MB_2U(SCH_1):PAGE182
    34 NC_M2_0_NC10 @S9S_MB_2U_LIB.S9S_MB_2U(SCH_1):NC_M2_0_NC10   I178 @S9S_MB_2U_LIB.S9S_MB_2U(SCH_1):PAGE182
    56 NC_M2_0_NC17 @S9S_MB_2U_LIB.S9S_MB_2U(SCH_1):NC_M2_0_NC17   I178 @S9S_MB_2U_LIB.S9S_MB_2U(SCH_1):PAGE182
    48 NC_M2_0_NC16 @S9S_MB_2U_LIB.S9S_MB_2U(SCH_1):NC_M2_0_NC16   I178 @S9S_MB_2U_LIB.S9S_MB_2U(SCH_1):PAGE182
    46 NC_M2_0_NC15 @S9S_MB_2U_LIB.S9S_MB_2U(SCH_1):NC_M2_0_NC15   I178 @S9S_MB_2U_LIB.S9S_MB_2U(SCH_1):PAGE182
    44 NC_M2_0_NC14 @S9S_MB_2U_LIB.S9S_MB_2U(SCH_1):NC_M2_0_NC14   I178 @S9S_MB_2U_LIB.S9S_MB_2U(SCH_1):PAGE182
    42 SMB_M2_P0_1V8AUX_SDA @S9S_MB_2U_LIB.S9S_MB_2U(SCH_1):SMB_M2_P0_1V8AUX_SDA   I178 @S9S_MB_2U_LIB.S9S_MB_2U(SCH_1):PAGE182
    40 SMB_M2_P0_1V8AUX_SCL @S9S_MB_2U_LIB.S9S_MB_2U(SCH_1):SMB_M2_P0_1V8AUX_SCL   I178 @S9S_MB_2U_LIB.S9S_MB_2U(SCH_1):PAGE182
    36 NC_M2_0_NC11 @S9S_MB_2U_LIB.S9S_MB_2U(SCH_1):NC_M2_0_NC11   I178 @S9S_MB_2U_LIB.S9S_MB_2U(SCH_1):PAGE182
    32 NC_M2_0_NC9 @S9S_MB_2U_LIB.S9S_MB_2U(SCH_1):NC_M2_0_NC9   I178 @S9S_MB_2U_LIB.S9S_MB_2U(SCH_1):PAGE182
    30 NC_M2_0_NC8 @S9S_MB_2U_LIB.S9S_MB_2U(SCH_1):NC_M2_0_NC8   I178 @S9S_MB_2U_LIB.S9S_MB_2U(SCH_1):PAGE182
    28 NC_M2_0_NC7 @S9S_MB_2U_LIB.S9S_MB_2U(SCH_1):NC_M2_0_NC7   I178 @S9S_MB_2U_LIB.S9S_MB_2U(SCH_1):PAGE182
    26 NC_M2_0_NC6 @S9S_MB_2U_LIB.S9S_MB_2U(SCH_1):NC_M2_0_NC6   I178 @S9S_MB_2U_LIB.S9S_MB_2U(SCH_1):PAGE182
    24 NC_M2_0_NC5 @S9S_MB_2U_LIB.S9S_MB_2U(SCH_1):NC_M2_0_NC5   I178 @S9S_MB_2U_LIB.S9S_MB_2U(SCH_1):PAGE182
    22 NC_M2_0_NC4 @S9S_MB_2U_LIB.S9S_MB_2U(SCH_1):NC_M2_0_NC4   I178 @S9S_MB_2U_LIB.S9S_MB_2U(SCH_1):PAGE182
     1 PCIE_M2_SSD0_PRSNT_N @S9S_MB_2U_LIB.S9S_MB_2U(SCH_1):PCIE_M2_SSD0_PRSNT_N   I178 @S9S_MB_2U_LIB.S9S_MB_2U(SCH_1):PAGE182
     3    GND @S9S_MB_2U_LIB.S9S_MB_2U(SCH_1):GND   I178 @S9S_MB_2U_LIB.S9S_MB_2U(SCH_1):PAGE182
     9    GND @S9S_MB_2U_LIB.S9S_MB_2U(SCH_1):GND   I178 @S9S_MB_2U_LIB.S9S_MB_2U(SCH_1):PAGE182
    15    GND @S9S_MB_2U_LIB.S9S_MB_2U(SCH_1):GND   I178 @S9S_MB_2U_LIB.S9S_MB_2U(SCH_1):PAGE182
    21    GND @S9S_MB_2U_LIB.S9S_MB_2U(SCH_1):GND   I178 @S9S_MB_2U_LIB.S9S_MB_2U(SCH_1):PAGE182
    27    GND @S9S_MB_2U_LIB.S9S_MB_2U(SCH_1):GND   I178 @S9S_MB_2U_LIB.S9S_MB_2U(SCH_1):PAGE182
    33    GND @S9S_MB_2U_LIB.S9S_MB_2U(SCH_1):GND   I178 @S9S_MB_2U_LIB.S9S_MB_2U(SCH_1):PAGE182
    39    GND @S9S_MB_2U_LIB.S9S_MB_2U(SCH_1):GND   I178 @S9S_MB_2U_LIB.S9S_MB_2U(SCH_1):PAGE182
    45    GND @S9S_MB_2U_LIB.S9S_MB_2U(SCH_1):GND   I178 @S9S_MB_2U_LIB.S9S_MB_2U(SCH_1):PAGE182
    51    GND @S9S_MB_2U_LIB.S9S_MB_2U(SCH_1):GND   I178 @S9S_MB_2U_LIB.S9S_MB_2U(SCH_1):PAGE182
     5 P3E_PCH_M2_RX_DN<0> @S9S_MB_2U_LIB.S9S_MB_2U(SCH_1):P3E_PCH_M2_RX_DN(0)   I178 @S9S_MB_2U_LIB.S9S_MB_2U(SCH_1):PAGE182
     7 P3E_PCH_M2_RX_DP<0> @S9S_MB_2U_LIB.S9S_MB_2U(SCH_1):P3E_PCH_M2_RX_DP(0)   I178 @S9S_MB_2U_LIB.S9S_MB_2U(SCH_1):PAGE182
    11 P3E_PCH_M2_TX_C_DP<0> @S9S_MB_2U_LIB.S9S_MB_2U(SCH_1):P3E_PCH_M2_TX_C_DP(0)   I178 @S9S_MB_2U_LIB.S9S_MB_2U(SCH_1):PAGE182
    13 P3E_PCH_M2_TX_C_DN<0> @S9S_MB_2U_LIB.S9S_MB_2U(SCH_1):P3E_PCH_M2_TX_C_DN(0)   I178 @S9S_MB_2U_LIB.S9S_MB_2U(SCH_1):PAGE182
    17 P3E_PCH_M2_RX_DN<1> @S9S_MB_2U_LIB.S9S_MB_2U(SCH_1):P3E_PCH_M2_RX_DN(1)   I178 @S9S_MB_2U_LIB.S9S_MB_2U(SCH_1):PAGE182
    19 P3E_PCH_M2_RX_DP<1> @S9S_MB_2U_LIB.S9S_MB_2U(SCH_1):P3E_PCH_M2_RX_DP(1)   I178 @S9S_MB_2U_LIB.S9S_MB_2U(SCH_1):PAGE182
    23 P3E_PCH_M2_TX_C_DP<1> @S9S_MB_2U_LIB.S9S_MB_2U(SCH_1):P3E_PCH_M2_TX_C_DP(1)   I178 @S9S_MB_2U_LIB.S9S_MB_2U(SCH_1):PAGE182
    25 P3E_PCH_M2_TX_C_DN<1> @S9S_MB_2U_LIB.S9S_MB_2U(SCH_1):P3E_PCH_M2_TX_C_DN(1)   I178 @S9S_MB_2U_LIB.S9S_MB_2U(SCH_1):PAGE182
    29 P3E_PCH_M2_RX_DN<2> @S9S_MB_2U_LIB.S9S_MB_2U(SCH_1):P3E_PCH_M2_RX_DN(2)   I178 @S9S_MB_2U_LIB.S9S_MB_2U(SCH_1):PAGE182
    31 P3E_PCH_M2_RX_DP<2> @S9S_MB_2U_LIB.S9S_MB_2U(SCH_1):P3E_PCH_M2_RX_DP(2)   I178 @S9S_MB_2U_LIB.S9S_MB_2U(SCH_1):PAGE182
    35 P3E_PCH_M2_TX_C_DP<2> @S9S_MB_2U_LIB.S9S_MB_2U(SCH_1):P3E_PCH_M2_TX_C_DP(2)   I178 @S9S_MB_2U_LIB.S9S_MB_2U(SCH_1):PAGE182
    37 P3E_PCH_M2_TX_C_DN<2> @S9S_MB_2U_LIB.S9S_MB_2U(SCH_1):P3E_PCH_M2_TX_C_DN(2)   I178 @S9S_MB_2U_LIB.S9S_MB_2U(SCH_1):PAGE182
    53 CLK_100M_PE_M2_0_DN @S9S_MB_2U_LIB.S9S_MB_2U(SCH_1):CLK_100M_PE_M2_0_DN   I178 @S9S_MB_2U_LIB.S9S_MB_2U(SCH_1):PAGE182
    55 CLK_100M_PE_M2_0_DP @S9S_MB_2U_LIB.S9S_MB_2U(SCH_1):CLK_100M_PE_M2_0_DP   I178 @S9S_MB_2U_LIB.S9S_MB_2U(SCH_1):PAGE182

 J63 PICOPROBE_BXA-DELTA-L 4.0,SMLFA
     2 DELTA_L_85_5INCH_TOP_DN @S9S_MB_2U_LIB.S9S_MB_2U(SCH_1):DELTA_L_85_5INCH_TOP_DN    I18 @S9S_MB_2U_LIB.S9S_MB_2U(SCH_1):PAGE287
     3 DELTA_L_GND_1 @S9S_MB_2U_LIB.S9S_MB_2U(SCH_1):DELTA_L_GND_1    I18 @S9S_MB_2U_LIB.S9S_MB_2U(SCH_1):PAGE287
     1 DELTA_L_85_5INCH_TOP_DP @S9S_MB_2U_LIB.S9S_MB_2U(SCH_1):DELTA_L_85_5INCH_TOP_DP    I18 @S9S_MB_2U_LIB.S9S_MB_2U(SCH_1):PAGE287

 J64 PICOPROBE_BXA-DELTA-L 4.0,SMLFA
     2 DELTA_L_85_5INCH_BOT_DN @S9S_MB_2U_LIB.S9S_MB_2U(SCH_1):DELTA_L_85_5INCH_BOT_DN    I17 @S9S_MB_2U_LIB.S9S_MB_2U(SCH_1):PAGE287
     3 DELTA_L_GND_1 @S9S_MB_2U_LIB.S9S_MB_2U(SCH_1):DELTA_L_GND_1    I17 @S9S_MB_2U_LIB.S9S_MB_2U(SCH_1):PAGE287
     1 DELTA_L_85_5INCH_BOT_DP @S9S_MB_2U_LIB.S9S_MB_2U(SCH_1):DELTA_L_85_5INCH_BOT_DP    I17 @S9S_MB_2U_LIB.S9S_MB_2U(SCH_1):PAGE287

 J65 PICOPROBE_BXA-DELTA-L 4.0,SMLFA
     2 DELTA_L_85_5INCH_IN1_DN @S9S_MB_2U_LIB.S9S_MB_2U(SCH_1):DELTA_L_85_5INCH_IN1_DN    I14 @S9S_MB_2U_LIB.S9S_MB_2U(SCH_1):PAGE287
     3 DELTA_L_GND_1 @S9S_MB_2U_LIB.S9S_MB_2U(SCH_1):DELTA_L_GND_1    I14 @S9S_MB_2U_LIB.S9S_MB_2U(SCH_1):PAGE287
     1 DELTA_L_85_5INCH_IN1_DP @S9S_MB_2U_LIB.S9S_MB_2U(SCH_1):DELTA_L_85_5INCH_IN1_DP    I14 @S9S_MB_2U_LIB.S9S_MB_2U(SCH_1):PAGE287

 J66 PICOPROBE_BXA-DELTA-L 4.0,SMLFA
     2 DELTA_L_85_5INCH_IN2_DN @S9S_MB_2U_LIB.S9S_MB_2U(SCH_1):DELTA_L_85_5INCH_IN2_DN    I12 @S9S_MB_2U_LIB.S9S_MB_2U(SCH_1):PAGE287
     3 DELTA_L_GND_1 @S9S_MB_2U_LIB.S9S_MB_2U(SCH_1):DELTA_L_GND_1    I12 @S9S_MB_2U_LIB.S9S_MB_2U(SCH_1):PAGE287
     1 DELTA_L_85_5INCH_IN2_DP @S9S_MB_2U_LIB.S9S_MB_2U(SCH_1):DELTA_L_85_5INCH_IN2_DP    I12 @S9S_MB_2U_LIB.S9S_MB_2U(SCH_1):PAGE287

 J67 PICOPROBE_BXA-DELTA-L 4.0,SMLFA
     2 DELTA_L_85_5INCH_IN3_DN @S9S_MB_2U_LIB.S9S_MB_2U(SCH_1):DELTA_L_85_5INCH_IN3_DN    I11 @S9S_MB_2U_LIB.S9S_MB_2U(SCH_1):PAGE287
     3 DELTA_L_GND_1 @S9S_MB_2U_LIB.S9S_MB_2U(SCH_1):DELTA_L_GND_1    I11 @S9S_MB_2U_LIB.S9S_MB_2U(SCH_1):PAGE287
     1 DELTA_L_85_5INCH_IN3_DP @S9S_MB_2U_LIB.S9S_MB_2U(SCH_1):DELTA_L_85_5INCH_IN3_DP    I11 @S9S_MB_2U_LIB.S9S_MB_2U(SCH_1):PAGE287

 J68 PICOPROBE_BXA-DELTA-L 4.0,SMLFA
     2 DELTA_L_85_5INCH_IN4_DN @S9S_MB_2U_LIB.S9S_MB_2U(SCH_1):DELTA_L_85_5INCH_IN4_DN     I8 @S9S_MB_2U_LIB.S9S_MB_2U(SCH_1):PAGE287
     3 DELTA_L_GND_1 @S9S_MB_2U_LIB.S9S_MB_2U(SCH_1):DELTA_L_GND_1     I8 @S9S_MB_2U_LIB.S9S_MB_2U(SCH_1):PAGE287
     1 DELTA_L_85_5INCH_IN4_DP @S9S_MB_2U_LIB.S9S_MB_2U(SCH_1):DELTA_L_85_5INCH_IN4_DP     I8 @S9S_MB_2U_LIB.S9S_MB_2U(SCH_1):PAGE287

 J69 PICOPROBE_BXA-DELTA-L 4.0,SMLFA
     2 DELTA_L_85_5INCH_TOP_DP @S9S_MB_2U_LIB.S9S_MB_2U(SCH_1):DELTA_L_85_5INCH_TOP_DP    I24 @S9S_MB_2U_LIB.S9S_MB_2U(SCH_1):PAGE287
     3 DELTA_L_GND_1 @S9S_MB_2U_LIB.S9S_MB_2U(SCH_1):DELTA_L_GND_1    I24 @S9S_MB_2U_LIB.S9S_MB_2U(SCH_1):PAGE287
     1 DELTA_L_85_5INCH_TOP_DN @S9S_MB_2U_LIB.S9S_MB_2U(SCH_1):DELTA_L_85_5INCH_TOP_DN    I24 @S9S_MB_2U_LIB.S9S_MB_2U(SCH_1):PAGE287

 J70 PICOPROBE_BXA-DELTA-L 4.0,SMLFA
     2 DELTA_L_85_5INCH_BOT_DP @S9S_MB_2U_LIB.S9S_MB_2U(SCH_1):DELTA_L_85_5INCH_BOT_DP    I23 @S9S_MB_2U_LIB.S9S_MB_2U(SCH_1):PAGE287
     3 DELTA_L_GND_1 @S9S_MB_2U_LIB.S9S_MB_2U(SCH_1):DELTA_L_GND_1    I23 @S9S_MB_2U_LIB.S9S_MB_2U(SCH_1):PAGE287
     1 DELTA_L_85_5INCH_BOT_DN @S9S_MB_2U_LIB.S9S_MB_2U(SCH_1):DELTA_L_85_5INCH_BOT_DN    I23 @S9S_MB_2U_LIB.S9S_MB_2U(SCH_1):PAGE287

 J71 PICOPROBE_BXA-DELTA-L 4.0,SMLFA
     2 DELTA_L_85_5INCH_IN1_DP @S9S_MB_2U_LIB.S9S_MB_2U(SCH_1):DELTA_L_85_5INCH_IN1_DP    I22 @S9S_MB_2U_LIB.S9S_MB_2U(SCH_1):PAGE287
     3 DELTA_L_GND_1 @S9S_MB_2U_LIB.S9S_MB_2U(SCH_1):DELTA_L_GND_1    I22 @S9S_MB_2U_LIB.S9S_MB_2U(SCH_1):PAGE287
     1 DELTA_L_85_5INCH_IN1_DN @S9S_MB_2U_LIB.S9S_MB_2U(SCH_1):DELTA_L_85_5INCH_IN1_DN    I22 @S9S_MB_2U_LIB.S9S_MB_2U(SCH_1):PAGE287

 J72 PICOPROBE_BXA-DELTA-L 4.0,SMLFA
     2 DELTA_L_85_5INCH_IN2_DP @S9S_MB_2U_LIB.S9S_MB_2U(SCH_1):DELTA_L_85_5INCH_IN2_DP    I21 @S9S_MB_2U_LIB.S9S_MB_2U(SCH_1):PAGE287
     3 DELTA_L_GND_1 @S9S_MB_2U_LIB.S9S_MB_2U(SCH_1):DELTA_L_GND_1    I21 @S9S_MB_2U_LIB.S9S_MB_2U(SCH_1):PAGE287
     1 DELTA_L_85_5INCH_IN2_DN @S9S_MB_2U_LIB.S9S_MB_2U(SCH_1):DELTA_L_85_5INCH_IN2_DN    I21 @S9S_MB_2U_LIB.S9S_MB_2U(SCH_1):PAGE287

 J73 PICOPROBE_BXA-DELTA-L 4.0,SMLFA
     2 DELTA_L_85_5INCH_IN3_DP @S9S_MB_2U_LIB.S9S_MB_2U(SCH_1):DELTA_L_85_5INCH_IN3_DP    I20 @S9S_MB_2U_LIB.S9S_MB_2U(SCH_1):PAGE287
     3 DELTA_L_GND_1 @S9S_MB_2U_LIB.S9S_MB_2U(SCH_1):DELTA_L_GND_1    I20 @S9S_MB_2U_LIB.S9S_MB_2U(SCH_1):PAGE287
     1 DELTA_L_85_5INCH_IN3_DN @S9S_MB_2U_LIB.S9S_MB_2U(SCH_1):DELTA_L_85_5INCH_IN3_DN    I20 @S9S_MB_2U_LIB.S9S_MB_2U(SCH_1):PAGE287

 J74 PICOPROBE_BXA-DELTA-L 4.0,SMLFA
     2 DELTA_L_85_5INCH_IN4_DP @S9S_MB_2U_LIB.S9S_MB_2U(SCH_1):DELTA_L_85_5INCH_IN4_DP    I19 @S9S_MB_2U_LIB.S9S_MB_2U(SCH_1):PAGE287
     3 DELTA_L_GND_1 @S9S_MB_2U_LIB.S9S_MB_2U(SCH_1):DELTA_L_GND_1    I19 @S9S_MB_2U_LIB.S9S_MB_2U(SCH_1):PAGE287
     1 DELTA_L_85_5INCH_IN4_DN @S9S_MB_2U_LIB.S9S_MB_2U(SCH_1):DELTA_L_85_5INCH_IN4_DN    I19 @S9S_MB_2U_LIB.S9S_MB_2U(SCH_1):PAGE287

 J75 PICOPROBE_BXA-DELTA-L 4.0,SMLFA
     2 DELTA_L_85_10INCH_TOP_DN @S9S_MB_2U_LIB.S9S_MB_2U(SCH_1):DELTA_L_85_10INCH_TOP_DN    I52 @S9S_MB_2U_LIB.S9S_MB_2U(SCH_1):PAGE287
     3 DELTA_L_GND_1 @S9S_MB_2U_LIB.S9S_MB_2U(SCH_1):DELTA_L_GND_1    I52 @S9S_MB_2U_LIB.S9S_MB_2U(SCH_1):PAGE287
     1 DELTA_L_85_10INCH_TOP_DP @S9S_MB_2U_LIB.S9S_MB_2U(SCH_1):DELTA_L_85_10INCH_TOP_DP    I52 @S9S_MB_2U_LIB.S9S_MB_2U(SCH_1):PAGE287

 J76 PICOPROBE_BXA-DELTA-L 4.0,SMLFA
     2 DELTA_L_85_10INCH_BOT_DN @S9S_MB_2U_LIB.S9S_MB_2U(SCH_1):DELTA_L_85_10INCH_BOT_DN    I51 @S9S_MB_2U_LIB.S9S_MB_2U(SCH_1):PAGE287
     3 DELTA_L_GND_1 @S9S_MB_2U_LIB.S9S_MB_2U(SCH_1):DELTA_L_GND_1    I51 @S9S_MB_2U_LIB.S9S_MB_2U(SCH_1):PAGE287
     1 DELTA_L_85_10INCH_BOT_DP @S9S_MB_2U_LIB.S9S_MB_2U(SCH_1):DELTA_L_85_10INCH_BOT_DP    I51 @S9S_MB_2U_LIB.S9S_MB_2U(SCH_1):PAGE287

 J77 PICOPROBE_BXA-DELTA-L 4.0,SMLFA
     2 DELTA_L_85_10INCH_IN1_DN @S9S_MB_2U_LIB.S9S_MB_2U(SCH_1):DELTA_L_85_10INCH_IN1_DN    I48 @S9S_MB_2U_LIB.S9S_MB_2U(SCH_1):PAGE287
     3 DELTA_L_GND_1 @S9S_MB_2U_LIB.S9S_MB_2U(SCH_1):DELTA_L_GND_1    I48 @S9S_MB_2U_LIB.S9S_MB_2U(SCH_1):PAGE287
     1 DELTA_L_85_10INCH_IN1_DP @S9S_MB_2U_LIB.S9S_MB_2U(SCH_1):DELTA_L_85_10INCH_IN1_DP    I48 @S9S_MB_2U_LIB.S9S_MB_2U(SCH_1):PAGE287

 J78 PICOPROBE_BXA-DELTA-L 4.0,SMLFA
     2 DELTA_L_85_10INCH_IN2_DN @S9S_MB_2U_LIB.S9S_MB_2U(SCH_1):DELTA_L_85_10INCH_IN2_DN    I43 @S9S_MB_2U_LIB.S9S_MB_2U(SCH_1):PAGE287
     3 DELTA_L_GND_1 @S9S_MB_2U_LIB.S9S_MB_2U(SCH_1):DELTA_L_GND_1    I43 @S9S_MB_2U_LIB.S9S_MB_2U(SCH_1):PAGE287
     1 DELTA_L_85_10INCH_IN2_DP @S9S_MB_2U_LIB.S9S_MB_2U(SCH_1):DELTA_L_85_10INCH_IN2_DP    I43 @S9S_MB_2U_LIB.S9S_MB_2U(SCH_1):PAGE287

 J79 PICOPROBE_BXA-DELTA-L 4.0,SMLFA
     2 DELTA_L_85_10INCH_IN3_DN @S9S_MB_2U_LIB.S9S_MB_2U(SCH_1):DELTA_L_85_10INCH_IN3_DN    I42 @S9S_MB_2U_LIB.S9S_MB_2U(SCH_1):PAGE287
     3 DELTA_L_GND_1 @S9S_MB_2U_LIB.S9S_MB_2U(SCH_1):DELTA_L_GND_1    I42 @S9S_MB_2U_LIB.S9S_MB_2U(SCH_1):PAGE287
     1 DELTA_L_85_10INCH_IN3_DP @S9S_MB_2U_LIB.S9S_MB_2U(SCH_1):DELTA_L_85_10INCH_IN3_DP    I42 @S9S_MB_2U_LIB.S9S_MB_2U(SCH_1):PAGE287

 J80 PICOPROBE_BXA-DELTA-L 4.0,SMLFA
     2 DELTA_L_85_10INCH_IN4_DN @S9S_MB_2U_LIB.S9S_MB_2U(SCH_1):DELTA_L_85_10INCH_IN4_DN    I39 @S9S_MB_2U_LIB.S9S_MB_2U(SCH_1):PAGE287
     3 DELTA_L_GND_1 @S9S_MB_2U_LIB.S9S_MB_2U(SCH_1):DELTA_L_GND_1    I39 @S9S_MB_2U_LIB.S9S_MB_2U(SCH_1):PAGE287
     1 DELTA_L_85_10INCH_IN4_DP @S9S_MB_2U_LIB.S9S_MB_2U(SCH_1):DELTA_L_85_10INCH_IN4_DP    I39 @S9S_MB_2U_LIB.S9S_MB_2U(SCH_1):PAGE287

 J81 PICOPROBE_BXA-DELTA-L 4.0,SMLFA
     2 DELTA_L_85_10INCH_TOP_DP @S9S_MB_2U_LIB.S9S_MB_2U(SCH_1):DELTA_L_85_10INCH_TOP_DP    I58 @S9S_MB_2U_LIB.S9S_MB_2U(SCH_1):PAGE287
     3 DELTA_L_GND_1 @S9S_MB_2U_LIB.S9S_MB_2U(SCH_1):DELTA_L_GND_1    I58 @S9S_MB_2U_LIB.S9S_MB_2U(SCH_1):PAGE287
     1 DELTA_L_85_10INCH_TOP_DN @S9S_MB_2U_LIB.S9S_MB_2U(SCH_1):DELTA_L_85_10INCH_TOP_DN    I58 @S9S_MB_2U_LIB.S9S_MB_2U(SCH_1):PAGE287

 J82 PICOPROBE_BXA-DELTA-L 4.0,SMLFA
     2 DELTA_L_85_10INCH_BOT_DP @S9S_MB_2U_LIB.S9S_MB_2U(SCH_1):DELTA_L_85_10INCH_BOT_DP    I57 @S9S_MB_2U_LIB.S9S_MB_2U(SCH_1):PAGE287
     3 DELTA_L_GND_1 @S9S_MB_2U_LIB.S9S_MB_2U(SCH_1):DELTA_L_GND_1    I57 @S9S_MB_2U_LIB.S9S_MB_2U(SCH_1):PAGE287
     1 DELTA_L_85_10INCH_BOT_DN @S9S_MB_2U_LIB.S9S_MB_2U(SCH_1):DELTA_L_85_10INCH_BOT_DN    I57 @S9S_MB_2U_LIB.S9S_MB_2U(SCH_1):PAGE287

 J83 PICOPROBE_BXA-DELTA-L 4.0,SMLFA
     2 DELTA_L_85_10INCH_IN1_DP @S9S_MB_2U_LIB.S9S_MB_2U(SCH_1):DELTA_L_85_10INCH_IN1_DP    I56 @S9S_MB_2U_LIB.S9S_MB_2U(SCH_1):PAGE287
     3 DELTA_L_GND_1 @S9S_MB_2U_LIB.S9S_MB_2U(SCH_1):DELTA_L_GND_1    I56 @S9S_MB_2U_LIB.S9S_MB_2U(SCH_1):PAGE287
     1 DELTA_L_85_10INCH_IN1_DN @S9S_MB_2U_LIB.S9S_MB_2U(SCH_1):DELTA_L_85_10INCH_IN1_DN    I56 @S9S_MB_2U_LIB.S9S_MB_2U(SCH_1):PAGE287

 J84 PICOPROBE_BXA-DELTA-L 4.0,SMLFA
     2 DELTA_L_85_10INCH_IN2_DP @S9S_MB_2U_LIB.S9S_MB_2U(SCH_1):DELTA_L_85_10INCH_IN2_DP    I55 @S9S_MB_2U_LIB.S9S_MB_2U(SCH_1):PAGE287
     3 DELTA_L_GND_1 @S9S_MB_2U_LIB.S9S_MB_2U(SCH_1):DELTA_L_GND_1    I55 @S9S_MB_2U_LIB.S9S_MB_2U(SCH_1):PAGE287
     1 DELTA_L_85_10INCH_IN2_DN @S9S_MB_2U_LIB.S9S_MB_2U(SCH_1):DELTA_L_85_10INCH_IN2_DN    I55 @S9S_MB_2U_LIB.S9S_MB_2U(SCH_1):PAGE287

 J85 PICOPROBE_BXA-DELTA-L 4.0,SMLFA
     2 DELTA_L_85_10INCH_IN3_DP @S9S_MB_2U_LIB.S9S_MB_2U(SCH_1):DELTA_L_85_10INCH_IN3_DP    I54 @S9S_MB_2U_LIB.S9S_MB_2U(SCH_1):PAGE287
     3 DELTA_L_GND_1 @S9S_MB_2U_LIB.S9S_MB_2U(SCH_1):DELTA_L_GND_1    I54 @S9S_MB_2U_LIB.S9S_MB_2U(SCH_1):PAGE287
     1 DELTA_L_85_10INCH_IN3_DN @S9S_MB_2U_LIB.S9S_MB_2U(SCH_1):DELTA_L_85_10INCH_IN3_DN    I54 @S9S_MB_2U_LIB.S9S_MB_2U(SCH_1):PAGE287

 J86 PICOPROBE_BXA-DELTA-L 4.0,SMLFA
     2 DELTA_L_85_10INCH_IN4_DP @S9S_MB_2U_LIB.S9S_MB_2U(SCH_1):DELTA_L_85_10INCH_IN4_DP    I53 @S9S_MB_2U_LIB.S9S_MB_2U(SCH_1):PAGE287
     3 DELTA_L_GND_1 @S9S_MB_2U_LIB.S9S_MB_2U(SCH_1):DELTA_L_GND_1    I53 @S9S_MB_2U_LIB.S9S_MB_2U(SCH_1):PAGE287
     1 DELTA_L_85_10INCH_IN4_DN @S9S_MB_2U_LIB.S9S_MB_2U(SCH_1):DELTA_L_85_10INCH_IN4_DN    I53 @S9S_MB_2U_LIB.S9S_MB_2U(SCH_1):PAGE287

 J90 SCONN56_123276793-SCONN56_1-23A
    B1 P12V_E1S_0 @S9S_MB_2U_LIB.S9S_MB_2U(SCH_1):P12V_E1S_0   I318 @S9S_MB_2U_LIB.S9S_MB_2U(SCH_1):PAGE297
    B2 P12V_E1S_0 @S9S_MB_2U_LIB.S9S_MB_2U(SCH_1):P12V_E1S_0   I318 @S9S_MB_2U_LIB.S9S_MB_2U(SCH_1):PAGE297
    B3 P12V_E1S_0 @S9S_MB_2U_LIB.S9S_MB_2U(SCH_1):P12V_E1S_0   I318 @S9S_MB_2U_LIB.S9S_MB_2U(SCH_1):PAGE297
    B4 P12V_E1S_0 @S9S_MB_2U_LIB.S9S_MB_2U(SCH_1):P12V_E1S_0   I318 @S9S_MB_2U_LIB.S9S_MB_2U(SCH_1):PAGE297
    B5 P12V_E1S_0 @S9S_MB_2U_LIB.S9S_MB_2U(SCH_1):P12V_E1S_0   I318 @S9S_MB_2U_LIB.S9S_MB_2U(SCH_1):PAGE297
    B6 P12V_E1S_0 @S9S_MB_2U_LIB.S9S_MB_2U(SCH_1):P12V_E1S_0   I318 @S9S_MB_2U_LIB.S9S_MB_2U(SCH_1):PAGE297
    A1    GND @S9S_MB_2U_LIB.S9S_MB_2U(SCH_1):GND   I318 @S9S_MB_2U_LIB.S9S_MB_2U(SCH_1):PAGE297
    A2    GND @S9S_MB_2U_LIB.S9S_MB_2U(SCH_1):GND   I318 @S9S_MB_2U_LIB.S9S_MB_2U(SCH_1):PAGE297
    A3    GND @S9S_MB_2U_LIB.S9S_MB_2U(SCH_1):GND   I318 @S9S_MB_2U_LIB.S9S_MB_2U(SCH_1):PAGE297
    A4    GND @S9S_MB_2U_LIB.S9S_MB_2U(SCH_1):GND   I318 @S9S_MB_2U_LIB.S9S_MB_2U(SCH_1):PAGE297
    A5    GND @S9S_MB_2U_LIB.S9S_MB_2U(SCH_1):GND   I318 @S9S_MB_2U_LIB.S9S_MB_2U(SCH_1):PAGE297
    A6    GND @S9S_MB_2U_LIB.S9S_MB_2U(SCH_1):GND   I318 @S9S_MB_2U_LIB.S9S_MB_2U(SCH_1):PAGE297
    B7 TP_E1S_0_MFG @S9S_MB_2U_LIB.S9S_MB_2U(SCH_1):TP_E1S_0_MFG   I318 @S9S_MB_2U_LIB.S9S_MB_2U(SCH_1):PAGE297
    B8 TP_E1S_0_RFU @S9S_MB_2U_LIB.S9S_MB_2U(SCH_1):TP_E1S_0_RFU   I318 @S9S_MB_2U_LIB.S9S_MB_2U(SCH_1):PAGE297
    B9 PU_E1S_0_DUALPORT_EN_N @S9S_MB_2U_LIB.S9S_MB_2U(SCH_1):PU_E1S_0_DUALPORT_EN_N   I318 @S9S_MB_2U_LIB.S9S_MB_2U(SCH_1):PAGE297
   B11 P3V3_E1S_0 @S9S_MB_2U_LIB.S9S_MB_2U(SCH_1):P3V3_E1S_0   I318 @S9S_MB_2U_LIB.S9S_MB_2U(SCH_1):PAGE297
   B12 E1S_0_PWRDIS @S9S_MB_2U_LIB.S9S_MB_2U(SCH_1):E1S_0_PWRDIS   I318 @S9S_MB_2U_LIB.S9S_MB_2U(SCH_1):PAGE297
   B13    GND @S9S_MB_2U_LIB.S9S_MB_2U(SCH_1):GND   I318 @S9S_MB_2U_LIB.S9S_MB_2U(SCH_1):PAGE297
   B16    GND @S9S_MB_2U_LIB.S9S_MB_2U(SCH_1):GND   I318 @S9S_MB_2U_LIB.S9S_MB_2U(SCH_1):PAGE297
   B19    GND @S9S_MB_2U_LIB.S9S_MB_2U(SCH_1):GND   I318 @S9S_MB_2U_LIB.S9S_MB_2U(SCH_1):PAGE297
   B22    GND @S9S_MB_2U_LIB.S9S_MB_2U(SCH_1):GND   I318 @S9S_MB_2U_LIB.S9S_MB_2U(SCH_1):PAGE297
   B25    GND @S9S_MB_2U_LIB.S9S_MB_2U(SCH_1):GND   I318 @S9S_MB_2U_LIB.S9S_MB_2U(SCH_1):PAGE297
   B28    GND @S9S_MB_2U_LIB.S9S_MB_2U(SCH_1):GND   I318 @S9S_MB_2U_LIB.S9S_MB_2U(SCH_1):PAGE297
   B14 CLK_100M_E1S_0_DN @S9S_MB_2U_LIB.S9S_MB_2U(SCH_1):CLK_100M_E1S_0_DN   I318 @S9S_MB_2U_LIB.S9S_MB_2U(SCH_1):PAGE297
   B15 CLK_100M_E1S_0_DP @S9S_MB_2U_LIB.S9S_MB_2U(SCH_1):CLK_100M_E1S_0_DP   I318 @S9S_MB_2U_LIB.S9S_MB_2U(SCH_1):PAGE297
   B17 P3E_PCH_E1S_TX_C_DP<0> @S9S_MB_2U_LIB.S9S_MB_2U(SCH_1):P3E_PCH_E1S_TX_C_DP(0)   I318 @S9S_MB_2U_LIB.S9S_MB_2U(SCH_1):PAGE297
   B18 P3E_PCH_E1S_TX_C_DN<0> @S9S_MB_2U_LIB.S9S_MB_2U(SCH_1):P3E_PCH_E1S_TX_C_DN(0)   I318 @S9S_MB_2U_LIB.S9S_MB_2U(SCH_1):PAGE297
   B20 P3E_PCH_E1S_TX_C_DP<1> @S9S_MB_2U_LIB.S9S_MB_2U(SCH_1):P3E_PCH_E1S_TX_C_DP(1)   I318 @S9S_MB_2U_LIB.S9S_MB_2U(SCH_1):PAGE297
   B21 P3E_PCH_E1S_TX_C_DN<1> @S9S_MB_2U_LIB.S9S_MB_2U(SCH_1):P3E_PCH_E1S_TX_C_DN(1)   I318 @S9S_MB_2U_LIB.S9S_MB_2U(SCH_1):PAGE297
   B23 P3E_PCH_E1S_TX_C_DN<2> @S9S_MB_2U_LIB.S9S_MB_2U(SCH_1):P3E_PCH_E1S_TX_C_DN(2)   I318 @S9S_MB_2U_LIB.S9S_MB_2U(SCH_1):PAGE297
   B24 P3E_PCH_E1S_TX_C_DP<2> @S9S_MB_2U_LIB.S9S_MB_2U(SCH_1):P3E_PCH_E1S_TX_C_DP(2)   I318 @S9S_MB_2U_LIB.S9S_MB_2U(SCH_1):PAGE297
   B26 P3E_PCH_E1S_TX_C_DN<3> @S9S_MB_2U_LIB.S9S_MB_2U(SCH_1):P3E_PCH_E1S_TX_C_DN(3)   I318 @S9S_MB_2U_LIB.S9S_MB_2U(SCH_1):PAGE297
   B27 P3E_PCH_E1S_TX_C_DP<3> @S9S_MB_2U_LIB.S9S_MB_2U(SCH_1):P3E_PCH_E1S_TX_C_DP(3)   I318 @S9S_MB_2U_LIB.S9S_MB_2U(SCH_1):PAGE297
    A7 SMB_E1S_3V3AUX_ISO_SCL @S9S_MB_2U_LIB.S9S_MB_2U(SCH_1):SMB_E1S_3V3AUX_ISO_SCL   I318 @S9S_MB_2U_LIB.S9S_MB_2U(SCH_1):PAGE297
    A8 SMB_E1S_3V3AUX_ISO_SDA @S9S_MB_2U_LIB.S9S_MB_2U(SCH_1):SMB_E1S_3V3AUX_ISO_SDA   I318 @S9S_MB_2U_LIB.S9S_MB_2U(SCH_1):PAGE297
    A9 RST_SMB_E1S_0_N @S9S_MB_2U_LIB.S9S_MB_2U(SCH_1):RST_SMB_E1S_0_N   I318 @S9S_MB_2U_LIB.S9S_MB_2U(SCH_1):PAGE297
   A10 E1S_0_LED_ACT_N @S9S_MB_2U_LIB.S9S_MB_2U(SCH_1):E1S_0_LED_ACT_N   I318 @S9S_MB_2U_LIB.S9S_MB_2U(SCH_1):PAGE297
   B10 RST_PCIE_PCH_E1S_PERST_N @S9S_MB_2U_LIB.S9S_MB_2U(SCH_1):RST_PCIE_PCH_E1S_PERST_N   I318 @S9S_MB_2U_LIB.S9S_MB_2U(SCH_1):PAGE297
   A11 E1S_0_PERST1_CLKREQ_N @S9S_MB_2U_LIB.S9S_MB_2U(SCH_1):E1S_0_PERST1_CLKREQ_N   I318 @S9S_MB_2U_LIB.S9S_MB_2U(SCH_1):PAGE297
   A12 E1S_0_PRSNT_N @S9S_MB_2U_LIB.S9S_MB_2U(SCH_1):E1S_0_PRSNT_N   I318 @S9S_MB_2U_LIB.S9S_MB_2U(SCH_1):PAGE297
   A13    GND @S9S_MB_2U_LIB.S9S_MB_2U(SCH_1):GND   I318 @S9S_MB_2U_LIB.S9S_MB_2U(SCH_1):PAGE297
   A16    GND @S9S_MB_2U_LIB.S9S_MB_2U(SCH_1):GND   I318 @S9S_MB_2U_LIB.S9S_MB_2U(SCH_1):PAGE297
   A19    GND @S9S_MB_2U_LIB.S9S_MB_2U(SCH_1):GND   I318 @S9S_MB_2U_LIB.S9S_MB_2U(SCH_1):PAGE297
   A22    GND @S9S_MB_2U_LIB.S9S_MB_2U(SCH_1):GND   I318 @S9S_MB_2U_LIB.S9S_MB_2U(SCH_1):PAGE297
   A25    GND @S9S_MB_2U_LIB.S9S_MB_2U(SCH_1):GND   I318 @S9S_MB_2U_LIB.S9S_MB_2U(SCH_1):PAGE297
   A28    GND @S9S_MB_2U_LIB.S9S_MB_2U(SCH_1):GND   I318 @S9S_MB_2U_LIB.S9S_MB_2U(SCH_1):PAGE297
   A14 TP_CLK_100M_E1S_0_DN @S9S_MB_2U_LIB.S9S_MB_2U(SCH_1):TP_CLK_100M_E1S_0_DN   I318 @S9S_MB_2U_LIB.S9S_MB_2U(SCH_1):PAGE297
   A15 TP_CLK_100M_E1S_0_DP @S9S_MB_2U_LIB.S9S_MB_2U(SCH_1):TP_CLK_100M_E1S_0_DP   I318 @S9S_MB_2U_LIB.S9S_MB_2U(SCH_1):PAGE297
   A17 P3E_PCH_E1S_RX_DP<0> @S9S_MB_2U_LIB.S9S_MB_2U(SCH_1):P3E_PCH_E1S_RX_DP(0)   I318 @S9S_MB_2U_LIB.S9S_MB_2U(SCH_1):PAGE297
   A18 P3E_PCH_E1S_RX_DN<0> @S9S_MB_2U_LIB.S9S_MB_2U(SCH_1):P3E_PCH_E1S_RX_DN(0)   I318 @S9S_MB_2U_LIB.S9S_MB_2U(SCH_1):PAGE297
   A20 P3E_PCH_E1S_RX_DN<1> @S9S_MB_2U_LIB.S9S_MB_2U(SCH_1):P3E_PCH_E1S_RX_DN(1)   I318 @S9S_MB_2U_LIB.S9S_MB_2U(SCH_1):PAGE297
   A21 P3E_PCH_E1S_RX_DP<1> @S9S_MB_2U_LIB.S9S_MB_2U(SCH_1):P3E_PCH_E1S_RX_DP(1)   I318 @S9S_MB_2U_LIB.S9S_MB_2U(SCH_1):PAGE297
   A23 P3E_PCH_E1S_RX_DN<2> @S9S_MB_2U_LIB.S9S_MB_2U(SCH_1):P3E_PCH_E1S_RX_DN(2)   I318 @S9S_MB_2U_LIB.S9S_MB_2U(SCH_1):PAGE297
   A24 P3E_PCH_E1S_RX_DP<2> @S9S_MB_2U_LIB.S9S_MB_2U(SCH_1):P3E_PCH_E1S_RX_DP(2)   I318 @S9S_MB_2U_LIB.S9S_MB_2U(SCH_1):PAGE297
   A26 P3E_PCH_E1S_RX_DN<3> @S9S_MB_2U_LIB.S9S_MB_2U(SCH_1):P3E_PCH_E1S_RX_DN(3)   I318 @S9S_MB_2U_LIB.S9S_MB_2U(SCH_1):PAGE297
   A27 P3E_PCH_E1S_RX_DP<3> @S9S_MB_2U_LIB.S9S_MB_2U(SCH_1):P3E_PCH_E1S_RX_DP(3)   I318 @S9S_MB_2U_LIB.S9S_MB_2U(SCH_1):PAGE297
    G2    GND @S9S_MB_2U_LIB.S9S_MB_2U(SCH_1):GND   I318 @S9S_MB_2U_LIB.S9S_MB_2U(SCH_1):PAGE297
    G1    GND @S9S_MB_2U_LIB.S9S_MB_2U(SCH_1):GND   I318 @S9S_MB_2U_LIB.S9S_MB_2U(SCH_1):PAGE297

J90_CON TP_TP_BOM ONLY-NA,TP12_BOM
     1     NC     NC    I69 @S9S_MB_2U_LIB.S9S_MB_2U(SCH_1):PAGE290

J100 SCONN20_513860200CV01-SCONN20_A
     1 SMB_SML0_ME_SCL @S9S_MB_2U_LIB.S9S_MB_2U(SCH_1):SMB_SML0_ME_SCL    I32 @S9S_MB_2U_LIB.S9S_MB_2U(SCH_1):PAGE215
     2    GND @S9S_MB_2U_LIB.S9S_MB_2U(SCH_1):GND    I32 @S9S_MB_2U_LIB.S9S_MB_2U(SCH_1):PAGE215
     3 SMB_SML0_ME_SDA @S9S_MB_2U_LIB.S9S_MB_2U(SCH_1):SMB_SML0_ME_SDA    I32 @S9S_MB_2U_LIB.S9S_MB_2U(SCH_1):PAGE215
     4 IRQ_SML0_ALERT_R1_N @S9S_MB_2U_LIB.S9S_MB_2U(SCH_1):IRQ_SML0_ALERT_R1_N    I32 @S9S_MB_2U_LIB.S9S_MB_2U(SCH_1):PAGE215
     5 SMB_PMBUS_SML1_ME_SCL @S9S_MB_2U_LIB.S9S_MB_2U(SCH_1):SMB_PMBUS_SML1_ME_SCL    I32 @S9S_MB_2U_LIB.S9S_MB_2U(SCH_1):PAGE215
     6    GND @S9S_MB_2U_LIB.S9S_MB_2U(SCH_1):GND    I32 @S9S_MB_2U_LIB.S9S_MB_2U(SCH_1):PAGE215
     7 SMB_PMBUS_SML1_ME_SDA @S9S_MB_2U_LIB.S9S_MB_2U(SCH_1):SMB_PMBUS_SML1_ME_SDA    I32 @S9S_MB_2U_LIB.S9S_MB_2U(SCH_1):PAGE215
     8 IRQ_SML1_PMBUS_ALERT_R_N @S9S_MB_2U_LIB.S9S_MB_2U(SCH_1):IRQ_SML1_PMBUS_ALERT_R_N    I32 @S9S_MB_2U_LIB.S9S_MB_2U(SCH_1):PAGE215
     9 RST_RSMRST_NM_HDR_N @S9S_MB_2U_LIB.S9S_MB_2U(SCH_1):RST_RSMRST_NM_HDR_N    I32 @S9S_MB_2U_LIB.S9S_MB_2U(SCH_1):PAGE215
    10    GND @S9S_MB_2U_LIB.S9S_MB_2U(SCH_1):GND    I32 @S9S_MB_2U_LIB.S9S_MB_2U(SCH_1):PAGE215
    11 SMB_HOST_ME_SCL @S9S_MB_2U_LIB.S9S_MB_2U(SCH_1):SMB_HOST_ME_SCL    I32 @S9S_MB_2U_LIB.S9S_MB_2U(SCH_1):PAGE215
    12    GND @S9S_MB_2U_LIB.S9S_MB_2U(SCH_1):GND    I32 @S9S_MB_2U_LIB.S9S_MB_2U(SCH_1):PAGE215
    13 SMB_HOST_ME_SDA @S9S_MB_2U_LIB.S9S_MB_2U(SCH_1):SMB_HOST_ME_SDA    I32 @S9S_MB_2U_LIB.S9S_MB_2U(SCH_1):PAGE215
    14     NC     NC    I32 @S9S_MB_2U_LIB.S9S_MB_2U(SCH_1):PAGE215
    15    GND @S9S_MB_2U_LIB.S9S_MB_2U(SCH_1):GND    I32 @S9S_MB_2U_LIB.S9S_MB_2U(SCH_1):PAGE215
    16 PECI_BMC_ME @S9S_MB_2U_LIB.S9S_MB_2U(SCH_1):PECI_BMC_ME    I32 @S9S_MB_2U_LIB.S9S_MB_2U(SCH_1):PAGE215
    17    GND @S9S_MB_2U_LIB.S9S_MB_2U(SCH_1):GND    I32 @S9S_MB_2U_LIB.S9S_MB_2U(SCH_1):PAGE215
    18 PWRGD_PS_PWROK_ME_CONN @S9S_MB_2U_LIB.S9S_MB_2U(SCH_1):PWRGD_PS_PWROK_ME_CONN    I32 @S9S_MB_2U_LIB.S9S_MB_2U(SCH_1):PAGE215
    19 FM_BIOS_POST_CMPLT_HDR_N @S9S_MB_2U_LIB.S9S_MB_2U(SCH_1):FM_BIOS_POST_CMPLT_HDR_N    I32 @S9S_MB_2U_LIB.S9S_MB_2U(SCH_1):PAGE215
    20     NC     NC    I32 @S9S_MB_2U_LIB.S9S_MB_2U(SCH_1):PAGE215

J104 CONN14_210HP207GBR1-CONN14_210A
     1 PU_ESPI_ENABLE_STRAP @S9S_MB_2U_LIB.S9S_MB_2U(SCH_1):PU_ESPI_ENABLE_STRAP   I134 @S9S_MB_2U_LIB.S9S_MB_2U(SCH_1):PAGE189
     2 JTAG_TRC_PCH_PTI<6> @S9S_MB_2U_LIB.S9S_MB_2U(SCH_1):JTAG_TRC_PCH_PTI(6)   I134 @S9S_MB_2U_LIB.S9S_MB_2U(SCH_1):PAGE189
     3 PU_BIOS_RCVR_BOOT @S9S_MB_2U_LIB.S9S_MB_2U(SCH_1):PU_BIOS_RCVR_BOOT   I134 @S9S_MB_2U_LIB.S9S_MB_2U(SCH_1):PAGE189
     4 FM_PCH_BIOS_RCVR_MODE @S9S_MB_2U_LIB.S9S_MB_2U(SCH_1):FM_PCH_BIOS_RCVR_MODE   I134 @S9S_MB_2U_LIB.S9S_MB_2U(SCH_1):PAGE189
     5 PU_SWAP_OVERRIDE_N @S9S_MB_2U_LIB.S9S_MB_2U(SCH_1):PU_SWAP_OVERRIDE_N   I134 @S9S_MB_2U_LIB.S9S_MB_2U(SCH_1):PAGE189
     6 FM_ADR_COMPLETE @S9S_MB_2U_LIB.S9S_MB_2U(SCH_1):FM_ADR_COMPLETE   I134 @S9S_MB_2U_LIB.S9S_MB_2U(SCH_1):PAGE189
     7 PD_BIOS_IMAGE_SWAP_N @S9S_MB_2U_LIB.S9S_MB_2U(SCH_1):PD_BIOS_IMAGE_SWAP_N   I134 @S9S_MB_2U_LIB.S9S_MB_2U(SCH_1):PAGE189
     8 FM_BIOS_IMAGE_SWAP_N @S9S_MB_2U_LIB.S9S_MB_2U(SCH_1):FM_BIOS_IMAGE_SWAP_N   I134 @S9S_MB_2U_LIB.S9S_MB_2U(SCH_1):PAGE189
     9 PU_FLASH_SECURITY_STRAP @S9S_MB_2U_LIB.S9S_MB_2U(SCH_1):PU_FLASH_SECURITY_STRAP   I134 @S9S_MB_2U_LIB.S9S_MB_2U(SCH_1):PAGE189
    10 FM_FLASH_SECURITY_STRAP @S9S_MB_2U_LIB.S9S_MB_2U(SCH_1):FM_FLASH_SECURITY_STRAP   I134 @S9S_MB_2U_LIB.S9S_MB_2U(SCH_1):PAGE189
    11 PD_ME_RCVR_N @S9S_MB_2U_LIB.S9S_MB_2U(SCH_1):PD_ME_RCVR_N   I134 @S9S_MB_2U_LIB.S9S_MB_2U(SCH_1):PAGE189
    12 FM_ME_RCVR_N @S9S_MB_2U_LIB.S9S_MB_2U(SCH_1):FM_ME_RCVR_N   I134 @S9S_MB_2U_LIB.S9S_MB_2U(SCH_1):PAGE189
    13 PD_PASSWORD_CLEAR @S9S_MB_2U_LIB.S9S_MB_2U(SCH_1):PD_PASSWORD_CLEAR   I134 @S9S_MB_2U_LIB.S9S_MB_2U(SCH_1):PAGE189
    14 FM_PASSWORD_CLEAR_N @S9S_MB_2U_LIB.S9S_MB_2U(SCH_1):FM_PASSWORD_CLEAR_N   I134 @S9S_MB_2U_LIB.S9S_MB_2U(SCH_1):PAGE189

J105 CONN112_10137002101LF-CONN112_A
    A8    GND @S9S_MB_2U_LIB.S9S_MB_2U(SCH_1):GND    I68 @S9S_MB_2U_LIB.S9S_MB_2U(SCH_1):PAGE142
    A7 GPU_3V3IO_RSVD1 @S9S_MB_2U_LIB.S9S_MB_2U(SCH_1):GPU_3V3IO_RSVD1    I68 @S9S_MB_2U_LIB.S9S_MB_2U(SCH_1):PAGE142
    A6    GND @S9S_MB_2U_LIB.S9S_MB_2U(SCH_1):GND    I68 @S9S_MB_2U_LIB.S9S_MB_2U(SCH_1):PAGE142
    A5 GPU_3V3IO_RSVD3 @S9S_MB_2U_LIB.S9S_MB_2U(SCH_1):GPU_3V3IO_RSVD3    I68 @S9S_MB_2U_LIB.S9S_MB_2U(SCH_1):PAGE142
    B8 P5E_CPU0_PE3_RX_DP<0> @S9S_MB_2U_LIB.S9S_MB_2U(SCH_1):P5E_CPU0_PE3_RX_DP(0)    I68 @S9S_MB_2U_LIB.S9S_MB_2U(SCH_1):PAGE142
    B7    GND @S9S_MB_2U_LIB.S9S_MB_2U(SCH_1):GND    I68 @S9S_MB_2U_LIB.S9S_MB_2U(SCH_1):PAGE142
    B6 P5E_CPU0_PE3_RX_DN<2> @S9S_MB_2U_LIB.S9S_MB_2U(SCH_1):P5E_CPU0_PE3_RX_DN(2)    I68 @S9S_MB_2U_LIB.S9S_MB_2U(SCH_1):PAGE142
    B5    GND @S9S_MB_2U_LIB.S9S_MB_2U(SCH_1):GND    I68 @S9S_MB_2U_LIB.S9S_MB_2U(SCH_1):PAGE142
    C8 P5E_CPU0_PE3_RX_DN<0> @S9S_MB_2U_LIB.S9S_MB_2U(SCH_1):P5E_CPU0_PE3_RX_DN(0)    I68 @S9S_MB_2U_LIB.S9S_MB_2U(SCH_1):PAGE142
    C7 P5E_CPU0_PE3_RX_DN<1> @S9S_MB_2U_LIB.S9S_MB_2U(SCH_1):P5E_CPU0_PE3_RX_DN(1)    I68 @S9S_MB_2U_LIB.S9S_MB_2U(SCH_1):PAGE142
    C6 P5E_CPU0_PE3_RX_DP<2> @S9S_MB_2U_LIB.S9S_MB_2U(SCH_1):P5E_CPU0_PE3_RX_DP(2)    I68 @S9S_MB_2U_LIB.S9S_MB_2U(SCH_1):PAGE142
    C5 P5E_CPU0_PE3_RX_DN<3> @S9S_MB_2U_LIB.S9S_MB_2U(SCH_1):P5E_CPU0_PE3_RX_DN(3)    I68 @S9S_MB_2U_LIB.S9S_MB_2U(SCH_1):PAGE142
    D8    GND @S9S_MB_2U_LIB.S9S_MB_2U(SCH_1):GND    I68 @S9S_MB_2U_LIB.S9S_MB_2U(SCH_1):PAGE142
    D7 P5E_CPU0_PE3_RX_DP<1> @S9S_MB_2U_LIB.S9S_MB_2U(SCH_1):P5E_CPU0_PE3_RX_DP(1)    I68 @S9S_MB_2U_LIB.S9S_MB_2U(SCH_1):PAGE142
    D6    GND @S9S_MB_2U_LIB.S9S_MB_2U(SCH_1):GND    I68 @S9S_MB_2U_LIB.S9S_MB_2U(SCH_1):PAGE142
    D5 P5E_CPU0_PE3_RX_DP<3> @S9S_MB_2U_LIB.S9S_MB_2U(SCH_1):P5E_CPU0_PE3_RX_DP(3)    I68 @S9S_MB_2U_LIB.S9S_MB_2U(SCH_1):PAGE142
    E8 P5E_CPU0_PE2_RX_DP<0> @S9S_MB_2U_LIB.S9S_MB_2U(SCH_1):P5E_CPU0_PE2_RX_DP(0)    I68 @S9S_MB_2U_LIB.S9S_MB_2U(SCH_1):PAGE142
    E7    GND @S9S_MB_2U_LIB.S9S_MB_2U(SCH_1):GND    I68 @S9S_MB_2U_LIB.S9S_MB_2U(SCH_1):PAGE142
    E6 P5E_CPU0_PE2_RX_DP<2> @S9S_MB_2U_LIB.S9S_MB_2U(SCH_1):P5E_CPU0_PE2_RX_DP(2)    I68 @S9S_MB_2U_LIB.S9S_MB_2U(SCH_1):PAGE142
    E5    GND @S9S_MB_2U_LIB.S9S_MB_2U(SCH_1):GND    I68 @S9S_MB_2U_LIB.S9S_MB_2U(SCH_1):PAGE142
    F8 P5E_CPU0_PE2_RX_DN<0> @S9S_MB_2U_LIB.S9S_MB_2U(SCH_1):P5E_CPU0_PE2_RX_DN(0)    I68 @S9S_MB_2U_LIB.S9S_MB_2U(SCH_1):PAGE142
    F7 P5E_CPU0_PE2_RX_DP<1> @S9S_MB_2U_LIB.S9S_MB_2U(SCH_1):P5E_CPU0_PE2_RX_DP(1)    I68 @S9S_MB_2U_LIB.S9S_MB_2U(SCH_1):PAGE142
    F6 P5E_CPU0_PE2_RX_DN<2> @S9S_MB_2U_LIB.S9S_MB_2U(SCH_1):P5E_CPU0_PE2_RX_DN(2)    I68 @S9S_MB_2U_LIB.S9S_MB_2U(SCH_1):PAGE142
    F5 P5E_CPU0_PE2_RX_DP<3> @S9S_MB_2U_LIB.S9S_MB_2U(SCH_1):P5E_CPU0_PE2_RX_DP(3)    I68 @S9S_MB_2U_LIB.S9S_MB_2U(SCH_1):PAGE142
    G8    GND @S9S_MB_2U_LIB.S9S_MB_2U(SCH_1):GND    I68 @S9S_MB_2U_LIB.S9S_MB_2U(SCH_1):PAGE142
    G7 P5E_CPU0_PE2_RX_DN<1> @S9S_MB_2U_LIB.S9S_MB_2U(SCH_1):P5E_CPU0_PE2_RX_DN(1)    I68 @S9S_MB_2U_LIB.S9S_MB_2U(SCH_1):PAGE142
    G6    GND @S9S_MB_2U_LIB.S9S_MB_2U(SCH_1):GND    I68 @S9S_MB_2U_LIB.S9S_MB_2U(SCH_1):PAGE142
    G5 P5E_CPU0_PE2_RX_DN<3> @S9S_MB_2U_LIB.S9S_MB_2U(SCH_1):P5E_CPU0_PE2_RX_DN(3)    I68 @S9S_MB_2U_LIB.S9S_MB_2U(SCH_1):PAGE142
    H8 P5E_CPU0_PE3_TX_C_DP<0> @S9S_MB_2U_LIB.S9S_MB_2U(SCH_1):P5E_CPU0_PE3_TX_C_DP(0)    I68 @S9S_MB_2U_LIB.S9S_MB_2U(SCH_1):PAGE142
    H7    GND @S9S_MB_2U_LIB.S9S_MB_2U(SCH_1):GND    I68 @S9S_MB_2U_LIB.S9S_MB_2U(SCH_1):PAGE142
    H6 P5E_CPU0_PE3_TX_C_DN<2> @S9S_MB_2U_LIB.S9S_MB_2U(SCH_1):P5E_CPU0_PE3_TX_C_DN(2)    I68 @S9S_MB_2U_LIB.S9S_MB_2U(SCH_1):PAGE142
    H5    GND @S9S_MB_2U_LIB.S9S_MB_2U(SCH_1):GND    I68 @S9S_MB_2U_LIB.S9S_MB_2U(SCH_1):PAGE142
    I8 P5E_CPU0_PE3_TX_C_DN<0> @S9S_MB_2U_LIB.S9S_MB_2U(SCH_1):P5E_CPU0_PE3_TX_C_DN(0)    I68 @S9S_MB_2U_LIB.S9S_MB_2U(SCH_1):PAGE142
    I7 P5E_CPU0_PE3_TX_C_DN<1> @S9S_MB_2U_LIB.S9S_MB_2U(SCH_1):P5E_CPU0_PE3_TX_C_DN(1)    I68 @S9S_MB_2U_LIB.S9S_MB_2U(SCH_1):PAGE142
    I6 P5E_CPU0_PE3_TX_C_DP<2> @S9S_MB_2U_LIB.S9S_MB_2U(SCH_1):P5E_CPU0_PE3_TX_C_DP(2)    I68 @S9S_MB_2U_LIB.S9S_MB_2U(SCH_1):PAGE142
    I5 P5E_CPU0_PE3_TX_C_DN<3> @S9S_MB_2U_LIB.S9S_MB_2U(SCH_1):P5E_CPU0_PE3_TX_C_DN(3)    I68 @S9S_MB_2U_LIB.S9S_MB_2U(SCH_1):PAGE142
    J8    GND @S9S_MB_2U_LIB.S9S_MB_2U(SCH_1):GND    I68 @S9S_MB_2U_LIB.S9S_MB_2U(SCH_1):PAGE142
    J7 P5E_CPU0_PE3_TX_C_DP<1> @S9S_MB_2U_LIB.S9S_MB_2U(SCH_1):P5E_CPU0_PE3_TX_C_DP(1)    I68 @S9S_MB_2U_LIB.S9S_MB_2U(SCH_1):PAGE142
    J6    GND @S9S_MB_2U_LIB.S9S_MB_2U(SCH_1):GND    I68 @S9S_MB_2U_LIB.S9S_MB_2U(SCH_1):PAGE142
    J5 P5E_CPU0_PE3_TX_C_DP<3> @S9S_MB_2U_LIB.S9S_MB_2U(SCH_1):P5E_CPU0_PE3_TX_C_DP(3)    I68 @S9S_MB_2U_LIB.S9S_MB_2U(SCH_1):PAGE142
    K8 P5E_CPU0_PE2_TX_C_DP<0> @S9S_MB_2U_LIB.S9S_MB_2U(SCH_1):P5E_CPU0_PE2_TX_C_DP(0)    I68 @S9S_MB_2U_LIB.S9S_MB_2U(SCH_1):PAGE142
    K7    GND @S9S_MB_2U_LIB.S9S_MB_2U(SCH_1):GND    I68 @S9S_MB_2U_LIB.S9S_MB_2U(SCH_1):PAGE142
    K6 P5E_CPU0_PE2_TX_C_DP<2> @S9S_MB_2U_LIB.S9S_MB_2U(SCH_1):P5E_CPU0_PE2_TX_C_DP(2)    I68 @S9S_MB_2U_LIB.S9S_MB_2U(SCH_1):PAGE142
    K5    GND @S9S_MB_2U_LIB.S9S_MB_2U(SCH_1):GND    I68 @S9S_MB_2U_LIB.S9S_MB_2U(SCH_1):PAGE142
    L8 P5E_CPU0_PE2_TX_C_DN<0> @S9S_MB_2U_LIB.S9S_MB_2U(SCH_1):P5E_CPU0_PE2_TX_C_DN(0)    I68 @S9S_MB_2U_LIB.S9S_MB_2U(SCH_1):PAGE142
    L7 P5E_CPU0_PE2_TX_C_DP<1> @S9S_MB_2U_LIB.S9S_MB_2U(SCH_1):P5E_CPU0_PE2_TX_C_DP(1)    I68 @S9S_MB_2U_LIB.S9S_MB_2U(SCH_1):PAGE142
    L6 P5E_CPU0_PE2_TX_C_DN<2> @S9S_MB_2U_LIB.S9S_MB_2U(SCH_1):P5E_CPU0_PE2_TX_C_DN(2)    I68 @S9S_MB_2U_LIB.S9S_MB_2U(SCH_1):PAGE142
    L5 P5E_CPU0_PE2_TX_C_DP<3> @S9S_MB_2U_LIB.S9S_MB_2U(SCH_1):P5E_CPU0_PE2_TX_C_DP(3)    I68 @S9S_MB_2U_LIB.S9S_MB_2U(SCH_1):PAGE142
    M5 P5E_CPU0_PE2_TX_C_DN<3> @S9S_MB_2U_LIB.S9S_MB_2U(SCH_1):P5E_CPU0_PE2_TX_C_DN(3)    I68 @S9S_MB_2U_LIB.S9S_MB_2U(SCH_1):PAGE142
    N5    GND @S9S_MB_2U_LIB.S9S_MB_2U(SCH_1):GND    I68 @S9S_MB_2U_LIB.S9S_MB_2U(SCH_1):PAGE142
    M6    GND @S9S_MB_2U_LIB.S9S_MB_2U(SCH_1):GND    I68 @S9S_MB_2U_LIB.S9S_MB_2U(SCH_1):PAGE142
    N6 RST_SWB_BIC_BUF_N @S9S_MB_2U_LIB.S9S_MB_2U(SCH_1):RST_SWB_BIC_BUF_N    I68 @S9S_MB_2U_LIB.S9S_MB_2U(SCH_1):PAGE142
    M7 P5E_CPU0_PE2_TX_C_DN<1> @S9S_MB_2U_LIB.S9S_MB_2U(SCH_1):P5E_CPU0_PE2_TX_C_DN(1)    I68 @S9S_MB_2U_LIB.S9S_MB_2U(SCH_1):PAGE142
    N7    GND @S9S_MB_2U_LIB.S9S_MB_2U(SCH_1):GND    I68 @S9S_MB_2U_LIB.S9S_MB_2U(SCH_1):PAGE142
    M8    GND @S9S_MB_2U_LIB.S9S_MB_2U(SCH_1):GND    I68 @S9S_MB_2U_LIB.S9S_MB_2U(SCH_1):PAGE142
    N8 RST_BMC_FROM_SWB_N @S9S_MB_2U_LIB.S9S_MB_2U(SCH_1):RST_BMC_FROM_SWB_N    I68 @S9S_MB_2U_LIB.S9S_MB_2U(SCH_1):PAGE142
    A4    GND @S9S_MB_2U_LIB.S9S_MB_2U(SCH_1):GND    I65 @S9S_MB_2U_LIB.S9S_MB_2U(SCH_1):PAGE142
    A3 GPU_WP_HW_CTRL_ISO @S9S_MB_2U_LIB.S9S_MB_2U(SCH_1):GPU_WP_HW_CTRL_ISO    I65 @S9S_MB_2U_LIB.S9S_MB_2U(SCH_1):PAGE142
    A2    GND @S9S_MB_2U_LIB.S9S_MB_2U(SCH_1):GND    I65 @S9S_MB_2U_LIB.S9S_MB_2U(SCH_1):PAGE142
    A1 GPU_3V3IO_RSVD4 @S9S_MB_2U_LIB.S9S_MB_2U(SCH_1):GPU_3V3IO_RSVD4    I65 @S9S_MB_2U_LIB.S9S_MB_2U(SCH_1):PAGE142
    B4 P5E_CPU0_PE3_RX_DP<4> @S9S_MB_2U_LIB.S9S_MB_2U(SCH_1):P5E_CPU0_PE3_RX_DP(4)    I65 @S9S_MB_2U_LIB.S9S_MB_2U(SCH_1):PAGE142
    B3    GND @S9S_MB_2U_LIB.S9S_MB_2U(SCH_1):GND    I65 @S9S_MB_2U_LIB.S9S_MB_2U(SCH_1):PAGE142
    B2 P5E_CPU0_PE3_RX_DP<6> @S9S_MB_2U_LIB.S9S_MB_2U(SCH_1):P5E_CPU0_PE3_RX_DP(6)    I65 @S9S_MB_2U_LIB.S9S_MB_2U(SCH_1):PAGE142
    B1    GND @S9S_MB_2U_LIB.S9S_MB_2U(SCH_1):GND    I65 @S9S_MB_2U_LIB.S9S_MB_2U(SCH_1):PAGE142
    C4 P5E_CPU0_PE3_RX_DN<4> @S9S_MB_2U_LIB.S9S_MB_2U(SCH_1):P5E_CPU0_PE3_RX_DN(4)    I65 @S9S_MB_2U_LIB.S9S_MB_2U(SCH_1):PAGE142
    C3 P5E_CPU0_PE3_RX_DP<5> @S9S_MB_2U_LIB.S9S_MB_2U(SCH_1):P5E_CPU0_PE3_RX_DP(5)    I65 @S9S_MB_2U_LIB.S9S_MB_2U(SCH_1):PAGE142
    C2 P5E_CPU0_PE3_RX_DN<6> @S9S_MB_2U_LIB.S9S_MB_2U(SCH_1):P5E_CPU0_PE3_RX_DN(6)    I65 @S9S_MB_2U_LIB.S9S_MB_2U(SCH_1):PAGE142
    C1 P5E_CPU0_PE3_RX_DP<7> @S9S_MB_2U_LIB.S9S_MB_2U(SCH_1):P5E_CPU0_PE3_RX_DP(7)    I65 @S9S_MB_2U_LIB.S9S_MB_2U(SCH_1):PAGE142
    D4    GND @S9S_MB_2U_LIB.S9S_MB_2U(SCH_1):GND    I65 @S9S_MB_2U_LIB.S9S_MB_2U(SCH_1):PAGE142
    D3 P5E_CPU0_PE3_RX_DN<5> @S9S_MB_2U_LIB.S9S_MB_2U(SCH_1):P5E_CPU0_PE3_RX_DN(5)    I65 @S9S_MB_2U_LIB.S9S_MB_2U(SCH_1):PAGE142
    D2    GND @S9S_MB_2U_LIB.S9S_MB_2U(SCH_1):GND    I65 @S9S_MB_2U_LIB.S9S_MB_2U(SCH_1):PAGE142
    D1 P5E_CPU0_PE3_RX_DN<7> @S9S_MB_2U_LIB.S9S_MB_2U(SCH_1):P5E_CPU0_PE3_RX_DN(7)    I65 @S9S_MB_2U_LIB.S9S_MB_2U(SCH_1):PAGE142
    E4 P5E_CPU0_PE2_RX_DP<4> @S9S_MB_2U_LIB.S9S_MB_2U(SCH_1):P5E_CPU0_PE2_RX_DP(4)    I65 @S9S_MB_2U_LIB.S9S_MB_2U(SCH_1):PAGE142
    E3    GND @S9S_MB_2U_LIB.S9S_MB_2U(SCH_1):GND    I65 @S9S_MB_2U_LIB.S9S_MB_2U(SCH_1):PAGE142
    E2 P5E_CPU0_PE2_RX_DP<6> @S9S_MB_2U_LIB.S9S_MB_2U(SCH_1):P5E_CPU0_PE2_RX_DP(6)    I65 @S9S_MB_2U_LIB.S9S_MB_2U(SCH_1):PAGE142
    E1    GND @S9S_MB_2U_LIB.S9S_MB_2U(SCH_1):GND    I65 @S9S_MB_2U_LIB.S9S_MB_2U(SCH_1):PAGE142
    F4 P5E_CPU0_PE2_RX_DN<4> @S9S_MB_2U_LIB.S9S_MB_2U(SCH_1):P5E_CPU0_PE2_RX_DN(4)    I65 @S9S_MB_2U_LIB.S9S_MB_2U(SCH_1):PAGE142
    F3 P5E_CPU0_PE2_RX_DP<5> @S9S_MB_2U_LIB.S9S_MB_2U(SCH_1):P5E_CPU0_PE2_RX_DP(5)    I65 @S9S_MB_2U_LIB.S9S_MB_2U(SCH_1):PAGE142
    F2 P5E_CPU0_PE2_RX_DN<6> @S9S_MB_2U_LIB.S9S_MB_2U(SCH_1):P5E_CPU0_PE2_RX_DN(6)    I65 @S9S_MB_2U_LIB.S9S_MB_2U(SCH_1):PAGE142
    F1 P5E_CPU0_PE2_RX_DP<7> @S9S_MB_2U_LIB.S9S_MB_2U(SCH_1):P5E_CPU0_PE2_RX_DP(7)    I65 @S9S_MB_2U_LIB.S9S_MB_2U(SCH_1):PAGE142
    G4    GND @S9S_MB_2U_LIB.S9S_MB_2U(SCH_1):GND    I65 @S9S_MB_2U_LIB.S9S_MB_2U(SCH_1):PAGE142
    G3 P5E_CPU0_PE2_RX_DN<5> @S9S_MB_2U_LIB.S9S_MB_2U(SCH_1):P5E_CPU0_PE2_RX_DN(5)    I65 @S9S_MB_2U_LIB.S9S_MB_2U(SCH_1):PAGE142
    G2    GND @S9S_MB_2U_LIB.S9S_MB_2U(SCH_1):GND    I65 @S9S_MB_2U_LIB.S9S_MB_2U(SCH_1):PAGE142
    G1 P5E_CPU0_PE2_RX_DN<7> @S9S_MB_2U_LIB.S9S_MB_2U(SCH_1):P5E_CPU0_PE2_RX_DN(7)    I65 @S9S_MB_2U_LIB.S9S_MB_2U(SCH_1):PAGE142
    H4 P5E_CPU0_PE3_TX_C_DN<4> @S9S_MB_2U_LIB.S9S_MB_2U(SCH_1):P5E_CPU0_PE3_TX_C_DN(4)    I65 @S9S_MB_2U_LIB.S9S_MB_2U(SCH_1):PAGE142
    H3    GND @S9S_MB_2U_LIB.S9S_MB_2U(SCH_1):GND    I65 @S9S_MB_2U_LIB.S9S_MB_2U(SCH_1):PAGE142
    H2 P5E_CPU0_PE3_TX_C_DN<6> @S9S_MB_2U_LIB.S9S_MB_2U(SCH_1):P5E_CPU0_PE3_TX_C_DN(6)    I65 @S9S_MB_2U_LIB.S9S_MB_2U(SCH_1):PAGE142
    H1    GND @S9S_MB_2U_LIB.S9S_MB_2U(SCH_1):GND    I65 @S9S_MB_2U_LIB.S9S_MB_2U(SCH_1):PAGE142
    I4 P5E_CPU0_PE3_TX_C_DP<4> @S9S_MB_2U_LIB.S9S_MB_2U(SCH_1):P5E_CPU0_PE3_TX_C_DP(4)    I65 @S9S_MB_2U_LIB.S9S_MB_2U(SCH_1):PAGE142
    I3 P5E_CPU0_PE3_TX_C_DN<5> @S9S_MB_2U_LIB.S9S_MB_2U(SCH_1):P5E_CPU0_PE3_TX_C_DN(5)    I65 @S9S_MB_2U_LIB.S9S_MB_2U(SCH_1):PAGE142
    I2 P5E_CPU0_PE3_TX_C_DP<6> @S9S_MB_2U_LIB.S9S_MB_2U(SCH_1):P5E_CPU0_PE3_TX_C_DP(6)    I65 @S9S_MB_2U_LIB.S9S_MB_2U(SCH_1):PAGE142
    I1 P5E_CPU0_PE3_TX_C_DN<7> @S9S_MB_2U_LIB.S9S_MB_2U(SCH_1):P5E_CPU0_PE3_TX_C_DN(7)    I65 @S9S_MB_2U_LIB.S9S_MB_2U(SCH_1):PAGE142
    J4    GND @S9S_MB_2U_LIB.S9S_MB_2U(SCH_1):GND    I65 @S9S_MB_2U_LIB.S9S_MB_2U(SCH_1):PAGE142
    J3 P5E_CPU0_PE3_TX_C_DP<5> @S9S_MB_2U_LIB.S9S_MB_2U(SCH_1):P5E_CPU0_PE3_TX_C_DP(5)    I65 @S9S_MB_2U_LIB.S9S_MB_2U(SCH_1):PAGE142
    J2    GND @S9S_MB_2U_LIB.S9S_MB_2U(SCH_1):GND    I65 @S9S_MB_2U_LIB.S9S_MB_2U(SCH_1):PAGE142
    J1 P5E_CPU0_PE3_TX_C_DP<7> @S9S_MB_2U_LIB.S9S_MB_2U(SCH_1):P5E_CPU0_PE3_TX_C_DP(7)    I65 @S9S_MB_2U_LIB.S9S_MB_2U(SCH_1):PAGE142
    K4 P5E_CPU0_PE2_TX_C_DP<4> @S9S_MB_2U_LIB.S9S_MB_2U(SCH_1):P5E_CPU0_PE2_TX_C_DP(4)    I65 @S9S_MB_2U_LIB.S9S_MB_2U(SCH_1):PAGE142
    K3    GND @S9S_MB_2U_LIB.S9S_MB_2U(SCH_1):GND    I65 @S9S_MB_2U_LIB.S9S_MB_2U(SCH_1):PAGE142
    K2 P5E_CPU0_PE2_TX_C_DP<6> @S9S_MB_2U_LIB.S9S_MB_2U(SCH_1):P5E_CPU0_PE2_TX_C_DP(6)    I65 @S9S_MB_2U_LIB.S9S_MB_2U(SCH_1):PAGE142
    K1    GND @S9S_MB_2U_LIB.S9S_MB_2U(SCH_1):GND    I65 @S9S_MB_2U_LIB.S9S_MB_2U(SCH_1):PAGE142
    L4 P5E_CPU0_PE2_TX_C_DN<4> @S9S_MB_2U_LIB.S9S_MB_2U(SCH_1):P5E_CPU0_PE2_TX_C_DN(4)    I65 @S9S_MB_2U_LIB.S9S_MB_2U(SCH_1):PAGE142
    L3 P5E_CPU0_PE2_TX_C_DP<5> @S9S_MB_2U_LIB.S9S_MB_2U(SCH_1):P5E_CPU0_PE2_TX_C_DP(5)    I65 @S9S_MB_2U_LIB.S9S_MB_2U(SCH_1):PAGE142
    L2 P5E_CPU0_PE2_TX_C_DN<6> @S9S_MB_2U_LIB.S9S_MB_2U(SCH_1):P5E_CPU0_PE2_TX_C_DN(6)    I65 @S9S_MB_2U_LIB.S9S_MB_2U(SCH_1):PAGE142
    L1 P5E_CPU0_PE2_TX_C_DP<7> @S9S_MB_2U_LIB.S9S_MB_2U(SCH_1):P5E_CPU0_PE2_TX_C_DP(7)    I65 @S9S_MB_2U_LIB.S9S_MB_2U(SCH_1):PAGE142
    M1 P5E_CPU0_PE2_TX_C_DN<7> @S9S_MB_2U_LIB.S9S_MB_2U(SCH_1):P5E_CPU0_PE2_TX_C_DN(7)    I65 @S9S_MB_2U_LIB.S9S_MB_2U(SCH_1):PAGE142
    N1    GND @S9S_MB_2U_LIB.S9S_MB_2U(SCH_1):GND    I65 @S9S_MB_2U_LIB.S9S_MB_2U(SCH_1):PAGE142
    M2    GND @S9S_MB_2U_LIB.S9S_MB_2U(SCH_1):GND    I65 @S9S_MB_2U_LIB.S9S_MB_2U(SCH_1):PAGE142
    N2 FM_SWB_PWR_EN_R_BUF @S9S_MB_2U_LIB.S9S_MB_2U(SCH_1):FM_SWB_PWR_EN_R_BUF    I65 @S9S_MB_2U_LIB.S9S_MB_2U(SCH_1):PAGE142
    M3 P5E_CPU0_PE2_TX_C_DN<5> @S9S_MB_2U_LIB.S9S_MB_2U(SCH_1):P5E_CPU0_PE2_TX_C_DN(5)    I65 @S9S_MB_2U_LIB.S9S_MB_2U(SCH_1):PAGE142
    N3    GND @S9S_MB_2U_LIB.S9S_MB_2U(SCH_1):GND    I65 @S9S_MB_2U_LIB.S9S_MB_2U(SCH_1):PAGE142
    M4    GND @S9S_MB_2U_LIB.S9S_MB_2U(SCH_1):GND    I65 @S9S_MB_2U_LIB.S9S_MB_2U(SCH_1):PAGE142
    N4 FM_SWB_BIC_READY_N @S9S_MB_2U_LIB.S9S_MB_2U(SCH_1):FM_SWB_BIC_READY_N    I65 @S9S_MB_2U_LIB.S9S_MB_2U(SCH_1):PAGE142

J106 CONN112_10137002101LF-CONN112_A
    A8    GND @S9S_MB_2U_LIB.S9S_MB_2U(SCH_1):GND    I68 @S9S_MB_2U_LIB.S9S_MB_2U(SCH_1):PAGE144
    A7 PRSNT_CABLE_GPU_A1_N @S9S_MB_2U_LIB.S9S_MB_2U(SCH_1):PRSNT_CABLE_GPU_A1_N    I68 @S9S_MB_2U_LIB.S9S_MB_2U(SCH_1):PAGE144
    A6    GND @S9S_MB_2U_LIB.S9S_MB_2U(SCH_1):GND    I68 @S9S_MB_2U_LIB.S9S_MB_2U(SCH_1):PAGE144
    A5 NC_J106_A5 @S9S_MB_2U_LIB.S9S_MB_2U(SCH_1):NC_J106_A5    I68 @S9S_MB_2U_LIB.S9S_MB_2U(SCH_1):PAGE144
    B8 P5E_CPU0_PE3_RX_DN<8> @S9S_MB_2U_LIB.S9S_MB_2U(SCH_1):P5E_CPU0_PE3_RX_DN(8)    I68 @S9S_MB_2U_LIB.S9S_MB_2U(SCH_1):PAGE144
    B7    GND @S9S_MB_2U_LIB.S9S_MB_2U(SCH_1):GND    I68 @S9S_MB_2U_LIB.S9S_MB_2U(SCH_1):PAGE144
    B6 P5E_CPU0_PE3_RX_DN<10> @S9S_MB_2U_LIB.S9S_MB_2U(SCH_1):P5E_CPU0_PE3_RX_DN(10)    I68 @S9S_MB_2U_LIB.S9S_MB_2U(SCH_1):PAGE144
    B5    GND @S9S_MB_2U_LIB.S9S_MB_2U(SCH_1):GND    I68 @S9S_MB_2U_LIB.S9S_MB_2U(SCH_1):PAGE144
    C8 P5E_CPU0_PE3_RX_DP<8> @S9S_MB_2U_LIB.S9S_MB_2U(SCH_1):P5E_CPU0_PE3_RX_DP(8)    I68 @S9S_MB_2U_LIB.S9S_MB_2U(SCH_1):PAGE144
    C7 P5E_CPU0_PE3_RX_DN<9> @S9S_MB_2U_LIB.S9S_MB_2U(SCH_1):P5E_CPU0_PE3_RX_DN(9)    I68 @S9S_MB_2U_LIB.S9S_MB_2U(SCH_1):PAGE144
    C6 P5E_CPU0_PE3_RX_DP<10> @S9S_MB_2U_LIB.S9S_MB_2U(SCH_1):P5E_CPU0_PE3_RX_DP(10)    I68 @S9S_MB_2U_LIB.S9S_MB_2U(SCH_1):PAGE144
    C5 P5E_CPU0_PE3_RX_DN<11> @S9S_MB_2U_LIB.S9S_MB_2U(SCH_1):P5E_CPU0_PE3_RX_DN(11)    I68 @S9S_MB_2U_LIB.S9S_MB_2U(SCH_1):PAGE144
    D8    GND @S9S_MB_2U_LIB.S9S_MB_2U(SCH_1):GND    I68 @S9S_MB_2U_LIB.S9S_MB_2U(SCH_1):PAGE144
    D7 P5E_CPU0_PE3_RX_DP<9> @S9S_MB_2U_LIB.S9S_MB_2U(SCH_1):P5E_CPU0_PE3_RX_DP(9)    I68 @S9S_MB_2U_LIB.S9S_MB_2U(SCH_1):PAGE144
    D6    GND @S9S_MB_2U_LIB.S9S_MB_2U(SCH_1):GND    I68 @S9S_MB_2U_LIB.S9S_MB_2U(SCH_1):PAGE144
    D5 P5E_CPU0_PE3_RX_DP<11> @S9S_MB_2U_LIB.S9S_MB_2U(SCH_1):P5E_CPU0_PE3_RX_DP(11)    I68 @S9S_MB_2U_LIB.S9S_MB_2U(SCH_1):PAGE144
    E8 P5E_CPU0_PE2_RX_DP<8> @S9S_MB_2U_LIB.S9S_MB_2U(SCH_1):P5E_CPU0_PE2_RX_DP(8)    I68 @S9S_MB_2U_LIB.S9S_MB_2U(SCH_1):PAGE144
    E7    GND @S9S_MB_2U_LIB.S9S_MB_2U(SCH_1):GND    I68 @S9S_MB_2U_LIB.S9S_MB_2U(SCH_1):PAGE144
    E6 P5E_CPU0_PE2_RX_DP<10> @S9S_MB_2U_LIB.S9S_MB_2U(SCH_1):P5E_CPU0_PE2_RX_DP(10)    I68 @S9S_MB_2U_LIB.S9S_MB_2U(SCH_1):PAGE144
    E5    GND @S9S_MB_2U_LIB.S9S_MB_2U(SCH_1):GND    I68 @S9S_MB_2U_LIB.S9S_MB_2U(SCH_1):PAGE144
    F8 P5E_CPU0_PE2_RX_DN<8> @S9S_MB_2U_LIB.S9S_MB_2U(SCH_1):P5E_CPU0_PE2_RX_DN(8)    I68 @S9S_MB_2U_LIB.S9S_MB_2U(SCH_1):PAGE144
    F7 P5E_CPU0_PE2_RX_DP<9> @S9S_MB_2U_LIB.S9S_MB_2U(SCH_1):P5E_CPU0_PE2_RX_DP(9)    I68 @S9S_MB_2U_LIB.S9S_MB_2U(SCH_1):PAGE144
    F6 P5E_CPU0_PE2_RX_DN<10> @S9S_MB_2U_LIB.S9S_MB_2U(SCH_1):P5E_CPU0_PE2_RX_DN(10)    I68 @S9S_MB_2U_LIB.S9S_MB_2U(SCH_1):PAGE144
    F5 P5E_CPU0_PE2_RX_DP<11> @S9S_MB_2U_LIB.S9S_MB_2U(SCH_1):P5E_CPU0_PE2_RX_DP(11)    I68 @S9S_MB_2U_LIB.S9S_MB_2U(SCH_1):PAGE144
    G8    GND @S9S_MB_2U_LIB.S9S_MB_2U(SCH_1):GND    I68 @S9S_MB_2U_LIB.S9S_MB_2U(SCH_1):PAGE144
    G7 P5E_CPU0_PE2_RX_DN<9> @S9S_MB_2U_LIB.S9S_MB_2U(SCH_1):P5E_CPU0_PE2_RX_DN(9)    I68 @S9S_MB_2U_LIB.S9S_MB_2U(SCH_1):PAGE144
    G6    GND @S9S_MB_2U_LIB.S9S_MB_2U(SCH_1):GND    I68 @S9S_MB_2U_LIB.S9S_MB_2U(SCH_1):PAGE144
    G5 P5E_CPU0_PE2_RX_DN<11> @S9S_MB_2U_LIB.S9S_MB_2U(SCH_1):P5E_CPU0_PE2_RX_DN(11)    I68 @S9S_MB_2U_LIB.S9S_MB_2U(SCH_1):PAGE144
    H8 P5E_CPU0_PE3_TX_C_DN<8> @S9S_MB_2U_LIB.S9S_MB_2U(SCH_1):P5E_CPU0_PE3_TX_C_DN(8)    I68 @S9S_MB_2U_LIB.S9S_MB_2U(SCH_1):PAGE144
    H7    GND @S9S_MB_2U_LIB.S9S_MB_2U(SCH_1):GND    I68 @S9S_MB_2U_LIB.S9S_MB_2U(SCH_1):PAGE144
    H6 P5E_CPU0_PE3_TX_C_DN<10> @S9S_MB_2U_LIB.S9S_MB_2U(SCH_1):P5E_CPU0_PE3_TX_C_DN(10)    I68 @S9S_MB_2U_LIB.S9S_MB_2U(SCH_1):PAGE144
    H5    GND @S9S_MB_2U_LIB.S9S_MB_2U(SCH_1):GND    I68 @S9S_MB_2U_LIB.S9S_MB_2U(SCH_1):PAGE144
    I8 P5E_CPU0_PE3_TX_C_DP<8> @S9S_MB_2U_LIB.S9S_MB_2U(SCH_1):P5E_CPU0_PE3_TX_C_DP(8)    I68 @S9S_MB_2U_LIB.S9S_MB_2U(SCH_1):PAGE144
    I7 P5E_CPU0_PE3_TX_C_DN<9> @S9S_MB_2U_LIB.S9S_MB_2U(SCH_1):P5E_CPU0_PE3_TX_C_DN(9)    I68 @S9S_MB_2U_LIB.S9S_MB_2U(SCH_1):PAGE144
    I6 P5E_CPU0_PE3_TX_C_DP<10> @S9S_MB_2U_LIB.S9S_MB_2U(SCH_1):P5E_CPU0_PE3_TX_C_DP(10)    I68 @S9S_MB_2U_LIB.S9S_MB_2U(SCH_1):PAGE144
    I5 P5E_CPU0_PE3_TX_C_DN<11> @S9S_MB_2U_LIB.S9S_MB_2U(SCH_1):P5E_CPU0_PE3_TX_C_DN(11)    I68 @S9S_MB_2U_LIB.S9S_MB_2U(SCH_1):PAGE144
    J8    GND @S9S_MB_2U_LIB.S9S_MB_2U(SCH_1):GND    I68 @S9S_MB_2U_LIB.S9S_MB_2U(SCH_1):PAGE144
    J7 P5E_CPU0_PE3_TX_C_DP<9> @S9S_MB_2U_LIB.S9S_MB_2U(SCH_1):P5E_CPU0_PE3_TX_C_DP(9)    I68 @S9S_MB_2U_LIB.S9S_MB_2U(SCH_1):PAGE144
    J6    GND @S9S_MB_2U_LIB.S9S_MB_2U(SCH_1):GND    I68 @S9S_MB_2U_LIB.S9S_MB_2U(SCH_1):PAGE144
    J5 P5E_CPU0_PE3_TX_C_DP<11> @S9S_MB_2U_LIB.S9S_MB_2U(SCH_1):P5E_CPU0_PE3_TX_C_DP(11)    I68 @S9S_MB_2U_LIB.S9S_MB_2U(SCH_1):PAGE144
    K8 P5E_CPU0_PE2_TX_C_DP<8> @S9S_MB_2U_LIB.S9S_MB_2U(SCH_1):P5E_CPU0_PE2_TX_C_DP(8)    I68 @S9S_MB_2U_LIB.S9S_MB_2U(SCH_1):PAGE144
    K7    GND @S9S_MB_2U_LIB.S9S_MB_2U(SCH_1):GND    I68 @S9S_MB_2U_LIB.S9S_MB_2U(SCH_1):PAGE144
    K6 P5E_CPU0_PE2_TX_C_DP<10> @S9S_MB_2U_LIB.S9S_MB_2U(SCH_1):P5E_CPU0_PE2_TX_C_DP(10)    I68 @S9S_MB_2U_LIB.S9S_MB_2U(SCH_1):PAGE144
    K5    GND @S9S_MB_2U_LIB.S9S_MB_2U(SCH_1):GND    I68 @S9S_MB_2U_LIB.S9S_MB_2U(SCH_1):PAGE144
    L8 P5E_CPU0_PE2_TX_C_DN<8> @S9S_MB_2U_LIB.S9S_MB_2U(SCH_1):P5E_CPU0_PE2_TX_C_DN(8)    I68 @S9S_MB_2U_LIB.S9S_MB_2U(SCH_1):PAGE144
    L7 P5E_CPU0_PE2_TX_C_DP<9> @S9S_MB_2U_LIB.S9S_MB_2U(SCH_1):P5E_CPU0_PE2_TX_C_DP(9)    I68 @S9S_MB_2U_LIB.S9S_MB_2U(SCH_1):PAGE144
    L6 P5E_CPU0_PE2_TX_C_DN<10> @S9S_MB_2U_LIB.S9S_MB_2U(SCH_1):P5E_CPU0_PE2_TX_C_DN(10)    I68 @S9S_MB_2U_LIB.S9S_MB_2U(SCH_1):PAGE144
    L5 P5E_CPU0_PE2_TX_C_DP<11> @S9S_MB_2U_LIB.S9S_MB_2U(SCH_1):P5E_CPU0_PE2_TX_C_DP(11)    I68 @S9S_MB_2U_LIB.S9S_MB_2U(SCH_1):PAGE144
    M5 P5E_CPU0_PE2_TX_C_DN<11> @S9S_MB_2U_LIB.S9S_MB_2U(SCH_1):P5E_CPU0_PE2_TX_C_DN(11)    I68 @S9S_MB_2U_LIB.S9S_MB_2U(SCH_1):PAGE144
    N5    GND @S9S_MB_2U_LIB.S9S_MB_2U(SCH_1):GND    I68 @S9S_MB_2U_LIB.S9S_MB_2U(SCH_1):PAGE144
    M6    GND @S9S_MB_2U_LIB.S9S_MB_2U(SCH_1):GND    I68 @S9S_MB_2U_LIB.S9S_MB_2U(SCH_1):PAGE144
    N6 UART_BMC_BIC_RX @S9S_MB_2U_LIB.S9S_MB_2U(SCH_1):UART_BMC_BIC_RX    I68 @S9S_MB_2U_LIB.S9S_MB_2U(SCH_1):PAGE144
    M7 P5E_CPU0_PE2_TX_C_DN<9> @S9S_MB_2U_LIB.S9S_MB_2U(SCH_1):P5E_CPU0_PE2_TX_C_DN(9)    I68 @S9S_MB_2U_LIB.S9S_MB_2U(SCH_1):PAGE144
    N7    GND @S9S_MB_2U_LIB.S9S_MB_2U(SCH_1):GND    I68 @S9S_MB_2U_LIB.S9S_MB_2U(SCH_1):PAGE144
    M8    GND @S9S_MB_2U_LIB.S9S_MB_2U(SCH_1):GND    I68 @S9S_MB_2U_LIB.S9S_MB_2U(SCH_1):PAGE144
    N8 UART_BMC_BIC_TX @S9S_MB_2U_LIB.S9S_MB_2U(SCH_1):UART_BMC_BIC_TX    I68 @S9S_MB_2U_LIB.S9S_MB_2U(SCH_1):PAGE144
    A4    GND @S9S_MB_2U_LIB.S9S_MB_2U(SCH_1):GND    I65 @S9S_MB_2U_LIB.S9S_MB_2U(SCH_1):PAGE144
    A3 FM_SWB_PWRGD @S9S_MB_2U_LIB.S9S_MB_2U(SCH_1):FM_SWB_PWRGD    I65 @S9S_MB_2U_LIB.S9S_MB_2U(SCH_1):PAGE144
    A2    GND @S9S_MB_2U_LIB.S9S_MB_2U(SCH_1):GND    I65 @S9S_MB_2U_LIB.S9S_MB_2U(SCH_1):PAGE144
    A1 PRSNT_CABLE_SWB_B1_N @S9S_MB_2U_LIB.S9S_MB_2U(SCH_1):PRSNT_CABLE_SWB_B1_N    I65 @S9S_MB_2U_LIB.S9S_MB_2U(SCH_1):PAGE144
    B4 P5E_CPU0_PE3_RX_DP<12> @S9S_MB_2U_LIB.S9S_MB_2U(SCH_1):P5E_CPU0_PE3_RX_DP(12)    I65 @S9S_MB_2U_LIB.S9S_MB_2U(SCH_1):PAGE144
    B3    GND @S9S_MB_2U_LIB.S9S_MB_2U(SCH_1):GND    I65 @S9S_MB_2U_LIB.S9S_MB_2U(SCH_1):PAGE144
    B2 P5E_CPU0_PE3_RX_DP<14> @S9S_MB_2U_LIB.S9S_MB_2U(SCH_1):P5E_CPU0_PE3_RX_DP(14)    I65 @S9S_MB_2U_LIB.S9S_MB_2U(SCH_1):PAGE144
    B1    GND @S9S_MB_2U_LIB.S9S_MB_2U(SCH_1):GND    I65 @S9S_MB_2U_LIB.S9S_MB_2U(SCH_1):PAGE144
    C4 P5E_CPU0_PE3_RX_DN<12> @S9S_MB_2U_LIB.S9S_MB_2U(SCH_1):P5E_CPU0_PE3_RX_DN(12)    I65 @S9S_MB_2U_LIB.S9S_MB_2U(SCH_1):PAGE144
    C3 P5E_CPU0_PE3_RX_DP<13> @S9S_MB_2U_LIB.S9S_MB_2U(SCH_1):P5E_CPU0_PE3_RX_DP(13)    I65 @S9S_MB_2U_LIB.S9S_MB_2U(SCH_1):PAGE144
    C2 P5E_CPU0_PE3_RX_DN<14> @S9S_MB_2U_LIB.S9S_MB_2U(SCH_1):P5E_CPU0_PE3_RX_DN(14)    I65 @S9S_MB_2U_LIB.S9S_MB_2U(SCH_1):PAGE144
    C1 P5E_CPU0_PE3_RX_DP<15> @S9S_MB_2U_LIB.S9S_MB_2U(SCH_1):P5E_CPU0_PE3_RX_DP(15)    I65 @S9S_MB_2U_LIB.S9S_MB_2U(SCH_1):PAGE144
    D4    GND @S9S_MB_2U_LIB.S9S_MB_2U(SCH_1):GND    I65 @S9S_MB_2U_LIB.S9S_MB_2U(SCH_1):PAGE144
    D3 P5E_CPU0_PE3_RX_DN<13> @S9S_MB_2U_LIB.S9S_MB_2U(SCH_1):P5E_CPU0_PE3_RX_DN(13)    I65 @S9S_MB_2U_LIB.S9S_MB_2U(SCH_1):PAGE144
    D2    GND @S9S_MB_2U_LIB.S9S_MB_2U(SCH_1):GND    I65 @S9S_MB_2U_LIB.S9S_MB_2U(SCH_1):PAGE144
    D1 P5E_CPU0_PE3_RX_DN<15> @S9S_MB_2U_LIB.S9S_MB_2U(SCH_1):P5E_CPU0_PE3_RX_DN(15)    I65 @S9S_MB_2U_LIB.S9S_MB_2U(SCH_1):PAGE144
    E4 P5E_CPU0_PE2_RX_DP<12> @S9S_MB_2U_LIB.S9S_MB_2U(SCH_1):P5E_CPU0_PE2_RX_DP(12)    I65 @S9S_MB_2U_LIB.S9S_MB_2U(SCH_1):PAGE144
    E3    GND @S9S_MB_2U_LIB.S9S_MB_2U(SCH_1):GND    I65 @S9S_MB_2U_LIB.S9S_MB_2U(SCH_1):PAGE144
    E2 P5E_CPU0_PE2_RX_DP<14> @S9S_MB_2U_LIB.S9S_MB_2U(SCH_1):P5E_CPU0_PE2_RX_DP(14)    I65 @S9S_MB_2U_LIB.S9S_MB_2U(SCH_1):PAGE144
    E1    GND @S9S_MB_2U_LIB.S9S_MB_2U(SCH_1):GND    I65 @S9S_MB_2U_LIB.S9S_MB_2U(SCH_1):PAGE144
    F4 P5E_CPU0_PE2_RX_DN<12> @S9S_MB_2U_LIB.S9S_MB_2U(SCH_1):P5E_CPU0_PE2_RX_DN(12)    I65 @S9S_MB_2U_LIB.S9S_MB_2U(SCH_1):PAGE144
    F3 P5E_CPU0_PE2_RX_DP<13> @S9S_MB_2U_LIB.S9S_MB_2U(SCH_1):P5E_CPU0_PE2_RX_DP(13)    I65 @S9S_MB_2U_LIB.S9S_MB_2U(SCH_1):PAGE144
    F2 P5E_CPU0_PE2_RX_DN<14> @S9S_MB_2U_LIB.S9S_MB_2U(SCH_1):P5E_CPU0_PE2_RX_DN(14)    I65 @S9S_MB_2U_LIB.S9S_MB_2U(SCH_1):PAGE144
    F1 P5E_CPU0_PE2_RX_DP<15> @S9S_MB_2U_LIB.S9S_MB_2U(SCH_1):P5E_CPU0_PE2_RX_DP(15)    I65 @S9S_MB_2U_LIB.S9S_MB_2U(SCH_1):PAGE144
    G4    GND @S9S_MB_2U_LIB.S9S_MB_2U(SCH_1):GND    I65 @S9S_MB_2U_LIB.S9S_MB_2U(SCH_1):PAGE144
    G3 P5E_CPU0_PE2_RX_DN<13> @S9S_MB_2U_LIB.S9S_MB_2U(SCH_1):P5E_CPU0_PE2_RX_DN(13)    I65 @S9S_MB_2U_LIB.S9S_MB_2U(SCH_1):PAGE144
    G2    GND @S9S_MB_2U_LIB.S9S_MB_2U(SCH_1):GND    I65 @S9S_MB_2U_LIB.S9S_MB_2U(SCH_1):PAGE144
    G1 P5E_CPU0_PE2_RX_DN<15> @S9S_MB_2U_LIB.S9S_MB_2U(SCH_1):P5E_CPU0_PE2_RX_DN(15)    I65 @S9S_MB_2U_LIB.S9S_MB_2U(SCH_1):PAGE144
    H4 P5E_CPU0_PE3_TX_C_DN<12> @S9S_MB_2U_LIB.S9S_MB_2U(SCH_1):P5E_CPU0_PE3_TX_C_DN(12)    I65 @S9S_MB_2U_LIB.S9S_MB_2U(SCH_1):PAGE144
    H3    GND @S9S_MB_2U_LIB.S9S_MB_2U(SCH_1):GND    I65 @S9S_MB_2U_LIB.S9S_MB_2U(SCH_1):PAGE144
    H2 P5E_CPU0_PE3_TX_C_DN<14> @S9S_MB_2U_LIB.S9S_MB_2U(SCH_1):P5E_CPU0_PE3_TX_C_DN(14)    I65 @S9S_MB_2U_LIB.S9S_MB_2U(SCH_1):PAGE144
    H1    GND @S9S_MB_2U_LIB.S9S_MB_2U(SCH_1):GND    I65 @S9S_MB_2U_LIB.S9S_MB_2U(SCH_1):PAGE144
    I4 P5E_CPU0_PE3_TX_C_DP<12> @S9S_MB_2U_LIB.S9S_MB_2U(SCH_1):P5E_CPU0_PE3_TX_C_DP(12)    I65 @S9S_MB_2U_LIB.S9S_MB_2U(SCH_1):PAGE144
    I3 P5E_CPU0_PE3_TX_C_DN<13> @S9S_MB_2U_LIB.S9S_MB_2U(SCH_1):P5E_CPU0_PE3_TX_C_DN(13)    I65 @S9S_MB_2U_LIB.S9S_MB_2U(SCH_1):PAGE144
    I2 P5E_CPU0_PE3_TX_C_DP<14> @S9S_MB_2U_LIB.S9S_MB_2U(SCH_1):P5E_CPU0_PE3_TX_C_DP(14)    I65 @S9S_MB_2U_LIB.S9S_MB_2U(SCH_1):PAGE144
    I1 P5E_CPU0_PE3_TX_C_DN<15> @S9S_MB_2U_LIB.S9S_MB_2U(SCH_1):P5E_CPU0_PE3_TX_C_DN(15)    I65 @S9S_MB_2U_LIB.S9S_MB_2U(SCH_1):PAGE144
    J4    GND @S9S_MB_2U_LIB.S9S_MB_2U(SCH_1):GND    I65 @S9S_MB_2U_LIB.S9S_MB_2U(SCH_1):PAGE144
    J3 P5E_CPU0_PE3_TX_C_DP<13> @S9S_MB_2U_LIB.S9S_MB_2U(SCH_1):P5E_CPU0_PE3_TX_C_DP(13)    I65 @S9S_MB_2U_LIB.S9S_MB_2U(SCH_1):PAGE144
    J2    GND @S9S_MB_2U_LIB.S9S_MB_2U(SCH_1):GND    I65 @S9S_MB_2U_LIB.S9S_MB_2U(SCH_1):PAGE144
    J1 P5E_CPU0_PE3_TX_C_DP<15> @S9S_MB_2U_LIB.S9S_MB_2U(SCH_1):P5E_CPU0_PE3_TX_C_DP(15)    I65 @S9S_MB_2U_LIB.S9S_MB_2U(SCH_1):PAGE144
    K4 P5E_CPU0_PE2_TX_C_DP<12> @S9S_MB_2U_LIB.S9S_MB_2U(SCH_1):P5E_CPU0_PE2_TX_C_DP(12)    I65 @S9S_MB_2U_LIB.S9S_MB_2U(SCH_1):PAGE144
    K3    GND @S9S_MB_2U_LIB.S9S_MB_2U(SCH_1):GND    I65 @S9S_MB_2U_LIB.S9S_MB_2U(SCH_1):PAGE144
    K2 P5E_CPU0_PE2_TX_C_DP<14> @S9S_MB_2U_LIB.S9S_MB_2U(SCH_1):P5E_CPU0_PE2_TX_C_DP(14)    I65 @S9S_MB_2U_LIB.S9S_MB_2U(SCH_1):PAGE144
    K1    GND @S9S_MB_2U_LIB.S9S_MB_2U(SCH_1):GND    I65 @S9S_MB_2U_LIB.S9S_MB_2U(SCH_1):PAGE144
    L4 P5E_CPU0_PE2_TX_C_DN<12> @S9S_MB_2U_LIB.S9S_MB_2U(SCH_1):P5E_CPU0_PE2_TX_C_DN(12)    I65 @S9S_MB_2U_LIB.S9S_MB_2U(SCH_1):PAGE144
    L3 P5E_CPU0_PE2_TX_C_DP<13> @S9S_MB_2U_LIB.S9S_MB_2U(SCH_1):P5E_CPU0_PE2_TX_C_DP(13)    I65 @S9S_MB_2U_LIB.S9S_MB_2U(SCH_1):PAGE144
    L2 P5E_CPU0_PE2_TX_C_DN<14> @S9S_MB_2U_LIB.S9S_MB_2U(SCH_1):P5E_CPU0_PE2_TX_C_DN(14)    I65 @S9S_MB_2U_LIB.S9S_MB_2U(SCH_1):PAGE144
    L1 P5E_CPU0_PE2_TX_C_DN<15> @S9S_MB_2U_LIB.S9S_MB_2U(SCH_1):P5E_CPU0_PE2_TX_C_DN(15)    I65 @S9S_MB_2U_LIB.S9S_MB_2U(SCH_1):PAGE144
    M1 P5E_CPU0_PE2_TX_C_DP<15> @S9S_MB_2U_LIB.S9S_MB_2U(SCH_1):P5E_CPU0_PE2_TX_C_DP(15)    I65 @S9S_MB_2U_LIB.S9S_MB_2U(SCH_1):PAGE144
    N1    GND @S9S_MB_2U_LIB.S9S_MB_2U(SCH_1):GND    I65 @S9S_MB_2U_LIB.S9S_MB_2U(SCH_1):PAGE144
    M2    GND @S9S_MB_2U_LIB.S9S_MB_2U(SCH_1):GND    I65 @S9S_MB_2U_LIB.S9S_MB_2U(SCH_1):PAGE144
    N2 I3C_BMC_SWB_BUF_SDA @S9S_MB_2U_LIB.S9S_MB_2U(SCH_1):I3C_BMC_SWB_BUF_SDA    I65 @S9S_MB_2U_LIB.S9S_MB_2U(SCH_1):PAGE144
    M3 P5E_CPU0_PE2_TX_C_DN<13> @S9S_MB_2U_LIB.S9S_MB_2U(SCH_1):P5E_CPU0_PE2_TX_C_DN(13)    I65 @S9S_MB_2U_LIB.S9S_MB_2U(SCH_1):PAGE144
    N3    GND @S9S_MB_2U_LIB.S9S_MB_2U(SCH_1):GND    I65 @S9S_MB_2U_LIB.S9S_MB_2U(SCH_1):PAGE144
    M4    GND @S9S_MB_2U_LIB.S9S_MB_2U(SCH_1):GND    I65 @S9S_MB_2U_LIB.S9S_MB_2U(SCH_1):PAGE144
    N4 I3C_BMC_SWB_BUF_SCL @S9S_MB_2U_LIB.S9S_MB_2U(SCH_1):I3C_BMC_SWB_BUF_SCL    I65 @S9S_MB_2U_LIB.S9S_MB_2U(SCH_1):PAGE144

J107 CONN112_10137002101LF-CONN112_A
    A8    GND @S9S_MB_2U_LIB.S9S_MB_2U(SCH_1):GND    I38 @S9S_MB_2U_LIB.S9S_MB_2U(SCH_1):PAGE317
    A7 SWB_HSC_PWRGD @S9S_MB_2U_LIB.S9S_MB_2U(SCH_1):SWB_HSC_PWRGD    I38 @S9S_MB_2U_LIB.S9S_MB_2U(SCH_1):PAGE317
    A6    GND @S9S_MB_2U_LIB.S9S_MB_2U(SCH_1):GND    I38 @S9S_MB_2U_LIB.S9S_MB_2U(SCH_1):PAGE317
    A5 NC_J107_A5 @S9S_MB_2U_LIB.S9S_MB_2U(SCH_1):NC_J107_A5    I38 @S9S_MB_2U_LIB.S9S_MB_2U(SCH_1):PAGE317
    B8 P5E_CPU0_PE0_RX_DN<0> @S9S_MB_2U_LIB.S9S_MB_2U(SCH_1):P5E_CPU0_PE0_RX_DN(0)    I38 @S9S_MB_2U_LIB.S9S_MB_2U(SCH_1):PAGE317
    B7    GND @S9S_MB_2U_LIB.S9S_MB_2U(SCH_1):GND    I38 @S9S_MB_2U_LIB.S9S_MB_2U(SCH_1):PAGE317
    B6 P5E_CPU0_PE0_RX_DN<2> @S9S_MB_2U_LIB.S9S_MB_2U(SCH_1):P5E_CPU0_PE0_RX_DN(2)    I38 @S9S_MB_2U_LIB.S9S_MB_2U(SCH_1):PAGE317
    B5    GND @S9S_MB_2U_LIB.S9S_MB_2U(SCH_1):GND    I38 @S9S_MB_2U_LIB.S9S_MB_2U(SCH_1):PAGE317
    C8 P5E_CPU0_PE0_RX_DP<0> @S9S_MB_2U_LIB.S9S_MB_2U(SCH_1):P5E_CPU0_PE0_RX_DP(0)    I38 @S9S_MB_2U_LIB.S9S_MB_2U(SCH_1):PAGE317
    C7 P5E_CPU0_PE0_RX_DP<1> @S9S_MB_2U_LIB.S9S_MB_2U(SCH_1):P5E_CPU0_PE0_RX_DP(1)    I38 @S9S_MB_2U_LIB.S9S_MB_2U(SCH_1):PAGE317
    C6 P5E_CPU0_PE0_RX_DP<2> @S9S_MB_2U_LIB.S9S_MB_2U(SCH_1):P5E_CPU0_PE0_RX_DP(2)    I38 @S9S_MB_2U_LIB.S9S_MB_2U(SCH_1):PAGE317
    C5 P5E_CPU0_PE0_RX_DP<3> @S9S_MB_2U_LIB.S9S_MB_2U(SCH_1):P5E_CPU0_PE0_RX_DP(3)    I38 @S9S_MB_2U_LIB.S9S_MB_2U(SCH_1):PAGE317
    D8    GND @S9S_MB_2U_LIB.S9S_MB_2U(SCH_1):GND    I38 @S9S_MB_2U_LIB.S9S_MB_2U(SCH_1):PAGE317
    D7 P5E_CPU0_PE0_RX_DN<1> @S9S_MB_2U_LIB.S9S_MB_2U(SCH_1):P5E_CPU0_PE0_RX_DN(1)    I38 @S9S_MB_2U_LIB.S9S_MB_2U(SCH_1):PAGE317
    D6    GND @S9S_MB_2U_LIB.S9S_MB_2U(SCH_1):GND    I38 @S9S_MB_2U_LIB.S9S_MB_2U(SCH_1):PAGE317
    D5 P5E_CPU0_PE0_RX_DN<3> @S9S_MB_2U_LIB.S9S_MB_2U(SCH_1):P5E_CPU0_PE0_RX_DN(3)    I38 @S9S_MB_2U_LIB.S9S_MB_2U(SCH_1):PAGE317
    E8 P5E_CPU0_PE4_RX_DP<15> @S9S_MB_2U_LIB.S9S_MB_2U(SCH_1):P5E_CPU0_PE4_RX_DP(15)    I38 @S9S_MB_2U_LIB.S9S_MB_2U(SCH_1):PAGE317
    E7    GND @S9S_MB_2U_LIB.S9S_MB_2U(SCH_1):GND    I38 @S9S_MB_2U_LIB.S9S_MB_2U(SCH_1):PAGE317
    E6 P5E_CPU0_PE4_RX_DP<13> @S9S_MB_2U_LIB.S9S_MB_2U(SCH_1):P5E_CPU0_PE4_RX_DP(13)    I38 @S9S_MB_2U_LIB.S9S_MB_2U(SCH_1):PAGE317
    E5    GND @S9S_MB_2U_LIB.S9S_MB_2U(SCH_1):GND    I38 @S9S_MB_2U_LIB.S9S_MB_2U(SCH_1):PAGE317
    F8 P5E_CPU0_PE4_RX_DN<15> @S9S_MB_2U_LIB.S9S_MB_2U(SCH_1):P5E_CPU0_PE4_RX_DN(15)    I38 @S9S_MB_2U_LIB.S9S_MB_2U(SCH_1):PAGE317
    F7 P5E_CPU0_PE4_RX_DN<14> @S9S_MB_2U_LIB.S9S_MB_2U(SCH_1):P5E_CPU0_PE4_RX_DN(14)    I38 @S9S_MB_2U_LIB.S9S_MB_2U(SCH_1):PAGE317
    F6 P5E_CPU0_PE4_RX_DN<13> @S9S_MB_2U_LIB.S9S_MB_2U(SCH_1):P5E_CPU0_PE4_RX_DN(13)    I38 @S9S_MB_2U_LIB.S9S_MB_2U(SCH_1):PAGE317
    F5 P5E_CPU0_PE4_RX_DN<12> @S9S_MB_2U_LIB.S9S_MB_2U(SCH_1):P5E_CPU0_PE4_RX_DN(12)    I38 @S9S_MB_2U_LIB.S9S_MB_2U(SCH_1):PAGE317
    G8    GND @S9S_MB_2U_LIB.S9S_MB_2U(SCH_1):GND    I38 @S9S_MB_2U_LIB.S9S_MB_2U(SCH_1):PAGE317
    G7 P5E_CPU0_PE4_RX_DP<14> @S9S_MB_2U_LIB.S9S_MB_2U(SCH_1):P5E_CPU0_PE4_RX_DP(14)    I38 @S9S_MB_2U_LIB.S9S_MB_2U(SCH_1):PAGE317
    G6    GND @S9S_MB_2U_LIB.S9S_MB_2U(SCH_1):GND    I38 @S9S_MB_2U_LIB.S9S_MB_2U(SCH_1):PAGE317
    G5 P5E_CPU0_PE4_RX_DP<12> @S9S_MB_2U_LIB.S9S_MB_2U(SCH_1):P5E_CPU0_PE4_RX_DP(12)    I38 @S9S_MB_2U_LIB.S9S_MB_2U(SCH_1):PAGE317
    H8 P5E_CPU0_PE0_TX_C_DN<0> @S9S_MB_2U_LIB.S9S_MB_2U(SCH_1):P5E_CPU0_PE0_TX_C_DN(0)    I38 @S9S_MB_2U_LIB.S9S_MB_2U(SCH_1):PAGE317
    H7    GND @S9S_MB_2U_LIB.S9S_MB_2U(SCH_1):GND    I38 @S9S_MB_2U_LIB.S9S_MB_2U(SCH_1):PAGE317
    H6 P5E_CPU0_PE0_TX_C_DN<2> @S9S_MB_2U_LIB.S9S_MB_2U(SCH_1):P5E_CPU0_PE0_TX_C_DN(2)    I38 @S9S_MB_2U_LIB.S9S_MB_2U(SCH_1):PAGE317
    H5    GND @S9S_MB_2U_LIB.S9S_MB_2U(SCH_1):GND    I38 @S9S_MB_2U_LIB.S9S_MB_2U(SCH_1):PAGE317
    I8 P5E_CPU0_PE0_TX_C_DP<0> @S9S_MB_2U_LIB.S9S_MB_2U(SCH_1):P5E_CPU0_PE0_TX_C_DP(0)    I38 @S9S_MB_2U_LIB.S9S_MB_2U(SCH_1):PAGE317
    I7 P5E_CPU0_PE0_TX_C_DN<1> @S9S_MB_2U_LIB.S9S_MB_2U(SCH_1):P5E_CPU0_PE0_TX_C_DN(1)    I38 @S9S_MB_2U_LIB.S9S_MB_2U(SCH_1):PAGE317
    I6 P5E_CPU0_PE0_TX_C_DP<2> @S9S_MB_2U_LIB.S9S_MB_2U(SCH_1):P5E_CPU0_PE0_TX_C_DP(2)    I38 @S9S_MB_2U_LIB.S9S_MB_2U(SCH_1):PAGE317
    I5 P5E_CPU0_PE0_TX_C_DN<3> @S9S_MB_2U_LIB.S9S_MB_2U(SCH_1):P5E_CPU0_PE0_TX_C_DN(3)    I38 @S9S_MB_2U_LIB.S9S_MB_2U(SCH_1):PAGE317
    J8    GND @S9S_MB_2U_LIB.S9S_MB_2U(SCH_1):GND    I38 @S9S_MB_2U_LIB.S9S_MB_2U(SCH_1):PAGE317
    J7 P5E_CPU0_PE0_TX_C_DP<1> @S9S_MB_2U_LIB.S9S_MB_2U(SCH_1):P5E_CPU0_PE0_TX_C_DP(1)    I38 @S9S_MB_2U_LIB.S9S_MB_2U(SCH_1):PAGE317
    J6    GND @S9S_MB_2U_LIB.S9S_MB_2U(SCH_1):GND    I38 @S9S_MB_2U_LIB.S9S_MB_2U(SCH_1):PAGE317
    J5 P5E_CPU0_PE0_TX_C_DP<3> @S9S_MB_2U_LIB.S9S_MB_2U(SCH_1):P5E_CPU0_PE0_TX_C_DP(3)    I38 @S9S_MB_2U_LIB.S9S_MB_2U(SCH_1):PAGE317
    K8 P5E_CPU0_PE4_TX_C_DN<15> @S9S_MB_2U_LIB.S9S_MB_2U(SCH_1):P5E_CPU0_PE4_TX_C_DN(15)    I38 @S9S_MB_2U_LIB.S9S_MB_2U(SCH_1):PAGE317
    K7    GND @S9S_MB_2U_LIB.S9S_MB_2U(SCH_1):GND    I38 @S9S_MB_2U_LIB.S9S_MB_2U(SCH_1):PAGE317
    K6 P5E_CPU0_PE4_TX_C_DN<13> @S9S_MB_2U_LIB.S9S_MB_2U(SCH_1):P5E_CPU0_PE4_TX_C_DN(13)    I38 @S9S_MB_2U_LIB.S9S_MB_2U(SCH_1):PAGE317
    K5    GND @S9S_MB_2U_LIB.S9S_MB_2U(SCH_1):GND    I38 @S9S_MB_2U_LIB.S9S_MB_2U(SCH_1):PAGE317
    L8 P5E_CPU0_PE4_TX_C_DP<15> @S9S_MB_2U_LIB.S9S_MB_2U(SCH_1):P5E_CPU0_PE4_TX_C_DP(15)    I38 @S9S_MB_2U_LIB.S9S_MB_2U(SCH_1):PAGE317
    L7 P5E_CPU0_PE4_TX_C_DN<14> @S9S_MB_2U_LIB.S9S_MB_2U(SCH_1):P5E_CPU0_PE4_TX_C_DN(14)    I38 @S9S_MB_2U_LIB.S9S_MB_2U(SCH_1):PAGE317
    L6 P5E_CPU0_PE4_TX_C_DP<13> @S9S_MB_2U_LIB.S9S_MB_2U(SCH_1):P5E_CPU0_PE4_TX_C_DP(13)    I38 @S9S_MB_2U_LIB.S9S_MB_2U(SCH_1):PAGE317
    L5 P5E_CPU0_PE4_TX_C_DN<12> @S9S_MB_2U_LIB.S9S_MB_2U(SCH_1):P5E_CPU0_PE4_TX_C_DN(12)    I38 @S9S_MB_2U_LIB.S9S_MB_2U(SCH_1):PAGE317
    M5 P5E_CPU0_PE4_TX_C_DP<12> @S9S_MB_2U_LIB.S9S_MB_2U(SCH_1):P5E_CPU0_PE4_TX_C_DP(12)    I38 @S9S_MB_2U_LIB.S9S_MB_2U(SCH_1):PAGE317
    N5    GND @S9S_MB_2U_LIB.S9S_MB_2U(SCH_1):GND    I38 @S9S_MB_2U_LIB.S9S_MB_2U(SCH_1):PAGE317
    M6    GND @S9S_MB_2U_LIB.S9S_MB_2U(SCH_1):GND    I38 @S9S_MB_2U_LIB.S9S_MB_2U(SCH_1):PAGE317
    N6 NC_J107_N6 @S9S_MB_2U_LIB.S9S_MB_2U(SCH_1):NC_J107_N6    I38 @S9S_MB_2U_LIB.S9S_MB_2U(SCH_1):PAGE317
    M7 P5E_CPU0_PE4_TX_C_DP<14> @S9S_MB_2U_LIB.S9S_MB_2U(SCH_1):P5E_CPU0_PE4_TX_C_DP(14)    I38 @S9S_MB_2U_LIB.S9S_MB_2U(SCH_1):PAGE317
    N7    GND @S9S_MB_2U_LIB.S9S_MB_2U(SCH_1):GND    I38 @S9S_MB_2U_LIB.S9S_MB_2U(SCH_1):PAGE317
    M8    GND @S9S_MB_2U_LIB.S9S_MB_2U(SCH_1):GND    I38 @S9S_MB_2U_LIB.S9S_MB_2U(SCH_1):PAGE317
    N8 SWB_HSC_EN_BUF @S9S_MB_2U_LIB.S9S_MB_2U(SCH_1):SWB_HSC_EN_BUF    I38 @S9S_MB_2U_LIB.S9S_MB_2U(SCH_1):PAGE317
    A4    GND @S9S_MB_2U_LIB.S9S_MB_2U(SCH_1):GND    I58 @S9S_MB_2U_LIB.S9S_MB_2U(SCH_1):PAGE317
    A3 NC_J107_A3 @S9S_MB_2U_LIB.S9S_MB_2U(SCH_1):NC_J107_A3    I58 @S9S_MB_2U_LIB.S9S_MB_2U(SCH_1):PAGE317
    A2    GND @S9S_MB_2U_LIB.S9S_MB_2U(SCH_1):GND    I58 @S9S_MB_2U_LIB.S9S_MB_2U(SCH_1):PAGE317
    A1 NC_J107_A1 @S9S_MB_2U_LIB.S9S_MB_2U(SCH_1):NC_J107_A1    I58 @S9S_MB_2U_LIB.S9S_MB_2U(SCH_1):PAGE317
    B4 P5E_CPU0_PE0_RX_DN<4> @S9S_MB_2U_LIB.S9S_MB_2U(SCH_1):P5E_CPU0_PE0_RX_DN(4)    I58 @S9S_MB_2U_LIB.S9S_MB_2U(SCH_1):PAGE317
    B3    GND @S9S_MB_2U_LIB.S9S_MB_2U(SCH_1):GND    I58 @S9S_MB_2U_LIB.S9S_MB_2U(SCH_1):PAGE317
    B2 P5E_CPU0_PE0_RX_DN<6> @S9S_MB_2U_LIB.S9S_MB_2U(SCH_1):P5E_CPU0_PE0_RX_DN(6)    I58 @S9S_MB_2U_LIB.S9S_MB_2U(SCH_1):PAGE317
    B1    GND @S9S_MB_2U_LIB.S9S_MB_2U(SCH_1):GND    I58 @S9S_MB_2U_LIB.S9S_MB_2U(SCH_1):PAGE317
    C4 P5E_CPU0_PE0_RX_DP<4> @S9S_MB_2U_LIB.S9S_MB_2U(SCH_1):P5E_CPU0_PE0_RX_DP(4)    I58 @S9S_MB_2U_LIB.S9S_MB_2U(SCH_1):PAGE317
    C3 P5E_CPU0_PE0_RX_DN<5> @S9S_MB_2U_LIB.S9S_MB_2U(SCH_1):P5E_CPU0_PE0_RX_DN(5)    I58 @S9S_MB_2U_LIB.S9S_MB_2U(SCH_1):PAGE317
    C2 P5E_CPU0_PE0_RX_DP<6> @S9S_MB_2U_LIB.S9S_MB_2U(SCH_1):P5E_CPU0_PE0_RX_DP(6)    I58 @S9S_MB_2U_LIB.S9S_MB_2U(SCH_1):PAGE317
    C1 P5E_CPU0_PE0_RX_DN<7> @S9S_MB_2U_LIB.S9S_MB_2U(SCH_1):P5E_CPU0_PE0_RX_DN(7)    I58 @S9S_MB_2U_LIB.S9S_MB_2U(SCH_1):PAGE317
    D4    GND @S9S_MB_2U_LIB.S9S_MB_2U(SCH_1):GND    I58 @S9S_MB_2U_LIB.S9S_MB_2U(SCH_1):PAGE317
    D3 P5E_CPU0_PE0_RX_DP<5> @S9S_MB_2U_LIB.S9S_MB_2U(SCH_1):P5E_CPU0_PE0_RX_DP(5)    I58 @S9S_MB_2U_LIB.S9S_MB_2U(SCH_1):PAGE317
    D2    GND @S9S_MB_2U_LIB.S9S_MB_2U(SCH_1):GND    I58 @S9S_MB_2U_LIB.S9S_MB_2U(SCH_1):PAGE317
    D1 P5E_CPU0_PE0_RX_DP<7> @S9S_MB_2U_LIB.S9S_MB_2U(SCH_1):P5E_CPU0_PE0_RX_DP(7)    I58 @S9S_MB_2U_LIB.S9S_MB_2U(SCH_1):PAGE317
    E4 P5E_CPU0_PE4_RX_DP<11> @S9S_MB_2U_LIB.S9S_MB_2U(SCH_1):P5E_CPU0_PE4_RX_DP(11)    I58 @S9S_MB_2U_LIB.S9S_MB_2U(SCH_1):PAGE317
    E3    GND @S9S_MB_2U_LIB.S9S_MB_2U(SCH_1):GND    I58 @S9S_MB_2U_LIB.S9S_MB_2U(SCH_1):PAGE317
    E2 P5E_CPU0_PE4_RX_DP<9> @S9S_MB_2U_LIB.S9S_MB_2U(SCH_1):P5E_CPU0_PE4_RX_DP(9)    I58 @S9S_MB_2U_LIB.S9S_MB_2U(SCH_1):PAGE317
    E1    GND @S9S_MB_2U_LIB.S9S_MB_2U(SCH_1):GND    I58 @S9S_MB_2U_LIB.S9S_MB_2U(SCH_1):PAGE317
    F4 P5E_CPU0_PE4_RX_DN<11> @S9S_MB_2U_LIB.S9S_MB_2U(SCH_1):P5E_CPU0_PE4_RX_DN(11)    I58 @S9S_MB_2U_LIB.S9S_MB_2U(SCH_1):PAGE317
    F3 P5E_CPU0_PE4_RX_DN<10> @S9S_MB_2U_LIB.S9S_MB_2U(SCH_1):P5E_CPU0_PE4_RX_DN(10)    I58 @S9S_MB_2U_LIB.S9S_MB_2U(SCH_1):PAGE317
    F2 P5E_CPU0_PE4_RX_DN<9> @S9S_MB_2U_LIB.S9S_MB_2U(SCH_1):P5E_CPU0_PE4_RX_DN(9)    I58 @S9S_MB_2U_LIB.S9S_MB_2U(SCH_1):PAGE317
    F1 P5E_CPU0_PE4_RX_DN<8> @S9S_MB_2U_LIB.S9S_MB_2U(SCH_1):P5E_CPU0_PE4_RX_DN(8)    I58 @S9S_MB_2U_LIB.S9S_MB_2U(SCH_1):PAGE317
    G4    GND @S9S_MB_2U_LIB.S9S_MB_2U(SCH_1):GND    I58 @S9S_MB_2U_LIB.S9S_MB_2U(SCH_1):PAGE317
    G3 P5E_CPU0_PE4_RX_DP<10> @S9S_MB_2U_LIB.S9S_MB_2U(SCH_1):P5E_CPU0_PE4_RX_DP(10)    I58 @S9S_MB_2U_LIB.S9S_MB_2U(SCH_1):PAGE317
    G2    GND @S9S_MB_2U_LIB.S9S_MB_2U(SCH_1):GND    I58 @S9S_MB_2U_LIB.S9S_MB_2U(SCH_1):PAGE317
    G1 P5E_CPU0_PE4_RX_DP<8> @S9S_MB_2U_LIB.S9S_MB_2U(SCH_1):P5E_CPU0_PE4_RX_DP(8)    I58 @S9S_MB_2U_LIB.S9S_MB_2U(SCH_1):PAGE317
    H4 P5E_CPU0_PE0_TX_C_DN<4> @S9S_MB_2U_LIB.S9S_MB_2U(SCH_1):P5E_CPU0_PE0_TX_C_DN(4)    I58 @S9S_MB_2U_LIB.S9S_MB_2U(SCH_1):PAGE317
    H3    GND @S9S_MB_2U_LIB.S9S_MB_2U(SCH_1):GND    I58 @S9S_MB_2U_LIB.S9S_MB_2U(SCH_1):PAGE317
    H2 P5E_CPU0_PE0_TX_C_DN<6> @S9S_MB_2U_LIB.S9S_MB_2U(SCH_1):P5E_CPU0_PE0_TX_C_DN(6)    I58 @S9S_MB_2U_LIB.S9S_MB_2U(SCH_1):PAGE317
    H1    GND @S9S_MB_2U_LIB.S9S_MB_2U(SCH_1):GND    I58 @S9S_MB_2U_LIB.S9S_MB_2U(SCH_1):PAGE317
    I4 P5E_CPU0_PE0_TX_C_DP<4> @S9S_MB_2U_LIB.S9S_MB_2U(SCH_1):P5E_CPU0_PE0_TX_C_DP(4)    I58 @S9S_MB_2U_LIB.S9S_MB_2U(SCH_1):PAGE317
    I3 P5E_CPU0_PE0_TX_C_DN<5> @S9S_MB_2U_LIB.S9S_MB_2U(SCH_1):P5E_CPU0_PE0_TX_C_DN(5)    I58 @S9S_MB_2U_LIB.S9S_MB_2U(SCH_1):PAGE317
    I2 P5E_CPU0_PE0_TX_C_DP<6> @S9S_MB_2U_LIB.S9S_MB_2U(SCH_1):P5E_CPU0_PE0_TX_C_DP(6)    I58 @S9S_MB_2U_LIB.S9S_MB_2U(SCH_1):PAGE317
    I1 P5E_CPU0_PE0_TX_C_DN<7> @S9S_MB_2U_LIB.S9S_MB_2U(SCH_1):P5E_CPU0_PE0_TX_C_DN(7)    I58 @S9S_MB_2U_LIB.S9S_MB_2U(SCH_1):PAGE317
    J4    GND @S9S_MB_2U_LIB.S9S_MB_2U(SCH_1):GND    I58 @S9S_MB_2U_LIB.S9S_MB_2U(SCH_1):PAGE317
    J3 P5E_CPU0_PE0_TX_C_DP<5> @S9S_MB_2U_LIB.S9S_MB_2U(SCH_1):P5E_CPU0_PE0_TX_C_DP(5)    I58 @S9S_MB_2U_LIB.S9S_MB_2U(SCH_1):PAGE317
    J2    GND @S9S_MB_2U_LIB.S9S_MB_2U(SCH_1):GND    I58 @S9S_MB_2U_LIB.S9S_MB_2U(SCH_1):PAGE317
    J1 P5E_CPU0_PE0_TX_C_DP<7> @S9S_MB_2U_LIB.S9S_MB_2U(SCH_1):P5E_CPU0_PE0_TX_C_DP(7)    I58 @S9S_MB_2U_LIB.S9S_MB_2U(SCH_1):PAGE317
    K4 P5E_CPU0_PE4_TX_C_DP<11> @S9S_MB_2U_LIB.S9S_MB_2U(SCH_1):P5E_CPU0_PE4_TX_C_DP(11)    I58 @S9S_MB_2U_LIB.S9S_MB_2U(SCH_1):PAGE317
    K3    GND @S9S_MB_2U_LIB.S9S_MB_2U(SCH_1):GND    I58 @S9S_MB_2U_LIB.S9S_MB_2U(SCH_1):PAGE317
    K2 P5E_CPU0_PE4_TX_C_DN<9> @S9S_MB_2U_LIB.S9S_MB_2U(SCH_1):P5E_CPU0_PE4_TX_C_DN(9)    I58 @S9S_MB_2U_LIB.S9S_MB_2U(SCH_1):PAGE317
    K1    GND @S9S_MB_2U_LIB.S9S_MB_2U(SCH_1):GND    I58 @S9S_MB_2U_LIB.S9S_MB_2U(SCH_1):PAGE317
    L4 P5E_CPU0_PE4_TX_C_DN<11> @S9S_MB_2U_LIB.S9S_MB_2U(SCH_1):P5E_CPU0_PE4_TX_C_DN(11)    I58 @S9S_MB_2U_LIB.S9S_MB_2U(SCH_1):PAGE317
    L3 P5E_CPU0_PE4_TX_C_DN<10> @S9S_MB_2U_LIB.S9S_MB_2U(SCH_1):P5E_CPU0_PE4_TX_C_DN(10)    I58 @S9S_MB_2U_LIB.S9S_MB_2U(SCH_1):PAGE317
    L2 P5E_CPU0_PE4_TX_C_DP<9> @S9S_MB_2U_LIB.S9S_MB_2U(SCH_1):P5E_CPU0_PE4_TX_C_DP(9)    I58 @S9S_MB_2U_LIB.S9S_MB_2U(SCH_1):PAGE317
    L1 P5E_CPU0_PE4_TX_C_DN<8> @S9S_MB_2U_LIB.S9S_MB_2U(SCH_1):P5E_CPU0_PE4_TX_C_DN(8)    I58 @S9S_MB_2U_LIB.S9S_MB_2U(SCH_1):PAGE317
    M1 P5E_CPU0_PE4_TX_C_DP<8> @S9S_MB_2U_LIB.S9S_MB_2U(SCH_1):P5E_CPU0_PE4_TX_C_DP(8)    I58 @S9S_MB_2U_LIB.S9S_MB_2U(SCH_1):PAGE317
    N1    GND @S9S_MB_2U_LIB.S9S_MB_2U(SCH_1):GND    I58 @S9S_MB_2U_LIB.S9S_MB_2U(SCH_1):PAGE317
    M2    GND @S9S_MB_2U_LIB.S9S_MB_2U(SCH_1):GND    I58 @S9S_MB_2U_LIB.S9S_MB_2U(SCH_1):PAGE317
    N2 PRSNT_CABLE_SWB_B2_N @S9S_MB_2U_LIB.S9S_MB_2U(SCH_1):PRSNT_CABLE_SWB_B2_N    I58 @S9S_MB_2U_LIB.S9S_MB_2U(SCH_1):PAGE317
    M3 P5E_CPU0_PE4_TX_C_DP<10> @S9S_MB_2U_LIB.S9S_MB_2U(SCH_1):P5E_CPU0_PE4_TX_C_DP(10)    I58 @S9S_MB_2U_LIB.S9S_MB_2U(SCH_1):PAGE317
    N3    GND @S9S_MB_2U_LIB.S9S_MB_2U(SCH_1):GND    I58 @S9S_MB_2U_LIB.S9S_MB_2U(SCH_1):PAGE317
    M4    GND @S9S_MB_2U_LIB.S9S_MB_2U(SCH_1):GND    I58 @S9S_MB_2U_LIB.S9S_MB_2U(SCH_1):PAGE317
    N4 NC_J107_N4 @S9S_MB_2U_LIB.S9S_MB_2U(SCH_1):NC_J107_N4    I58 @S9S_MB_2U_LIB.S9S_MB_2U(SCH_1):PAGE317

J108 CONN112_10137002101LF-CONN112_A
    A8    GND @S9S_MB_2U_LIB.S9S_MB_2U(SCH_1):GND    I76 @S9S_MB_2U_LIB.S9S_MB_2U(SCH_1):PAGE320
    A7 GPU_FPGA_OVERT_N @S9S_MB_2U_LIB.S9S_MB_2U(SCH_1):GPU_FPGA_OVERT_N    I76 @S9S_MB_2U_LIB.S9S_MB_2U(SCH_1):PAGE320
    A6    GND @S9S_MB_2U_LIB.S9S_MB_2U(SCH_1):GND    I76 @S9S_MB_2U_LIB.S9S_MB_2U(SCH_1):PAGE320
    A5 GPU_3V3IO_RSVD5_FFU @S9S_MB_2U_LIB.S9S_MB_2U(SCH_1):GPU_3V3IO_RSVD5_FFU    I76 @S9S_MB_2U_LIB.S9S_MB_2U(SCH_1):PAGE320
    B8 P5E_CPU0_PE0_RX_DN<8> @S9S_MB_2U_LIB.S9S_MB_2U(SCH_1):P5E_CPU0_PE0_RX_DN(8)    I76 @S9S_MB_2U_LIB.S9S_MB_2U(SCH_1):PAGE320
    B7    GND @S9S_MB_2U_LIB.S9S_MB_2U(SCH_1):GND    I76 @S9S_MB_2U_LIB.S9S_MB_2U(SCH_1):PAGE320
    B6 P5E_CPU0_PE0_RX_DN<10> @S9S_MB_2U_LIB.S9S_MB_2U(SCH_1):P5E_CPU0_PE0_RX_DN(10)    I76 @S9S_MB_2U_LIB.S9S_MB_2U(SCH_1):PAGE320
    B5    GND @S9S_MB_2U_LIB.S9S_MB_2U(SCH_1):GND    I76 @S9S_MB_2U_LIB.S9S_MB_2U(SCH_1):PAGE320
    C8 P5E_CPU0_PE0_RX_DP<8> @S9S_MB_2U_LIB.S9S_MB_2U(SCH_1):P5E_CPU0_PE0_RX_DP(8)    I76 @S9S_MB_2U_LIB.S9S_MB_2U(SCH_1):PAGE320
    C7 P5E_CPU0_PE0_RX_DN<9> @S9S_MB_2U_LIB.S9S_MB_2U(SCH_1):P5E_CPU0_PE0_RX_DN(9)    I76 @S9S_MB_2U_LIB.S9S_MB_2U(SCH_1):PAGE320
    C6 P5E_CPU0_PE0_RX_DP<10> @S9S_MB_2U_LIB.S9S_MB_2U(SCH_1):P5E_CPU0_PE0_RX_DP(10)    I76 @S9S_MB_2U_LIB.S9S_MB_2U(SCH_1):PAGE320
    C5 P5E_CPU0_PE0_RX_DP<11> @S9S_MB_2U_LIB.S9S_MB_2U(SCH_1):P5E_CPU0_PE0_RX_DP(11)    I76 @S9S_MB_2U_LIB.S9S_MB_2U(SCH_1):PAGE320
    D8    GND @S9S_MB_2U_LIB.S9S_MB_2U(SCH_1):GND    I76 @S9S_MB_2U_LIB.S9S_MB_2U(SCH_1):PAGE320
    D7 P5E_CPU0_PE0_RX_DP<9> @S9S_MB_2U_LIB.S9S_MB_2U(SCH_1):P5E_CPU0_PE0_RX_DP(9)    I76 @S9S_MB_2U_LIB.S9S_MB_2U(SCH_1):PAGE320
    D6    GND @S9S_MB_2U_LIB.S9S_MB_2U(SCH_1):GND    I76 @S9S_MB_2U_LIB.S9S_MB_2U(SCH_1):PAGE320
    D5 P5E_CPU0_PE0_RX_DN<11> @S9S_MB_2U_LIB.S9S_MB_2U(SCH_1):P5E_CPU0_PE0_RX_DN(11)    I76 @S9S_MB_2U_LIB.S9S_MB_2U(SCH_1):PAGE320
    E8 P5E_CPU0_PE4_RX_DP<7> @S9S_MB_2U_LIB.S9S_MB_2U(SCH_1):P5E_CPU0_PE4_RX_DP(7)    I76 @S9S_MB_2U_LIB.S9S_MB_2U(SCH_1):PAGE320
    E7    GND @S9S_MB_2U_LIB.S9S_MB_2U(SCH_1):GND    I76 @S9S_MB_2U_LIB.S9S_MB_2U(SCH_1):PAGE320
    E6 P5E_CPU0_PE4_RX_DP<5> @S9S_MB_2U_LIB.S9S_MB_2U(SCH_1):P5E_CPU0_PE4_RX_DP(5)    I76 @S9S_MB_2U_LIB.S9S_MB_2U(SCH_1):PAGE320
    E5    GND @S9S_MB_2U_LIB.S9S_MB_2U(SCH_1):GND    I76 @S9S_MB_2U_LIB.S9S_MB_2U(SCH_1):PAGE320
    F8 P5E_CPU0_PE4_RX_DN<7> @S9S_MB_2U_LIB.S9S_MB_2U(SCH_1):P5E_CPU0_PE4_RX_DN(7)    I76 @S9S_MB_2U_LIB.S9S_MB_2U(SCH_1):PAGE320
    F7 P5E_CPU0_PE4_RX_DN<6> @S9S_MB_2U_LIB.S9S_MB_2U(SCH_1):P5E_CPU0_PE4_RX_DN(6)    I76 @S9S_MB_2U_LIB.S9S_MB_2U(SCH_1):PAGE320
    F6 P5E_CPU0_PE4_RX_DN<5> @S9S_MB_2U_LIB.S9S_MB_2U(SCH_1):P5E_CPU0_PE4_RX_DN(5)    I76 @S9S_MB_2U_LIB.S9S_MB_2U(SCH_1):PAGE320
    F5 P5E_CPU0_PE4_RX_DN<4> @S9S_MB_2U_LIB.S9S_MB_2U(SCH_1):P5E_CPU0_PE4_RX_DN(4)    I76 @S9S_MB_2U_LIB.S9S_MB_2U(SCH_1):PAGE320
    G8    GND @S9S_MB_2U_LIB.S9S_MB_2U(SCH_1):GND    I76 @S9S_MB_2U_LIB.S9S_MB_2U(SCH_1):PAGE320
    G7 P5E_CPU0_PE4_RX_DP<6> @S9S_MB_2U_LIB.S9S_MB_2U(SCH_1):P5E_CPU0_PE4_RX_DP(6)    I76 @S9S_MB_2U_LIB.S9S_MB_2U(SCH_1):PAGE320
    G6    GND @S9S_MB_2U_LIB.S9S_MB_2U(SCH_1):GND    I76 @S9S_MB_2U_LIB.S9S_MB_2U(SCH_1):PAGE320
    G5 P5E_CPU0_PE4_RX_DP<4> @S9S_MB_2U_LIB.S9S_MB_2U(SCH_1):P5E_CPU0_PE4_RX_DP(4)    I76 @S9S_MB_2U_LIB.S9S_MB_2U(SCH_1):PAGE320
    H8 P5E_CPU0_PE0_TX_C_DN<8> @S9S_MB_2U_LIB.S9S_MB_2U(SCH_1):P5E_CPU0_PE0_TX_C_DN(8)    I76 @S9S_MB_2U_LIB.S9S_MB_2U(SCH_1):PAGE320
    H7    GND @S9S_MB_2U_LIB.S9S_MB_2U(SCH_1):GND    I76 @S9S_MB_2U_LIB.S9S_MB_2U(SCH_1):PAGE320
    H6 P5E_CPU0_PE0_TX_C_DN<10> @S9S_MB_2U_LIB.S9S_MB_2U(SCH_1):P5E_CPU0_PE0_TX_C_DN(10)    I76 @S9S_MB_2U_LIB.S9S_MB_2U(SCH_1):PAGE320
    H5    GND @S9S_MB_2U_LIB.S9S_MB_2U(SCH_1):GND    I76 @S9S_MB_2U_LIB.S9S_MB_2U(SCH_1):PAGE320
    I8 P5E_CPU0_PE0_TX_C_DP<8> @S9S_MB_2U_LIB.S9S_MB_2U(SCH_1):P5E_CPU0_PE0_TX_C_DP(8)    I76 @S9S_MB_2U_LIB.S9S_MB_2U(SCH_1):PAGE320
    I7 P5E_CPU0_PE0_TX_C_DN<9> @S9S_MB_2U_LIB.S9S_MB_2U(SCH_1):P5E_CPU0_PE0_TX_C_DN(9)    I76 @S9S_MB_2U_LIB.S9S_MB_2U(SCH_1):PAGE320
    I6 P5E_CPU0_PE0_TX_C_DP<10> @S9S_MB_2U_LIB.S9S_MB_2U(SCH_1):P5E_CPU0_PE0_TX_C_DP(10)    I76 @S9S_MB_2U_LIB.S9S_MB_2U(SCH_1):PAGE320
    I5 P5E_CPU0_PE0_TX_C_DN<11> @S9S_MB_2U_LIB.S9S_MB_2U(SCH_1):P5E_CPU0_PE0_TX_C_DN(11)    I76 @S9S_MB_2U_LIB.S9S_MB_2U(SCH_1):PAGE320
    J8    GND @S9S_MB_2U_LIB.S9S_MB_2U(SCH_1):GND    I76 @S9S_MB_2U_LIB.S9S_MB_2U(SCH_1):PAGE320
    J7 P5E_CPU0_PE0_TX_C_DP<9> @S9S_MB_2U_LIB.S9S_MB_2U(SCH_1):P5E_CPU0_PE0_TX_C_DP(9)    I76 @S9S_MB_2U_LIB.S9S_MB_2U(SCH_1):PAGE320
    J6    GND @S9S_MB_2U_LIB.S9S_MB_2U(SCH_1):GND    I76 @S9S_MB_2U_LIB.S9S_MB_2U(SCH_1):PAGE320
    J5 P5E_CPU0_PE0_TX_C_DP<11> @S9S_MB_2U_LIB.S9S_MB_2U(SCH_1):P5E_CPU0_PE0_TX_C_DP(11)    I76 @S9S_MB_2U_LIB.S9S_MB_2U(SCH_1):PAGE320
    K8 P5E_CPU0_PE4_TX_C_DN<7> @S9S_MB_2U_LIB.S9S_MB_2U(SCH_1):P5E_CPU0_PE4_TX_C_DN(7)    I76 @S9S_MB_2U_LIB.S9S_MB_2U(SCH_1):PAGE320
    K7    GND @S9S_MB_2U_LIB.S9S_MB_2U(SCH_1):GND    I76 @S9S_MB_2U_LIB.S9S_MB_2U(SCH_1):PAGE320
    K6 P5E_CPU0_PE4_TX_C_DN<5> @S9S_MB_2U_LIB.S9S_MB_2U(SCH_1):P5E_CPU0_PE4_TX_C_DN(5)    I76 @S9S_MB_2U_LIB.S9S_MB_2U(SCH_1):PAGE320
    K5    GND @S9S_MB_2U_LIB.S9S_MB_2U(SCH_1):GND    I76 @S9S_MB_2U_LIB.S9S_MB_2U(SCH_1):PAGE320
    L8 P5E_CPU0_PE4_TX_C_DP<7> @S9S_MB_2U_LIB.S9S_MB_2U(SCH_1):P5E_CPU0_PE4_TX_C_DP(7)    I76 @S9S_MB_2U_LIB.S9S_MB_2U(SCH_1):PAGE320
    L7 P5E_CPU0_PE4_TX_C_DN<6> @S9S_MB_2U_LIB.S9S_MB_2U(SCH_1):P5E_CPU0_PE4_TX_C_DN(6)    I76 @S9S_MB_2U_LIB.S9S_MB_2U(SCH_1):PAGE320
    L6 P5E_CPU0_PE4_TX_C_DP<5> @S9S_MB_2U_LIB.S9S_MB_2U(SCH_1):P5E_CPU0_PE4_TX_C_DP(5)    I76 @S9S_MB_2U_LIB.S9S_MB_2U(SCH_1):PAGE320
    L5 P5E_CPU0_PE4_TX_C_DN<4> @S9S_MB_2U_LIB.S9S_MB_2U(SCH_1):P5E_CPU0_PE4_TX_C_DN(4)    I76 @S9S_MB_2U_LIB.S9S_MB_2U(SCH_1):PAGE320
    M5 P5E_CPU0_PE4_TX_C_DP<4> @S9S_MB_2U_LIB.S9S_MB_2U(SCH_1):P5E_CPU0_PE4_TX_C_DP(4)    I76 @S9S_MB_2U_LIB.S9S_MB_2U(SCH_1):PAGE320
    N5    GND @S9S_MB_2U_LIB.S9S_MB_2U(SCH_1):GND    I76 @S9S_MB_2U_LIB.S9S_MB_2U(SCH_1):PAGE320
    M6    GND @S9S_MB_2U_LIB.S9S_MB_2U(SCH_1):GND    I76 @S9S_MB_2U_LIB.S9S_MB_2U(SCH_1):PAGE320
    N6 NC_J108_N6 @S9S_MB_2U_LIB.S9S_MB_2U(SCH_1):NC_J108_N6    I76 @S9S_MB_2U_LIB.S9S_MB_2U(SCH_1):PAGE320
    M7 P5E_CPU0_PE4_TX_C_DP<6> @S9S_MB_2U_LIB.S9S_MB_2U(SCH_1):P5E_CPU0_PE4_TX_C_DP(6)    I76 @S9S_MB_2U_LIB.S9S_MB_2U(SCH_1):PAGE320
    N7    GND @S9S_MB_2U_LIB.S9S_MB_2U(SCH_1):GND    I76 @S9S_MB_2U_LIB.S9S_MB_2U(SCH_1):PAGE320
    M8    GND @S9S_MB_2U_LIB.S9S_MB_2U(SCH_1):GND    I76 @S9S_MB_2U_LIB.S9S_MB_2U(SCH_1):PAGE320
    N8 PRSNT_CABLE_GPU_A3_N @S9S_MB_2U_LIB.S9S_MB_2U(SCH_1):PRSNT_CABLE_GPU_A3_N    I76 @S9S_MB_2U_LIB.S9S_MB_2U(SCH_1):PAGE320
    A4    GND @S9S_MB_2U_LIB.S9S_MB_2U(SCH_1):GND    I57 @S9S_MB_2U_LIB.S9S_MB_2U(SCH_1):PAGE320
    A3 PRSNT_CABLE_GPU_A2_N @S9S_MB_2U_LIB.S9S_MB_2U(SCH_1):PRSNT_CABLE_GPU_A2_N    I57 @S9S_MB_2U_LIB.S9S_MB_2U(SCH_1):PAGE320
    A2    GND @S9S_MB_2U_LIB.S9S_MB_2U(SCH_1):GND    I57 @S9S_MB_2U_LIB.S9S_MB_2U(SCH_1):PAGE320
    A1 GPU_3V3IO_RSVD3_FFU @S9S_MB_2U_LIB.S9S_MB_2U(SCH_1):GPU_3V3IO_RSVD3_FFU    I57 @S9S_MB_2U_LIB.S9S_MB_2U(SCH_1):PAGE320
    B4 P5E_CPU0_PE0_RX_DN<12> @S9S_MB_2U_LIB.S9S_MB_2U(SCH_1):P5E_CPU0_PE0_RX_DN(12)    I57 @S9S_MB_2U_LIB.S9S_MB_2U(SCH_1):PAGE320
    B3    GND @S9S_MB_2U_LIB.S9S_MB_2U(SCH_1):GND    I57 @S9S_MB_2U_LIB.S9S_MB_2U(SCH_1):PAGE320
    B2 P5E_CPU0_PE0_RX_DN<14> @S9S_MB_2U_LIB.S9S_MB_2U(SCH_1):P5E_CPU0_PE0_RX_DN(14)    I57 @S9S_MB_2U_LIB.S9S_MB_2U(SCH_1):PAGE320
    B1    GND @S9S_MB_2U_LIB.S9S_MB_2U(SCH_1):GND    I57 @S9S_MB_2U_LIB.S9S_MB_2U(SCH_1):PAGE320
    C4 P5E_CPU0_PE0_RX_DP<12> @S9S_MB_2U_LIB.S9S_MB_2U(SCH_1):P5E_CPU0_PE0_RX_DP(12)    I57 @S9S_MB_2U_LIB.S9S_MB_2U(SCH_1):PAGE320
    C3 P5E_CPU0_PE0_RX_DN<13> @S9S_MB_2U_LIB.S9S_MB_2U(SCH_1):P5E_CPU0_PE0_RX_DN(13)    I57 @S9S_MB_2U_LIB.S9S_MB_2U(SCH_1):PAGE320
    C2 P5E_CPU0_PE0_RX_DP<14> @S9S_MB_2U_LIB.S9S_MB_2U(SCH_1):P5E_CPU0_PE0_RX_DP(14)    I57 @S9S_MB_2U_LIB.S9S_MB_2U(SCH_1):PAGE320
    C1 P5E_CPU0_PE0_RX_DN<15> @S9S_MB_2U_LIB.S9S_MB_2U(SCH_1):P5E_CPU0_PE0_RX_DN(15)    I57 @S9S_MB_2U_LIB.S9S_MB_2U(SCH_1):PAGE320
    D4    GND @S9S_MB_2U_LIB.S9S_MB_2U(SCH_1):GND    I57 @S9S_MB_2U_LIB.S9S_MB_2U(SCH_1):PAGE320
    D3 P5E_CPU0_PE0_RX_DP<13> @S9S_MB_2U_LIB.S9S_MB_2U(SCH_1):P5E_CPU0_PE0_RX_DP(13)    I57 @S9S_MB_2U_LIB.S9S_MB_2U(SCH_1):PAGE320
    D2    GND @S9S_MB_2U_LIB.S9S_MB_2U(SCH_1):GND    I57 @S9S_MB_2U_LIB.S9S_MB_2U(SCH_1):PAGE320
    D1 P5E_CPU0_PE0_RX_DP<15> @S9S_MB_2U_LIB.S9S_MB_2U(SCH_1):P5E_CPU0_PE0_RX_DP(15)    I57 @S9S_MB_2U_LIB.S9S_MB_2U(SCH_1):PAGE320
    E4 P5E_CPU0_PE4_RX_DP<3> @S9S_MB_2U_LIB.S9S_MB_2U(SCH_1):P5E_CPU0_PE4_RX_DP(3)    I57 @S9S_MB_2U_LIB.S9S_MB_2U(SCH_1):PAGE320
    E3    GND @S9S_MB_2U_LIB.S9S_MB_2U(SCH_1):GND    I57 @S9S_MB_2U_LIB.S9S_MB_2U(SCH_1):PAGE320
    E2 P5E_CPU0_PE4_RX_DP<1> @S9S_MB_2U_LIB.S9S_MB_2U(SCH_1):P5E_CPU0_PE4_RX_DP(1)    I57 @S9S_MB_2U_LIB.S9S_MB_2U(SCH_1):PAGE320
    E1    GND @S9S_MB_2U_LIB.S9S_MB_2U(SCH_1):GND    I57 @S9S_MB_2U_LIB.S9S_MB_2U(SCH_1):PAGE320
    F4 P5E_CPU0_PE4_RX_DN<3> @S9S_MB_2U_LIB.S9S_MB_2U(SCH_1):P5E_CPU0_PE4_RX_DN(3)    I57 @S9S_MB_2U_LIB.S9S_MB_2U(SCH_1):PAGE320
    F3 P5E_CPU0_PE4_RX_DN<2> @S9S_MB_2U_LIB.S9S_MB_2U(SCH_1):P5E_CPU0_PE4_RX_DN(2)    I57 @S9S_MB_2U_LIB.S9S_MB_2U(SCH_1):PAGE320
    F2 P5E_CPU0_PE4_RX_DN<1> @S9S_MB_2U_LIB.S9S_MB_2U(SCH_1):P5E_CPU0_PE4_RX_DN(1)    I57 @S9S_MB_2U_LIB.S9S_MB_2U(SCH_1):PAGE320
    F1 P5E_CPU0_PE4_RX_DN<0> @S9S_MB_2U_LIB.S9S_MB_2U(SCH_1):P5E_CPU0_PE4_RX_DN(0)    I57 @S9S_MB_2U_LIB.S9S_MB_2U(SCH_1):PAGE320
    G4    GND @S9S_MB_2U_LIB.S9S_MB_2U(SCH_1):GND    I57 @S9S_MB_2U_LIB.S9S_MB_2U(SCH_1):PAGE320
    G3 P5E_CPU0_PE4_RX_DP<2> @S9S_MB_2U_LIB.S9S_MB_2U(SCH_1):P5E_CPU0_PE4_RX_DP(2)    I57 @S9S_MB_2U_LIB.S9S_MB_2U(SCH_1):PAGE320
    G2    GND @S9S_MB_2U_LIB.S9S_MB_2U(SCH_1):GND    I57 @S9S_MB_2U_LIB.S9S_MB_2U(SCH_1):PAGE320
    G1 P5E_CPU0_PE4_RX_DP<0> @S9S_MB_2U_LIB.S9S_MB_2U(SCH_1):P5E_CPU0_PE4_RX_DP(0)    I57 @S9S_MB_2U_LIB.S9S_MB_2U(SCH_1):PAGE320
    H4 P5E_CPU0_PE0_TX_C_DN<12> @S9S_MB_2U_LIB.S9S_MB_2U(SCH_1):P5E_CPU0_PE0_TX_C_DN(12)    I57 @S9S_MB_2U_LIB.S9S_MB_2U(SCH_1):PAGE320
    H3    GND @S9S_MB_2U_LIB.S9S_MB_2U(SCH_1):GND    I57 @S9S_MB_2U_LIB.S9S_MB_2U(SCH_1):PAGE320
    H2 P5E_CPU0_PE0_TX_C_DN<14> @S9S_MB_2U_LIB.S9S_MB_2U(SCH_1):P5E_CPU0_PE0_TX_C_DN(14)    I57 @S9S_MB_2U_LIB.S9S_MB_2U(SCH_1):PAGE320
    H1    GND @S9S_MB_2U_LIB.S9S_MB_2U(SCH_1):GND    I57 @S9S_MB_2U_LIB.S9S_MB_2U(SCH_1):PAGE320
    I4 P5E_CPU0_PE0_TX_C_DP<12> @S9S_MB_2U_LIB.S9S_MB_2U(SCH_1):P5E_CPU0_PE0_TX_C_DP(12)    I57 @S9S_MB_2U_LIB.S9S_MB_2U(SCH_1):PAGE320
    I3 P5E_CPU0_PE0_TX_C_DN<13> @S9S_MB_2U_LIB.S9S_MB_2U(SCH_1):P5E_CPU0_PE0_TX_C_DN(13)    I57 @S9S_MB_2U_LIB.S9S_MB_2U(SCH_1):PAGE320
    I2 P5E_CPU0_PE0_TX_C_DP<14> @S9S_MB_2U_LIB.S9S_MB_2U(SCH_1):P5E_CPU0_PE0_TX_C_DP(14)    I57 @S9S_MB_2U_LIB.S9S_MB_2U(SCH_1):PAGE320
    I1 P5E_CPU0_PE0_TX_C_DN<15> @S9S_MB_2U_LIB.S9S_MB_2U(SCH_1):P5E_CPU0_PE0_TX_C_DN(15)    I57 @S9S_MB_2U_LIB.S9S_MB_2U(SCH_1):PAGE320
    J4    GND @S9S_MB_2U_LIB.S9S_MB_2U(SCH_1):GND    I57 @S9S_MB_2U_LIB.S9S_MB_2U(SCH_1):PAGE320
    J3 P5E_CPU0_PE0_TX_C_DP<13> @S9S_MB_2U_LIB.S9S_MB_2U(SCH_1):P5E_CPU0_PE0_TX_C_DP(13)    I57 @S9S_MB_2U_LIB.S9S_MB_2U(SCH_1):PAGE320
    J2    GND @S9S_MB_2U_LIB.S9S_MB_2U(SCH_1):GND    I57 @S9S_MB_2U_LIB.S9S_MB_2U(SCH_1):PAGE320
    J1 P5E_CPU0_PE0_TX_C_DP<15> @S9S_MB_2U_LIB.S9S_MB_2U(SCH_1):P5E_CPU0_PE0_TX_C_DP(15)    I57 @S9S_MB_2U_LIB.S9S_MB_2U(SCH_1):PAGE320
    K4 P5E_CPU0_PE4_TX_C_DN<3> @S9S_MB_2U_LIB.S9S_MB_2U(SCH_1):P5E_CPU0_PE4_TX_C_DN(3)    I57 @S9S_MB_2U_LIB.S9S_MB_2U(SCH_1):PAGE320
    K3    GND @S9S_MB_2U_LIB.S9S_MB_2U(SCH_1):GND    I57 @S9S_MB_2U_LIB.S9S_MB_2U(SCH_1):PAGE320
    K2 P5E_CPU0_PE4_TX_C_DP<1> @S9S_MB_2U_LIB.S9S_MB_2U(SCH_1):P5E_CPU0_PE4_TX_C_DP(1)    I57 @S9S_MB_2U_LIB.S9S_MB_2U(SCH_1):PAGE320
    K1    GND @S9S_MB_2U_LIB.S9S_MB_2U(SCH_1):GND    I57 @S9S_MB_2U_LIB.S9S_MB_2U(SCH_1):PAGE320
    L4 P5E_CPU0_PE4_TX_C_DP<3> @S9S_MB_2U_LIB.S9S_MB_2U(SCH_1):P5E_CPU0_PE4_TX_C_DP(3)    I57 @S9S_MB_2U_LIB.S9S_MB_2U(SCH_1):PAGE320
    L3 P5E_CPU0_PE4_TX_C_DN<2> @S9S_MB_2U_LIB.S9S_MB_2U(SCH_1):P5E_CPU0_PE4_TX_C_DN(2)    I57 @S9S_MB_2U_LIB.S9S_MB_2U(SCH_1):PAGE320
    L2 P5E_CPU0_PE4_TX_C_DN<1> @S9S_MB_2U_LIB.S9S_MB_2U(SCH_1):P5E_CPU0_PE4_TX_C_DN(1)    I57 @S9S_MB_2U_LIB.S9S_MB_2U(SCH_1):PAGE320
    L1 P5E_CPU0_PE4_TX_C_DN<0> @S9S_MB_2U_LIB.S9S_MB_2U(SCH_1):P5E_CPU0_PE4_TX_C_DN(0)    I57 @S9S_MB_2U_LIB.S9S_MB_2U(SCH_1):PAGE320
    M1 P5E_CPU0_PE4_TX_C_DP<0> @S9S_MB_2U_LIB.S9S_MB_2U(SCH_1):P5E_CPU0_PE4_TX_C_DP(0)    I57 @S9S_MB_2U_LIB.S9S_MB_2U(SCH_1):PAGE320
    N1    GND @S9S_MB_2U_LIB.S9S_MB_2U(SCH_1):GND    I57 @S9S_MB_2U_LIB.S9S_MB_2U(SCH_1):PAGE320
    M2    GND @S9S_MB_2U_LIB.S9S_MB_2U(SCH_1):GND    I57 @S9S_MB_2U_LIB.S9S_MB_2U(SCH_1):PAGE320
    N2 NC_J108_N2 @S9S_MB_2U_LIB.S9S_MB_2U(SCH_1):NC_J108_N2    I57 @S9S_MB_2U_LIB.S9S_MB_2U(SCH_1):PAGE320
    M3 P5E_CPU0_PE4_TX_C_DP<2> @S9S_MB_2U_LIB.S9S_MB_2U(SCH_1):P5E_CPU0_PE4_TX_C_DP(2)    I57 @S9S_MB_2U_LIB.S9S_MB_2U(SCH_1):PAGE320
    N3    GND @S9S_MB_2U_LIB.S9S_MB_2U(SCH_1):GND    I57 @S9S_MB_2U_LIB.S9S_MB_2U(SCH_1):PAGE320
    M4    GND @S9S_MB_2U_LIB.S9S_MB_2U(SCH_1):GND    I57 @S9S_MB_2U_LIB.S9S_MB_2U(SCH_1):PAGE320
    N4 NC_J108_N4 @S9S_MB_2U_LIB.S9S_MB_2U(SCH_1):NC_J108_N4    I57 @S9S_MB_2U_LIB.S9S_MB_2U(SCH_1):PAGE320

J109 CONN112_10137002101LF-CONN112_A
    A8    GND @S9S_MB_2U_LIB.S9S_MB_2U(SCH_1):GND    I76 @S9S_MB_2U_LIB.S9S_MB_2U(SCH_1):PAGE319
    A7 SMB_BMC_SWB_BUF_SDA @S9S_MB_2U_LIB.S9S_MB_2U(SCH_1):SMB_BMC_SWB_BUF_SDA    I76 @S9S_MB_2U_LIB.S9S_MB_2U(SCH_1):PAGE319
    A6    GND @S9S_MB_2U_LIB.S9S_MB_2U(SCH_1):GND    I76 @S9S_MB_2U_LIB.S9S_MB_2U(SCH_1):PAGE319
    A5 SMB_BMC_SWB_BUF_SCL @S9S_MB_2U_LIB.S9S_MB_2U(SCH_1):SMB_BMC_SWB_BUF_SCL    I76 @S9S_MB_2U_LIB.S9S_MB_2U(SCH_1):PAGE319
    B8 P5E_CPU1_PE3_RX_DP<0> @S9S_MB_2U_LIB.S9S_MB_2U(SCH_1):P5E_CPU1_PE3_RX_DP(0)    I76 @S9S_MB_2U_LIB.S9S_MB_2U(SCH_1):PAGE319
    B7    GND @S9S_MB_2U_LIB.S9S_MB_2U(SCH_1):GND    I76 @S9S_MB_2U_LIB.S9S_MB_2U(SCH_1):PAGE319
    B6 P5E_CPU1_PE3_RX_DN<2> @S9S_MB_2U_LIB.S9S_MB_2U(SCH_1):P5E_CPU1_PE3_RX_DN(2)    I76 @S9S_MB_2U_LIB.S9S_MB_2U(SCH_1):PAGE319
    B5    GND @S9S_MB_2U_LIB.S9S_MB_2U(SCH_1):GND    I76 @S9S_MB_2U_LIB.S9S_MB_2U(SCH_1):PAGE319
    C8 P5E_CPU1_PE3_RX_DN<0> @S9S_MB_2U_LIB.S9S_MB_2U(SCH_1):P5E_CPU1_PE3_RX_DN(0)    I76 @S9S_MB_2U_LIB.S9S_MB_2U(SCH_1):PAGE319
    C7 P5E_CPU1_PE3_RX_DN<1> @S9S_MB_2U_LIB.S9S_MB_2U(SCH_1):P5E_CPU1_PE3_RX_DN(1)    I76 @S9S_MB_2U_LIB.S9S_MB_2U(SCH_1):PAGE319
    C6 P5E_CPU1_PE3_RX_DP<2> @S9S_MB_2U_LIB.S9S_MB_2U(SCH_1):P5E_CPU1_PE3_RX_DP(2)    I76 @S9S_MB_2U_LIB.S9S_MB_2U(SCH_1):PAGE319
    C5 P5E_CPU1_PE3_RX_DN<3> @S9S_MB_2U_LIB.S9S_MB_2U(SCH_1):P5E_CPU1_PE3_RX_DN(3)    I76 @S9S_MB_2U_LIB.S9S_MB_2U(SCH_1):PAGE319
    D8    GND @S9S_MB_2U_LIB.S9S_MB_2U(SCH_1):GND    I76 @S9S_MB_2U_LIB.S9S_MB_2U(SCH_1):PAGE319
    D7 P5E_CPU1_PE3_RX_DP<1> @S9S_MB_2U_LIB.S9S_MB_2U(SCH_1):P5E_CPU1_PE3_RX_DP(1)    I76 @S9S_MB_2U_LIB.S9S_MB_2U(SCH_1):PAGE319
    D6    GND @S9S_MB_2U_LIB.S9S_MB_2U(SCH_1):GND    I76 @S9S_MB_2U_LIB.S9S_MB_2U(SCH_1):PAGE319
    D5 P5E_CPU1_PE3_RX_DP<3> @S9S_MB_2U_LIB.S9S_MB_2U(SCH_1):P5E_CPU1_PE3_RX_DP(3)    I76 @S9S_MB_2U_LIB.S9S_MB_2U(SCH_1):PAGE319
    E8 P5E_CPU1_PE2_RX_DP<0> @S9S_MB_2U_LIB.S9S_MB_2U(SCH_1):P5E_CPU1_PE2_RX_DP(0)    I76 @S9S_MB_2U_LIB.S9S_MB_2U(SCH_1):PAGE319
    E7    GND @S9S_MB_2U_LIB.S9S_MB_2U(SCH_1):GND    I76 @S9S_MB_2U_LIB.S9S_MB_2U(SCH_1):PAGE319
    E6 P5E_CPU1_PE2_RX_DP<2> @S9S_MB_2U_LIB.S9S_MB_2U(SCH_1):P5E_CPU1_PE2_RX_DP(2)    I76 @S9S_MB_2U_LIB.S9S_MB_2U(SCH_1):PAGE319
    E5    GND @S9S_MB_2U_LIB.S9S_MB_2U(SCH_1):GND    I76 @S9S_MB_2U_LIB.S9S_MB_2U(SCH_1):PAGE319
    F8 P5E_CPU1_PE2_RX_DN<0> @S9S_MB_2U_LIB.S9S_MB_2U(SCH_1):P5E_CPU1_PE2_RX_DN(0)    I76 @S9S_MB_2U_LIB.S9S_MB_2U(SCH_1):PAGE319
    F7 P5E_CPU1_PE2_RX_DP<1> @S9S_MB_2U_LIB.S9S_MB_2U(SCH_1):P5E_CPU1_PE2_RX_DP(1)    I76 @S9S_MB_2U_LIB.S9S_MB_2U(SCH_1):PAGE319
    F6 P5E_CPU1_PE2_RX_DN<2> @S9S_MB_2U_LIB.S9S_MB_2U(SCH_1):P5E_CPU1_PE2_RX_DN(2)    I76 @S9S_MB_2U_LIB.S9S_MB_2U(SCH_1):PAGE319
    F5 P5E_CPU1_PE2_RX_DP<3> @S9S_MB_2U_LIB.S9S_MB_2U(SCH_1):P5E_CPU1_PE2_RX_DP(3)    I76 @S9S_MB_2U_LIB.S9S_MB_2U(SCH_1):PAGE319
    G8    GND @S9S_MB_2U_LIB.S9S_MB_2U(SCH_1):GND    I76 @S9S_MB_2U_LIB.S9S_MB_2U(SCH_1):PAGE319
    G7 P5E_CPU1_PE2_RX_DN<1> @S9S_MB_2U_LIB.S9S_MB_2U(SCH_1):P5E_CPU1_PE2_RX_DN(1)    I76 @S9S_MB_2U_LIB.S9S_MB_2U(SCH_1):PAGE319
    G6    GND @S9S_MB_2U_LIB.S9S_MB_2U(SCH_1):GND    I76 @S9S_MB_2U_LIB.S9S_MB_2U(SCH_1):PAGE319
    G5 P5E_CPU1_PE2_RX_DN<3> @S9S_MB_2U_LIB.S9S_MB_2U(SCH_1):P5E_CPU1_PE2_RX_DN(3)    I76 @S9S_MB_2U_LIB.S9S_MB_2U(SCH_1):PAGE319
    H8 P5E_CPU1_PE3_TX_C_DP<0> @S9S_MB_2U_LIB.S9S_MB_2U(SCH_1):P5E_CPU1_PE3_TX_C_DP(0)    I76 @S9S_MB_2U_LIB.S9S_MB_2U(SCH_1):PAGE319
    H7    GND @S9S_MB_2U_LIB.S9S_MB_2U(SCH_1):GND    I76 @S9S_MB_2U_LIB.S9S_MB_2U(SCH_1):PAGE319
    H6 P5E_CPU1_PE3_TX_C_DN<2> @S9S_MB_2U_LIB.S9S_MB_2U(SCH_1):P5E_CPU1_PE3_TX_C_DN(2)    I76 @S9S_MB_2U_LIB.S9S_MB_2U(SCH_1):PAGE319
    H5    GND @S9S_MB_2U_LIB.S9S_MB_2U(SCH_1):GND    I76 @S9S_MB_2U_LIB.S9S_MB_2U(SCH_1):PAGE319
    I8 P5E_CPU1_PE3_TX_C_DN<0> @S9S_MB_2U_LIB.S9S_MB_2U(SCH_1):P5E_CPU1_PE3_TX_C_DN(0)    I76 @S9S_MB_2U_LIB.S9S_MB_2U(SCH_1):PAGE319
    I7 P5E_CPU1_PE3_TX_C_DN<1> @S9S_MB_2U_LIB.S9S_MB_2U(SCH_1):P5E_CPU1_PE3_TX_C_DN(1)    I76 @S9S_MB_2U_LIB.S9S_MB_2U(SCH_1):PAGE319
    I6 P5E_CPU1_PE3_TX_C_DP<2> @S9S_MB_2U_LIB.S9S_MB_2U(SCH_1):P5E_CPU1_PE3_TX_C_DP(2)    I76 @S9S_MB_2U_LIB.S9S_MB_2U(SCH_1):PAGE319
    I5 P5E_CPU1_PE3_TX_C_DN<3> @S9S_MB_2U_LIB.S9S_MB_2U(SCH_1):P5E_CPU1_PE3_TX_C_DN(3)    I76 @S9S_MB_2U_LIB.S9S_MB_2U(SCH_1):PAGE319
    J8    GND @S9S_MB_2U_LIB.S9S_MB_2U(SCH_1):GND    I76 @S9S_MB_2U_LIB.S9S_MB_2U(SCH_1):PAGE319
    J7 P5E_CPU1_PE3_TX_C_DP<1> @S9S_MB_2U_LIB.S9S_MB_2U(SCH_1):P5E_CPU1_PE3_TX_C_DP(1)    I76 @S9S_MB_2U_LIB.S9S_MB_2U(SCH_1):PAGE319
    J6    GND @S9S_MB_2U_LIB.S9S_MB_2U(SCH_1):GND    I76 @S9S_MB_2U_LIB.S9S_MB_2U(SCH_1):PAGE319
    J5 P5E_CPU1_PE3_TX_C_DP<3> @S9S_MB_2U_LIB.S9S_MB_2U(SCH_1):P5E_CPU1_PE3_TX_C_DP(3)    I76 @S9S_MB_2U_LIB.S9S_MB_2U(SCH_1):PAGE319
    K8 P5E_CPU1_PE2_TX_C_DP<0> @S9S_MB_2U_LIB.S9S_MB_2U(SCH_1):P5E_CPU1_PE2_TX_C_DP(0)    I76 @S9S_MB_2U_LIB.S9S_MB_2U(SCH_1):PAGE319
    K7    GND @S9S_MB_2U_LIB.S9S_MB_2U(SCH_1):GND    I76 @S9S_MB_2U_LIB.S9S_MB_2U(SCH_1):PAGE319
    K6 P5E_CPU1_PE2_TX_C_DP<2> @S9S_MB_2U_LIB.S9S_MB_2U(SCH_1):P5E_CPU1_PE2_TX_C_DP(2)    I76 @S9S_MB_2U_LIB.S9S_MB_2U(SCH_1):PAGE319
    K5    GND @S9S_MB_2U_LIB.S9S_MB_2U(SCH_1):GND    I76 @S9S_MB_2U_LIB.S9S_MB_2U(SCH_1):PAGE319
    L8 P5E_CPU1_PE2_TX_C_DN<0> @S9S_MB_2U_LIB.S9S_MB_2U(SCH_1):P5E_CPU1_PE2_TX_C_DN(0)    I76 @S9S_MB_2U_LIB.S9S_MB_2U(SCH_1):PAGE319
    L7 P5E_CPU1_PE2_TX_C_DP<1> @S9S_MB_2U_LIB.S9S_MB_2U(SCH_1):P5E_CPU1_PE2_TX_C_DP(1)    I76 @S9S_MB_2U_LIB.S9S_MB_2U(SCH_1):PAGE319
    L6 P5E_CPU1_PE2_TX_C_DN<2> @S9S_MB_2U_LIB.S9S_MB_2U(SCH_1):P5E_CPU1_PE2_TX_C_DN(2)    I76 @S9S_MB_2U_LIB.S9S_MB_2U(SCH_1):PAGE319
    L5 P5E_CPU1_PE2_TX_C_DP<3> @S9S_MB_2U_LIB.S9S_MB_2U(SCH_1):P5E_CPU1_PE2_TX_C_DP(3)    I76 @S9S_MB_2U_LIB.S9S_MB_2U(SCH_1):PAGE319
    M5 P5E_CPU1_PE2_TX_C_DN<3> @S9S_MB_2U_LIB.S9S_MB_2U(SCH_1):P5E_CPU1_PE2_TX_C_DN(3)    I76 @S9S_MB_2U_LIB.S9S_MB_2U(SCH_1):PAGE319
    N5    GND @S9S_MB_2U_LIB.S9S_MB_2U(SCH_1):GND    I76 @S9S_MB_2U_LIB.S9S_MB_2U(SCH_1):PAGE319
    M6    GND @S9S_MB_2U_LIB.S9S_MB_2U(SCH_1):GND    I76 @S9S_MB_2U_LIB.S9S_MB_2U(SCH_1):PAGE319
    N6 GPU_3V3IO_RSVD1_FFU @S9S_MB_2U_LIB.S9S_MB_2U(SCH_1):GPU_3V3IO_RSVD1_FFU    I76 @S9S_MB_2U_LIB.S9S_MB_2U(SCH_1):PAGE319
    M7 P5E_CPU1_PE2_TX_C_DN<1> @S9S_MB_2U_LIB.S9S_MB_2U(SCH_1):P5E_CPU1_PE2_TX_C_DN(1)    I76 @S9S_MB_2U_LIB.S9S_MB_2U(SCH_1):PAGE319
    N7    GND @S9S_MB_2U_LIB.S9S_MB_2U(SCH_1):GND    I76 @S9S_MB_2U_LIB.S9S_MB_2U(SCH_1):PAGE319
    M8    GND @S9S_MB_2U_LIB.S9S_MB_2U(SCH_1):GND    I76 @S9S_MB_2U_LIB.S9S_MB_2U(SCH_1):PAGE319
    N8 PRSNT_CABLE_GPU_B3_N @S9S_MB_2U_LIB.S9S_MB_2U(SCH_1):PRSNT_CABLE_GPU_B3_N    I76 @S9S_MB_2U_LIB.S9S_MB_2U(SCH_1):PAGE319
    A4    GND @S9S_MB_2U_LIB.S9S_MB_2U(SCH_1):GND    I53 @S9S_MB_2U_LIB.S9S_MB_2U(SCH_1):PAGE319
    A3 BIC_MONITER @S9S_MB_2U_LIB.S9S_MB_2U(SCH_1):BIC_MONITER    I53 @S9S_MB_2U_LIB.S9S_MB_2U(SCH_1):PAGE319
    A2    GND @S9S_MB_2U_LIB.S9S_MB_2U(SCH_1):GND    I53 @S9S_MB_2U_LIB.S9S_MB_2U(SCH_1):PAGE319
    A1 BMC_MONITER_BUF @S9S_MB_2U_LIB.S9S_MB_2U(SCH_1):BMC_MONITER_BUF    I53 @S9S_MB_2U_LIB.S9S_MB_2U(SCH_1):PAGE319
    B4 P5E_CPU1_PE3_RX_DP<4> @S9S_MB_2U_LIB.S9S_MB_2U(SCH_1):P5E_CPU1_PE3_RX_DP(4)    I53 @S9S_MB_2U_LIB.S9S_MB_2U(SCH_1):PAGE319
    B3    GND @S9S_MB_2U_LIB.S9S_MB_2U(SCH_1):GND    I53 @S9S_MB_2U_LIB.S9S_MB_2U(SCH_1):PAGE319
    B2 P5E_CPU1_PE3_RX_DP<6> @S9S_MB_2U_LIB.S9S_MB_2U(SCH_1):P5E_CPU1_PE3_RX_DP(6)    I53 @S9S_MB_2U_LIB.S9S_MB_2U(SCH_1):PAGE319
    B1    GND @S9S_MB_2U_LIB.S9S_MB_2U(SCH_1):GND    I53 @S9S_MB_2U_LIB.S9S_MB_2U(SCH_1):PAGE319
    C4 P5E_CPU1_PE3_RX_DN<4> @S9S_MB_2U_LIB.S9S_MB_2U(SCH_1):P5E_CPU1_PE3_RX_DN(4)    I53 @S9S_MB_2U_LIB.S9S_MB_2U(SCH_1):PAGE319
    C3 P5E_CPU1_PE3_RX_DP<5> @S9S_MB_2U_LIB.S9S_MB_2U(SCH_1):P5E_CPU1_PE3_RX_DP(5)    I53 @S9S_MB_2U_LIB.S9S_MB_2U(SCH_1):PAGE319
    C2 P5E_CPU1_PE3_RX_DN<6> @S9S_MB_2U_LIB.S9S_MB_2U(SCH_1):P5E_CPU1_PE3_RX_DN(6)    I53 @S9S_MB_2U_LIB.S9S_MB_2U(SCH_1):PAGE319
    C1 P5E_CPU1_PE3_RX_DP<7> @S9S_MB_2U_LIB.S9S_MB_2U(SCH_1):P5E_CPU1_PE3_RX_DP(7)    I53 @S9S_MB_2U_LIB.S9S_MB_2U(SCH_1):PAGE319
    D4    GND @S9S_MB_2U_LIB.S9S_MB_2U(SCH_1):GND    I53 @S9S_MB_2U_LIB.S9S_MB_2U(SCH_1):PAGE319
    D3 P5E_CPU1_PE3_RX_DN<5> @S9S_MB_2U_LIB.S9S_MB_2U(SCH_1):P5E_CPU1_PE3_RX_DN(5)    I53 @S9S_MB_2U_LIB.S9S_MB_2U(SCH_1):PAGE319
    D2    GND @S9S_MB_2U_LIB.S9S_MB_2U(SCH_1):GND    I53 @S9S_MB_2U_LIB.S9S_MB_2U(SCH_1):PAGE319
    D1 P5E_CPU1_PE3_RX_DN<7> @S9S_MB_2U_LIB.S9S_MB_2U(SCH_1):P5E_CPU1_PE3_RX_DN(7)    I53 @S9S_MB_2U_LIB.S9S_MB_2U(SCH_1):PAGE319
    E4 P5E_CPU1_PE2_RX_DP<4> @S9S_MB_2U_LIB.S9S_MB_2U(SCH_1):P5E_CPU1_PE2_RX_DP(4)    I53 @S9S_MB_2U_LIB.S9S_MB_2U(SCH_1):PAGE319
    E3    GND @S9S_MB_2U_LIB.S9S_MB_2U(SCH_1):GND    I53 @S9S_MB_2U_LIB.S9S_MB_2U(SCH_1):PAGE319
    E2 P5E_CPU1_PE2_RX_DP<6> @S9S_MB_2U_LIB.S9S_MB_2U(SCH_1):P5E_CPU1_PE2_RX_DP(6)    I53 @S9S_MB_2U_LIB.S9S_MB_2U(SCH_1):PAGE319
    E1    GND @S9S_MB_2U_LIB.S9S_MB_2U(SCH_1):GND    I53 @S9S_MB_2U_LIB.S9S_MB_2U(SCH_1):PAGE319
    F4 P5E_CPU1_PE2_RX_DN<4> @S9S_MB_2U_LIB.S9S_MB_2U(SCH_1):P5E_CPU1_PE2_RX_DN(4)    I53 @S9S_MB_2U_LIB.S9S_MB_2U(SCH_1):PAGE319
    F3 P5E_CPU1_PE2_RX_DP<5> @S9S_MB_2U_LIB.S9S_MB_2U(SCH_1):P5E_CPU1_PE2_RX_DP(5)    I53 @S9S_MB_2U_LIB.S9S_MB_2U(SCH_1):PAGE319
    F2 P5E_CPU1_PE2_RX_DN<6> @S9S_MB_2U_LIB.S9S_MB_2U(SCH_1):P5E_CPU1_PE2_RX_DN(6)    I53 @S9S_MB_2U_LIB.S9S_MB_2U(SCH_1):PAGE319
    F1 P5E_CPU1_PE2_RX_DP<7> @S9S_MB_2U_LIB.S9S_MB_2U(SCH_1):P5E_CPU1_PE2_RX_DP(7)    I53 @S9S_MB_2U_LIB.S9S_MB_2U(SCH_1):PAGE319
    G4    GND @S9S_MB_2U_LIB.S9S_MB_2U(SCH_1):GND    I53 @S9S_MB_2U_LIB.S9S_MB_2U(SCH_1):PAGE319
    G3 P5E_CPU1_PE2_RX_DN<5> @S9S_MB_2U_LIB.S9S_MB_2U(SCH_1):P5E_CPU1_PE2_RX_DN(5)    I53 @S9S_MB_2U_LIB.S9S_MB_2U(SCH_1):PAGE319
    G2    GND @S9S_MB_2U_LIB.S9S_MB_2U(SCH_1):GND    I53 @S9S_MB_2U_LIB.S9S_MB_2U(SCH_1):PAGE319
    G1 P5E_CPU1_PE2_RX_DN<7> @S9S_MB_2U_LIB.S9S_MB_2U(SCH_1):P5E_CPU1_PE2_RX_DN(7)    I53 @S9S_MB_2U_LIB.S9S_MB_2U(SCH_1):PAGE319
    H4 P5E_CPU1_PE3_TX_C_DN<4> @S9S_MB_2U_LIB.S9S_MB_2U(SCH_1):P5E_CPU1_PE3_TX_C_DN(4)    I53 @S9S_MB_2U_LIB.S9S_MB_2U(SCH_1):PAGE319
    H3    GND @S9S_MB_2U_LIB.S9S_MB_2U(SCH_1):GND    I53 @S9S_MB_2U_LIB.S9S_MB_2U(SCH_1):PAGE319
    H2 P5E_CPU1_PE3_TX_C_DN<6> @S9S_MB_2U_LIB.S9S_MB_2U(SCH_1):P5E_CPU1_PE3_TX_C_DN(6)    I53 @S9S_MB_2U_LIB.S9S_MB_2U(SCH_1):PAGE319
    H1    GND @S9S_MB_2U_LIB.S9S_MB_2U(SCH_1):GND    I53 @S9S_MB_2U_LIB.S9S_MB_2U(SCH_1):PAGE319
    I4 P5E_CPU1_PE3_TX_C_DP<4> @S9S_MB_2U_LIB.S9S_MB_2U(SCH_1):P5E_CPU1_PE3_TX_C_DP(4)    I53 @S9S_MB_2U_LIB.S9S_MB_2U(SCH_1):PAGE319
    I3 P5E_CPU1_PE3_TX_C_DN<5> @S9S_MB_2U_LIB.S9S_MB_2U(SCH_1):P5E_CPU1_PE3_TX_C_DN(5)    I53 @S9S_MB_2U_LIB.S9S_MB_2U(SCH_1):PAGE319
    I2 P5E_CPU1_PE3_TX_C_DP<6> @S9S_MB_2U_LIB.S9S_MB_2U(SCH_1):P5E_CPU1_PE3_TX_C_DP(6)    I53 @S9S_MB_2U_LIB.S9S_MB_2U(SCH_1):PAGE319
    I1 P5E_CPU1_PE3_TX_C_DN<7> @S9S_MB_2U_LIB.S9S_MB_2U(SCH_1):P5E_CPU1_PE3_TX_C_DN(7)    I53 @S9S_MB_2U_LIB.S9S_MB_2U(SCH_1):PAGE319
    J4    GND @S9S_MB_2U_LIB.S9S_MB_2U(SCH_1):GND    I53 @S9S_MB_2U_LIB.S9S_MB_2U(SCH_1):PAGE319
    J3 P5E_CPU1_PE3_TX_C_DP<5> @S9S_MB_2U_LIB.S9S_MB_2U(SCH_1):P5E_CPU1_PE3_TX_C_DP(5)    I53 @S9S_MB_2U_LIB.S9S_MB_2U(SCH_1):PAGE319
    J2    GND @S9S_MB_2U_LIB.S9S_MB_2U(SCH_1):GND    I53 @S9S_MB_2U_LIB.S9S_MB_2U(SCH_1):PAGE319
    J1 P5E_CPU1_PE3_TX_C_DP<7> @S9S_MB_2U_LIB.S9S_MB_2U(SCH_1):P5E_CPU1_PE3_TX_C_DP(7)    I53 @S9S_MB_2U_LIB.S9S_MB_2U(SCH_1):PAGE319
    K4 P5E_CPU1_PE2_TX_C_DP<4> @S9S_MB_2U_LIB.S9S_MB_2U(SCH_1):P5E_CPU1_PE2_TX_C_DP(4)    I53 @S9S_MB_2U_LIB.S9S_MB_2U(SCH_1):PAGE319
    K3    GND @S9S_MB_2U_LIB.S9S_MB_2U(SCH_1):GND    I53 @S9S_MB_2U_LIB.S9S_MB_2U(SCH_1):PAGE319
    K2 P5E_CPU1_PE2_TX_C_DP<6> @S9S_MB_2U_LIB.S9S_MB_2U(SCH_1):P5E_CPU1_PE2_TX_C_DP(6)    I53 @S9S_MB_2U_LIB.S9S_MB_2U(SCH_1):PAGE319
    K1    GND @S9S_MB_2U_LIB.S9S_MB_2U(SCH_1):GND    I53 @S9S_MB_2U_LIB.S9S_MB_2U(SCH_1):PAGE319
    L4 P5E_CPU1_PE2_TX_C_DN<4> @S9S_MB_2U_LIB.S9S_MB_2U(SCH_1):P5E_CPU1_PE2_TX_C_DN(4)    I53 @S9S_MB_2U_LIB.S9S_MB_2U(SCH_1):PAGE319
    L3 P5E_CPU1_PE2_TX_C_DP<5> @S9S_MB_2U_LIB.S9S_MB_2U(SCH_1):P5E_CPU1_PE2_TX_C_DP(5)    I53 @S9S_MB_2U_LIB.S9S_MB_2U(SCH_1):PAGE319
    L2 P5E_CPU1_PE2_TX_C_DN<6> @S9S_MB_2U_LIB.S9S_MB_2U(SCH_1):P5E_CPU1_PE2_TX_C_DN(6)    I53 @S9S_MB_2U_LIB.S9S_MB_2U(SCH_1):PAGE319
    L1 P5E_CPU1_PE2_TX_C_DP<7> @S9S_MB_2U_LIB.S9S_MB_2U(SCH_1):P5E_CPU1_PE2_TX_C_DP(7)    I53 @S9S_MB_2U_LIB.S9S_MB_2U(SCH_1):PAGE319
    M1 P5E_CPU1_PE2_TX_C_DN<7> @S9S_MB_2U_LIB.S9S_MB_2U(SCH_1):P5E_CPU1_PE2_TX_C_DN(7)    I53 @S9S_MB_2U_LIB.S9S_MB_2U(SCH_1):PAGE319
    N1    GND @S9S_MB_2U_LIB.S9S_MB_2U(SCH_1):GND    I53 @S9S_MB_2U_LIB.S9S_MB_2U(SCH_1):PAGE319
    M2    GND @S9S_MB_2U_LIB.S9S_MB_2U(SCH_1):GND    I53 @S9S_MB_2U_LIB.S9S_MB_2U(SCH_1):PAGE319
    N2 GPU_FPGA_EROT_FATALERR_N @S9S_MB_2U_LIB.S9S_MB_2U(SCH_1):GPU_FPGA_EROT_FATALERR_N    I53 @S9S_MB_2U_LIB.S9S_MB_2U(SCH_1):PAGE319
    M3 P5E_CPU1_PE2_TX_C_DN<5> @S9S_MB_2U_LIB.S9S_MB_2U(SCH_1):P5E_CPU1_PE2_TX_C_DN(5)    I53 @S9S_MB_2U_LIB.S9S_MB_2U(SCH_1):PAGE319
    N3    GND @S9S_MB_2U_LIB.S9S_MB_2U(SCH_1):GND    I53 @S9S_MB_2U_LIB.S9S_MB_2U(SCH_1):PAGE319
    M4    GND @S9S_MB_2U_LIB.S9S_MB_2U(SCH_1):GND    I53 @S9S_MB_2U_LIB.S9S_MB_2U(SCH_1):PAGE319
    N4 GPU_3V3IO_RSVD0_FFU @S9S_MB_2U_LIB.S9S_MB_2U(SCH_1):GPU_3V3IO_RSVD0_FFU    I53 @S9S_MB_2U_LIB.S9S_MB_2U(SCH_1):PAGE319

J110 CONN112_10137002101LF-CONN112_A
    A8    GND @S9S_MB_2U_LIB.S9S_MB_2U(SCH_1):GND    I16 @S9S_MB_2U_LIB.S9S_MB_2U(SCH_1):PAGE318
    A7 GPU_BASE_STBY_EN_BUF @S9S_MB_2U_LIB.S9S_MB_2U(SCH_1):GPU_BASE_STBY_EN_BUF    I16 @S9S_MB_2U_LIB.S9S_MB_2U(SCH_1):PAGE318
    A6    GND @S9S_MB_2U_LIB.S9S_MB_2U(SCH_1):GND    I16 @S9S_MB_2U_LIB.S9S_MB_2U(SCH_1):PAGE318
    A5 GPU_BASE_HMC_READY @S9S_MB_2U_LIB.S9S_MB_2U(SCH_1):GPU_BASE_HMC_READY    I16 @S9S_MB_2U_LIB.S9S_MB_2U(SCH_1):PAGE318
    B8 P5E_CPU1_PE3_RX_DN<8> @S9S_MB_2U_LIB.S9S_MB_2U(SCH_1):P5E_CPU1_PE3_RX_DN(8)    I16 @S9S_MB_2U_LIB.S9S_MB_2U(SCH_1):PAGE318
    B7    GND @S9S_MB_2U_LIB.S9S_MB_2U(SCH_1):GND    I16 @S9S_MB_2U_LIB.S9S_MB_2U(SCH_1):PAGE318
    B6 P5E_CPU1_PE3_RX_DN<10> @S9S_MB_2U_LIB.S9S_MB_2U(SCH_1):P5E_CPU1_PE3_RX_DN(10)    I16 @S9S_MB_2U_LIB.S9S_MB_2U(SCH_1):PAGE318
    B5    GND @S9S_MB_2U_LIB.S9S_MB_2U(SCH_1):GND    I16 @S9S_MB_2U_LIB.S9S_MB_2U(SCH_1):PAGE318
    C8 P5E_CPU1_PE3_RX_DP<8> @S9S_MB_2U_LIB.S9S_MB_2U(SCH_1):P5E_CPU1_PE3_RX_DP(8)    I16 @S9S_MB_2U_LIB.S9S_MB_2U(SCH_1):PAGE318
    C7 P5E_CPU1_PE3_RX_DN<9> @S9S_MB_2U_LIB.S9S_MB_2U(SCH_1):P5E_CPU1_PE3_RX_DN(9)    I16 @S9S_MB_2U_LIB.S9S_MB_2U(SCH_1):PAGE318
    C6 P5E_CPU1_PE3_RX_DP<10> @S9S_MB_2U_LIB.S9S_MB_2U(SCH_1):P5E_CPU1_PE3_RX_DP(10)    I16 @S9S_MB_2U_LIB.S9S_MB_2U(SCH_1):PAGE318
    C5 P5E_CPU1_PE3_RX_DN<11> @S9S_MB_2U_LIB.S9S_MB_2U(SCH_1):P5E_CPU1_PE3_RX_DN(11)    I16 @S9S_MB_2U_LIB.S9S_MB_2U(SCH_1):PAGE318
    D8    GND @S9S_MB_2U_LIB.S9S_MB_2U(SCH_1):GND    I16 @S9S_MB_2U_LIB.S9S_MB_2U(SCH_1):PAGE318
    D7 P5E_CPU1_PE3_RX_DP<9> @S9S_MB_2U_LIB.S9S_MB_2U(SCH_1):P5E_CPU1_PE3_RX_DP(9)    I16 @S9S_MB_2U_LIB.S9S_MB_2U(SCH_1):PAGE318
    D6    GND @S9S_MB_2U_LIB.S9S_MB_2U(SCH_1):GND    I16 @S9S_MB_2U_LIB.S9S_MB_2U(SCH_1):PAGE318
    D5 P5E_CPU1_PE3_RX_DP<11> @S9S_MB_2U_LIB.S9S_MB_2U(SCH_1):P5E_CPU1_PE3_RX_DP(11)    I16 @S9S_MB_2U_LIB.S9S_MB_2U(SCH_1):PAGE318
    E8 P5E_CPU1_PE2_RX_DP<8> @S9S_MB_2U_LIB.S9S_MB_2U(SCH_1):P5E_CPU1_PE2_RX_DP(8)    I16 @S9S_MB_2U_LIB.S9S_MB_2U(SCH_1):PAGE318
    E7    GND @S9S_MB_2U_LIB.S9S_MB_2U(SCH_1):GND    I16 @S9S_MB_2U_LIB.S9S_MB_2U(SCH_1):PAGE318
    E6 P5E_CPU1_PE2_RX_DP<10> @S9S_MB_2U_LIB.S9S_MB_2U(SCH_1):P5E_CPU1_PE2_RX_DP(10)    I16 @S9S_MB_2U_LIB.S9S_MB_2U(SCH_1):PAGE318
    E5    GND @S9S_MB_2U_LIB.S9S_MB_2U(SCH_1):GND    I16 @S9S_MB_2U_LIB.S9S_MB_2U(SCH_1):PAGE318
    F8 P5E_CPU1_PE2_RX_DN<8> @S9S_MB_2U_LIB.S9S_MB_2U(SCH_1):P5E_CPU1_PE2_RX_DN(8)    I16 @S9S_MB_2U_LIB.S9S_MB_2U(SCH_1):PAGE318
    F7 P5E_CPU1_PE2_RX_DP<9> @S9S_MB_2U_LIB.S9S_MB_2U(SCH_1):P5E_CPU1_PE2_RX_DP(9)    I16 @S9S_MB_2U_LIB.S9S_MB_2U(SCH_1):PAGE318
    F6 P5E_CPU1_PE2_RX_DN<10> @S9S_MB_2U_LIB.S9S_MB_2U(SCH_1):P5E_CPU1_PE2_RX_DN(10)    I16 @S9S_MB_2U_LIB.S9S_MB_2U(SCH_1):PAGE318
    F5 P5E_CPU1_PE2_RX_DP<11> @S9S_MB_2U_LIB.S9S_MB_2U(SCH_1):P5E_CPU1_PE2_RX_DP(11)    I16 @S9S_MB_2U_LIB.S9S_MB_2U(SCH_1):PAGE318
    G8    GND @S9S_MB_2U_LIB.S9S_MB_2U(SCH_1):GND    I16 @S9S_MB_2U_LIB.S9S_MB_2U(SCH_1):PAGE318
    G7 P5E_CPU1_PE2_RX_DN<9> @S9S_MB_2U_LIB.S9S_MB_2U(SCH_1):P5E_CPU1_PE2_RX_DN(9)    I16 @S9S_MB_2U_LIB.S9S_MB_2U(SCH_1):PAGE318
    G6    GND @S9S_MB_2U_LIB.S9S_MB_2U(SCH_1):GND    I16 @S9S_MB_2U_LIB.S9S_MB_2U(SCH_1):PAGE318
    G5 P5E_CPU1_PE2_RX_DN<11> @S9S_MB_2U_LIB.S9S_MB_2U(SCH_1):P5E_CPU1_PE2_RX_DN(11)    I16 @S9S_MB_2U_LIB.S9S_MB_2U(SCH_1):PAGE318
    H8 P5E_CPU1_PE3_TX_C_DN<8> @S9S_MB_2U_LIB.S9S_MB_2U(SCH_1):P5E_CPU1_PE3_TX_C_DN(8)    I16 @S9S_MB_2U_LIB.S9S_MB_2U(SCH_1):PAGE318
    H7    GND @S9S_MB_2U_LIB.S9S_MB_2U(SCH_1):GND    I16 @S9S_MB_2U_LIB.S9S_MB_2U(SCH_1):PAGE318
    H6 P5E_CPU1_PE3_TX_C_DN<10> @S9S_MB_2U_LIB.S9S_MB_2U(SCH_1):P5E_CPU1_PE3_TX_C_DN(10)    I16 @S9S_MB_2U_LIB.S9S_MB_2U(SCH_1):PAGE318
    H5    GND @S9S_MB_2U_LIB.S9S_MB_2U(SCH_1):GND    I16 @S9S_MB_2U_LIB.S9S_MB_2U(SCH_1):PAGE318
    I8 P5E_CPU1_PE3_TX_C_DP<8> @S9S_MB_2U_LIB.S9S_MB_2U(SCH_1):P5E_CPU1_PE3_TX_C_DP(8)    I16 @S9S_MB_2U_LIB.S9S_MB_2U(SCH_1):PAGE318
    I7 P5E_CPU1_PE3_TX_C_DN<9> @S9S_MB_2U_LIB.S9S_MB_2U(SCH_1):P5E_CPU1_PE3_TX_C_DN(9)    I16 @S9S_MB_2U_LIB.S9S_MB_2U(SCH_1):PAGE318
    I6 P5E_CPU1_PE3_TX_C_DP<10> @S9S_MB_2U_LIB.S9S_MB_2U(SCH_1):P5E_CPU1_PE3_TX_C_DP(10)    I16 @S9S_MB_2U_LIB.S9S_MB_2U(SCH_1):PAGE318
    I5 P5E_CPU1_PE3_TX_C_DN<11> @S9S_MB_2U_LIB.S9S_MB_2U(SCH_1):P5E_CPU1_PE3_TX_C_DN(11)    I16 @S9S_MB_2U_LIB.S9S_MB_2U(SCH_1):PAGE318
    J8    GND @S9S_MB_2U_LIB.S9S_MB_2U(SCH_1):GND    I16 @S9S_MB_2U_LIB.S9S_MB_2U(SCH_1):PAGE318
    J7 P5E_CPU1_PE3_TX_C_DP<9> @S9S_MB_2U_LIB.S9S_MB_2U(SCH_1):P5E_CPU1_PE3_TX_C_DP(9)    I16 @S9S_MB_2U_LIB.S9S_MB_2U(SCH_1):PAGE318
    J6    GND @S9S_MB_2U_LIB.S9S_MB_2U(SCH_1):GND    I16 @S9S_MB_2U_LIB.S9S_MB_2U(SCH_1):PAGE318
    J5 P5E_CPU1_PE3_TX_C_DP<11> @S9S_MB_2U_LIB.S9S_MB_2U(SCH_1):P5E_CPU1_PE3_TX_C_DP(11)    I16 @S9S_MB_2U_LIB.S9S_MB_2U(SCH_1):PAGE318
    K8 P5E_CPU1_PE2_TX_C_DP<8> @S9S_MB_2U_LIB.S9S_MB_2U(SCH_1):P5E_CPU1_PE2_TX_C_DP(8)    I16 @S9S_MB_2U_LIB.S9S_MB_2U(SCH_1):PAGE318
    K7    GND @S9S_MB_2U_LIB.S9S_MB_2U(SCH_1):GND    I16 @S9S_MB_2U_LIB.S9S_MB_2U(SCH_1):PAGE318
    K6 P5E_CPU1_PE2_TX_C_DP<10> @S9S_MB_2U_LIB.S9S_MB_2U(SCH_1):P5E_CPU1_PE2_TX_C_DP(10)    I16 @S9S_MB_2U_LIB.S9S_MB_2U(SCH_1):PAGE318
    K5    GND @S9S_MB_2U_LIB.S9S_MB_2U(SCH_1):GND    I16 @S9S_MB_2U_LIB.S9S_MB_2U(SCH_1):PAGE318
    L8 P5E_CPU1_PE2_TX_C_DN<8> @S9S_MB_2U_LIB.S9S_MB_2U(SCH_1):P5E_CPU1_PE2_TX_C_DN(8)    I16 @S9S_MB_2U_LIB.S9S_MB_2U(SCH_1):PAGE318
    L7 P5E_CPU1_PE2_TX_C_DP<9> @S9S_MB_2U_LIB.S9S_MB_2U(SCH_1):P5E_CPU1_PE2_TX_C_DP(9)    I16 @S9S_MB_2U_LIB.S9S_MB_2U(SCH_1):PAGE318
    L6 P5E_CPU1_PE2_TX_C_DN<10> @S9S_MB_2U_LIB.S9S_MB_2U(SCH_1):P5E_CPU1_PE2_TX_C_DN(10)    I16 @S9S_MB_2U_LIB.S9S_MB_2U(SCH_1):PAGE318
    L5 P5E_CPU1_PE2_TX_C_DP<11> @S9S_MB_2U_LIB.S9S_MB_2U(SCH_1):P5E_CPU1_PE2_TX_C_DP(11)    I16 @S9S_MB_2U_LIB.S9S_MB_2U(SCH_1):PAGE318
    M5 P5E_CPU1_PE2_TX_C_DN<11> @S9S_MB_2U_LIB.S9S_MB_2U(SCH_1):P5E_CPU1_PE2_TX_C_DN(11)    I16 @S9S_MB_2U_LIB.S9S_MB_2U(SCH_1):PAGE318
    N5    GND @S9S_MB_2U_LIB.S9S_MB_2U(SCH_1):GND    I16 @S9S_MB_2U_LIB.S9S_MB_2U(SCH_1):PAGE318
    M6    GND @S9S_MB_2U_LIB.S9S_MB_2U(SCH_1):GND    I16 @S9S_MB_2U_LIB.S9S_MB_2U(SCH_1):PAGE318
    N6 FM_SMB_2_ALERT_GPU_N @S9S_MB_2U_LIB.S9S_MB_2U(SCH_1):FM_SMB_2_ALERT_GPU_N    I16 @S9S_MB_2U_LIB.S9S_MB_2U(SCH_1):PAGE318
    M7 P5E_CPU1_PE2_TX_C_DN<9> @S9S_MB_2U_LIB.S9S_MB_2U(SCH_1):P5E_CPU1_PE2_TX_C_DN(9)    I16 @S9S_MB_2U_LIB.S9S_MB_2U(SCH_1):PAGE318
    N7    GND @S9S_MB_2U_LIB.S9S_MB_2U(SCH_1):GND    I16 @S9S_MB_2U_LIB.S9S_MB_2U(SCH_1):PAGE318
    M8    GND @S9S_MB_2U_LIB.S9S_MB_2U(SCH_1):GND    I16 @S9S_MB_2U_LIB.S9S_MB_2U(SCH_1):PAGE318
    N8 GPU_FPGA_EROT_RST_BUF_N @S9S_MB_2U_LIB.S9S_MB_2U(SCH_1):GPU_FPGA_EROT_RST_BUF_N    I16 @S9S_MB_2U_LIB.S9S_MB_2U(SCH_1):PAGE318
    A4    GND @S9S_MB_2U_LIB.S9S_MB_2U(SCH_1):GND    I54 @S9S_MB_2U_LIB.S9S_MB_2U(SCH_1):PAGE318
    A3 GPU_HMC_PRSNT_N @S9S_MB_2U_LIB.S9S_MB_2U(SCH_1):GPU_HMC_PRSNT_N    I54 @S9S_MB_2U_LIB.S9S_MB_2U(SCH_1):PAGE318
    A2    GND @S9S_MB_2U_LIB.S9S_MB_2U(SCH_1):GND    I54 @S9S_MB_2U_LIB.S9S_MB_2U(SCH_1):PAGE318
    A1 GPU_FPGA_EROT_RECOV_BUF_N @S9S_MB_2U_LIB.S9S_MB_2U(SCH_1):GPU_FPGA_EROT_RECOV_BUF_N    I54 @S9S_MB_2U_LIB.S9S_MB_2U(SCH_1):PAGE318
    B4 P5E_CPU1_PE3_RX_DP<12> @S9S_MB_2U_LIB.S9S_MB_2U(SCH_1):P5E_CPU1_PE3_RX_DP(12)    I54 @S9S_MB_2U_LIB.S9S_MB_2U(SCH_1):PAGE318
    B3    GND @S9S_MB_2U_LIB.S9S_MB_2U(SCH_1):GND    I54 @S9S_MB_2U_LIB.S9S_MB_2U(SCH_1):PAGE318
    B2 P5E_CPU1_PE3_RX_DP<14> @S9S_MB_2U_LIB.S9S_MB_2U(SCH_1):P5E_CPU1_PE3_RX_DP(14)    I54 @S9S_MB_2U_LIB.S9S_MB_2U(SCH_1):PAGE318
    B1    GND @S9S_MB_2U_LIB.S9S_MB_2U(SCH_1):GND    I54 @S9S_MB_2U_LIB.S9S_MB_2U(SCH_1):PAGE318
    C4 P5E_CPU1_PE3_RX_DN<12> @S9S_MB_2U_LIB.S9S_MB_2U(SCH_1):P5E_CPU1_PE3_RX_DN(12)    I54 @S9S_MB_2U_LIB.S9S_MB_2U(SCH_1):PAGE318
    C3 P5E_CPU1_PE3_RX_DP<13> @S9S_MB_2U_LIB.S9S_MB_2U(SCH_1):P5E_CPU1_PE3_RX_DP(13)    I54 @S9S_MB_2U_LIB.S9S_MB_2U(SCH_1):PAGE318
    C2 P5E_CPU1_PE3_RX_DN<14> @S9S_MB_2U_LIB.S9S_MB_2U(SCH_1):P5E_CPU1_PE3_RX_DN(14)    I54 @S9S_MB_2U_LIB.S9S_MB_2U(SCH_1):PAGE318
    C1 P5E_CPU1_PE3_RX_DP<15> @S9S_MB_2U_LIB.S9S_MB_2U(SCH_1):P5E_CPU1_PE3_RX_DP(15)    I54 @S9S_MB_2U_LIB.S9S_MB_2U(SCH_1):PAGE318
    D4    GND @S9S_MB_2U_LIB.S9S_MB_2U(SCH_1):GND    I54 @S9S_MB_2U_LIB.S9S_MB_2U(SCH_1):PAGE318
    D3 P5E_CPU1_PE3_RX_DN<13> @S9S_MB_2U_LIB.S9S_MB_2U(SCH_1):P5E_CPU1_PE3_RX_DN(13)    I54 @S9S_MB_2U_LIB.S9S_MB_2U(SCH_1):PAGE318
    D2    GND @S9S_MB_2U_LIB.S9S_MB_2U(SCH_1):GND    I54 @S9S_MB_2U_LIB.S9S_MB_2U(SCH_1):PAGE318
    D1 P5E_CPU1_PE3_RX_DN<15> @S9S_MB_2U_LIB.S9S_MB_2U(SCH_1):P5E_CPU1_PE3_RX_DN(15)    I54 @S9S_MB_2U_LIB.S9S_MB_2U(SCH_1):PAGE318
    E4 P5E_CPU1_PE2_RX_DP<12> @S9S_MB_2U_LIB.S9S_MB_2U(SCH_1):P5E_CPU1_PE2_RX_DP(12)    I54 @S9S_MB_2U_LIB.S9S_MB_2U(SCH_1):PAGE318
    E3    GND @S9S_MB_2U_LIB.S9S_MB_2U(SCH_1):GND    I54 @S9S_MB_2U_LIB.S9S_MB_2U(SCH_1):PAGE318
    E2 P5E_CPU1_PE2_RX_DP<14> @S9S_MB_2U_LIB.S9S_MB_2U(SCH_1):P5E_CPU1_PE2_RX_DP(14)    I54 @S9S_MB_2U_LIB.S9S_MB_2U(SCH_1):PAGE318
    E1    GND @S9S_MB_2U_LIB.S9S_MB_2U(SCH_1):GND    I54 @S9S_MB_2U_LIB.S9S_MB_2U(SCH_1):PAGE318
    F4 P5E_CPU1_PE2_RX_DN<12> @S9S_MB_2U_LIB.S9S_MB_2U(SCH_1):P5E_CPU1_PE2_RX_DN(12)    I54 @S9S_MB_2U_LIB.S9S_MB_2U(SCH_1):PAGE318
    F3 P5E_CPU1_PE2_RX_DP<13> @S9S_MB_2U_LIB.S9S_MB_2U(SCH_1):P5E_CPU1_PE2_RX_DP(13)    I54 @S9S_MB_2U_LIB.S9S_MB_2U(SCH_1):PAGE318
    F2 P5E_CPU1_PE2_RX_DN<14> @S9S_MB_2U_LIB.S9S_MB_2U(SCH_1):P5E_CPU1_PE2_RX_DN(14)    I54 @S9S_MB_2U_LIB.S9S_MB_2U(SCH_1):PAGE318
    F1 P5E_CPU1_PE2_RX_DP<15> @S9S_MB_2U_LIB.S9S_MB_2U(SCH_1):P5E_CPU1_PE2_RX_DP(15)    I54 @S9S_MB_2U_LIB.S9S_MB_2U(SCH_1):PAGE318
    G4    GND @S9S_MB_2U_LIB.S9S_MB_2U(SCH_1):GND    I54 @S9S_MB_2U_LIB.S9S_MB_2U(SCH_1):PAGE318
    G3 P5E_CPU1_PE2_RX_DN<13> @S9S_MB_2U_LIB.S9S_MB_2U(SCH_1):P5E_CPU1_PE2_RX_DN(13)    I54 @S9S_MB_2U_LIB.S9S_MB_2U(SCH_1):PAGE318
    G2    GND @S9S_MB_2U_LIB.S9S_MB_2U(SCH_1):GND    I54 @S9S_MB_2U_LIB.S9S_MB_2U(SCH_1):PAGE318
    G1 P5E_CPU1_PE2_RX_DN<15> @S9S_MB_2U_LIB.S9S_MB_2U(SCH_1):P5E_CPU1_PE2_RX_DN(15)    I54 @S9S_MB_2U_LIB.S9S_MB_2U(SCH_1):PAGE318
    H4 P5E_CPU1_PE3_TX_C_DN<12> @S9S_MB_2U_LIB.S9S_MB_2U(SCH_1):P5E_CPU1_PE3_TX_C_DN(12)    I54 @S9S_MB_2U_LIB.S9S_MB_2U(SCH_1):PAGE318
    H3    GND @S9S_MB_2U_LIB.S9S_MB_2U(SCH_1):GND    I54 @S9S_MB_2U_LIB.S9S_MB_2U(SCH_1):PAGE318
    H2 P5E_CPU1_PE3_TX_C_DN<14> @S9S_MB_2U_LIB.S9S_MB_2U(SCH_1):P5E_CPU1_PE3_TX_C_DN(14)    I54 @S9S_MB_2U_LIB.S9S_MB_2U(SCH_1):PAGE318
    H1    GND @S9S_MB_2U_LIB.S9S_MB_2U(SCH_1):GND    I54 @S9S_MB_2U_LIB.S9S_MB_2U(SCH_1):PAGE318
    I4 P5E_CPU1_PE3_TX_C_DP<12> @S9S_MB_2U_LIB.S9S_MB_2U(SCH_1):P5E_CPU1_PE3_TX_C_DP(12)    I54 @S9S_MB_2U_LIB.S9S_MB_2U(SCH_1):PAGE318
    I3 P5E_CPU1_PE3_TX_C_DN<13> @S9S_MB_2U_LIB.S9S_MB_2U(SCH_1):P5E_CPU1_PE3_TX_C_DN(13)    I54 @S9S_MB_2U_LIB.S9S_MB_2U(SCH_1):PAGE318
    I2 P5E_CPU1_PE3_TX_C_DP<14> @S9S_MB_2U_LIB.S9S_MB_2U(SCH_1):P5E_CPU1_PE3_TX_C_DP(14)    I54 @S9S_MB_2U_LIB.S9S_MB_2U(SCH_1):PAGE318
    I1 P5E_CPU1_PE3_TX_C_DN<15> @S9S_MB_2U_LIB.S9S_MB_2U(SCH_1):P5E_CPU1_PE3_TX_C_DN(15)    I54 @S9S_MB_2U_LIB.S9S_MB_2U(SCH_1):PAGE318
    J4    GND @S9S_MB_2U_LIB.S9S_MB_2U(SCH_1):GND    I54 @S9S_MB_2U_LIB.S9S_MB_2U(SCH_1):PAGE318
    J3 P5E_CPU1_PE3_TX_C_DP<13> @S9S_MB_2U_LIB.S9S_MB_2U(SCH_1):P5E_CPU1_PE3_TX_C_DP(13)    I54 @S9S_MB_2U_LIB.S9S_MB_2U(SCH_1):PAGE318
    J2    GND @S9S_MB_2U_LIB.S9S_MB_2U(SCH_1):GND    I54 @S9S_MB_2U_LIB.S9S_MB_2U(SCH_1):PAGE318
    J1 P5E_CPU1_PE3_TX_C_DP<15> @S9S_MB_2U_LIB.S9S_MB_2U(SCH_1):P5E_CPU1_PE3_TX_C_DP(15)    I54 @S9S_MB_2U_LIB.S9S_MB_2U(SCH_1):PAGE318
    K4 P5E_CPU1_PE2_TX_C_DP<12> @S9S_MB_2U_LIB.S9S_MB_2U(SCH_1):P5E_CPU1_PE2_TX_C_DP(12)    I54 @S9S_MB_2U_LIB.S9S_MB_2U(SCH_1):PAGE318
    K3    GND @S9S_MB_2U_LIB.S9S_MB_2U(SCH_1):GND    I54 @S9S_MB_2U_LIB.S9S_MB_2U(SCH_1):PAGE318
    K2 P5E_CPU1_PE2_TX_C_DP<14> @S9S_MB_2U_LIB.S9S_MB_2U(SCH_1):P5E_CPU1_PE2_TX_C_DP(14)    I54 @S9S_MB_2U_LIB.S9S_MB_2U(SCH_1):PAGE318
    K1    GND @S9S_MB_2U_LIB.S9S_MB_2U(SCH_1):GND    I54 @S9S_MB_2U_LIB.S9S_MB_2U(SCH_1):PAGE318
    L4 P5E_CPU1_PE2_TX_C_DN<12> @S9S_MB_2U_LIB.S9S_MB_2U(SCH_1):P5E_CPU1_PE2_TX_C_DN(12)    I54 @S9S_MB_2U_LIB.S9S_MB_2U(SCH_1):PAGE318
    L3 P5E_CPU1_PE2_TX_C_DP<13> @S9S_MB_2U_LIB.S9S_MB_2U(SCH_1):P5E_CPU1_PE2_TX_C_DP(13)    I54 @S9S_MB_2U_LIB.S9S_MB_2U(SCH_1):PAGE318
    L2 P5E_CPU1_PE2_TX_C_DN<14> @S9S_MB_2U_LIB.S9S_MB_2U(SCH_1):P5E_CPU1_PE2_TX_C_DN(14)    I54 @S9S_MB_2U_LIB.S9S_MB_2U(SCH_1):PAGE318
    L1 P5E_CPU1_PE2_TX_C_DP<15> @S9S_MB_2U_LIB.S9S_MB_2U(SCH_1):P5E_CPU1_PE2_TX_C_DP(15)    I54 @S9S_MB_2U_LIB.S9S_MB_2U(SCH_1):PAGE318
    M1 P5E_CPU1_PE2_TX_C_DN<15> @S9S_MB_2U_LIB.S9S_MB_2U(SCH_1):P5E_CPU1_PE2_TX_C_DN(15)    I54 @S9S_MB_2U_LIB.S9S_MB_2U(SCH_1):PAGE318
    N1    GND @S9S_MB_2U_LIB.S9S_MB_2U(SCH_1):GND    I54 @S9S_MB_2U_LIB.S9S_MB_2U(SCH_1):PAGE318
    M2    GND @S9S_MB_2U_LIB.S9S_MB_2U(SCH_1):GND    I54 @S9S_MB_2U_LIB.S9S_MB_2U(SCH_1):PAGE318
    N2 GPU_FPGA_BOOT_EN_BUF @S9S_MB_2U_LIB.S9S_MB_2U(SCH_1):GPU_FPGA_BOOT_EN_BUF    I54 @S9S_MB_2U_LIB.S9S_MB_2U(SCH_1):PAGE318
    M3 P5E_CPU1_PE2_TX_C_DN<13> @S9S_MB_2U_LIB.S9S_MB_2U(SCH_1):P5E_CPU1_PE2_TX_C_DN(13)    I54 @S9S_MB_2U_LIB.S9S_MB_2U(SCH_1):PAGE318
    N3    GND @S9S_MB_2U_LIB.S9S_MB_2U(SCH_1):GND    I54 @S9S_MB_2U_LIB.S9S_MB_2U(SCH_1):PAGE318
    M4    GND @S9S_MB_2U_LIB.S9S_MB_2U(SCH_1):GND    I54 @S9S_MB_2U_LIB.S9S_MB_2U(SCH_1):PAGE318
    N4 FM_SMB_1_ALERT_GPU_N @S9S_MB_2U_LIB.S9S_MB_2U(SCH_1):FM_SMB_1_ALERT_GPU_N    I54 @S9S_MB_2U_LIB.S9S_MB_2U(SCH_1):PAGE318

J111 CONN112_10137002101LF-CONN112_A
    A8    GND @S9S_MB_2U_LIB.S9S_MB_2U(SCH_1):GND    I74 @S9S_MB_2U_LIB.S9S_MB_2U(SCH_1):PAGE148
    A7 GPU_FPGA_RST_R_BUF_N @S9S_MB_2U_LIB.S9S_MB_2U(SCH_1):GPU_FPGA_RST_R_BUF_N    I74 @S9S_MB_2U_LIB.S9S_MB_2U(SCH_1):PAGE148
    A6    GND @S9S_MB_2U_LIB.S9S_MB_2U(SCH_1):GND    I74 @S9S_MB_2U_LIB.S9S_MB_2U(SCH_1):PAGE148
    A5 GPU_PEX_STRAP0 @S9S_MB_2U_LIB.S9S_MB_2U(SCH_1):GPU_PEX_STRAP0    I74 @S9S_MB_2U_LIB.S9S_MB_2U(SCH_1):PAGE148
    B8 P5E_CPU1_PE0_RX_DN<0> @S9S_MB_2U_LIB.S9S_MB_2U(SCH_1):P5E_CPU1_PE0_RX_DN(0)    I74 @S9S_MB_2U_LIB.S9S_MB_2U(SCH_1):PAGE148
    B7    GND @S9S_MB_2U_LIB.S9S_MB_2U(SCH_1):GND    I74 @S9S_MB_2U_LIB.S9S_MB_2U(SCH_1):PAGE148
    B6 P5E_CPU1_PE0_RX_DN<2> @S9S_MB_2U_LIB.S9S_MB_2U(SCH_1):P5E_CPU1_PE0_RX_DN(2)    I74 @S9S_MB_2U_LIB.S9S_MB_2U(SCH_1):PAGE148
    B5    GND @S9S_MB_2U_LIB.S9S_MB_2U(SCH_1):GND    I74 @S9S_MB_2U_LIB.S9S_MB_2U(SCH_1):PAGE148
    C8 P5E_CPU1_PE0_RX_DP<0> @S9S_MB_2U_LIB.S9S_MB_2U(SCH_1):P5E_CPU1_PE0_RX_DP(0)    I74 @S9S_MB_2U_LIB.S9S_MB_2U(SCH_1):PAGE148
    C7 P5E_CPU1_PE0_RX_DP<1> @S9S_MB_2U_LIB.S9S_MB_2U(SCH_1):P5E_CPU1_PE0_RX_DP(1)    I74 @S9S_MB_2U_LIB.S9S_MB_2U(SCH_1):PAGE148
    C6 P5E_CPU1_PE0_RX_DP<2> @S9S_MB_2U_LIB.S9S_MB_2U(SCH_1):P5E_CPU1_PE0_RX_DP(2)    I74 @S9S_MB_2U_LIB.S9S_MB_2U(SCH_1):PAGE148
    C5 P5E_CPU1_PE0_RX_DP<3> @S9S_MB_2U_LIB.S9S_MB_2U(SCH_1):P5E_CPU1_PE0_RX_DP(3)    I74 @S9S_MB_2U_LIB.S9S_MB_2U(SCH_1):PAGE148
    D8    GND @S9S_MB_2U_LIB.S9S_MB_2U(SCH_1):GND    I74 @S9S_MB_2U_LIB.S9S_MB_2U(SCH_1):PAGE148
    D7 P5E_CPU1_PE0_RX_DN<1> @S9S_MB_2U_LIB.S9S_MB_2U(SCH_1):P5E_CPU1_PE0_RX_DN(1)    I74 @S9S_MB_2U_LIB.S9S_MB_2U(SCH_1):PAGE148
    D6    GND @S9S_MB_2U_LIB.S9S_MB_2U(SCH_1):GND    I74 @S9S_MB_2U_LIB.S9S_MB_2U(SCH_1):PAGE148
    D5 P5E_CPU1_PE0_RX_DN<3> @S9S_MB_2U_LIB.S9S_MB_2U(SCH_1):P5E_CPU1_PE0_RX_DN(3)    I74 @S9S_MB_2U_LIB.S9S_MB_2U(SCH_1):PAGE148
    E8 P5E_CPU1_PE4_RX_DP<15> @S9S_MB_2U_LIB.S9S_MB_2U(SCH_1):P5E_CPU1_PE4_RX_DP(15)    I74 @S9S_MB_2U_LIB.S9S_MB_2U(SCH_1):PAGE148
    E7    GND @S9S_MB_2U_LIB.S9S_MB_2U(SCH_1):GND    I74 @S9S_MB_2U_LIB.S9S_MB_2U(SCH_1):PAGE148
    E6 P5E_CPU1_PE4_RX_DP<13> @S9S_MB_2U_LIB.S9S_MB_2U(SCH_1):P5E_CPU1_PE4_RX_DP(13)    I74 @S9S_MB_2U_LIB.S9S_MB_2U(SCH_1):PAGE148
    E5    GND @S9S_MB_2U_LIB.S9S_MB_2U(SCH_1):GND    I74 @S9S_MB_2U_LIB.S9S_MB_2U(SCH_1):PAGE148
    F8 P5E_CPU1_PE4_RX_DN<15> @S9S_MB_2U_LIB.S9S_MB_2U(SCH_1):P5E_CPU1_PE4_RX_DN(15)    I74 @S9S_MB_2U_LIB.S9S_MB_2U(SCH_1):PAGE148
    F7 P5E_CPU1_PE4_RX_DN<14> @S9S_MB_2U_LIB.S9S_MB_2U(SCH_1):P5E_CPU1_PE4_RX_DN(14)    I74 @S9S_MB_2U_LIB.S9S_MB_2U(SCH_1):PAGE148
    F6 P5E_CPU1_PE4_RX_DN<13> @S9S_MB_2U_LIB.S9S_MB_2U(SCH_1):P5E_CPU1_PE4_RX_DN(13)    I74 @S9S_MB_2U_LIB.S9S_MB_2U(SCH_1):PAGE148
    F5 P5E_CPU1_PE4_RX_DN<12> @S9S_MB_2U_LIB.S9S_MB_2U(SCH_1):P5E_CPU1_PE4_RX_DN(12)    I74 @S9S_MB_2U_LIB.S9S_MB_2U(SCH_1):PAGE148
    G8    GND @S9S_MB_2U_LIB.S9S_MB_2U(SCH_1):GND    I74 @S9S_MB_2U_LIB.S9S_MB_2U(SCH_1):PAGE148
    G7 P5E_CPU1_PE4_RX_DP<14> @S9S_MB_2U_LIB.S9S_MB_2U(SCH_1):P5E_CPU1_PE4_RX_DP(14)    I74 @S9S_MB_2U_LIB.S9S_MB_2U(SCH_1):PAGE148
    G6    GND @S9S_MB_2U_LIB.S9S_MB_2U(SCH_1):GND    I74 @S9S_MB_2U_LIB.S9S_MB_2U(SCH_1):PAGE148
    G5 P5E_CPU1_PE4_RX_DP<12> @S9S_MB_2U_LIB.S9S_MB_2U(SCH_1):P5E_CPU1_PE4_RX_DP(12)    I74 @S9S_MB_2U_LIB.S9S_MB_2U(SCH_1):PAGE148
    H8 P5E_CPU1_PE0_TX_C_DN<0> @S9S_MB_2U_LIB.S9S_MB_2U(SCH_1):P5E_CPU1_PE0_TX_C_DN(0)    I74 @S9S_MB_2U_LIB.S9S_MB_2U(SCH_1):PAGE148
    H7    GND @S9S_MB_2U_LIB.S9S_MB_2U(SCH_1):GND    I74 @S9S_MB_2U_LIB.S9S_MB_2U(SCH_1):PAGE148
    H6 P5E_CPU1_PE0_TX_C_DN<2> @S9S_MB_2U_LIB.S9S_MB_2U(SCH_1):P5E_CPU1_PE0_TX_C_DN(2)    I74 @S9S_MB_2U_LIB.S9S_MB_2U(SCH_1):PAGE148
    H5    GND @S9S_MB_2U_LIB.S9S_MB_2U(SCH_1):GND    I74 @S9S_MB_2U_LIB.S9S_MB_2U(SCH_1):PAGE148
    I8 P5E_CPU1_PE0_TX_C_DP<0> @S9S_MB_2U_LIB.S9S_MB_2U(SCH_1):P5E_CPU1_PE0_TX_C_DP(0)    I74 @S9S_MB_2U_LIB.S9S_MB_2U(SCH_1):PAGE148
    I7 P5E_CPU1_PE0_TX_C_DN<1> @S9S_MB_2U_LIB.S9S_MB_2U(SCH_1):P5E_CPU1_PE0_TX_C_DN(1)    I74 @S9S_MB_2U_LIB.S9S_MB_2U(SCH_1):PAGE148
    I6 P5E_CPU1_PE0_TX_C_DP<2> @S9S_MB_2U_LIB.S9S_MB_2U(SCH_1):P5E_CPU1_PE0_TX_C_DP(2)    I74 @S9S_MB_2U_LIB.S9S_MB_2U(SCH_1):PAGE148
    I5 P5E_CPU1_PE0_TX_C_DN<3> @S9S_MB_2U_LIB.S9S_MB_2U(SCH_1):P5E_CPU1_PE0_TX_C_DN(3)    I74 @S9S_MB_2U_LIB.S9S_MB_2U(SCH_1):PAGE148
    J8    GND @S9S_MB_2U_LIB.S9S_MB_2U(SCH_1):GND    I74 @S9S_MB_2U_LIB.S9S_MB_2U(SCH_1):PAGE148
    J7 P5E_CPU1_PE0_TX_C_DP<1> @S9S_MB_2U_LIB.S9S_MB_2U(SCH_1):P5E_CPU1_PE0_TX_C_DP(1)    I74 @S9S_MB_2U_LIB.S9S_MB_2U(SCH_1):PAGE148
    J6    GND @S9S_MB_2U_LIB.S9S_MB_2U(SCH_1):GND    I74 @S9S_MB_2U_LIB.S9S_MB_2U(SCH_1):PAGE148
    J5 P5E_CPU1_PE0_TX_C_DP<3> @S9S_MB_2U_LIB.S9S_MB_2U(SCH_1):P5E_CPU1_PE0_TX_C_DP(3)    I74 @S9S_MB_2U_LIB.S9S_MB_2U(SCH_1):PAGE148
    K8 P5E_CPU1_PE4_TX_C_DN<15> @S9S_MB_2U_LIB.S9S_MB_2U(SCH_1):P5E_CPU1_PE4_TX_C_DN(15)    I74 @S9S_MB_2U_LIB.S9S_MB_2U(SCH_1):PAGE148
    K7    GND @S9S_MB_2U_LIB.S9S_MB_2U(SCH_1):GND    I74 @S9S_MB_2U_LIB.S9S_MB_2U(SCH_1):PAGE148
    K6 P5E_CPU1_PE4_TX_C_DN<13> @S9S_MB_2U_LIB.S9S_MB_2U(SCH_1):P5E_CPU1_PE4_TX_C_DN(13)    I74 @S9S_MB_2U_LIB.S9S_MB_2U(SCH_1):PAGE148
    K5    GND @S9S_MB_2U_LIB.S9S_MB_2U(SCH_1):GND    I74 @S9S_MB_2U_LIB.S9S_MB_2U(SCH_1):PAGE148
    L8 P5E_CPU1_PE4_TX_C_DP<15> @S9S_MB_2U_LIB.S9S_MB_2U(SCH_1):P5E_CPU1_PE4_TX_C_DP(15)    I74 @S9S_MB_2U_LIB.S9S_MB_2U(SCH_1):PAGE148
    L7 P5E_CPU1_PE4_TX_C_DN<14> @S9S_MB_2U_LIB.S9S_MB_2U(SCH_1):P5E_CPU1_PE4_TX_C_DN(14)    I74 @S9S_MB_2U_LIB.S9S_MB_2U(SCH_1):PAGE148
    L6 P5E_CPU1_PE4_TX_C_DP<13> @S9S_MB_2U_LIB.S9S_MB_2U(SCH_1):P5E_CPU1_PE4_TX_C_DP(13)    I74 @S9S_MB_2U_LIB.S9S_MB_2U(SCH_1):PAGE148
    L5 P5E_CPU1_PE4_TX_C_DN<12> @S9S_MB_2U_LIB.S9S_MB_2U(SCH_1):P5E_CPU1_PE4_TX_C_DN(12)    I74 @S9S_MB_2U_LIB.S9S_MB_2U(SCH_1):PAGE148
    M5 P5E_CPU1_PE4_TX_C_DP<12> @S9S_MB_2U_LIB.S9S_MB_2U(SCH_1):P5E_CPU1_PE4_TX_C_DP(12)    I74 @S9S_MB_2U_LIB.S9S_MB_2U(SCH_1):PAGE148
    N5    GND @S9S_MB_2U_LIB.S9S_MB_2U(SCH_1):GND    I74 @S9S_MB_2U_LIB.S9S_MB_2U(SCH_1):PAGE148
    M6    GND @S9S_MB_2U_LIB.S9S_MB_2U(SCH_1):GND    I74 @S9S_MB_2U_LIB.S9S_MB_2U(SCH_1):PAGE148
    N6 FM_GPU_PWRGD @S9S_MB_2U_LIB.S9S_MB_2U(SCH_1):FM_GPU_PWRGD    I74 @S9S_MB_2U_LIB.S9S_MB_2U(SCH_1):PAGE148
    M7 P5E_CPU1_PE4_TX_C_DP<14> @S9S_MB_2U_LIB.S9S_MB_2U(SCH_1):P5E_CPU1_PE4_TX_C_DP(14)    I74 @S9S_MB_2U_LIB.S9S_MB_2U(SCH_1):PAGE148
    N7    GND @S9S_MB_2U_LIB.S9S_MB_2U(SCH_1):GND    I74 @S9S_MB_2U_LIB.S9S_MB_2U(SCH_1):PAGE148
    M8    GND @S9S_MB_2U_LIB.S9S_MB_2U(SCH_1):GND    I74 @S9S_MB_2U_LIB.S9S_MB_2U(SCH_1):PAGE148
    N8 GPU_BASE_ID1 @S9S_MB_2U_LIB.S9S_MB_2U(SCH_1):GPU_BASE_ID1    I74 @S9S_MB_2U_LIB.S9S_MB_2U(SCH_1):PAGE148
    A4    GND @S9S_MB_2U_LIB.S9S_MB_2U(SCH_1):GND    I75 @S9S_MB_2U_LIB.S9S_MB_2U(SCH_1):PAGE148
    A3 GPU_BASE_ID0 @S9S_MB_2U_LIB.S9S_MB_2U(SCH_1):GPU_BASE_ID0    I75 @S9S_MB_2U_LIB.S9S_MB_2U(SCH_1):PAGE148
    A2    GND @S9S_MB_2U_LIB.S9S_MB_2U(SCH_1):GND    I75 @S9S_MB_2U_LIB.S9S_MB_2U(SCH_1):PAGE148
    A1 GPU_PEX_STRAP1 @S9S_MB_2U_LIB.S9S_MB_2U(SCH_1):GPU_PEX_STRAP1    I75 @S9S_MB_2U_LIB.S9S_MB_2U(SCH_1):PAGE148
    B4 P5E_CPU1_PE0_RX_DN<4> @S9S_MB_2U_LIB.S9S_MB_2U(SCH_1):P5E_CPU1_PE0_RX_DN(4)    I75 @S9S_MB_2U_LIB.S9S_MB_2U(SCH_1):PAGE148
    B3    GND @S9S_MB_2U_LIB.S9S_MB_2U(SCH_1):GND    I75 @S9S_MB_2U_LIB.S9S_MB_2U(SCH_1):PAGE148
    B2 P5E_CPU1_PE0_RX_DN<6> @S9S_MB_2U_LIB.S9S_MB_2U(SCH_1):P5E_CPU1_PE0_RX_DN(6)    I75 @S9S_MB_2U_LIB.S9S_MB_2U(SCH_1):PAGE148
    B1    GND @S9S_MB_2U_LIB.S9S_MB_2U(SCH_1):GND    I75 @S9S_MB_2U_LIB.S9S_MB_2U(SCH_1):PAGE148
    C4 P5E_CPU1_PE0_RX_DP<4> @S9S_MB_2U_LIB.S9S_MB_2U(SCH_1):P5E_CPU1_PE0_RX_DP(4)    I75 @S9S_MB_2U_LIB.S9S_MB_2U(SCH_1):PAGE148
    C3 P5E_CPU1_PE0_RX_DN<5> @S9S_MB_2U_LIB.S9S_MB_2U(SCH_1):P5E_CPU1_PE0_RX_DN(5)    I75 @S9S_MB_2U_LIB.S9S_MB_2U(SCH_1):PAGE148
    C2 P5E_CPU1_PE0_RX_DP<6> @S9S_MB_2U_LIB.S9S_MB_2U(SCH_1):P5E_CPU1_PE0_RX_DP(6)    I75 @S9S_MB_2U_LIB.S9S_MB_2U(SCH_1):PAGE148
    C1 P5E_CPU1_PE0_RX_DN<7> @S9S_MB_2U_LIB.S9S_MB_2U(SCH_1):P5E_CPU1_PE0_RX_DN(7)    I75 @S9S_MB_2U_LIB.S9S_MB_2U(SCH_1):PAGE148
    D4    GND @S9S_MB_2U_LIB.S9S_MB_2U(SCH_1):GND    I75 @S9S_MB_2U_LIB.S9S_MB_2U(SCH_1):PAGE148
    D3 P5E_CPU1_PE0_RX_DP<5> @S9S_MB_2U_LIB.S9S_MB_2U(SCH_1):P5E_CPU1_PE0_RX_DP(5)    I75 @S9S_MB_2U_LIB.S9S_MB_2U(SCH_1):PAGE148
    D2    GND @S9S_MB_2U_LIB.S9S_MB_2U(SCH_1):GND    I75 @S9S_MB_2U_LIB.S9S_MB_2U(SCH_1):PAGE148
    D1 P5E_CPU1_PE0_RX_DP<7> @S9S_MB_2U_LIB.S9S_MB_2U(SCH_1):P5E_CPU1_PE0_RX_DP(7)    I75 @S9S_MB_2U_LIB.S9S_MB_2U(SCH_1):PAGE148
    E4 P5E_CPU1_PE4_RX_DP<11> @S9S_MB_2U_LIB.S9S_MB_2U(SCH_1):P5E_CPU1_PE4_RX_DP(11)    I75 @S9S_MB_2U_LIB.S9S_MB_2U(SCH_1):PAGE148
    E3    GND @S9S_MB_2U_LIB.S9S_MB_2U(SCH_1):GND    I75 @S9S_MB_2U_LIB.S9S_MB_2U(SCH_1):PAGE148
    E2 P5E_CPU1_PE4_RX_DP<9> @S9S_MB_2U_LIB.S9S_MB_2U(SCH_1):P5E_CPU1_PE4_RX_DP(9)    I75 @S9S_MB_2U_LIB.S9S_MB_2U(SCH_1):PAGE148
    E1    GND @S9S_MB_2U_LIB.S9S_MB_2U(SCH_1):GND    I75 @S9S_MB_2U_LIB.S9S_MB_2U(SCH_1):PAGE148
    F4 P5E_CPU1_PE4_RX_DN<11> @S9S_MB_2U_LIB.S9S_MB_2U(SCH_1):P5E_CPU1_PE4_RX_DN(11)    I75 @S9S_MB_2U_LIB.S9S_MB_2U(SCH_1):PAGE148
    F3 P5E_CPU1_PE4_RX_DN<10> @S9S_MB_2U_LIB.S9S_MB_2U(SCH_1):P5E_CPU1_PE4_RX_DN(10)    I75 @S9S_MB_2U_LIB.S9S_MB_2U(SCH_1):PAGE148
    F2 P5E_CPU1_PE4_RX_DN<9> @S9S_MB_2U_LIB.S9S_MB_2U(SCH_1):P5E_CPU1_PE4_RX_DN(9)    I75 @S9S_MB_2U_LIB.S9S_MB_2U(SCH_1):PAGE148
    F1 P5E_CPU1_PE4_RX_DN<8> @S9S_MB_2U_LIB.S9S_MB_2U(SCH_1):P5E_CPU1_PE4_RX_DN(8)    I75 @S9S_MB_2U_LIB.S9S_MB_2U(SCH_1):PAGE148
    G4    GND @S9S_MB_2U_LIB.S9S_MB_2U(SCH_1):GND    I75 @S9S_MB_2U_LIB.S9S_MB_2U(SCH_1):PAGE148
    G3 P5E_CPU1_PE4_RX_DP<10> @S9S_MB_2U_LIB.S9S_MB_2U(SCH_1):P5E_CPU1_PE4_RX_DP(10)    I75 @S9S_MB_2U_LIB.S9S_MB_2U(SCH_1):PAGE148
    G2    GND @S9S_MB_2U_LIB.S9S_MB_2U(SCH_1):GND    I75 @S9S_MB_2U_LIB.S9S_MB_2U(SCH_1):PAGE148
    G1 P5E_CPU1_PE4_RX_DP<8> @S9S_MB_2U_LIB.S9S_MB_2U(SCH_1):P5E_CPU1_PE4_RX_DP(8)    I75 @S9S_MB_2U_LIB.S9S_MB_2U(SCH_1):PAGE148
    H4 P5E_CPU1_PE0_TX_C_DN<4> @S9S_MB_2U_LIB.S9S_MB_2U(SCH_1):P5E_CPU1_PE0_TX_C_DN(4)    I75 @S9S_MB_2U_LIB.S9S_MB_2U(SCH_1):PAGE148
    H3    GND @S9S_MB_2U_LIB.S9S_MB_2U(SCH_1):GND    I75 @S9S_MB_2U_LIB.S9S_MB_2U(SCH_1):PAGE148
    H2 P5E_CPU1_PE0_TX_C_DN<6> @S9S_MB_2U_LIB.S9S_MB_2U(SCH_1):P5E_CPU1_PE0_TX_C_DN(6)    I75 @S9S_MB_2U_LIB.S9S_MB_2U(SCH_1):PAGE148
    H1    GND @S9S_MB_2U_LIB.S9S_MB_2U(SCH_1):GND    I75 @S9S_MB_2U_LIB.S9S_MB_2U(SCH_1):PAGE148
    I4 P5E_CPU1_PE0_TX_C_DP<4> @S9S_MB_2U_LIB.S9S_MB_2U(SCH_1):P5E_CPU1_PE0_TX_C_DP(4)    I75 @S9S_MB_2U_LIB.S9S_MB_2U(SCH_1):PAGE148
    I3 P5E_CPU1_PE0_TX_C_DN<5> @S9S_MB_2U_LIB.S9S_MB_2U(SCH_1):P5E_CPU1_PE0_TX_C_DN(5)    I75 @S9S_MB_2U_LIB.S9S_MB_2U(SCH_1):PAGE148
    I2 P5E_CPU1_PE0_TX_C_DP<6> @S9S_MB_2U_LIB.S9S_MB_2U(SCH_1):P5E_CPU1_PE0_TX_C_DP(6)    I75 @S9S_MB_2U_LIB.S9S_MB_2U(SCH_1):PAGE148
    I1 P5E_CPU1_PE0_TX_C_DN<7> @S9S_MB_2U_LIB.S9S_MB_2U(SCH_1):P5E_CPU1_PE0_TX_C_DN(7)    I75 @S9S_MB_2U_LIB.S9S_MB_2U(SCH_1):PAGE148
    J4    GND @S9S_MB_2U_LIB.S9S_MB_2U(SCH_1):GND    I75 @S9S_MB_2U_LIB.S9S_MB_2U(SCH_1):PAGE148
    J3 P5E_CPU1_PE0_TX_C_DP<5> @S9S_MB_2U_LIB.S9S_MB_2U(SCH_1):P5E_CPU1_PE0_TX_C_DP(5)    I75 @S9S_MB_2U_LIB.S9S_MB_2U(SCH_1):PAGE148
    J2    GND @S9S_MB_2U_LIB.S9S_MB_2U(SCH_1):GND    I75 @S9S_MB_2U_LIB.S9S_MB_2U(SCH_1):PAGE148
    J1 P5E_CPU1_PE0_TX_C_DP<7> @S9S_MB_2U_LIB.S9S_MB_2U(SCH_1):P5E_CPU1_PE0_TX_C_DP(7)    I75 @S9S_MB_2U_LIB.S9S_MB_2U(SCH_1):PAGE148
    K4 P5E_CPU1_PE4_TX_C_DP<11> @S9S_MB_2U_LIB.S9S_MB_2U(SCH_1):P5E_CPU1_PE4_TX_C_DP(11)    I75 @S9S_MB_2U_LIB.S9S_MB_2U(SCH_1):PAGE148
    K3    GND @S9S_MB_2U_LIB.S9S_MB_2U(SCH_1):GND    I75 @S9S_MB_2U_LIB.S9S_MB_2U(SCH_1):PAGE148
    K2 P5E_CPU1_PE4_TX_C_DN<9> @S9S_MB_2U_LIB.S9S_MB_2U(SCH_1):P5E_CPU1_PE4_TX_C_DN(9)    I75 @S9S_MB_2U_LIB.S9S_MB_2U(SCH_1):PAGE148
    K1    GND @S9S_MB_2U_LIB.S9S_MB_2U(SCH_1):GND    I75 @S9S_MB_2U_LIB.S9S_MB_2U(SCH_1):PAGE148
    L4 P5E_CPU1_PE4_TX_C_DN<11> @S9S_MB_2U_LIB.S9S_MB_2U(SCH_1):P5E_CPU1_PE4_TX_C_DN(11)    I75 @S9S_MB_2U_LIB.S9S_MB_2U(SCH_1):PAGE148
    L3 P5E_CPU1_PE4_TX_C_DN<10> @S9S_MB_2U_LIB.S9S_MB_2U(SCH_1):P5E_CPU1_PE4_TX_C_DN(10)    I75 @S9S_MB_2U_LIB.S9S_MB_2U(SCH_1):PAGE148
    L2 P5E_CPU1_PE4_TX_C_DP<9> @S9S_MB_2U_LIB.S9S_MB_2U(SCH_1):P5E_CPU1_PE4_TX_C_DP(9)    I75 @S9S_MB_2U_LIB.S9S_MB_2U(SCH_1):PAGE148
    L1 P5E_CPU1_PE4_TX_C_DN<8> @S9S_MB_2U_LIB.S9S_MB_2U(SCH_1):P5E_CPU1_PE4_TX_C_DN(8)    I75 @S9S_MB_2U_LIB.S9S_MB_2U(SCH_1):PAGE148
    M1 P5E_CPU1_PE4_TX_C_DP<8> @S9S_MB_2U_LIB.S9S_MB_2U(SCH_1):P5E_CPU1_PE4_TX_C_DP(8)    I75 @S9S_MB_2U_LIB.S9S_MB_2U(SCH_1):PAGE148
    N1    GND @S9S_MB_2U_LIB.S9S_MB_2U(SCH_1):GND    I75 @S9S_MB_2U_LIB.S9S_MB_2U(SCH_1):PAGE148
    M2    GND @S9S_MB_2U_LIB.S9S_MB_2U(SCH_1):GND    I75 @S9S_MB_2U_LIB.S9S_MB_2U(SCH_1):PAGE148
    N2 GPU_PRSNT_N @S9S_MB_2U_LIB.S9S_MB_2U(SCH_1):GPU_PRSNT_N    I75 @S9S_MB_2U_LIB.S9S_MB_2U(SCH_1):PAGE148
    M3 P5E_CPU1_PE4_TX_C_DP<10> @S9S_MB_2U_LIB.S9S_MB_2U(SCH_1):P5E_CPU1_PE4_TX_C_DP(10)    I75 @S9S_MB_2U_LIB.S9S_MB_2U(SCH_1):PAGE148
    N3    GND @S9S_MB_2U_LIB.S9S_MB_2U(SCH_1):GND    I75 @S9S_MB_2U_LIB.S9S_MB_2U(SCH_1):PAGE148
    M4    GND @S9S_MB_2U_LIB.S9S_MB_2U(SCH_1):GND    I75 @S9S_MB_2U_LIB.S9S_MB_2U(SCH_1):PAGE148
    N4 FM_GPU_PWR_EN_R_BUF @S9S_MB_2U_LIB.S9S_MB_2U(SCH_1):FM_GPU_PWR_EN_R_BUF    I75 @S9S_MB_2U_LIB.S9S_MB_2U(SCH_1):PAGE148

J112 CONN160_10131762101LF-CONN160_A
    A8    GND @S9S_MB_2U_LIB.S9S_MB_2U(SCH_1):GND    I75 @S9S_MB_2U_LIB.S9S_MB_2U(SCH_1):PAGE149
    A7 PRSNT_SWB_N @S9S_MB_2U_LIB.S9S_MB_2U(SCH_1):PRSNT_SWB_N    I75 @S9S_MB_2U_LIB.S9S_MB_2U(SCH_1):PAGE149
    A6    GND @S9S_MB_2U_LIB.S9S_MB_2U(SCH_1):GND    I75 @S9S_MB_2U_LIB.S9S_MB_2U(SCH_1):PAGE149
    A5 RST_PERST_1_SWB_BUF_N @S9S_MB_2U_LIB.S9S_MB_2U(SCH_1):RST_PERST_1_SWB_BUF_N    I75 @S9S_MB_2U_LIB.S9S_MB_2U(SCH_1):PAGE149
    B8 P5E_CPU1_PE0_RX_DN<8> @S9S_MB_2U_LIB.S9S_MB_2U(SCH_1):P5E_CPU1_PE0_RX_DN(8)    I75 @S9S_MB_2U_LIB.S9S_MB_2U(SCH_1):PAGE149
    B7    GND @S9S_MB_2U_LIB.S9S_MB_2U(SCH_1):GND    I75 @S9S_MB_2U_LIB.S9S_MB_2U(SCH_1):PAGE149
    B6 P5E_CPU1_PE0_RX_DN<10> @S9S_MB_2U_LIB.S9S_MB_2U(SCH_1):P5E_CPU1_PE0_RX_DN(10)    I75 @S9S_MB_2U_LIB.S9S_MB_2U(SCH_1):PAGE149
    B5    GND @S9S_MB_2U_LIB.S9S_MB_2U(SCH_1):GND    I75 @S9S_MB_2U_LIB.S9S_MB_2U(SCH_1):PAGE149
    C8 P5E_CPU1_PE0_RX_DP<8> @S9S_MB_2U_LIB.S9S_MB_2U(SCH_1):P5E_CPU1_PE0_RX_DP(8)    I75 @S9S_MB_2U_LIB.S9S_MB_2U(SCH_1):PAGE149
    C7 P5E_CPU1_PE0_RX_DN<9> @S9S_MB_2U_LIB.S9S_MB_2U(SCH_1):P5E_CPU1_PE0_RX_DN(9)    I75 @S9S_MB_2U_LIB.S9S_MB_2U(SCH_1):PAGE149
    C6 P5E_CPU1_PE0_RX_DP<10> @S9S_MB_2U_LIB.S9S_MB_2U(SCH_1):P5E_CPU1_PE0_RX_DP(10)    I75 @S9S_MB_2U_LIB.S9S_MB_2U(SCH_1):PAGE149
    C5 P5E_CPU1_PE0_RX_DP<11> @S9S_MB_2U_LIB.S9S_MB_2U(SCH_1):P5E_CPU1_PE0_RX_DP(11)    I75 @S9S_MB_2U_LIB.S9S_MB_2U(SCH_1):PAGE149
    D8    GND @S9S_MB_2U_LIB.S9S_MB_2U(SCH_1):GND    I75 @S9S_MB_2U_LIB.S9S_MB_2U(SCH_1):PAGE149
    D7 P5E_CPU1_PE0_RX_DP<9> @S9S_MB_2U_LIB.S9S_MB_2U(SCH_1):P5E_CPU1_PE0_RX_DP(9)    I75 @S9S_MB_2U_LIB.S9S_MB_2U(SCH_1):PAGE149
    D6    GND @S9S_MB_2U_LIB.S9S_MB_2U(SCH_1):GND    I75 @S9S_MB_2U_LIB.S9S_MB_2U(SCH_1):PAGE149
    D5 P5E_CPU1_PE0_RX_DN<11> @S9S_MB_2U_LIB.S9S_MB_2U(SCH_1):P5E_CPU1_PE0_RX_DN(11)    I75 @S9S_MB_2U_LIB.S9S_MB_2U(SCH_1):PAGE149
    E8 P5E_CPU1_PE4_RX_DP<7> @S9S_MB_2U_LIB.S9S_MB_2U(SCH_1):P5E_CPU1_PE4_RX_DP(7)    I75 @S9S_MB_2U_LIB.S9S_MB_2U(SCH_1):PAGE149
    E7    GND @S9S_MB_2U_LIB.S9S_MB_2U(SCH_1):GND    I75 @S9S_MB_2U_LIB.S9S_MB_2U(SCH_1):PAGE149
    E6 P5E_CPU1_PE4_RX_DP<5> @S9S_MB_2U_LIB.S9S_MB_2U(SCH_1):P5E_CPU1_PE4_RX_DP(5)    I75 @S9S_MB_2U_LIB.S9S_MB_2U(SCH_1):PAGE149
    E5    GND @S9S_MB_2U_LIB.S9S_MB_2U(SCH_1):GND    I75 @S9S_MB_2U_LIB.S9S_MB_2U(SCH_1):PAGE149
    F8 P5E_CPU1_PE4_RX_DN<7> @S9S_MB_2U_LIB.S9S_MB_2U(SCH_1):P5E_CPU1_PE4_RX_DN(7)    I75 @S9S_MB_2U_LIB.S9S_MB_2U(SCH_1):PAGE149
    F7 P5E_CPU1_PE4_RX_DN<6> @S9S_MB_2U_LIB.S9S_MB_2U(SCH_1):P5E_CPU1_PE4_RX_DN(6)    I75 @S9S_MB_2U_LIB.S9S_MB_2U(SCH_1):PAGE149
    F6 P5E_CPU1_PE4_RX_DN<5> @S9S_MB_2U_LIB.S9S_MB_2U(SCH_1):P5E_CPU1_PE4_RX_DN(5)    I75 @S9S_MB_2U_LIB.S9S_MB_2U(SCH_1):PAGE149
    F5 P5E_CPU1_PE4_RX_DN<4> @S9S_MB_2U_LIB.S9S_MB_2U(SCH_1):P5E_CPU1_PE4_RX_DN(4)    I75 @S9S_MB_2U_LIB.S9S_MB_2U(SCH_1):PAGE149
    G8    GND @S9S_MB_2U_LIB.S9S_MB_2U(SCH_1):GND    I75 @S9S_MB_2U_LIB.S9S_MB_2U(SCH_1):PAGE149
    G7 P5E_CPU1_PE4_RX_DP<6> @S9S_MB_2U_LIB.S9S_MB_2U(SCH_1):P5E_CPU1_PE4_RX_DP(6)    I75 @S9S_MB_2U_LIB.S9S_MB_2U(SCH_1):PAGE149
    G6    GND @S9S_MB_2U_LIB.S9S_MB_2U(SCH_1):GND    I75 @S9S_MB_2U_LIB.S9S_MB_2U(SCH_1):PAGE149
    G5 P5E_CPU1_PE4_RX_DP<4> @S9S_MB_2U_LIB.S9S_MB_2U(SCH_1):P5E_CPU1_PE4_RX_DP(4)    I75 @S9S_MB_2U_LIB.S9S_MB_2U(SCH_1):PAGE149
    H8 P5E_CPU1_PE0_TX_C_DN<8> @S9S_MB_2U_LIB.S9S_MB_2U(SCH_1):P5E_CPU1_PE0_TX_C_DN(8)    I75 @S9S_MB_2U_LIB.S9S_MB_2U(SCH_1):PAGE149
    H7    GND @S9S_MB_2U_LIB.S9S_MB_2U(SCH_1):GND    I75 @S9S_MB_2U_LIB.S9S_MB_2U(SCH_1):PAGE149
    H6 P5E_CPU1_PE0_TX_C_DN<10> @S9S_MB_2U_LIB.S9S_MB_2U(SCH_1):P5E_CPU1_PE0_TX_C_DN(10)    I75 @S9S_MB_2U_LIB.S9S_MB_2U(SCH_1):PAGE149
    H5    GND @S9S_MB_2U_LIB.S9S_MB_2U(SCH_1):GND    I75 @S9S_MB_2U_LIB.S9S_MB_2U(SCH_1):PAGE149
    I8 P5E_CPU1_PE0_TX_C_DP<8> @S9S_MB_2U_LIB.S9S_MB_2U(SCH_1):P5E_CPU1_PE0_TX_C_DP(8)    I75 @S9S_MB_2U_LIB.S9S_MB_2U(SCH_1):PAGE149
    I7 P5E_CPU1_PE0_TX_C_DN<9> @S9S_MB_2U_LIB.S9S_MB_2U(SCH_1):P5E_CPU1_PE0_TX_C_DN(9)    I75 @S9S_MB_2U_LIB.S9S_MB_2U(SCH_1):PAGE149
    I6 P5E_CPU1_PE0_TX_C_DP<10> @S9S_MB_2U_LIB.S9S_MB_2U(SCH_1):P5E_CPU1_PE0_TX_C_DP(10)    I75 @S9S_MB_2U_LIB.S9S_MB_2U(SCH_1):PAGE149
    I5 P5E_CPU1_PE0_TX_C_DN<11> @S9S_MB_2U_LIB.S9S_MB_2U(SCH_1):P5E_CPU1_PE0_TX_C_DN(11)    I75 @S9S_MB_2U_LIB.S9S_MB_2U(SCH_1):PAGE149
    J8    GND @S9S_MB_2U_LIB.S9S_MB_2U(SCH_1):GND    I75 @S9S_MB_2U_LIB.S9S_MB_2U(SCH_1):PAGE149
    J7 P5E_CPU1_PE0_TX_C_DP<9> @S9S_MB_2U_LIB.S9S_MB_2U(SCH_1):P5E_CPU1_PE0_TX_C_DP(9)    I75 @S9S_MB_2U_LIB.S9S_MB_2U(SCH_1):PAGE149
    J6    GND @S9S_MB_2U_LIB.S9S_MB_2U(SCH_1):GND    I75 @S9S_MB_2U_LIB.S9S_MB_2U(SCH_1):PAGE149
    J5 P5E_CPU1_PE0_TX_C_DP<11> @S9S_MB_2U_LIB.S9S_MB_2U(SCH_1):P5E_CPU1_PE0_TX_C_DP(11)    I75 @S9S_MB_2U_LIB.S9S_MB_2U(SCH_1):PAGE149
    K8 P5E_CPU1_PE4_TX_C_DN<7> @S9S_MB_2U_LIB.S9S_MB_2U(SCH_1):P5E_CPU1_PE4_TX_C_DN(7)    I75 @S9S_MB_2U_LIB.S9S_MB_2U(SCH_1):PAGE149
    K7    GND @S9S_MB_2U_LIB.S9S_MB_2U(SCH_1):GND    I75 @S9S_MB_2U_LIB.S9S_MB_2U(SCH_1):PAGE149
    K6 P5E_CPU1_PE4_TX_C_DN<5> @S9S_MB_2U_LIB.S9S_MB_2U(SCH_1):P5E_CPU1_PE4_TX_C_DN(5)    I75 @S9S_MB_2U_LIB.S9S_MB_2U(SCH_1):PAGE149
    K5    GND @S9S_MB_2U_LIB.S9S_MB_2U(SCH_1):GND    I75 @S9S_MB_2U_LIB.S9S_MB_2U(SCH_1):PAGE149
    L8 P5E_CPU1_PE4_TX_C_DP<7> @S9S_MB_2U_LIB.S9S_MB_2U(SCH_1):P5E_CPU1_PE4_TX_C_DP(7)    I75 @S9S_MB_2U_LIB.S9S_MB_2U(SCH_1):PAGE149
    L7 P5E_CPU1_PE4_TX_C_DN<6> @S9S_MB_2U_LIB.S9S_MB_2U(SCH_1):P5E_CPU1_PE4_TX_C_DN(6)    I75 @S9S_MB_2U_LIB.S9S_MB_2U(SCH_1):PAGE149
    L6 P5E_CPU1_PE4_TX_C_DP<5> @S9S_MB_2U_LIB.S9S_MB_2U(SCH_1):P5E_CPU1_PE4_TX_C_DP(5)    I75 @S9S_MB_2U_LIB.S9S_MB_2U(SCH_1):PAGE149
    L5 P5E_CPU1_PE4_TX_C_DN<4> @S9S_MB_2U_LIB.S9S_MB_2U(SCH_1):P5E_CPU1_PE4_TX_C_DN(4)    I75 @S9S_MB_2U_LIB.S9S_MB_2U(SCH_1):PAGE149
    M5 P5E_CPU1_PE4_TX_C_DP<4> @S9S_MB_2U_LIB.S9S_MB_2U(SCH_1):P5E_CPU1_PE4_TX_C_DP(4)    I75 @S9S_MB_2U_LIB.S9S_MB_2U(SCH_1):PAGE149
    N5    GND @S9S_MB_2U_LIB.S9S_MB_2U(SCH_1):GND    I75 @S9S_MB_2U_LIB.S9S_MB_2U(SCH_1):PAGE149
    M6    GND @S9S_MB_2U_LIB.S9S_MB_2U(SCH_1):GND    I75 @S9S_MB_2U_LIB.S9S_MB_2U(SCH_1):PAGE149
    N6 P2E_MB_BMC_RX_DN<0> @S9S_MB_2U_LIB.S9S_MB_2U(SCH_1):P2E_MB_BMC_RX_DN(0)    I75 @S9S_MB_2U_LIB.S9S_MB_2U(SCH_1):PAGE149
    M7 P5E_CPU1_PE4_TX_C_DP<6> @S9S_MB_2U_LIB.S9S_MB_2U(SCH_1):P5E_CPU1_PE4_TX_C_DP(6)    I75 @S9S_MB_2U_LIB.S9S_MB_2U(SCH_1):PAGE149
    N7    GND @S9S_MB_2U_LIB.S9S_MB_2U(SCH_1):GND    I75 @S9S_MB_2U_LIB.S9S_MB_2U(SCH_1):PAGE149
    M8    GND @S9S_MB_2U_LIB.S9S_MB_2U(SCH_1):GND    I75 @S9S_MB_2U_LIB.S9S_MB_2U(SCH_1):PAGE149
    N8 P3E_PCH_NVS_RX_DN<0> @S9S_MB_2U_LIB.S9S_MB_2U(SCH_1):P3E_PCH_NVS_RX_DN(0)    I75 @S9S_MB_2U_LIB.S9S_MB_2U(SCH_1):PAGE149
    O5 NC_J112_O5 @S9S_MB_2U_LIB.S9S_MB_2U(SCH_1):NC_J112_O5    I75 @S9S_MB_2U_LIB.S9S_MB_2U(SCH_1):PAGE149
    P5 NC_J112_P5 @S9S_MB_2U_LIB.S9S_MB_2U(SCH_1):NC_J112_P5    I75 @S9S_MB_2U_LIB.S9S_MB_2U(SCH_1):PAGE149
    Q5    GND @S9S_MB_2U_LIB.S9S_MB_2U(SCH_1):GND    I75 @S9S_MB_2U_LIB.S9S_MB_2U(SCH_1):PAGE149
    R5 NC_J112_R5 @S9S_MB_2U_LIB.S9S_MB_2U(SCH_1):NC_J112_R5    I75 @S9S_MB_2U_LIB.S9S_MB_2U(SCH_1):PAGE149
    S5 NC_J112_S5 @S9S_MB_2U_LIB.S9S_MB_2U(SCH_1):NC_J112_S5    I75 @S9S_MB_2U_LIB.S9S_MB_2U(SCH_1):PAGE149
    T5    GND @S9S_MB_2U_LIB.S9S_MB_2U(SCH_1):GND    I75 @S9S_MB_2U_LIB.S9S_MB_2U(SCH_1):PAGE149
    O6 P2E_MB_BMC_RX_DP<0> @S9S_MB_2U_LIB.S9S_MB_2U(SCH_1):P2E_MB_BMC_RX_DP(0)    I75 @S9S_MB_2U_LIB.S9S_MB_2U(SCH_1):PAGE149
    P6    GND @S9S_MB_2U_LIB.S9S_MB_2U(SCH_1):GND    I75 @S9S_MB_2U_LIB.S9S_MB_2U(SCH_1):PAGE149
    Q6 P2E_MB_BMC_TX_BUF_C_DN<0> @S9S_MB_2U_LIB.S9S_MB_2U(SCH_1):P2E_MB_BMC_TX_BUF_C_DN(0)    I75 @S9S_MB_2U_LIB.S9S_MB_2U(SCH_1):PAGE149
    R6 P2E_MB_BMC_TX_BUF_C_DP<0> @S9S_MB_2U_LIB.S9S_MB_2U(SCH_1):P2E_MB_BMC_TX_BUF_C_DP(0)    I75 @S9S_MB_2U_LIB.S9S_MB_2U(SCH_1):PAGE149
    S6    GND @S9S_MB_2U_LIB.S9S_MB_2U(SCH_1):GND    I75 @S9S_MB_2U_LIB.S9S_MB_2U(SCH_1):PAGE149
    T6 GPU_FPGA_THERM_OVERT_N @S9S_MB_2U_LIB.S9S_MB_2U(SCH_1):GPU_FPGA_THERM_OVERT_N    I75 @S9S_MB_2U_LIB.S9S_MB_2U(SCH_1):PAGE149
    O7 P3E_PCH_NVS_RX_DN<1> @S9S_MB_2U_LIB.S9S_MB_2U(SCH_1):P3E_PCH_NVS_RX_DN(1)    I75 @S9S_MB_2U_LIB.S9S_MB_2U(SCH_1):PAGE149
    P7 P3E_PCH_NVS_RX_DP<1> @S9S_MB_2U_LIB.S9S_MB_2U(SCH_1):P3E_PCH_NVS_RX_DP(1)    I75 @S9S_MB_2U_LIB.S9S_MB_2U(SCH_1):PAGE149
    Q7    GND @S9S_MB_2U_LIB.S9S_MB_2U(SCH_1):GND    I75 @S9S_MB_2U_LIB.S9S_MB_2U(SCH_1):PAGE149
    R7 P3E_PCH_NVS_TX_C_DN<1> @S9S_MB_2U_LIB.S9S_MB_2U(SCH_1):P3E_PCH_NVS_TX_C_DN(1)    I75 @S9S_MB_2U_LIB.S9S_MB_2U(SCH_1):PAGE149
    S7 P3E_PCH_NVS_TX_C_DP<1> @S9S_MB_2U_LIB.S9S_MB_2U(SCH_1):P3E_PCH_NVS_TX_C_DP(1)    I75 @S9S_MB_2U_LIB.S9S_MB_2U(SCH_1):PAGE149
    T7    GND @S9S_MB_2U_LIB.S9S_MB_2U(SCH_1):GND    I75 @S9S_MB_2U_LIB.S9S_MB_2U(SCH_1):PAGE149
    O8 P3E_PCH_NVS_RX_DP<0> @S9S_MB_2U_LIB.S9S_MB_2U(SCH_1):P3E_PCH_NVS_RX_DP(0)    I75 @S9S_MB_2U_LIB.S9S_MB_2U(SCH_1):PAGE149
    P8    GND @S9S_MB_2U_LIB.S9S_MB_2U(SCH_1):GND    I75 @S9S_MB_2U_LIB.S9S_MB_2U(SCH_1):PAGE149
    Q8 P3E_PCH_NVS_TX_C_DN<0> @S9S_MB_2U_LIB.S9S_MB_2U(SCH_1):P3E_PCH_NVS_TX_C_DN(0)    I75 @S9S_MB_2U_LIB.S9S_MB_2U(SCH_1):PAGE149
    R8 P3E_PCH_NVS_TX_C_DP<0> @S9S_MB_2U_LIB.S9S_MB_2U(SCH_1):P3E_PCH_NVS_TX_C_DP(0)    I75 @S9S_MB_2U_LIB.S9S_MB_2U(SCH_1):PAGE149
    S8    GND @S9S_MB_2U_LIB.S9S_MB_2U(SCH_1):GND    I75 @S9S_MB_2U_LIB.S9S_MB_2U(SCH_1):PAGE149
    T8 RST_PERST_0_SWB_BUF_N @S9S_MB_2U_LIB.S9S_MB_2U(SCH_1):RST_PERST_0_SWB_BUF_N    I75 @S9S_MB_2U_LIB.S9S_MB_2U(SCH_1):PAGE149
    A4    GND @S9S_MB_2U_LIB.S9S_MB_2U(SCH_1):GND    I76 @S9S_MB_2U_LIB.S9S_MB_2U(SCH_1):PAGE149
    A3 HGX_DETECT_N_ISO @S9S_MB_2U_LIB.S9S_MB_2U(SCH_1):HGX_DETECT_N_ISO    I76 @S9S_MB_2U_LIB.S9S_MB_2U(SCH_1):PAGE149
    A2    GND @S9S_MB_2U_LIB.S9S_MB_2U(SCH_1):GND    I76 @S9S_MB_2U_LIB.S9S_MB_2U(SCH_1):PAGE149
    A1 RST_PERST_2_SWB_BUF_N @S9S_MB_2U_LIB.S9S_MB_2U(SCH_1):RST_PERST_2_SWB_BUF_N    I76 @S9S_MB_2U_LIB.S9S_MB_2U(SCH_1):PAGE149
    B4 P5E_CPU1_PE0_RX_DN<12> @S9S_MB_2U_LIB.S9S_MB_2U(SCH_1):P5E_CPU1_PE0_RX_DN(12)    I76 @S9S_MB_2U_LIB.S9S_MB_2U(SCH_1):PAGE149
    B3    GND @S9S_MB_2U_LIB.S9S_MB_2U(SCH_1):GND    I76 @S9S_MB_2U_LIB.S9S_MB_2U(SCH_1):PAGE149
    B2 P5E_CPU1_PE0_RX_DN<14> @S9S_MB_2U_LIB.S9S_MB_2U(SCH_1):P5E_CPU1_PE0_RX_DN(14)    I76 @S9S_MB_2U_LIB.S9S_MB_2U(SCH_1):PAGE149
    B1    GND @S9S_MB_2U_LIB.S9S_MB_2U(SCH_1):GND    I76 @S9S_MB_2U_LIB.S9S_MB_2U(SCH_1):PAGE149
    C4 P5E_CPU1_PE0_RX_DP<12> @S9S_MB_2U_LIB.S9S_MB_2U(SCH_1):P5E_CPU1_PE0_RX_DP(12)    I76 @S9S_MB_2U_LIB.S9S_MB_2U(SCH_1):PAGE149
    C3 P5E_CPU1_PE0_RX_DN<13> @S9S_MB_2U_LIB.S9S_MB_2U(SCH_1):P5E_CPU1_PE0_RX_DN(13)    I76 @S9S_MB_2U_LIB.S9S_MB_2U(SCH_1):PAGE149
    C2 P5E_CPU1_PE0_RX_DP<14> @S9S_MB_2U_LIB.S9S_MB_2U(SCH_1):P5E_CPU1_PE0_RX_DP(14)    I76 @S9S_MB_2U_LIB.S9S_MB_2U(SCH_1):PAGE149
    C1 P5E_CPU1_PE0_RX_DN<15> @S9S_MB_2U_LIB.S9S_MB_2U(SCH_1):P5E_CPU1_PE0_RX_DN(15)    I76 @S9S_MB_2U_LIB.S9S_MB_2U(SCH_1):PAGE149
    D4    GND @S9S_MB_2U_LIB.S9S_MB_2U(SCH_1):GND    I76 @S9S_MB_2U_LIB.S9S_MB_2U(SCH_1):PAGE149
    D3 P5E_CPU1_PE0_RX_DP<13> @S9S_MB_2U_LIB.S9S_MB_2U(SCH_1):P5E_CPU1_PE0_RX_DP(13)    I76 @S9S_MB_2U_LIB.S9S_MB_2U(SCH_1):PAGE149
    D2    GND @S9S_MB_2U_LIB.S9S_MB_2U(SCH_1):GND    I76 @S9S_MB_2U_LIB.S9S_MB_2U(SCH_1):PAGE149
    D1 P5E_CPU1_PE0_RX_DP<15> @S9S_MB_2U_LIB.S9S_MB_2U(SCH_1):P5E_CPU1_PE0_RX_DP(15)    I76 @S9S_MB_2U_LIB.S9S_MB_2U(SCH_1):PAGE149
    E4 P5E_CPU1_PE4_RX_DP<3> @S9S_MB_2U_LIB.S9S_MB_2U(SCH_1):P5E_CPU1_PE4_RX_DP(3)    I76 @S9S_MB_2U_LIB.S9S_MB_2U(SCH_1):PAGE149
    E3    GND @S9S_MB_2U_LIB.S9S_MB_2U(SCH_1):GND    I76 @S9S_MB_2U_LIB.S9S_MB_2U(SCH_1):PAGE149
    E2 P5E_CPU1_PE4_RX_DP<1> @S9S_MB_2U_LIB.S9S_MB_2U(SCH_1):P5E_CPU1_PE4_RX_DP(1)    I76 @S9S_MB_2U_LIB.S9S_MB_2U(SCH_1):PAGE149
    E1    GND @S9S_MB_2U_LIB.S9S_MB_2U(SCH_1):GND    I76 @S9S_MB_2U_LIB.S9S_MB_2U(SCH_1):PAGE149
    F4 P5E_CPU1_PE4_RX_DN<3> @S9S_MB_2U_LIB.S9S_MB_2U(SCH_1):P5E_CPU1_PE4_RX_DN(3)    I76 @S9S_MB_2U_LIB.S9S_MB_2U(SCH_1):PAGE149
    F3 P5E_CPU1_PE4_RX_DN<2> @S9S_MB_2U_LIB.S9S_MB_2U(SCH_1):P5E_CPU1_PE4_RX_DN(2)    I76 @S9S_MB_2U_LIB.S9S_MB_2U(SCH_1):PAGE149
    F2 P5E_CPU1_PE4_RX_DN<1> @S9S_MB_2U_LIB.S9S_MB_2U(SCH_1):P5E_CPU1_PE4_RX_DN(1)    I76 @S9S_MB_2U_LIB.S9S_MB_2U(SCH_1):PAGE149
    F1 P5E_CPU1_PE4_RX_DN<0> @S9S_MB_2U_LIB.S9S_MB_2U(SCH_1):P5E_CPU1_PE4_RX_DN(0)    I76 @S9S_MB_2U_LIB.S9S_MB_2U(SCH_1):PAGE149
    G4    GND @S9S_MB_2U_LIB.S9S_MB_2U(SCH_1):GND    I76 @S9S_MB_2U_LIB.S9S_MB_2U(SCH_1):PAGE149
    G3 P5E_CPU1_PE4_RX_DP<2> @S9S_MB_2U_LIB.S9S_MB_2U(SCH_1):P5E_CPU1_PE4_RX_DP(2)    I76 @S9S_MB_2U_LIB.S9S_MB_2U(SCH_1):PAGE149
    G2    GND @S9S_MB_2U_LIB.S9S_MB_2U(SCH_1):GND    I76 @S9S_MB_2U_LIB.S9S_MB_2U(SCH_1):PAGE149
    G1 P5E_CPU1_PE4_RX_DP<0> @S9S_MB_2U_LIB.S9S_MB_2U(SCH_1):P5E_CPU1_PE4_RX_DP(0)    I76 @S9S_MB_2U_LIB.S9S_MB_2U(SCH_1):PAGE149
    H4 P5E_CPU1_PE0_TX_C_DN<12> @S9S_MB_2U_LIB.S9S_MB_2U(SCH_1):P5E_CPU1_PE0_TX_C_DN(12)    I76 @S9S_MB_2U_LIB.S9S_MB_2U(SCH_1):PAGE149
    H3    GND @S9S_MB_2U_LIB.S9S_MB_2U(SCH_1):GND    I76 @S9S_MB_2U_LIB.S9S_MB_2U(SCH_1):PAGE149
    H2 P5E_CPU1_PE0_TX_C_DN<14> @S9S_MB_2U_LIB.S9S_MB_2U(SCH_1):P5E_CPU1_PE0_TX_C_DN(14)    I76 @S9S_MB_2U_LIB.S9S_MB_2U(SCH_1):PAGE149
    H1    GND @S9S_MB_2U_LIB.S9S_MB_2U(SCH_1):GND    I76 @S9S_MB_2U_LIB.S9S_MB_2U(SCH_1):PAGE149
    I4 P5E_CPU1_PE0_TX_C_DP<12> @S9S_MB_2U_LIB.S9S_MB_2U(SCH_1):P5E_CPU1_PE0_TX_C_DP(12)    I76 @S9S_MB_2U_LIB.S9S_MB_2U(SCH_1):PAGE149
    I3 P5E_CPU1_PE0_TX_C_DN<13> @S9S_MB_2U_LIB.S9S_MB_2U(SCH_1):P5E_CPU1_PE0_TX_C_DN(13)    I76 @S9S_MB_2U_LIB.S9S_MB_2U(SCH_1):PAGE149
    I2 P5E_CPU1_PE0_TX_C_DP<14> @S9S_MB_2U_LIB.S9S_MB_2U(SCH_1):P5E_CPU1_PE0_TX_C_DP(14)    I76 @S9S_MB_2U_LIB.S9S_MB_2U(SCH_1):PAGE149
    I1 P5E_CPU1_PE0_TX_C_DN<15> @S9S_MB_2U_LIB.S9S_MB_2U(SCH_1):P5E_CPU1_PE0_TX_C_DN(15)    I76 @S9S_MB_2U_LIB.S9S_MB_2U(SCH_1):PAGE149
    J4    GND @S9S_MB_2U_LIB.S9S_MB_2U(SCH_1):GND    I76 @S9S_MB_2U_LIB.S9S_MB_2U(SCH_1):PAGE149
    J3 P5E_CPU1_PE0_TX_C_DP<13> @S9S_MB_2U_LIB.S9S_MB_2U(SCH_1):P5E_CPU1_PE0_TX_C_DP(13)    I76 @S9S_MB_2U_LIB.S9S_MB_2U(SCH_1):PAGE149
    J2    GND @S9S_MB_2U_LIB.S9S_MB_2U(SCH_1):GND    I76 @S9S_MB_2U_LIB.S9S_MB_2U(SCH_1):PAGE149
    J1 P5E_CPU1_PE0_TX_C_DP<15> @S9S_MB_2U_LIB.S9S_MB_2U(SCH_1):P5E_CPU1_PE0_TX_C_DP(15)    I76 @S9S_MB_2U_LIB.S9S_MB_2U(SCH_1):PAGE149
    K4 P5E_CPU1_PE4_TX_C_DN<3> @S9S_MB_2U_LIB.S9S_MB_2U(SCH_1):P5E_CPU1_PE4_TX_C_DN(3)    I76 @S9S_MB_2U_LIB.S9S_MB_2U(SCH_1):PAGE149
    K3    GND @S9S_MB_2U_LIB.S9S_MB_2U(SCH_1):GND    I76 @S9S_MB_2U_LIB.S9S_MB_2U(SCH_1):PAGE149
    K2 P5E_CPU1_PE4_TX_C_DP<1> @S9S_MB_2U_LIB.S9S_MB_2U(SCH_1):P5E_CPU1_PE4_TX_C_DP(1)    I76 @S9S_MB_2U_LIB.S9S_MB_2U(SCH_1):PAGE149
    K1    GND @S9S_MB_2U_LIB.S9S_MB_2U(SCH_1):GND    I76 @S9S_MB_2U_LIB.S9S_MB_2U(SCH_1):PAGE149
    L4 P5E_CPU1_PE4_TX_C_DP<3> @S9S_MB_2U_LIB.S9S_MB_2U(SCH_1):P5E_CPU1_PE4_TX_C_DP(3)    I76 @S9S_MB_2U_LIB.S9S_MB_2U(SCH_1):PAGE149
    L3 P5E_CPU1_PE4_TX_C_DN<2> @S9S_MB_2U_LIB.S9S_MB_2U(SCH_1):P5E_CPU1_PE4_TX_C_DN(2)    I76 @S9S_MB_2U_LIB.S9S_MB_2U(SCH_1):PAGE149
    L2 P5E_CPU1_PE4_TX_C_DN<1> @S9S_MB_2U_LIB.S9S_MB_2U(SCH_1):P5E_CPU1_PE4_TX_C_DN(1)    I76 @S9S_MB_2U_LIB.S9S_MB_2U(SCH_1):PAGE149
    L1 P5E_CPU1_PE4_TX_C_DN<0> @S9S_MB_2U_LIB.S9S_MB_2U(SCH_1):P5E_CPU1_PE4_TX_C_DN(0)    I76 @S9S_MB_2U_LIB.S9S_MB_2U(SCH_1):PAGE149
    M1 P5E_CPU1_PE4_TX_C_DP<0> @S9S_MB_2U_LIB.S9S_MB_2U(SCH_1):P5E_CPU1_PE4_TX_C_DP(0)    I76 @S9S_MB_2U_LIB.S9S_MB_2U(SCH_1):PAGE149
    N1    GND @S9S_MB_2U_LIB.S9S_MB_2U(SCH_1):GND    I76 @S9S_MB_2U_LIB.S9S_MB_2U(SCH_1):PAGE149
    M2    GND @S9S_MB_2U_LIB.S9S_MB_2U(SCH_1):GND    I76 @S9S_MB_2U_LIB.S9S_MB_2U(SCH_1):PAGE149
    N2 NC_J112_N2 @S9S_MB_2U_LIB.S9S_MB_2U(SCH_1):NC_J112_N2    I76 @S9S_MB_2U_LIB.S9S_MB_2U(SCH_1):PAGE149
    M3 P5E_CPU1_PE4_TX_C_DP<2> @S9S_MB_2U_LIB.S9S_MB_2U(SCH_1):P5E_CPU1_PE4_TX_C_DP(2)    I76 @S9S_MB_2U_LIB.S9S_MB_2U(SCH_1):PAGE149
    N3    GND @S9S_MB_2U_LIB.S9S_MB_2U(SCH_1):GND    I76 @S9S_MB_2U_LIB.S9S_MB_2U(SCH_1):PAGE149
    M4    GND @S9S_MB_2U_LIB.S9S_MB_2U(SCH_1):GND    I76 @S9S_MB_2U_LIB.S9S_MB_2U(SCH_1):PAGE149
    N4 CLK_100M_GPU_1_DN @S9S_MB_2U_LIB.S9S_MB_2U(SCH_1):CLK_100M_GPU_1_DN    I76 @S9S_MB_2U_LIB.S9S_MB_2U(SCH_1):PAGE149
    O1 CLK_100M_GPU_2_DN @S9S_MB_2U_LIB.S9S_MB_2U(SCH_1):CLK_100M_GPU_2_DN    I76 @S9S_MB_2U_LIB.S9S_MB_2U(SCH_1):PAGE149
    P1 CLK_100M_GPU_2_DP @S9S_MB_2U_LIB.S9S_MB_2U(SCH_1):CLK_100M_GPU_2_DP    I76 @S9S_MB_2U_LIB.S9S_MB_2U(SCH_1):PAGE149
    Q1    GND @S9S_MB_2U_LIB.S9S_MB_2U(SCH_1):GND    I76 @S9S_MB_2U_LIB.S9S_MB_2U(SCH_1):PAGE149
    R1 USB2_HUB_BUF_SWB_DN @S9S_MB_2U_LIB.S9S_MB_2U(SCH_1):USB2_HUB_BUF_SWB_DN    I76 @S9S_MB_2U_LIB.S9S_MB_2U(SCH_1):PAGE149
    S1 USB2_HUB_BUF_SWB_DP @S9S_MB_2U_LIB.S9S_MB_2U(SCH_1):USB2_HUB_BUF_SWB_DP    I76 @S9S_MB_2U_LIB.S9S_MB_2U(SCH_1):PAGE149
    T1    GND @S9S_MB_2U_LIB.S9S_MB_2U(SCH_1):GND    I76 @S9S_MB_2U_LIB.S9S_MB_2U(SCH_1):PAGE149
    O2 NC_J112_O2 @S9S_MB_2U_LIB.S9S_MB_2U(SCH_1):NC_J112_O2    I76 @S9S_MB_2U_LIB.S9S_MB_2U(SCH_1):PAGE149
    P2    GND @S9S_MB_2U_LIB.S9S_MB_2U(SCH_1):GND    I76 @S9S_MB_2U_LIB.S9S_MB_2U(SCH_1):PAGE149
    Q2 CLK_100M_GPU_FPGA_DN @S9S_MB_2U_LIB.S9S_MB_2U(SCH_1):CLK_100M_GPU_FPGA_DN    I76 @S9S_MB_2U_LIB.S9S_MB_2U(SCH_1):PAGE149
    R2 CLK_100M_GPU_FPGA_DP @S9S_MB_2U_LIB.S9S_MB_2U(SCH_1):CLK_100M_GPU_FPGA_DP    I76 @S9S_MB_2U_LIB.S9S_MB_2U(SCH_1):PAGE149
    S2    GND @S9S_MB_2U_LIB.S9S_MB_2U(SCH_1):GND    I76 @S9S_MB_2U_LIB.S9S_MB_2U(SCH_1):PAGE149
    T2 GPU_FPGA_READY @S9S_MB_2U_LIB.S9S_MB_2U(SCH_1):GPU_FPGA_READY    I76 @S9S_MB_2U_LIB.S9S_MB_2U(SCH_1):PAGE149
    O3 CLK_100M_SWB_DN @S9S_MB_2U_LIB.S9S_MB_2U(SCH_1):CLK_100M_SWB_DN    I76 @S9S_MB_2U_LIB.S9S_MB_2U(SCH_1):PAGE149
    P3 CLK_100M_SWB_DP @S9S_MB_2U_LIB.S9S_MB_2U(SCH_1):CLK_100M_SWB_DP    I76 @S9S_MB_2U_LIB.S9S_MB_2U(SCH_1):PAGE149
    Q3    GND @S9S_MB_2U_LIB.S9S_MB_2U(SCH_1):GND    I76 @S9S_MB_2U_LIB.S9S_MB_2U(SCH_1):PAGE149
    R3 SMB_2_BMC_GPU_BUF_SCL @S9S_MB_2U_LIB.S9S_MB_2U(SCH_1):SMB_2_BMC_GPU_BUF_SCL    I76 @S9S_MB_2U_LIB.S9S_MB_2U(SCH_1):PAGE149
    S3 SMB_2_BMC_GPU_BUF_SDA @S9S_MB_2U_LIB.S9S_MB_2U(SCH_1):SMB_2_BMC_GPU_BUF_SDA    I76 @S9S_MB_2U_LIB.S9S_MB_2U(SCH_1):PAGE149
    T3    GND @S9S_MB_2U_LIB.S9S_MB_2U(SCH_1):GND    I76 @S9S_MB_2U_LIB.S9S_MB_2U(SCH_1):PAGE149
    O4 CLK_100M_GPU_1_DP @S9S_MB_2U_LIB.S9S_MB_2U(SCH_1):CLK_100M_GPU_1_DP    I76 @S9S_MB_2U_LIB.S9S_MB_2U(SCH_1):PAGE149
    P4    GND @S9S_MB_2U_LIB.S9S_MB_2U(SCH_1):GND    I76 @S9S_MB_2U_LIB.S9S_MB_2U(SCH_1):PAGE149
    Q4 SMB_1_BMC_GPU_BUF_SCL @S9S_MB_2U_LIB.S9S_MB_2U(SCH_1):SMB_1_BMC_GPU_BUF_SCL    I76 @S9S_MB_2U_LIB.S9S_MB_2U(SCH_1):PAGE149
    R4 SMB_1_BMC_GPU_BUF_SDA @S9S_MB_2U_LIB.S9S_MB_2U(SCH_1):SMB_1_BMC_GPU_BUF_SDA    I76 @S9S_MB_2U_LIB.S9S_MB_2U(SCH_1):PAGE149
    S4    GND @S9S_MB_2U_LIB.S9S_MB_2U(SCH_1):GND    I76 @S9S_MB_2U_LIB.S9S_MB_2U(SCH_1):PAGE149
    T4 GPU_NVS_PWR_BRAKE_N_BUF @S9S_MB_2U_LIB.S9S_MB_2U(SCH_1):GPU_NVS_PWR_BRAKE_N_BUF    I76 @S9S_MB_2U_LIB.S9S_MB_2U(SCH_1):PAGE149

J114 PICOPROBE_BXA-DELTA-L 4.0,SMLFA
     2 DELTA_L_85_5INCH_IN5_DN @S9S_MB_2U_LIB.S9S_MB_2U(SCH_1):DELTA_L_85_5INCH_IN5_DN     I4 @S9S_MB_2U_LIB.S9S_MB_2U(SCH_1):PAGE287
     3 DELTA_L_GND_1 @S9S_MB_2U_LIB.S9S_MB_2U(SCH_1):DELTA_L_GND_1     I4 @S9S_MB_2U_LIB.S9S_MB_2U(SCH_1):PAGE287
     1 DELTA_L_85_5INCH_IN5_DP @S9S_MB_2U_LIB.S9S_MB_2U(SCH_1):DELTA_L_85_5INCH_IN5_DP     I4 @S9S_MB_2U_LIB.S9S_MB_2U(SCH_1):PAGE287

J115 PICOPROBE_BXA-DELTA-L 4.0,SMLFA
     2 DELTA_L_85_5INCH_IN6_DN @S9S_MB_2U_LIB.S9S_MB_2U(SCH_1):DELTA_L_85_5INCH_IN6_DN     I3 @S9S_MB_2U_LIB.S9S_MB_2U(SCH_1):PAGE287
     3 DELTA_L_GND_1 @S9S_MB_2U_LIB.S9S_MB_2U(SCH_1):DELTA_L_GND_1     I3 @S9S_MB_2U_LIB.S9S_MB_2U(SCH_1):PAGE287
     1 DELTA_L_85_5INCH_IN6_DP @S9S_MB_2U_LIB.S9S_MB_2U(SCH_1):DELTA_L_85_5INCH_IN6_DP     I3 @S9S_MB_2U_LIB.S9S_MB_2U(SCH_1):PAGE287

J116 PICOPROBE_BXA-DELTA-L 4.0,SMLFA
     2 DELTA_L_85_5INCH_IN5_DP @S9S_MB_2U_LIB.S9S_MB_2U(SCH_1):DELTA_L_85_5INCH_IN5_DP     I6 @S9S_MB_2U_LIB.S9S_MB_2U(SCH_1):PAGE287
     3 DELTA_L_GND_1 @S9S_MB_2U_LIB.S9S_MB_2U(SCH_1):DELTA_L_GND_1     I6 @S9S_MB_2U_LIB.S9S_MB_2U(SCH_1):PAGE287
     1 DELTA_L_85_5INCH_IN5_DN @S9S_MB_2U_LIB.S9S_MB_2U(SCH_1):DELTA_L_85_5INCH_IN5_DN     I6 @S9S_MB_2U_LIB.S9S_MB_2U(SCH_1):PAGE287

J117 PICOPROBE_BXA-DELTA-L 4.0,SMLFA
     2 DELTA_L_85_5INCH_IN6_DP @S9S_MB_2U_LIB.S9S_MB_2U(SCH_1):DELTA_L_85_5INCH_IN6_DP     I5 @S9S_MB_2U_LIB.S9S_MB_2U(SCH_1):PAGE287
     3 DELTA_L_GND_1 @S9S_MB_2U_LIB.S9S_MB_2U(SCH_1):DELTA_L_GND_1     I5 @S9S_MB_2U_LIB.S9S_MB_2U(SCH_1):PAGE287
     1 DELTA_L_85_5INCH_IN6_DN @S9S_MB_2U_LIB.S9S_MB_2U(SCH_1):DELTA_L_85_5INCH_IN6_DN     I5 @S9S_MB_2U_LIB.S9S_MB_2U(SCH_1):PAGE287

J118 PICOPROBE_BXA-DELTA-L 4.0,SMLFA
     2 DELTA_L_85_10INCH_IN5_DN @S9S_MB_2U_LIB.S9S_MB_2U(SCH_1):DELTA_L_85_10INCH_IN5_DN    I30 @S9S_MB_2U_LIB.S9S_MB_2U(SCH_1):PAGE287
     3 DELTA_L_GND_1 @S9S_MB_2U_LIB.S9S_MB_2U(SCH_1):DELTA_L_GND_1    I30 @S9S_MB_2U_LIB.S9S_MB_2U(SCH_1):PAGE287
     1 DELTA_L_85_10INCH_IN5_DP @S9S_MB_2U_LIB.S9S_MB_2U(SCH_1):DELTA_L_85_10INCH_IN5_DP    I30 @S9S_MB_2U_LIB.S9S_MB_2U(SCH_1):PAGE287

J119 PICOPROBE_BXA-DELTA-L 4.0,SMLFA
     2 DELTA_L_85_10INCH_IN6_DN @S9S_MB_2U_LIB.S9S_MB_2U(SCH_1):DELTA_L_85_10INCH_IN6_DN    I28 @S9S_MB_2U_LIB.S9S_MB_2U(SCH_1):PAGE287
     3 DELTA_L_GND_1 @S9S_MB_2U_LIB.S9S_MB_2U(SCH_1):DELTA_L_GND_1    I28 @S9S_MB_2U_LIB.S9S_MB_2U(SCH_1):PAGE287
     1 DELTA_L_85_10INCH_IN6_DP @S9S_MB_2U_LIB.S9S_MB_2U(SCH_1):DELTA_L_85_10INCH_IN6_DP    I28 @S9S_MB_2U_LIB.S9S_MB_2U(SCH_1):PAGE287

J120 PICOPROBE_BXA-DELTA-L 4.0,SMLFA
     2 DELTA_L_85_10INCH_IN5_DP @S9S_MB_2U_LIB.S9S_MB_2U(SCH_1):DELTA_L_85_10INCH_IN5_DP    I32 @S9S_MB_2U_LIB.S9S_MB_2U(SCH_1):PAGE287
     3 DELTA_L_GND_1 @S9S_MB_2U_LIB.S9S_MB_2U(SCH_1):DELTA_L_GND_1    I32 @S9S_MB_2U_LIB.S9S_MB_2U(SCH_1):PAGE287
     1 DELTA_L_85_10INCH_IN5_DN @S9S_MB_2U_LIB.S9S_MB_2U(SCH_1):DELTA_L_85_10INCH_IN5_DN    I32 @S9S_MB_2U_LIB.S9S_MB_2U(SCH_1):PAGE287

J121 PICOPROBE_BXA-DELTA-L 4.0,SMLFA
     2 DELTA_L_85_10INCH_IN6_DP @S9S_MB_2U_LIB.S9S_MB_2U(SCH_1):DELTA_L_85_10INCH_IN6_DP    I31 @S9S_MB_2U_LIB.S9S_MB_2U(SCH_1):PAGE287
     3 DELTA_L_GND_1 @S9S_MB_2U_LIB.S9S_MB_2U(SCH_1):DELTA_L_GND_1    I31 @S9S_MB_2U_LIB.S9S_MB_2U(SCH_1):PAGE287
     1 DELTA_L_85_10INCH_IN6_DN @S9S_MB_2U_LIB.S9S_MB_2U(SCH_1):DELTA_L_85_10INCH_IN6_DN    I31 @S9S_MB_2U_LIB.S9S_MB_2U(SCH_1):PAGE287

J122 CONN1_10165288101LF-CONN1_1016A
SCR_H1     NC     NC   I238 @S9S_MB_2U_LIB.S9S_MB_2U(SCH_1):PAGE289

J123 CONN1_10165288101LF-CONN1_1016A
SCR_H1     NC     NC   I239 @S9S_MB_2U_LIB.S9S_MB_2U(SCH_1):PAGE289

 JP4 CONN3_210HP1030BR1-CONN3_210-HA
     3 SMB_SML0_3V3AUX_PCH_SDA @S9S_MB_2U_LIB.S9S_MB_2U(SCH_1):SMB_SML0_3V3AUX_PCH_SDA   I256 @S9S_MB_2U_LIB.S9S_MB_2U(SCH_1):PAGE175
     2    GND @S9S_MB_2U_LIB.S9S_MB_2U(SCH_1):GND   I256 @S9S_MB_2U_LIB.S9S_MB_2U(SCH_1):PAGE175
     1 SMB_SML0_3V3AUX_PCH_SCL @S9S_MB_2U_LIB.S9S_MB_2U(SCH_1):SMB_SML0_3V3AUX_PCH_SCL   I256 @S9S_MB_2U_LIB.S9S_MB_2U(SCH_1):PAGE175

 JP7 CONN3_210HP1030BR1-CONN3_210-HB
     3 FM_SMB_PEHPCPU1_PCIE_ALERT_N @S9S_MB_2U_LIB.S9S_MB_2U(SCH_1):FM_SMB_PEHPCPU1_PCIE_ALERT_N    I64 @S9S_MB_2U_LIB.S9S_MB_2U(SCH_1):PAGE223
     2    GND @S9S_MB_2U_LIB.S9S_MB_2U(SCH_1):GND    I64 @S9S_MB_2U_LIB.S9S_MB_2U(SCH_1):PAGE223
     1 FM_SMB_PEHPCPU0_PCIE_ALERT_N @S9S_MB_2U_LIB.S9S_MB_2U(SCH_1):FM_SMB_PEHPCPU0_PCIE_ALERT_N    I64 @S9S_MB_2U_LIB.S9S_MB_2U(SCH_1):PAGE223

 JP9 CONN3_210HP1030BR1-CONN3_210-HA
     3 SMB_SML1_PMBUS_3V3AUX_PCH_SDA_1 @S9S_MB_2U_LIB.S9S_MB_2U(SCH_1):SMB_SML1_PMBUS_3V3AUX_PCH_SDA_R1   I263 @S9S_MB_2U_LIB.S9S_MB_2U(SCH_1):PAGE175
     2    GND @S9S_MB_2U_LIB.S9S_MB_2U(SCH_1):GND   I263 @S9S_MB_2U_LIB.S9S_MB_2U(SCH_1):PAGE175
     1 SMB_SML1_PMBUS_3V3AUX_PCH_SCL_1 @S9S_MB_2U_LIB.S9S_MB_2U(SCH_1):SMB_SML1_PMBUS_3V3AUX_PCH_SCL_R1   I263 @S9S_MB_2U_LIB.S9S_MB_2U(SCH_1):PAGE175

JP10 CONN3_210HP1030BR1-CONN3_210-HB
     3    GND @S9S_MB_2U_LIB.S9S_MB_2U(SCH_1):GND    I51 @S9S_MB_2U_LIB.S9S_MB_2U(SCH_1):PAGE327
     2 SMB_SML1_PMBUS_HSC_MODULE_SDA @S9S_MB_2U_LIB.S9S_MB_2U(SCH_1):SMB_SML1_PMBUS_HSC_MODULE_SDA    I51 @S9S_MB_2U_LIB.S9S_MB_2U(SCH_1):PAGE327
     1 SMB_SML1_PMBUS_HSC_MODULE_SCL @S9S_MB_2U_LIB.S9S_MB_2U(SCH_1):SMB_SML1_PMBUS_HSC_MODULE_SCL    I51 @S9S_MB_2U_LIB.S9S_MB_2U(SCH_1):PAGE327

JP15 CONN3_210HP1030BR1-CONN3_210-HB
     3 PD_FORCE_PWRON @S9S_MB_2U_LIB.S9S_MB_2U(SCH_1):PD_FORCE_PWRON   I187 @S9S_MB_2U_LIB.S9S_MB_2U(SCH_1):PAGE312
     2 FM_FORCE_PWRON_LVC3 @S9S_MB_2U_LIB.S9S_MB_2U(SCH_1):FM_FORCE_PWRON_LVC3   I187 @S9S_MB_2U_LIB.S9S_MB_2U(SCH_1):PAGE312
     1 PU_FORCE_PWRON @S9S_MB_2U_LIB.S9S_MB_2U(SCH_1):PU_FORCE_PWRON   I187 @S9S_MB_2U_LIB.S9S_MB_2U(SCH_1):PAGE312

JP15_23 TP_TP_BOM ONLY-NA,TP12_BOM
     1     NC     NC    I71 @S9S_MB_2U_LIB.S9S_MB_2U(SCH_1):PAGE290

JP16 CONN3_210HP1030BR1-CONN3_210-HB
     3    GND @S9S_MB_2U_LIB.S9S_MB_2U(SCH_1):GND    I13 @S9S_MB_2U_LIB.S9S_MB_2U(SCH_1):PAGE235
     2 JTAG_BMC_SW_OE @S9S_MB_2U_LIB.S9S_MB_2U(SCH_1):JTAG_BMC_SW_OE    I13 @S9S_MB_2U_LIB.S9S_MB_2U(SCH_1):PAGE235
     1 PU_JTAG_SW_PU @S9S_MB_2U_LIB.S9S_MB_2U(SCH_1):PU_JTAG_SW_PU    I13 @S9S_MB_2U_LIB.S9S_MB_2U(SCH_1):PAGE235

JP16_23 TP_TP_BOM ONLY-NA,TP12_BOM
     1     NC     NC    I72 @S9S_MB_2U_LIB.S9S_MB_2U(SCH_1):PAGE290

JP4003 CONN3_210HP1030BR1-CONN3_210-HB
     3    GND @S9S_MB_2U_LIB.S9S_MB_2U(SCH_1):GND    I12 @S9S_MB_2U_LIB.S9S_MB_2U(SCH_1):PAGE303
     2 PDB_PRSNT_N @S9S_MB_2U_LIB.S9S_MB_2U(SCH_1):PDB_PRSNT_N    I12 @S9S_MB_2U_LIB.S9S_MB_2U(SCH_1):PAGE303
     1     NC     NC    I12 @S9S_MB_2U_LIB.S9S_MB_2U(SCH_1):PAGE303

JP4003_12 TP_TP_BOM ONLY-NA,TP12_BOM
     1     NC     NC    I70 @S9S_MB_2U_LIB.S9S_MB_2U(SCH_1):PAGE290

  L1 Q_INDUCTOR_SMLF-FCM2012KF-601TA
     2 P3V3_AUX_CLK_GEN_VDD_CK440 @S9S_MB_2U_LIB.S9S_MB_2U(SCH_1):P3V3_AUX_CLK_GEN_VDD_CK440    I20 @S9S_MB_2U_LIB.S9S_MB_2U(SCH_1):PAGE199
     1 P3V3_AUX @S9S_MB_2U_LIB.S9S_MB_2U(SCH_1):P3V3_AUX    I20 @S9S_MB_2U_LIB.S9S_MB_2U(SCH_1):PAGE199

  L2 Q_INDUCTOR_SMLF-BLM15PX121SN1DA
     2 P1V05_PCH_PLL_AUX @S9S_MB_2U_LIB.S9S_MB_2U(SCH_1):P1V05_PCH_PLL_AUX   I164 @S9S_MB_2U_LIB.S9S_MB_2U(SCH_1):PAGE181
     1 P1V05_PCH_AUX @S9S_MB_2U_LIB.S9S_MB_2U(SCH_1):P1V05_PCH_AUX   I164 @S9S_MB_2U_LIB.S9S_MB_2U(SCH_1):PAGE181

  L3 Q_INDUCTOR_SMLF-BLM18SG331TN1DA
     2 P3V3_DB2000_VDD @S9S_MB_2U_LIB.S9S_MB_2U(SCH_1):P3V3_DB2000_VDD   I170 @S9S_MB_2U_LIB.S9S_MB_2U(SCH_1):PAGE195
     1   P3V3 @S9S_MB_2U_LIB.S9S_MB_2U(SCH_1):P3V3   I170 @S9S_MB_2U_LIB.S9S_MB_2U(SCH_1):PAGE195

  L4 Q_INDUCTOR_SMLF-BLM18SG331TN1DA
     2 P3V3_DB2000_FB_VDD @S9S_MB_2U_LIB.S9S_MB_2U(SCH_1):P3V3_DB2000_FB_VDD   I177 @S9S_MB_2U_LIB.S9S_MB_2U(SCH_1):PAGE195
     1   P3V3 @S9S_MB_2U_LIB.S9S_MB_2U(SCH_1):P3V3   I177 @S9S_MB_2U_LIB.S9S_MB_2U(SCH_1):PAGE195

 L10 Q_INDUCTOR_SMLF-BLM18PG121SN1DA
     2 P1V8_PCH_PLL_AUX @S9S_MB_2U_LIB.S9S_MB_2U(SCH_1):P1V8_PCH_PLL_AUX   I145 @S9S_MB_2U_LIB.S9S_MB_2U(SCH_1):PAGE181
     1 P1V8_PCH_AUX @S9S_MB_2U_LIB.S9S_MB_2U(SCH_1):P1V8_PCH_AUX   I145 @S9S_MB_2U_LIB.S9S_MB_2U(SCH_1):PAGE181

 L13 Q_INDUCTOR_SMLF-FCM2012KF-601TA
     2 P3V3_AUX_CLK_GEN_VDDXTAL_CK440 @S9S_MB_2U_LIB.S9S_MB_2U(SCH_1):P3V3_AUX_CLK_GEN_VDDXTAL_CK440    I41 @S9S_MB_2U_LIB.S9S_MB_2U(SCH_1):PAGE199
     1 P3V3_AUX @S9S_MB_2U_LIB.S9S_MB_2U(SCH_1):P3V3_AUX    I41 @S9S_MB_2U_LIB.S9S_MB_2U(SCH_1):PAGE199

 L14 Q_INDUCTOR_SMLF-FCM2012KF-601TA
     2 P3V3_AUX_CLK_GEN_VDDMXCK_CK440 @S9S_MB_2U_LIB.S9S_MB_2U(SCH_1):P3V3_AUX_CLK_GEN_VDDMXCK_CK440    I60 @S9S_MB_2U_LIB.S9S_MB_2U(SCH_1):PAGE199
     1 P3V3_AUX @S9S_MB_2U_LIB.S9S_MB_2U(SCH_1):P3V3_AUX    I60 @S9S_MB_2U_LIB.S9S_MB_2U(SCH_1):PAGE199

 L15 Q_INDUCTOR_SMLF-BLM18PG300SN1DA
     2 P3V3_AUX @S9S_MB_2U_LIB.S9S_MB_2U(SCH_1):P3V3_AUX    I62 @S9S_MB_2U_LIB.S9S_MB_2U(SCH_1):PAGE239
     1 P3V3_MAX11617_VDD @S9S_MB_2U_LIB.S9S_MB_2U(SCH_1):P3V3_MAX11617 _VDD    I62 @S9S_MB_2U_LIB.S9S_MB_2U(SCH_1):PAGE239

 L16 Q_INDUCTOR_SMLF-BLM18PG300SN1DB
     2 P3V3_ADC128_VCC @S9S_MB_2U_LIB.S9S_MB_2U(SCH_1):P3V3_ADC128_VCC   I118 @S9S_MB_2U_LIB.S9S_MB_2U(SCH_1):PAGE239
     1 P3V3_AUX @S9S_MB_2U_LIB.S9S_MB_2U(SCH_1):P3V3_AUX   I118 @S9S_MB_2U_LIB.S9S_MB_2U(SCH_1):PAGE239

 L17 Q_INDUCTOR_SMLF-FCM2012KF-601TA
     2 VFG3P3_CLK_GEN @S9S_MB_2U_LIB.S9S_MB_2U(SCH_1):VFG3P3_CLK_GEN   I155 @S9S_MB_2U_LIB.S9S_MB_2U(SCH_1):PAGE201
     1 P3V3_AUX @S9S_MB_2U_LIB.S9S_MB_2U(SCH_1):P3V3_AUX   I155 @S9S_MB_2U_LIB.S9S_MB_2U(SCH_1):PAGE201

 L18 Q_INDUCTOR_SMLF-BLM15PX121SN1DB
     2 P3V3_AUX_USB_BUF @S9S_MB_2U_LIB.S9S_MB_2U(SCH_1):P3V3_AUX_USB_BUF    I35 @S9S_MB_2U_LIB.S9S_MB_2U(SCH_1):PAGE162
     1 P3V3_AUX @S9S_MB_2U_LIB.S9S_MB_2U(SCH_1):P3V3_AUX    I35 @S9S_MB_2U_LIB.S9S_MB_2U(SCH_1):PAGE162

 L19 Q_INDUCTOR_SMLF-FCM2012KF-601TA
     2 P3V3_9ZXL045 @S9S_MB_2U_LIB.S9S_MB_2U(SCH_1):P3V3_9ZXL045    I81 @S9S_MB_2U_LIB.S9S_MB_2U(SCH_1):PAGE200
     1   P3V3 @S9S_MB_2U_LIB.S9S_MB_2U(SCH_1):P3V3    I81 @S9S_MB_2U_LIB.S9S_MB_2U(SCH_1):PAGE200

 L20 Q_INDUCTOR_SMLF-FCM2012KF-601TA
     2 P3V3_9ZXL045_VDD @S9S_MB_2U_LIB.S9S_MB_2U(SCH_1):P3V3_9ZXL045_VDD    I82 @S9S_MB_2U_LIB.S9S_MB_2U(SCH_1):PAGE200
     1   P3V3 @S9S_MB_2U_LIB.S9S_MB_2U(SCH_1):P3V3    I82 @S9S_MB_2U_LIB.S9S_MB_2U(SCH_1):PAGE200

 ME2 ME_DUMMY_SYMBOL-PICKUP_SMDC20,A

 ME3 ME_DUMMY_SYMBOL-PICKUP_SMDC20,A

 ME4 ME_DUMMY_SYMBOL-PICKUP_SMDC20,A

 ME9 ME_DUMMY_SYMBOL-PICKUP_SMDC20,A

ME10 ME_DUMMY_SYMBOL-PICKUP_SMDC20,A

ME11 ME_DUMMY_SYMBOL-PICKUP_SMDC20,A

ME12 ME_DUMMY_SYMBOL-PICKUP_SMDC20,A

ME13 ME_DUMMY_SYMBOL-PICKUP_SMDC20,A

ME14 ME_DUMMY_SYMBOL-PICKUP_SMDC20,A

ME15 ME_DUMMY_SYMBOL-PICKUP_SMDC20,A

ME17 ME_DUMMY_SYMBOL-QUANTA_LOGO_7XA

ME18 ME_DUMMY_SYMBOL-WEEE,MECH,EMPTA

ME20 ME_DUMMY_SYMBOL-PB-E1_SMALL,MEA

ME21 ME_DUMMY_SYMBOL-PCB_VENDOR_LOGA

ME22 ME_DUMMY_SYMBOL-SNLABEL_27X6,MA

ME27 ME_DUMMY_SYMBOL-CBS_3X558-8,MEA

ME28 ME_DUMMY_SYMBOL-EFI BIOS LABELA

ME29 ME_DUMMY_SYMBOL-SNLABEL_15X5,MA

OSC1 Q_OSC4P_SMLF-50MHZ,OSC,BF65000A
     1 CLK_50M_EN @S9S_MB_2U_LIB.S9S_MB_2U(SCH_1):CLK_50M_EN    I76 @S9S_MB_2U_LIB.S9S_MB_2U(SCH_1):PAGE152
     3 CLK_50M_RMII @S9S_MB_2U_LIB.S9S_MB_2U(SCH_1):CLK_50M_RMII    I76 @S9S_MB_2U_LIB.S9S_MB_2U(SCH_1):PAGE152
     2    GND @S9S_MB_2U_LIB.S9S_MB_2U(SCH_1):GND    I76 @S9S_MB_2U_LIB.S9S_MB_2U(SCH_1):PAGE152
     4 P3V3_AUX @S9S_MB_2U_LIB.S9S_MB_2U(SCH_1):P3V3_AUX    I76 @S9S_MB_2U_LIB.S9S_MB_2U(SCH_1):PAGE152

OSC2 Q_OSC4P_SMLF-25MHZ,OSC,BF62500A
     1 PU_CLK25M_OSC_FPGA_EN @S9S_MB_2U_LIB.S9S_MB_2U(SCH_1):PU_CLK25M_OSC_FPGA_EN   I127 @S9S_MB_2U_LIB.S9S_MB_2U(SCH_1):PAGE313
     3 CLK_25M_OSC_FPGA_R @S9S_MB_2U_LIB.S9S_MB_2U(SCH_1):CLK_25M_OSC_FPGA_R   I127 @S9S_MB_2U_LIB.S9S_MB_2U(SCH_1):PAGE313
     2    GND @S9S_MB_2U_LIB.S9S_MB_2U(SCH_1):GND   I127 @S9S_MB_2U_LIB.S9S_MB_2U(SCH_1):PAGE313
     4 P3V3_AUX @S9S_MB_2U_LIB.S9S_MB_2U(SCH_1):P3V3_AUX   I127 @S9S_MB_2U_LIB.S9S_MB_2U(SCH_1):PAGE313

 PC1 Q_CAP_C0805-22UF,4V,20%,X6S,CHA
     1 PVCCD_HV_CPU0 @S9S_MB_2U_LIB.S9S_MB_2U(SCH_1):PVCCD_HV_CPU0    I29 @S9S_MB_2U_LIB.S9S_MB_2U(SCH_1):PAGE265
     2    GND @S9S_MB_2U_LIB.S9S_MB_2U(SCH_1):GND    I29 @S9S_MB_2U_LIB.S9S_MB_2U(SCH_1):PAGE265

 PC2 Q_CAP_C0805-22UF,4V,20%,X6S,CHA
     1 PVCCD_HV_CPU1 @S9S_MB_2U_LIB.S9S_MB_2U(SCH_1):PVCCD_HV_CPU1    I30 @S9S_MB_2U_LIB.S9S_MB_2U(SCH_1):PAGE283
     2    GND @S9S_MB_2U_LIB.S9S_MB_2U(SCH_1):GND    I30 @S9S_MB_2U_LIB.S9S_MB_2U(SCH_1):PAGE283

 PC3 Q_CAPP_THLF-270UF,16V,20%,OSCOA
     1 SW_P3V3_AUX_FLT @S9S_MB_2U_LIB.S9S_MB_2U(SCH_1):SW_P3V3_AUX_FLT   I103 @S9S_MB_2U_LIB.S9S_MB_2U(SCH_1):PAGE245
     2    GND @S9S_MB_2U_LIB.S9S_MB_2U(SCH_1):GND   I103 @S9S_MB_2U_LIB.S9S_MB_2U(SCH_1):PAGE245

 PC8 Q_CAP_C0603-4.7UF,16V,10%,X6S,A
     1 P12V_AUX @S9S_MB_2U_LIB.S9S_MB_2U(SCH_1):P12V_AUX   I118 @S9S_MB_2U_LIB.S9S_MB_2U(SCH_1):PAGE245
     2    GND @S9S_MB_2U_LIB.S9S_MB_2U(SCH_1):GND   I118 @S9S_MB_2U_LIB.S9S_MB_2U(SCH_1):PAGE245

PC16 Q_CAPP_THLF-560UF,2.5V,20%,OSCA
     1 PVCCIN_CPU0 @S9S_MB_2U_LIB.S9S_MB_2U(SCH_1):PVCCIN_CPU0    I56 @S9S_MB_2U_LIB.S9S_MB_2U(SCH_1):PAGE253
     2    GND @S9S_MB_2U_LIB.S9S_MB_2U(SCH_1):GND    I56 @S9S_MB_2U_LIB.S9S_MB_2U(SCH_1):PAGE253

PC27 Q_CAP_0402-3300PF,50V,10%,X7R,A
     1 PVNN_MAIN_CPU0_REF @S9S_MB_2U_LIB.S9S_MB_2U(SCH_1):PVNN_MAIN_CPU0_REF    I25 @S9S_MB_2U_LIB.S9S_MB_2U(SCH_1):PAGE268
     2    GND @S9S_MB_2U_LIB.S9S_MB_2U(SCH_1):GND    I25 @S9S_MB_2U_LIB.S9S_MB_2U(SCH_1):PAGE268

PC28 Q_CAP_0402-3300PF,50V,10%,X7R,A
     1 PVNN_MAIN_CPU1_REF @S9S_MB_2U_LIB.S9S_MB_2U(SCH_1):PVNN_MAIN_CPU1_REF    I23 @S9S_MB_2U_LIB.S9S_MB_2U(SCH_1):PAGE286
     2    GND @S9S_MB_2U_LIB.S9S_MB_2U(SCH_1):GND    I23 @S9S_MB_2U_LIB.S9S_MB_2U(SCH_1):PAGE286

PC71 Q_CAP_C0805-22UF,16V,20%,X6S,CA
     1 SW_P3V3_AUX_FLT @S9S_MB_2U_LIB.S9S_MB_2U(SCH_1):SW_P3V3_AUX_FLT   I114 @S9S_MB_2U_LIB.S9S_MB_2U(SCH_1):PAGE245
     2    GND @S9S_MB_2U_LIB.S9S_MB_2U(SCH_1):GND   I114 @S9S_MB_2U_LIB.S9S_MB_2U(SCH_1):PAGE245

PC83 Q_CAPP_THLF-560UF,2.5V,20%,OSCA
     1 PVCCIN_CPU1 @S9S_MB_2U_LIB.S9S_MB_2U(SCH_1):PVCCIN_CPU1    I56 @S9S_MB_2U_LIB.S9S_MB_2U(SCH_1):PAGE271
     2    GND @S9S_MB_2U_LIB.S9S_MB_2U(SCH_1):GND    I56 @S9S_MB_2U_LIB.S9S_MB_2U(SCH_1):PAGE271

PC100 Q_CAP_0402-470PF,50V,10%,X7R,TA
     1 PVCCFA_EHV_FIVRA_CPU0_BTSEN @S9S_MB_2U_LIB.S9S_MB_2U(SCH_1):PVCCFA_EHV_FIVRA_CPU0_BTSEN   I116 @S9S_MB_2U_LIB.S9S_MB_2U(SCH_1):PAGE252
     2    GND @S9S_MB_2U_LIB.S9S_MB_2U(SCH_1):GND   I116 @S9S_MB_2U_LIB.S9S_MB_2U(SCH_1):PAGE252

PC101 Q_CAP_0402-470PF,50V,10%,X7R,TA
     1 PVCCFA_EHV_FIVRA_CPU1_BTSEN @S9S_MB_2U_LIB.S9S_MB_2U(SCH_1):PVCCFA_EHV_FIVRA_CPU1_BTSEN    I92 @S9S_MB_2U_LIB.S9S_MB_2U(SCH_1):PAGE270
     2    GND @S9S_MB_2U_LIB.S9S_MB_2U(SCH_1):GND    I92 @S9S_MB_2U_LIB.S9S_MB_2U(SCH_1):PAGE270

PC113 Q_CAP_C0402-1UF,25V,10%,X6S,CHA
     1 P1V05_PCH_AUX_VCC @S9S_MB_2U_LIB.S9S_MB_2U(SCH_1):P1V05_PCH_AUX_VCC     I2 @S9S_MB_2U_LIB.S9S_MB_2U(SCH_1):PAGE248
     2    GND @S9S_MB_2U_LIB.S9S_MB_2U(SCH_1):GND     I2 @S9S_MB_2U_LIB.S9S_MB_2U(SCH_1):PAGE248

PC117 Q_CAPP_SMLF-330UF,2V,35%,SPCAPA
     1 P1V05_PCH_AUX @S9S_MB_2U_LIB.S9S_MB_2U(SCH_1):P1V05_PCH_AUX    I40 @S9S_MB_2U_LIB.S9S_MB_2U(SCH_1):PAGE248
     2    GND @S9S_MB_2U_LIB.S9S_MB_2U(SCH_1):GND    I40 @S9S_MB_2U_LIB.S9S_MB_2U(SCH_1):PAGE248

PC175 Q_CAP_C0402-2.2UF,10V,10%,X6S,A
     1 PVCCFA_EHV_CPU0_VDD1 @S9S_MB_2U_LIB.S9S_MB_2U(SCH_1):PVCCFA_EHV_CPU0_VDD1    I12 @S9S_MB_2U_LIB.S9S_MB_2U(SCH_1):PAGE262
     2    GND @S9S_MB_2U_LIB.S9S_MB_2U(SCH_1):GND    I12 @S9S_MB_2U_LIB.S9S_MB_2U(SCH_1):PAGE262

PC176 Q_CAP_0402-3300PF,50V,10%,X7R,A
     1 SW_P12V_PVCCINFAON_CPU0_FLT @S9S_MB_2U_LIB.S9S_MB_2U(SCH_1):SW_P12V_PVCCINFAON_CPU0_FLT    I24 @S9S_MB_2U_LIB.S9S_MB_2U(SCH_1):PAGE262
     2    GND @S9S_MB_2U_LIB.S9S_MB_2U(SCH_1):GND    I24 @S9S_MB_2U_LIB.S9S_MB_2U(SCH_1):PAGE262

PC177 Q_CAP_C0402-1UF,16V,10%,X6S,CHA
     1 SW_P12V_PVCCINFAON_CPU0_FLT @S9S_MB_2U_LIB.S9S_MB_2U(SCH_1):SW_P12V_PVCCINFAON_CPU0_FLT    I25 @S9S_MB_2U_LIB.S9S_MB_2U(SCH_1):PAGE262
     2    GND @S9S_MB_2U_LIB.S9S_MB_2U(SCH_1):GND    I25 @S9S_MB_2U_LIB.S9S_MB_2U(SCH_1):PAGE262

PC178 Q_CAP_C0402-100NF,50V,10%,X7R,A
     1 SW_PVCCFA_EHV_CPU0_BOOT1_R @S9S_MB_2U_LIB.S9S_MB_2U(SCH_1):SW_PVCCFA_EHV_CPU0_BOOT1_R    I20 @S9S_MB_2U_LIB.S9S_MB_2U(SCH_1):PAGE262
     2 SW_PVCCFA_EHV_CPU0_BOOTR1 @S9S_MB_2U_LIB.S9S_MB_2U(SCH_1):SW_PVCCFA_EHV_CPU0_BOOTR1    I20 @S9S_MB_2U_LIB.S9S_MB_2U(SCH_1):PAGE262

PC179 Q_CAP_C0805-22UF,16V,20%,X6S,CA
     1 SW_P12V_PVCCINFAON_CPU0_FLT @S9S_MB_2U_LIB.S9S_MB_2U(SCH_1):SW_P12V_PVCCINFAON_CPU0_FLT    I26 @S9S_MB_2U_LIB.S9S_MB_2U(SCH_1):PAGE262
     2    GND @S9S_MB_2U_LIB.S9S_MB_2U(SCH_1):GND    I26 @S9S_MB_2U_LIB.S9S_MB_2U(SCH_1):PAGE262

PC180 Q_CAP_C0805-22UF,16V,20%,X6S,CA
     1 SW_P12V_PVCCINFAON_CPU0_FLT @S9S_MB_2U_LIB.S9S_MB_2U(SCH_1):SW_P12V_PVCCINFAON_CPU0_FLT    I27 @S9S_MB_2U_LIB.S9S_MB_2U(SCH_1):PAGE262
     2    GND @S9S_MB_2U_LIB.S9S_MB_2U(SCH_1):GND    I27 @S9S_MB_2U_LIB.S9S_MB_2U(SCH_1):PAGE262

PC181 Q_CAP_C0402-100NF,50V,10%,X7R,A
     1 PVCCFA_EHV_CPU0 @S9S_MB_2U_LIB.S9S_MB_2U(SCH_1):PVCCFA_EHV_CPU0    I28 @S9S_MB_2U_LIB.S9S_MB_2U(SCH_1):PAGE262
     2    GND @S9S_MB_2U_LIB.S9S_MB_2U(SCH_1):GND    I28 @S9S_MB_2U_LIB.S9S_MB_2U(SCH_1):PAGE262

PC184 Q_CAP_C0805-22UF,4V,20%,X6S,CHA
     1 PVCCFA_EHV_CPU0 @S9S_MB_2U_LIB.S9S_MB_2U(SCH_1):PVCCFA_EHV_CPU0    I31 @S9S_MB_2U_LIB.S9S_MB_2U(SCH_1):PAGE262
     2    GND @S9S_MB_2U_LIB.S9S_MB_2U(SCH_1):GND    I31 @S9S_MB_2U_LIB.S9S_MB_2U(SCH_1):PAGE262

PC186 Q_CAP_C0805-22UF,4V,20%,X6S,CHA
     1 PVCCFA_EHV_CPU0 @S9S_MB_2U_LIB.S9S_MB_2U(SCH_1):PVCCFA_EHV_CPU0    I32 @S9S_MB_2U_LIB.S9S_MB_2U(SCH_1):PAGE262
     2    GND @S9S_MB_2U_LIB.S9S_MB_2U(SCH_1):GND    I32 @S9S_MB_2U_LIB.S9S_MB_2U(SCH_1):PAGE262

PC187 Q_CAP_C0402-2.2UF,10V,10%,X6S,A
     1 PVCCINFAON_CPU0_VDD1 @S9S_MB_2U_LIB.S9S_MB_2U(SCH_1):PVCCINFAON_CPU0_VDD1    I24 @S9S_MB_2U_LIB.S9S_MB_2U(SCH_1):PAGE261
     2    GND @S9S_MB_2U_LIB.S9S_MB_2U(SCH_1):GND    I24 @S9S_MB_2U_LIB.S9S_MB_2U(SCH_1):PAGE261

PC188 Q_CAP_C0402-2.2UF,10V,10%,X6S,A
     1 PVCCINFAON_CPU0_VDD2 @S9S_MB_2U_LIB.S9S_MB_2U(SCH_1):PVCCINFAON_CPU0_VDD2    I13 @S9S_MB_2U_LIB.S9S_MB_2U(SCH_1):PAGE261
     2    GND @S9S_MB_2U_LIB.S9S_MB_2U(SCH_1):GND    I13 @S9S_MB_2U_LIB.S9S_MB_2U(SCH_1):PAGE261

PC189 Q_CAPP_SMLF-330UF,2.5V,+10/-35A
     1 PVCCIN_CPU1 @S9S_MB_2U_LIB.S9S_MB_2U(SCH_1):PVCCIN_CPU1    I62 @S9S_MB_2U_LIB.S9S_MB_2U(SCH_1):PAGE271
     2    GND @S9S_MB_2U_LIB.S9S_MB_2U(SCH_1):GND    I62 @S9S_MB_2U_LIB.S9S_MB_2U(SCH_1):PAGE271

PC189_P0_1 Q_CAP_0402-3300PF,50V,10%,X7R,A
     1 SW_P12V_PVCCINFAON_CPU0_FLT @S9S_MB_2U_LIB.S9S_MB_2U(SCH_1):SW_P12V_PVCCINFAON_CPU0_FLT    I45 @S9S_MB_2U_LIB.S9S_MB_2U(SCH_1):PAGE261
     2    GND @S9S_MB_2U_LIB.S9S_MB_2U(SCH_1):GND    I45 @S9S_MB_2U_LIB.S9S_MB_2U(SCH_1):PAGE261

PC190 Q_CAP_C0402-1UF,25V,10%,X6S,CHA
     1 P3V3_OCP_VCC_2 @S9S_MB_2U_LIB.S9S_MB_2U(SCH_1):P3V3_OCP_VCC_2    I91 @S9S_MB_2U_LIB.S9S_MB_2U(SCH_1):PAGE131
     2    GND @S9S_MB_2U_LIB.S9S_MB_2U(SCH_1):GND    I91 @S9S_MB_2U_LIB.S9S_MB_2U(SCH_1):PAGE131

PC190_P0_2 Q_CAP_0402-3300PF,50V,10%,X7R,A
     1 SW_P12V_PVCCINFAON_CPU0_FLT @S9S_MB_2U_LIB.S9S_MB_2U(SCH_1):SW_P12V_PVCCINFAON_CPU0_FLT    I32 @S9S_MB_2U_LIB.S9S_MB_2U(SCH_1):PAGE261
     2    GND @S9S_MB_2U_LIB.S9S_MB_2U(SCH_1):GND    I32 @S9S_MB_2U_LIB.S9S_MB_2U(SCH_1):PAGE261

PC191_P0_1 Q_CAP_C0402-1UF,16V,10%,X6S,CHA
     1 SW_P12V_PVCCINFAON_CPU0_FLT @S9S_MB_2U_LIB.S9S_MB_2U(SCH_1):SW_P12V_PVCCINFAON_CPU0_FLT    I48 @S9S_MB_2U_LIB.S9S_MB_2U(SCH_1):PAGE261
     2    GND @S9S_MB_2U_LIB.S9S_MB_2U(SCH_1):GND    I48 @S9S_MB_2U_LIB.S9S_MB_2U(SCH_1):PAGE261

PC192_P0_2 Q_CAP_C0402-1UF,16V,10%,X6S,CHA
     1 SW_P12V_PVCCINFAON_CPU0_FLT @S9S_MB_2U_LIB.S9S_MB_2U(SCH_1):SW_P12V_PVCCINFAON_CPU0_FLT    I35 @S9S_MB_2U_LIB.S9S_MB_2U(SCH_1):PAGE261
     2    GND @S9S_MB_2U_LIB.S9S_MB_2U(SCH_1):GND    I35 @S9S_MB_2U_LIB.S9S_MB_2U(SCH_1):PAGE261

PC193 Q_CAP_C0402-100NF,50V,10%,X7R,A
     1 SW_PVCCINFAON_CPU0_BOOT1_R @S9S_MB_2U_LIB.S9S_MB_2U(SCH_1):SW_PVCCINFAON_CPU0_BOOT1_R    I51 @S9S_MB_2U_LIB.S9S_MB_2U(SCH_1):PAGE261
     2 SW_PVCCINFAON_CPU0_BOOTR1 @S9S_MB_2U_LIB.S9S_MB_2U(SCH_1):SW_PVCCINFAON_CPU0_BOOTR1    I51 @S9S_MB_2U_LIB.S9S_MB_2U(SCH_1):PAGE261

PC194 Q_CAP_C0402-100NF,50V,10%,X7R,A
     1 SW_PVCCINFAON_CPU0_BOOT2_R @S9S_MB_2U_LIB.S9S_MB_2U(SCH_1):SW_PVCCINFAON_CPU0_BOOT2_R    I38 @S9S_MB_2U_LIB.S9S_MB_2U(SCH_1):PAGE261
     2 SW_PVCCINFAON_CPU0_BOOTR2 @S9S_MB_2U_LIB.S9S_MB_2U(SCH_1):SW_PVCCINFAON_CPU0_BOOTR2    I38 @S9S_MB_2U_LIB.S9S_MB_2U(SCH_1):PAGE261

PC195_P0_1 Q_CAP_C0805-22UF,16V,20%,X6S,CA
     1 SW_P12V_PVCCINFAON_CPU0_FLT @S9S_MB_2U_LIB.S9S_MB_2U(SCH_1):SW_P12V_PVCCINFAON_CPU0_FLT    I49 @S9S_MB_2U_LIB.S9S_MB_2U(SCH_1):PAGE261
     2    GND @S9S_MB_2U_LIB.S9S_MB_2U(SCH_1):GND    I49 @S9S_MB_2U_LIB.S9S_MB_2U(SCH_1):PAGE261

PC196_P0_2 Q_CAP_C0805-22UF,16V,20%,X6S,CA
     1 SW_P12V_PVCCINFAON_CPU0_FLT @S9S_MB_2U_LIB.S9S_MB_2U(SCH_1):SW_P12V_PVCCINFAON_CPU0_FLT    I36 @S9S_MB_2U_LIB.S9S_MB_2U(SCH_1):PAGE261
     2    GND @S9S_MB_2U_LIB.S9S_MB_2U(SCH_1):GND    I36 @S9S_MB_2U_LIB.S9S_MB_2U(SCH_1):PAGE261

PC197_P0_1 Q_CAP_C0805-22UF,16V,20%,X6S,CA
     1 SW_P12V_PVCCINFAON_CPU0_FLT @S9S_MB_2U_LIB.S9S_MB_2U(SCH_1):SW_P12V_PVCCINFAON_CPU0_FLT    I50 @S9S_MB_2U_LIB.S9S_MB_2U(SCH_1):PAGE261
     2    GND @S9S_MB_2U_LIB.S9S_MB_2U(SCH_1):GND    I50 @S9S_MB_2U_LIB.S9S_MB_2U(SCH_1):PAGE261

PC198_P0_2 Q_CAP_C0805-22UF,16V,20%,X6S,CA
     1 SW_P12V_PVCCINFAON_CPU0_FLT @S9S_MB_2U_LIB.S9S_MB_2U(SCH_1):SW_P12V_PVCCINFAON_CPU0_FLT    I37 @S9S_MB_2U_LIB.S9S_MB_2U(SCH_1):PAGE261
     2    GND @S9S_MB_2U_LIB.S9S_MB_2U(SCH_1):GND    I37 @S9S_MB_2U_LIB.S9S_MB_2U(SCH_1):PAGE261

PC199_P0_1 Q_CAP_C0402-100NF,50V,10%,X7R,A
     1 PVCCINFAON_CPU0 @S9S_MB_2U_LIB.S9S_MB_2U(SCH_1):PVCCINFAON_CPU0    I54 @S9S_MB_2U_LIB.S9S_MB_2U(SCH_1):PAGE261
     2    GND @S9S_MB_2U_LIB.S9S_MB_2U(SCH_1):GND    I54 @S9S_MB_2U_LIB.S9S_MB_2U(SCH_1):PAGE261

PC202_P0_1 Q_CAP_C0805-22UF,4V,20%,X6S,CHA
     1 PVCCINFAON_CPU0 @S9S_MB_2U_LIB.S9S_MB_2U(SCH_1):PVCCINFAON_CPU0    I56 @S9S_MB_2U_LIB.S9S_MB_2U(SCH_1):PAGE261
     2    GND @S9S_MB_2U_LIB.S9S_MB_2U(SCH_1):GND    I56 @S9S_MB_2U_LIB.S9S_MB_2U(SCH_1):PAGE261

PC203_P0_2 Q_CAP_C0805-22UF,4V,20%,X6S,CHA
     1 PVCCINFAON_CPU0 @S9S_MB_2U_LIB.S9S_MB_2U(SCH_1):PVCCINFAON_CPU0    I40 @S9S_MB_2U_LIB.S9S_MB_2U(SCH_1):PAGE261
     2    GND @S9S_MB_2U_LIB.S9S_MB_2U(SCH_1):GND    I40 @S9S_MB_2U_LIB.S9S_MB_2U(SCH_1):PAGE261

PC204_P0_1 Q_CAP_C0805-22UF,4V,20%,X6S,CHA
     1 PVCCINFAON_CPU0 @S9S_MB_2U_LIB.S9S_MB_2U(SCH_1):PVCCINFAON_CPU0    I57 @S9S_MB_2U_LIB.S9S_MB_2U(SCH_1):PAGE261
     2    GND @S9S_MB_2U_LIB.S9S_MB_2U(SCH_1):GND    I57 @S9S_MB_2U_LIB.S9S_MB_2U(SCH_1):PAGE261

PC205_P0_2 Q_CAP_C0805-22UF,4V,20%,X6S,CHA
     1 PVCCINFAON_CPU0 @S9S_MB_2U_LIB.S9S_MB_2U(SCH_1):PVCCINFAON_CPU0    I41 @S9S_MB_2U_LIB.S9S_MB_2U(SCH_1):PAGE261
     2    GND @S9S_MB_2U_LIB.S9S_MB_2U(SCH_1):GND    I41 @S9S_MB_2U_LIB.S9S_MB_2U(SCH_1):PAGE261

PC207 Q_CAPP_THLF-270UF,16V,20%,OSCOA
     1 SW_P12V_PVCCINFAON_CPU0_FLT @S9S_MB_2U_LIB.S9S_MB_2U(SCH_1):SW_P12V_PVCCINFAON_CPU0_FLT    I74 @S9S_MB_2U_LIB.S9S_MB_2U(SCH_1):PAGE261
     2    GND @S9S_MB_2U_LIB.S9S_MB_2U(SCH_1):GND    I74 @S9S_MB_2U_LIB.S9S_MB_2U(SCH_1):PAGE261

PC208 Q_CAPP_THLF-270UF,16V,20%,OSCOA
     1 SW_P12V_PVCCINFAON_CPU0_FLT @S9S_MB_2U_LIB.S9S_MB_2U(SCH_1):SW_P12V_PVCCINFAON_CPU0_FLT    I75 @S9S_MB_2U_LIB.S9S_MB_2U(SCH_1):PAGE261
     2    GND @S9S_MB_2U_LIB.S9S_MB_2U(SCH_1):GND    I75 @S9S_MB_2U_LIB.S9S_MB_2U(SCH_1):PAGE261

PC214 Q_CAP_0402-0.1UF,25V,10%,EMPTYA
     1 PVCCINFAON_CPU0_CSPIN @S9S_MB_2U_LIB.S9S_MB_2U(SCH_1):PVCCINFAON_CPU0_CSPIN    I20 @S9S_MB_2U_LIB.S9S_MB_2U(SCH_1):PAGE260
     2    GND @S9S_MB_2U_LIB.S9S_MB_2U(SCH_1):GND    I20 @S9S_MB_2U_LIB.S9S_MB_2U(SCH_1):PAGE260

PC215 Q_CAP_0402-3300PF,50V,10%,X7R,A
     1 SH_PVCCINFAON_CPU0_R @S9S_MB_2U_LIB.S9S_MB_2U(SCH_1):SH_PVCCINFAON_CPU0_R    I50 @S9S_MB_2U_LIB.S9S_MB_2U(SCH_1):PAGE260
     2 VSENSE_PVCCINFAON_CPU0_DN @S9S_MB_2U_LIB.S9S_MB_2U(SCH_1):VSENSE_PVCCINFAON_CPU0_DN    I50 @S9S_MB_2U_LIB.S9S_MB_2U(SCH_1):PAGE260

PC216 Q_CAP_0402-3300PF,50V,10%,X7R,A
     1 SH_PVCCFA_EHV_CPU0_R @S9S_MB_2U_LIB.S9S_MB_2U(SCH_1):SH_PVCCFA_EHV_CPU0_R    I48 @S9S_MB_2U_LIB.S9S_MB_2U(SCH_1):PAGE260
     2 VSENSE_PVCCFA_EHV_CPU0_DN @S9S_MB_2U_LIB.S9S_MB_2U(SCH_1):VSENSE_PVCCFA_EHV_CPU0_DN    I48 @S9S_MB_2U_LIB.S9S_MB_2U(SCH_1):PAGE260

PC221 Q_CAP_0402-0.1UF,25V,10%,X7R,CA
     1 PVCCINFAON_CPU0_VIN_CSNIN @S9S_MB_2U_LIB.S9S_MB_2U(SCH_1):PVCCINFAON_CPU0_VIN_CSNIN    I63 @S9S_MB_2U_LIB.S9S_MB_2U(SCH_1):PAGE260
     2    GND @S9S_MB_2U_LIB.S9S_MB_2U(SCH_1):GND    I63 @S9S_MB_2U_LIB.S9S_MB_2U(SCH_1):PAGE260

PC222 Q_CAP_0402-470PF,50V,10%,X7R,TA
     1 PVCCINFAON_CPU0_ATSEN @S9S_MB_2U_LIB.S9S_MB_2U(SCH_1):PVCCINFAON_CPU0_ATSEN    I69 @S9S_MB_2U_LIB.S9S_MB_2U(SCH_1):PAGE260
     2    GND @S9S_MB_2U_LIB.S9S_MB_2U(SCH_1):GND    I69 @S9S_MB_2U_LIB.S9S_MB_2U(SCH_1):PAGE260

PC223 Q_CAP_C0402-100NF,50V,10%,EMPTA
     1 PVCCINFAON_CPU0_VCC @S9S_MB_2U_LIB.S9S_MB_2U(SCH_1):PVCCINFAON_CPU0_VCC    I98 @S9S_MB_2U_LIB.S9S_MB_2U(SCH_1):PAGE260
     2    GND @S9S_MB_2U_LIB.S9S_MB_2U(SCH_1):GND    I98 @S9S_MB_2U_LIB.S9S_MB_2U(SCH_1):PAGE260

PC224 Q_CAP_C0402-10UF,6.3V,20%,X6S,B
     1 PVCCINFAON_CPU0_VREF @S9S_MB_2U_LIB.S9S_MB_2U(SCH_1):PVCCINFAON_CPU0_VREF    I92 @S9S_MB_2U_LIB.S9S_MB_2U(SCH_1):PAGE260
     2    GND @S9S_MB_2U_LIB.S9S_MB_2U(SCH_1):GND    I92 @S9S_MB_2U_LIB.S9S_MB_2U(SCH_1):PAGE260

PC225 Q_CAP_C0402-1UF,16V,10%,X6S,CHA
     1 PVCCINFAON_CPU0_VCC @S9S_MB_2U_LIB.S9S_MB_2U(SCH_1):PVCCINFAON_CPU0_VCC    I99 @S9S_MB_2U_LIB.S9S_MB_2U(SCH_1):PAGE260
     2    GND @S9S_MB_2U_LIB.S9S_MB_2U(SCH_1):GND    I99 @S9S_MB_2U_LIB.S9S_MB_2U(SCH_1):PAGE260

PC226 Q_CAP_C0402-2.2UF,10V,10%,X6S,A
     1 PVCCIN_CPU0_VDD8 @S9S_MB_2U_LIB.S9S_MB_2U(SCH_1):PVCCIN_CPU0_VDD8    I11 @S9S_MB_2U_LIB.S9S_MB_2U(SCH_1):PAGE256
     2    GND @S9S_MB_2U_LIB.S9S_MB_2U(SCH_1):GND    I11 @S9S_MB_2U_LIB.S9S_MB_2U(SCH_1):PAGE256

PC227 Q_CAP_C0402-2.2UF,10V,10%,X6S,A
     1 PVCCIN_CPU0_VDD7 @S9S_MB_2U_LIB.S9S_MB_2U(SCH_1):PVCCIN_CPU0_VDD7    I31 @S9S_MB_2U_LIB.S9S_MB_2U(SCH_1):PAGE256
     2    GND @S9S_MB_2U_LIB.S9S_MB_2U(SCH_1):GND    I31 @S9S_MB_2U_LIB.S9S_MB_2U(SCH_1):PAGE256

PC228_P0_8 Q_CAP_C0402-2.2UF,10V,10%,X6S,A
     1 PVCCIN_CPU0_PVCC @S9S_MB_2U_LIB.S9S_MB_2U(SCH_1):PVCCIN_CPU0_PVCC    I15 @S9S_MB_2U_LIB.S9S_MB_2U(SCH_1):PAGE256
     2    GND @S9S_MB_2U_LIB.S9S_MB_2U(SCH_1):GND    I15 @S9S_MB_2U_LIB.S9S_MB_2U(SCH_1):PAGE256

PC229_P0_7 Q_CAP_C0402-2.2UF,10V,10%,X6S,A
     1 PVCCIN_CPU0_PVCC @S9S_MB_2U_LIB.S9S_MB_2U(SCH_1):PVCCIN_CPU0_PVCC    I36 @S9S_MB_2U_LIB.S9S_MB_2U(SCH_1):PAGE256
     2    GND @S9S_MB_2U_LIB.S9S_MB_2U(SCH_1):GND    I36 @S9S_MB_2U_LIB.S9S_MB_2U(SCH_1):PAGE256

PC230_P0_8 Q_CAP_0402-3300PF,50V,10%,X7R,A
     1 SW_P12V_PVCCIN_CPU0_FLT @S9S_MB_2U_LIB.S9S_MB_2U(SCH_1):SW_P12V_PVCCIN_CPU0_FLT    I17 @S9S_MB_2U_LIB.S9S_MB_2U(SCH_1):PAGE256
     2    GND @S9S_MB_2U_LIB.S9S_MB_2U(SCH_1):GND    I17 @S9S_MB_2U_LIB.S9S_MB_2U(SCH_1):PAGE256

PC231_P0_7 Q_CAP_0402-3300PF,50V,10%,X7R,A
     1 SW_P12V_PVCCIN_CPU0_FLT @S9S_MB_2U_LIB.S9S_MB_2U(SCH_1):SW_P12V_PVCCIN_CPU0_FLT    I41 @S9S_MB_2U_LIB.S9S_MB_2U(SCH_1):PAGE256
     2    GND @S9S_MB_2U_LIB.S9S_MB_2U(SCH_1):GND    I41 @S9S_MB_2U_LIB.S9S_MB_2U(SCH_1):PAGE256

PC232_P0_8 Q_CAP_C0402-1UF,16V,10%,X6S,CHA
     1 SW_P12V_PVCCIN_CPU0_FLT @S9S_MB_2U_LIB.S9S_MB_2U(SCH_1):SW_P12V_PVCCIN_CPU0_FLT    I20 @S9S_MB_2U_LIB.S9S_MB_2U(SCH_1):PAGE256
     2    GND @S9S_MB_2U_LIB.S9S_MB_2U(SCH_1):GND    I20 @S9S_MB_2U_LIB.S9S_MB_2U(SCH_1):PAGE256

PC233_P0_7 Q_CAP_C0402-1UF,16V,10%,X6S,CHA
     1 SW_P12V_PVCCIN_CPU0_FLT @S9S_MB_2U_LIB.S9S_MB_2U(SCH_1):SW_P12V_PVCCIN_CPU0_FLT    I42 @S9S_MB_2U_LIB.S9S_MB_2U(SCH_1):PAGE256
     2    GND @S9S_MB_2U_LIB.S9S_MB_2U(SCH_1):GND    I42 @S9S_MB_2U_LIB.S9S_MB_2U(SCH_1):PAGE256

PC234 Q_CAP_C0402-100NF,50V,10%,X7R,A
     1 SW_PVCCIN_CPU0_BOOT8_R @S9S_MB_2U_LIB.S9S_MB_2U(SCH_1):SW_PVCCIN_CPU0_BOOT8_R    I45 @S9S_MB_2U_LIB.S9S_MB_2U(SCH_1):PAGE256
     2 SW_PVCCIN_CPU0_BOOTR8 @S9S_MB_2U_LIB.S9S_MB_2U(SCH_1):SW_PVCCIN_CPU0_BOOTR8    I45 @S9S_MB_2U_LIB.S9S_MB_2U(SCH_1):PAGE256

PC235 Q_CAP_C0402-100NF,50V,10%,X7R,A
     1 SW_PVCCIN_CPU0_BOOT7_R @S9S_MB_2U_LIB.S9S_MB_2U(SCH_1):SW_PVCCIN_CPU0_BOOT7_R    I59 @S9S_MB_2U_LIB.S9S_MB_2U(SCH_1):PAGE256
     2 SW_PVCCIN_CPU0_BOOTR7 @S9S_MB_2U_LIB.S9S_MB_2U(SCH_1):SW_PVCCIN_CPU0_BOOTR7    I59 @S9S_MB_2U_LIB.S9S_MB_2U(SCH_1):PAGE256

PC236_P0_8 Q_CAP_C0805-22UF,16V,20%,X6S,CA
     1 SW_P12V_PVCCIN_CPU0_FLT @S9S_MB_2U_LIB.S9S_MB_2U(SCH_1):SW_P12V_PVCCIN_CPU0_FLT    I21 @S9S_MB_2U_LIB.S9S_MB_2U(SCH_1):PAGE256
     2    GND @S9S_MB_2U_LIB.S9S_MB_2U(SCH_1):GND    I21 @S9S_MB_2U_LIB.S9S_MB_2U(SCH_1):PAGE256

PC237 Q_CAP_0402-680PF,50V,10%,X7R,TA
     1 PVNN_MAIN_CPU0_FB @S9S_MB_2U_LIB.S9S_MB_2U(SCH_1):PVNN_MAIN_CPU0_FB    I35 @S9S_MB_2U_LIB.S9S_MB_2U(SCH_1):PAGE268
     2 PVNN_MAIN_CPU0_FB_RC @S9S_MB_2U_LIB.S9S_MB_2U(SCH_1):PVNN_MAIN_CPU0_FB_RC    I35 @S9S_MB_2U_LIB.S9S_MB_2U(SCH_1):PAGE268

PC237_P0_7 Q_CAP_C0805-22UF,16V,20%,X6S,CA
     1 SW_P12V_PVCCIN_CPU0_FLT @S9S_MB_2U_LIB.S9S_MB_2U(SCH_1):SW_P12V_PVCCIN_CPU0_FLT    I43 @S9S_MB_2U_LIB.S9S_MB_2U(SCH_1):PAGE256
     2    GND @S9S_MB_2U_LIB.S9S_MB_2U(SCH_1):GND    I43 @S9S_MB_2U_LIB.S9S_MB_2U(SCH_1):PAGE256

PC238 Q_CAP_0402-680PF,50V,10%,X7R,TA
     1 PVNN_MAIN_CPU1_FB @S9S_MB_2U_LIB.S9S_MB_2U(SCH_1):PVNN_MAIN_CPU1_FB    I33 @S9S_MB_2U_LIB.S9S_MB_2U(SCH_1):PAGE286
     2 PVNN_MAIN_CPU1_FB_RC @S9S_MB_2U_LIB.S9S_MB_2U(SCH_1):PVNN_MAIN_CPU1_FB_RC    I33 @S9S_MB_2U_LIB.S9S_MB_2U(SCH_1):PAGE286

PC238_P0_8 Q_CAP_C0805-22UF,16V,20%,X6S,CA
     1 SW_P12V_PVCCIN_CPU0_FLT @S9S_MB_2U_LIB.S9S_MB_2U(SCH_1):SW_P12V_PVCCIN_CPU0_FLT    I47 @S9S_MB_2U_LIB.S9S_MB_2U(SCH_1):PAGE256
     2    GND @S9S_MB_2U_LIB.S9S_MB_2U(SCH_1):GND    I47 @S9S_MB_2U_LIB.S9S_MB_2U(SCH_1):PAGE256

PC239_P0_7 Q_CAP_C0805-22UF,16V,20%,X6S,CA
     1 SW_P12V_PVCCIN_CPU0_FLT @S9S_MB_2U_LIB.S9S_MB_2U(SCH_1):SW_P12V_PVCCIN_CPU0_FLT    I63 @S9S_MB_2U_LIB.S9S_MB_2U(SCH_1):PAGE256
     2    GND @S9S_MB_2U_LIB.S9S_MB_2U(SCH_1):GND    I63 @S9S_MB_2U_LIB.S9S_MB_2U(SCH_1):PAGE256

PC240_P0_8 Q_CAP_C0805-22UF,16V,20%,X6S,CA
     1 SW_P12V_PVCCIN_CPU0_FLT @S9S_MB_2U_LIB.S9S_MB_2U(SCH_1):SW_P12V_PVCCIN_CPU0_FLT    I48 @S9S_MB_2U_LIB.S9S_MB_2U(SCH_1):PAGE256
     2    GND @S9S_MB_2U_LIB.S9S_MB_2U(SCH_1):GND    I48 @S9S_MB_2U_LIB.S9S_MB_2U(SCH_1):PAGE256

PC241_P0_7 Q_CAP_C0805-22UF,16V,20%,X6S,CA
     1 SW_P12V_PVCCIN_CPU0_FLT @S9S_MB_2U_LIB.S9S_MB_2U(SCH_1):SW_P12V_PVCCIN_CPU0_FLT    I64 @S9S_MB_2U_LIB.S9S_MB_2U(SCH_1):PAGE256
     2    GND @S9S_MB_2U_LIB.S9S_MB_2U(SCH_1):GND    I64 @S9S_MB_2U_LIB.S9S_MB_2U(SCH_1):PAGE256

PC242_P0_8 Q_CAP_C0402-1UF,16V,10%,X6S,CHA
     1 PVCCIN_CPU0 @S9S_MB_2U_LIB.S9S_MB_2U(SCH_1):PVCCIN_CPU0    I52 @S9S_MB_2U_LIB.S9S_MB_2U(SCH_1):PAGE256
     2    GND @S9S_MB_2U_LIB.S9S_MB_2U(SCH_1):GND    I52 @S9S_MB_2U_LIB.S9S_MB_2U(SCH_1):PAGE256

PC243_P0_7 Q_CAP_C0402-1UF,16V,10%,X6S,CHA
     1 PVCCIN_CPU0 @S9S_MB_2U_LIB.S9S_MB_2U(SCH_1):PVCCIN_CPU0    I62 @S9S_MB_2U_LIB.S9S_MB_2U(SCH_1):PAGE256
     2    GND @S9S_MB_2U_LIB.S9S_MB_2U(SCH_1):GND    I62 @S9S_MB_2U_LIB.S9S_MB_2U(SCH_1):PAGE256

PC244_P0_8 Q_CAP_C0805-22UF,4V,20%,X6S,CHA
     1 PVCCIN_CPU0 @S9S_MB_2U_LIB.S9S_MB_2U(SCH_1):PVCCIN_CPU0    I53 @S9S_MB_2U_LIB.S9S_MB_2U(SCH_1):PAGE256
     2    GND @S9S_MB_2U_LIB.S9S_MB_2U(SCH_1):GND    I53 @S9S_MB_2U_LIB.S9S_MB_2U(SCH_1):PAGE256

PC245_P0_7 Q_CAP_C0805-22UF,4V,20%,X6S,CHA
     1 PVCCIN_CPU0 @S9S_MB_2U_LIB.S9S_MB_2U(SCH_1):PVCCIN_CPU0    I66 @S9S_MB_2U_LIB.S9S_MB_2U(SCH_1):PAGE256
     2    GND @S9S_MB_2U_LIB.S9S_MB_2U(SCH_1):GND    I66 @S9S_MB_2U_LIB.S9S_MB_2U(SCH_1):PAGE256

PC246_P0_8 Q_CAP_C0805-22UF,4V,20%,X6S,CHA
     1 PVCCIN_CPU0 @S9S_MB_2U_LIB.S9S_MB_2U(SCH_1):PVCCIN_CPU0    I54 @S9S_MB_2U_LIB.S9S_MB_2U(SCH_1):PAGE256
     2    GND @S9S_MB_2U_LIB.S9S_MB_2U(SCH_1):GND    I54 @S9S_MB_2U_LIB.S9S_MB_2U(SCH_1):PAGE256

PC247_P0_7 Q_CAP_C0805-22UF,4V,20%,X6S,CHA
     1 PVCCIN_CPU0 @S9S_MB_2U_LIB.S9S_MB_2U(SCH_1):PVCCIN_CPU0    I67 @S9S_MB_2U_LIB.S9S_MB_2U(SCH_1):PAGE256
     2    GND @S9S_MB_2U_LIB.S9S_MB_2U(SCH_1):GND    I67 @S9S_MB_2U_LIB.S9S_MB_2U(SCH_1):PAGE256

PC248 Q_CAP_C0402-2.2UF,10V,10%,X6S,A
     1 PVCCIN_CPU0_VDD6 @S9S_MB_2U_LIB.S9S_MB_2U(SCH_1):PVCCIN_CPU0_VDD6    I13 @S9S_MB_2U_LIB.S9S_MB_2U(SCH_1):PAGE255
     2    GND @S9S_MB_2U_LIB.S9S_MB_2U(SCH_1):GND    I13 @S9S_MB_2U_LIB.S9S_MB_2U(SCH_1):PAGE255

PC249 Q_CAP_C0402-2.2UF,10V,10%,X6S,A
     1 PVCCIN_CPU0_VDD5 @S9S_MB_2U_LIB.S9S_MB_2U(SCH_1):PVCCIN_CPU0_VDD5    I24 @S9S_MB_2U_LIB.S9S_MB_2U(SCH_1):PAGE255
     2    GND @S9S_MB_2U_LIB.S9S_MB_2U(SCH_1):GND    I24 @S9S_MB_2U_LIB.S9S_MB_2U(SCH_1):PAGE255

PC250_P0_6 Q_CAP_C0402-2.2UF,10V,10%,X6S,A
     1 PVCCIN_CPU0_PVCC @S9S_MB_2U_LIB.S9S_MB_2U(SCH_1):PVCCIN_CPU0_PVCC    I17 @S9S_MB_2U_LIB.S9S_MB_2U(SCH_1):PAGE255
     2    GND @S9S_MB_2U_LIB.S9S_MB_2U(SCH_1):GND    I17 @S9S_MB_2U_LIB.S9S_MB_2U(SCH_1):PAGE255

PC251_P0_5 Q_CAP_C0402-2.2UF,10V,10%,X6S,A
     1 PVCCIN_CPU0_PVCC @S9S_MB_2U_LIB.S9S_MB_2U(SCH_1):PVCCIN_CPU0_PVCC    I29 @S9S_MB_2U_LIB.S9S_MB_2U(SCH_1):PAGE255
     2    GND @S9S_MB_2U_LIB.S9S_MB_2U(SCH_1):GND    I29 @S9S_MB_2U_LIB.S9S_MB_2U(SCH_1):PAGE255

PC252_P0_6 Q_CAP_0402-3300PF,50V,10%,X7R,A
     1 SW_P12V_PVCCIN_CPU0_FLT @S9S_MB_2U_LIB.S9S_MB_2U(SCH_1):SW_P12V_PVCCIN_CPU0_FLT    I34 @S9S_MB_2U_LIB.S9S_MB_2U(SCH_1):PAGE255
     2    GND @S9S_MB_2U_LIB.S9S_MB_2U(SCH_1):GND    I34 @S9S_MB_2U_LIB.S9S_MB_2U(SCH_1):PAGE255

PC253_P0_5 Q_CAP_0402-3300PF,50V,10%,X7R,A
     1 SW_P12V_PVCCIN_CPU0_FLT @S9S_MB_2U_LIB.S9S_MB_2U(SCH_1):SW_P12V_PVCCIN_CPU0_FLT    I48 @S9S_MB_2U_LIB.S9S_MB_2U(SCH_1):PAGE255
     2    GND @S9S_MB_2U_LIB.S9S_MB_2U(SCH_1):GND    I48 @S9S_MB_2U_LIB.S9S_MB_2U(SCH_1):PAGE255

PC254_P0_6 Q_CAP_C0402-1UF,16V,10%,X6S,CHA
     1 SW_P12V_PVCCIN_CPU0_FLT @S9S_MB_2U_LIB.S9S_MB_2U(SCH_1):SW_P12V_PVCCIN_CPU0_FLT    I37 @S9S_MB_2U_LIB.S9S_MB_2U(SCH_1):PAGE255
     2    GND @S9S_MB_2U_LIB.S9S_MB_2U(SCH_1):GND    I37 @S9S_MB_2U_LIB.S9S_MB_2U(SCH_1):PAGE255

PC255_P0_5 Q_CAP_C0402-1UF,16V,10%,X6S,CHA
     1 SW_P12V_PVCCIN_CPU0_FLT @S9S_MB_2U_LIB.S9S_MB_2U(SCH_1):SW_P12V_PVCCIN_CPU0_FLT    I52 @S9S_MB_2U_LIB.S9S_MB_2U(SCH_1):PAGE255
     2    GND @S9S_MB_2U_LIB.S9S_MB_2U(SCH_1):GND    I52 @S9S_MB_2U_LIB.S9S_MB_2U(SCH_1):PAGE255

PC256 Q_CAP_C0402-100NF,50V,10%,X7R,A
     1 SW_PVCCIN_CPU0_BOOT6_R @S9S_MB_2U_LIB.S9S_MB_2U(SCH_1):SW_PVCCIN_CPU0_BOOT6_R    I33 @S9S_MB_2U_LIB.S9S_MB_2U(SCH_1):PAGE255
     2 SW_PVCCIN_CPU0_BOOTR6 @S9S_MB_2U_LIB.S9S_MB_2U(SCH_1):SW_PVCCIN_CPU0_BOOTR6    I33 @S9S_MB_2U_LIB.S9S_MB_2U(SCH_1):PAGE255

PC257 Q_CAP_C0402-100NF,50V,10%,X7R,A
     1 SW_PVCCIN_CPU0_BOOT5_R @S9S_MB_2U_LIB.S9S_MB_2U(SCH_1):SW_PVCCIN_CPU0_BOOT5_R    I51 @S9S_MB_2U_LIB.S9S_MB_2U(SCH_1):PAGE255
     2 SW_PVCCIN_CPU0_BOOTR5 @S9S_MB_2U_LIB.S9S_MB_2U(SCH_1):SW_PVCCIN_CPU0_BOOTR5    I51 @S9S_MB_2U_LIB.S9S_MB_2U(SCH_1):PAGE255

PC258_P0_6 Q_CAP_C0805-22UF,16V,20%,X6S,CA
     1 SW_P12V_PVCCIN_CPU0_FLT @S9S_MB_2U_LIB.S9S_MB_2U(SCH_1):SW_P12V_PVCCIN_CPU0_FLT    I38 @S9S_MB_2U_LIB.S9S_MB_2U(SCH_1):PAGE255
     2    GND @S9S_MB_2U_LIB.S9S_MB_2U(SCH_1):GND    I38 @S9S_MB_2U_LIB.S9S_MB_2U(SCH_1):PAGE255

PC259_P0_5 Q_CAP_C0805-22UF,16V,20%,X6S,CA
     1 SW_P12V_PVCCIN_CPU0_FLT @S9S_MB_2U_LIB.S9S_MB_2U(SCH_1):SW_P12V_PVCCIN_CPU0_FLT    I53 @S9S_MB_2U_LIB.S9S_MB_2U(SCH_1):PAGE255
     2    GND @S9S_MB_2U_LIB.S9S_MB_2U(SCH_1):GND    I53 @S9S_MB_2U_LIB.S9S_MB_2U(SCH_1):PAGE255

PC260_P0_6 Q_CAP_C0805-22UF,16V,20%,X6S,CA
     1 SW_P12V_PVCCIN_CPU0_FLT @S9S_MB_2U_LIB.S9S_MB_2U(SCH_1):SW_P12V_PVCCIN_CPU0_FLT    I39 @S9S_MB_2U_LIB.S9S_MB_2U(SCH_1):PAGE255
     2    GND @S9S_MB_2U_LIB.S9S_MB_2U(SCH_1):GND    I39 @S9S_MB_2U_LIB.S9S_MB_2U(SCH_1):PAGE255

PC261_P0_5 Q_CAP_C0805-22UF,16V,20%,X6S,CA
     1 SW_P12V_PVCCIN_CPU0_FLT @S9S_MB_2U_LIB.S9S_MB_2U(SCH_1):SW_P12V_PVCCIN_CPU0_FLT    I54 @S9S_MB_2U_LIB.S9S_MB_2U(SCH_1):PAGE255
     2    GND @S9S_MB_2U_LIB.S9S_MB_2U(SCH_1):GND    I54 @S9S_MB_2U_LIB.S9S_MB_2U(SCH_1):PAGE255

PC262_P0_6 Q_CAP_C0805-22UF,16V,20%,X6S,CA
     1 SW_P12V_PVCCIN_CPU0_FLT @S9S_MB_2U_LIB.S9S_MB_2U(SCH_1):SW_P12V_PVCCIN_CPU0_FLT    I43 @S9S_MB_2U_LIB.S9S_MB_2U(SCH_1):PAGE255
     2    GND @S9S_MB_2U_LIB.S9S_MB_2U(SCH_1):GND    I43 @S9S_MB_2U_LIB.S9S_MB_2U(SCH_1):PAGE255

PC263_P0_5 Q_CAP_C0805-22UF,16V,20%,X6S,CA
     1 SW_P12V_PVCCIN_CPU0_FLT @S9S_MB_2U_LIB.S9S_MB_2U(SCH_1):SW_P12V_PVCCIN_CPU0_FLT    I56 @S9S_MB_2U_LIB.S9S_MB_2U(SCH_1):PAGE255
     2    GND @S9S_MB_2U_LIB.S9S_MB_2U(SCH_1):GND    I56 @S9S_MB_2U_LIB.S9S_MB_2U(SCH_1):PAGE255

PC266_P0_6 Q_CAP_C0805-22UF,4V,20%,X6S,CHA
     1 PVCCIN_CPU0 @S9S_MB_2U_LIB.S9S_MB_2U(SCH_1):PVCCIN_CPU0    I42 @S9S_MB_2U_LIB.S9S_MB_2U(SCH_1):PAGE255
     2    GND @S9S_MB_2U_LIB.S9S_MB_2U(SCH_1):GND    I42 @S9S_MB_2U_LIB.S9S_MB_2U(SCH_1):PAGE255

PC267_P0_5 Q_CAP_C0805-22UF,4V,20%,X6S,CHA
     1 PVCCIN_CPU0 @S9S_MB_2U_LIB.S9S_MB_2U(SCH_1):PVCCIN_CPU0    I63 @S9S_MB_2U_LIB.S9S_MB_2U(SCH_1):PAGE255
     2    GND @S9S_MB_2U_LIB.S9S_MB_2U(SCH_1):GND    I63 @S9S_MB_2U_LIB.S9S_MB_2U(SCH_1):PAGE255

PC268_P0_6 Q_CAP_C0805-22UF,4V,20%,X6S,CHA
     1 PVCCIN_CPU0 @S9S_MB_2U_LIB.S9S_MB_2U(SCH_1):PVCCIN_CPU0    I59 @S9S_MB_2U_LIB.S9S_MB_2U(SCH_1):PAGE255
     2    GND @S9S_MB_2U_LIB.S9S_MB_2U(SCH_1):GND    I59 @S9S_MB_2U_LIB.S9S_MB_2U(SCH_1):PAGE255

PC269_P0_5 Q_CAP_C0805-22UF,4V,20%,X6S,CHA
     1 PVCCIN_CPU0 @S9S_MB_2U_LIB.S9S_MB_2U(SCH_1):PVCCIN_CPU0    I64 @S9S_MB_2U_LIB.S9S_MB_2U(SCH_1):PAGE255
     2    GND @S9S_MB_2U_LIB.S9S_MB_2U(SCH_1):GND    I64 @S9S_MB_2U_LIB.S9S_MB_2U(SCH_1):PAGE255

PC270 Q_CAP_C0402-2.2UF,10V,10%,X6S,A
     1 PVCCIN_CPU0_VDD4 @S9S_MB_2U_LIB.S9S_MB_2U(SCH_1):PVCCIN_CPU0_VDD4    I11 @S9S_MB_2U_LIB.S9S_MB_2U(SCH_1):PAGE254
     2    GND @S9S_MB_2U_LIB.S9S_MB_2U(SCH_1):GND    I11 @S9S_MB_2U_LIB.S9S_MB_2U(SCH_1):PAGE254

PC271 Q_CAP_C0402-2.2UF,10V,10%,X6S,A
     1 PVCCIN_CPU0_VDD3 @S9S_MB_2U_LIB.S9S_MB_2U(SCH_1):PVCCIN_CPU0_VDD3    I25 @S9S_MB_2U_LIB.S9S_MB_2U(SCH_1):PAGE254
     2    GND @S9S_MB_2U_LIB.S9S_MB_2U(SCH_1):GND    I25 @S9S_MB_2U_LIB.S9S_MB_2U(SCH_1):PAGE254

PC272_P0_4 Q_CAP_C0402-2.2UF,10V,10%,X6S,A
     1 PVCCIN_CPU0_PVCC @S9S_MB_2U_LIB.S9S_MB_2U(SCH_1):PVCCIN_CPU0_PVCC    I17 @S9S_MB_2U_LIB.S9S_MB_2U(SCH_1):PAGE254
     2    GND @S9S_MB_2U_LIB.S9S_MB_2U(SCH_1):GND    I17 @S9S_MB_2U_LIB.S9S_MB_2U(SCH_1):PAGE254

PC273_P0_3 Q_CAP_C0402-2.2UF,10V,10%,X6S,A
     1 PVCCIN_CPU0_PVCC @S9S_MB_2U_LIB.S9S_MB_2U(SCH_1):PVCCIN_CPU0_PVCC    I30 @S9S_MB_2U_LIB.S9S_MB_2U(SCH_1):PAGE254
     2    GND @S9S_MB_2U_LIB.S9S_MB_2U(SCH_1):GND    I30 @S9S_MB_2U_LIB.S9S_MB_2U(SCH_1):PAGE254

PC274_P0_4 Q_CAP_0402-3300PF,50V,10%,X7R,A
     1 SW_P12V_PVCCIN_CPU0_FLT @S9S_MB_2U_LIB.S9S_MB_2U(SCH_1):SW_P12V_PVCCIN_CPU0_FLT    I35 @S9S_MB_2U_LIB.S9S_MB_2U(SCH_1):PAGE254
     2    GND @S9S_MB_2U_LIB.S9S_MB_2U(SCH_1):GND    I35 @S9S_MB_2U_LIB.S9S_MB_2U(SCH_1):PAGE254

PC275_P0_3 Q_CAP_0402-3300PF,50V,10%,X7R,A
     1 SW_P12V_PVCCIN_CPU0_FLT @S9S_MB_2U_LIB.S9S_MB_2U(SCH_1):SW_P12V_PVCCIN_CPU0_FLT    I48 @S9S_MB_2U_LIB.S9S_MB_2U(SCH_1):PAGE254
     2    GND @S9S_MB_2U_LIB.S9S_MB_2U(SCH_1):GND    I48 @S9S_MB_2U_LIB.S9S_MB_2U(SCH_1):PAGE254

PC276_P0_4 Q_CAP_C0402-1UF,16V,10%,X6S,CHA
     1 SW_P12V_PVCCIN_CPU0_FLT @S9S_MB_2U_LIB.S9S_MB_2U(SCH_1):SW_P12V_PVCCIN_CPU0_FLT    I38 @S9S_MB_2U_LIB.S9S_MB_2U(SCH_1):PAGE254
     2    GND @S9S_MB_2U_LIB.S9S_MB_2U(SCH_1):GND    I38 @S9S_MB_2U_LIB.S9S_MB_2U(SCH_1):PAGE254

PC277_P0_3 Q_CAP_C0402-1UF,16V,10%,X6S,CHA
     1 SW_P12V_PVCCIN_CPU0_FLT @S9S_MB_2U_LIB.S9S_MB_2U(SCH_1):SW_P12V_PVCCIN_CPU0_FLT    I52 @S9S_MB_2U_LIB.S9S_MB_2U(SCH_1):PAGE254
     2    GND @S9S_MB_2U_LIB.S9S_MB_2U(SCH_1):GND    I52 @S9S_MB_2U_LIB.S9S_MB_2U(SCH_1):PAGE254

PC278 Q_CAP_C0402-100NF,50V,10%,X7R,A
     1 SW_PVCCIN_CPU0_BOOT4_R @S9S_MB_2U_LIB.S9S_MB_2U(SCH_1):SW_PVCCIN_CPU0_BOOT4_R    I34 @S9S_MB_2U_LIB.S9S_MB_2U(SCH_1):PAGE254
     2 SW_PVCCIN_CPU0_BOOTR4 @S9S_MB_2U_LIB.S9S_MB_2U(SCH_1):SW_PVCCIN_CPU0_BOOTR4    I34 @S9S_MB_2U_LIB.S9S_MB_2U(SCH_1):PAGE254

PC279 Q_CAP_C0402-100NF,50V,10%,X7R,A
     1 SW_PVCCIN_CPU0_BOOT3_R @S9S_MB_2U_LIB.S9S_MB_2U(SCH_1):SW_PVCCIN_CPU0_BOOT3_R    I51 @S9S_MB_2U_LIB.S9S_MB_2U(SCH_1):PAGE254
     2 SW_PVCCIN_CPU0_BOOTR3 @S9S_MB_2U_LIB.S9S_MB_2U(SCH_1):SW_PVCCIN_CPU0_BOOTR3    I51 @S9S_MB_2U_LIB.S9S_MB_2U(SCH_1):PAGE254

PC280_P0_4 Q_CAP_C0805-22UF,16V,20%,X6S,CA
     1 SW_P12V_PVCCIN_CPU0_FLT @S9S_MB_2U_LIB.S9S_MB_2U(SCH_1):SW_P12V_PVCCIN_CPU0_FLT    I39 @S9S_MB_2U_LIB.S9S_MB_2U(SCH_1):PAGE254
     2    GND @S9S_MB_2U_LIB.S9S_MB_2U(SCH_1):GND    I39 @S9S_MB_2U_LIB.S9S_MB_2U(SCH_1):PAGE254

PC281_P0_3 Q_CAP_C0805-22UF,16V,20%,X6S,CA
     1 SW_P12V_PVCCIN_CPU0_FLT @S9S_MB_2U_LIB.S9S_MB_2U(SCH_1):SW_P12V_PVCCIN_CPU0_FLT    I53 @S9S_MB_2U_LIB.S9S_MB_2U(SCH_1):PAGE254
     2    GND @S9S_MB_2U_LIB.S9S_MB_2U(SCH_1):GND    I53 @S9S_MB_2U_LIB.S9S_MB_2U(SCH_1):PAGE254

PC282_P0_4 Q_CAP_C0805-22UF,16V,20%,X6S,CA
     1 SW_P12V_PVCCIN_CPU0_FLT @S9S_MB_2U_LIB.S9S_MB_2U(SCH_1):SW_P12V_PVCCIN_CPU0_FLT    I40 @S9S_MB_2U_LIB.S9S_MB_2U(SCH_1):PAGE254
     2    GND @S9S_MB_2U_LIB.S9S_MB_2U(SCH_1):GND    I40 @S9S_MB_2U_LIB.S9S_MB_2U(SCH_1):PAGE254

PC283_P0_3 Q_CAP_C0805-22UF,16V,20%,X6S,CA
     1 SW_P12V_PVCCIN_CPU0_FLT @S9S_MB_2U_LIB.S9S_MB_2U(SCH_1):SW_P12V_PVCCIN_CPU0_FLT    I54 @S9S_MB_2U_LIB.S9S_MB_2U(SCH_1):PAGE254
     2    GND @S9S_MB_2U_LIB.S9S_MB_2U(SCH_1):GND    I54 @S9S_MB_2U_LIB.S9S_MB_2U(SCH_1):PAGE254

PC284_P0_4 Q_CAP_C0805-22UF,16V,20%,X6S,CA
     1 SW_P12V_PVCCIN_CPU0_FLT @S9S_MB_2U_LIB.S9S_MB_2U(SCH_1):SW_P12V_PVCCIN_CPU0_FLT    I43 @S9S_MB_2U_LIB.S9S_MB_2U(SCH_1):PAGE254
     2    GND @S9S_MB_2U_LIB.S9S_MB_2U(SCH_1):GND    I43 @S9S_MB_2U_LIB.S9S_MB_2U(SCH_1):PAGE254

PC285_P0_3 Q_CAP_C0805-22UF,16V,20%,X6S,CA
     1 SW_P12V_PVCCIN_CPU0_FLT @S9S_MB_2U_LIB.S9S_MB_2U(SCH_1):SW_P12V_PVCCIN_CPU0_FLT    I56 @S9S_MB_2U_LIB.S9S_MB_2U(SCH_1):PAGE254
     2    GND @S9S_MB_2U_LIB.S9S_MB_2U(SCH_1):GND    I56 @S9S_MB_2U_LIB.S9S_MB_2U(SCH_1):PAGE254

PC288_P0_4 Q_CAP_C0805-22UF,4V,20%,X6S,CHA
     1 PVCCIN_CPU0 @S9S_MB_2U_LIB.S9S_MB_2U(SCH_1):PVCCIN_CPU0    I60 @S9S_MB_2U_LIB.S9S_MB_2U(SCH_1):PAGE254
     2    GND @S9S_MB_2U_LIB.S9S_MB_2U(SCH_1):GND    I60 @S9S_MB_2U_LIB.S9S_MB_2U(SCH_1):PAGE254

PC289_P0_3 Q_CAP_C0805-22UF,4V,20%,X6S,CHA
     1 PVCCIN_CPU0 @S9S_MB_2U_LIB.S9S_MB_2U(SCH_1):PVCCIN_CPU0    I59 @S9S_MB_2U_LIB.S9S_MB_2U(SCH_1):PAGE254
     2    GND @S9S_MB_2U_LIB.S9S_MB_2U(SCH_1):GND    I59 @S9S_MB_2U_LIB.S9S_MB_2U(SCH_1):PAGE254

PC290_P0_4 Q_CAP_C0805-22UF,4V,20%,X6S,CHA
     1 PVCCIN_CPU0 @S9S_MB_2U_LIB.S9S_MB_2U(SCH_1):PVCCIN_CPU0    I61 @S9S_MB_2U_LIB.S9S_MB_2U(SCH_1):PAGE254
     2    GND @S9S_MB_2U_LIB.S9S_MB_2U(SCH_1):GND    I61 @S9S_MB_2U_LIB.S9S_MB_2U(SCH_1):PAGE254

PC291_P0_3 Q_CAP_C0805-22UF,4V,20%,X6S,CHA
     1 PVCCIN_CPU0 @S9S_MB_2U_LIB.S9S_MB_2U(SCH_1):PVCCIN_CPU0    I65 @S9S_MB_2U_LIB.S9S_MB_2U(SCH_1):PAGE254
     2    GND @S9S_MB_2U_LIB.S9S_MB_2U(SCH_1):GND    I65 @S9S_MB_2U_LIB.S9S_MB_2U(SCH_1):PAGE254

PC292 Q_CAP_C0402-2.2UF,10V,10%,X6S,A
     1 PVCCIN_CPU0_VDD2 @S9S_MB_2U_LIB.S9S_MB_2U(SCH_1):PVCCIN_CPU0_VDD2     I9 @S9S_MB_2U_LIB.S9S_MB_2U(SCH_1):PAGE253
     2    GND @S9S_MB_2U_LIB.S9S_MB_2U(SCH_1):GND     I9 @S9S_MB_2U_LIB.S9S_MB_2U(SCH_1):PAGE253

PC293 Q_CAP_C0402-2.2UF,10V,10%,X6S,A
     1 PVCCIN_CPU0_VDD1 @S9S_MB_2U_LIB.S9S_MB_2U(SCH_1):PVCCIN_CPU0_VDD1    I36 @S9S_MB_2U_LIB.S9S_MB_2U(SCH_1):PAGE253
     2    GND @S9S_MB_2U_LIB.S9S_MB_2U(SCH_1):GND    I36 @S9S_MB_2U_LIB.S9S_MB_2U(SCH_1):PAGE253

PC294_P0_2 Q_CAP_C0402-2.2UF,10V,10%,X6S,A
     1 PVCCIN_CPU0_PVCC @S9S_MB_2U_LIB.S9S_MB_2U(SCH_1):PVCCIN_CPU0_PVCC    I15 @S9S_MB_2U_LIB.S9S_MB_2U(SCH_1):PAGE253
     2    GND @S9S_MB_2U_LIB.S9S_MB_2U(SCH_1):GND    I15 @S9S_MB_2U_LIB.S9S_MB_2U(SCH_1):PAGE253

PC295_P0_1 Q_CAP_C0402-2.2UF,10V,10%,X6S,A
     1 PVCCIN_CPU0_PVCC @S9S_MB_2U_LIB.S9S_MB_2U(SCH_1):PVCCIN_CPU0_PVCC    I39 @S9S_MB_2U_LIB.S9S_MB_2U(SCH_1):PAGE253
     2    GND @S9S_MB_2U_LIB.S9S_MB_2U(SCH_1):GND    I39 @S9S_MB_2U_LIB.S9S_MB_2U(SCH_1):PAGE253

PC296_P0_2 Q_CAP_0402-3300PF,50V,10%,X7R,A
     1 SW_P12V_PVCCIN_CPU0_FLT @S9S_MB_2U_LIB.S9S_MB_2U(SCH_1):SW_P12V_PVCCIN_CPU0_FLT    I19 @S9S_MB_2U_LIB.S9S_MB_2U(SCH_1):PAGE253
     2    GND @S9S_MB_2U_LIB.S9S_MB_2U(SCH_1):GND    I19 @S9S_MB_2U_LIB.S9S_MB_2U(SCH_1):PAGE253

PC297_P0_1 Q_CAP_0402-3300PF,50V,10%,X7R,A
     1 SW_P12V_PVCCIN_CPU0_FLT @S9S_MB_2U_LIB.S9S_MB_2U(SCH_1):SW_P12V_PVCCIN_CPU0_FLT    I44 @S9S_MB_2U_LIB.S9S_MB_2U(SCH_1):PAGE253
     2    GND @S9S_MB_2U_LIB.S9S_MB_2U(SCH_1):GND    I44 @S9S_MB_2U_LIB.S9S_MB_2U(SCH_1):PAGE253

PC298_P0_2 Q_CAP_C0402-1UF,16V,10%,X6S,CHA
     1 SW_P12V_PVCCIN_CPU0_FLT @S9S_MB_2U_LIB.S9S_MB_2U(SCH_1):SW_P12V_PVCCIN_CPU0_FLT    I22 @S9S_MB_2U_LIB.S9S_MB_2U(SCH_1):PAGE253
     2    GND @S9S_MB_2U_LIB.S9S_MB_2U(SCH_1):GND    I22 @S9S_MB_2U_LIB.S9S_MB_2U(SCH_1):PAGE253

PC299_P0_1 Q_CAP_C0402-1UF,16V,10%,X6S,CHA
     1 SW_P12V_PVCCIN_CPU0_FLT @S9S_MB_2U_LIB.S9S_MB_2U(SCH_1):SW_P12V_PVCCIN_CPU0_FLT    I47 @S9S_MB_2U_LIB.S9S_MB_2U(SCH_1):PAGE253
     2    GND @S9S_MB_2U_LIB.S9S_MB_2U(SCH_1):GND    I47 @S9S_MB_2U_LIB.S9S_MB_2U(SCH_1):PAGE253

PC300 Q_CAP_C0402-100NF,50V,10%,X7R,A
     1 SW_PVCCIN_CPU0_BOOT2_R @S9S_MB_2U_LIB.S9S_MB_2U(SCH_1):SW_PVCCIN_CPU0_BOOT2_R    I20 @S9S_MB_2U_LIB.S9S_MB_2U(SCH_1):PAGE253
     2 SW_PVCCIN_CPU0_BOOTR2 @S9S_MB_2U_LIB.S9S_MB_2U(SCH_1):SW_PVCCIN_CPU0_BOOTR2    I20 @S9S_MB_2U_LIB.S9S_MB_2U(SCH_1):PAGE253

PC301 Q_CAP_C0402-100NF,50V,10%,X7R,A
     1 SW_PVCCIN_CPU0_BOOT1_R @S9S_MB_2U_LIB.S9S_MB_2U(SCH_1):SW_PVCCIN_CPU0_BOOT1_R    I48 @S9S_MB_2U_LIB.S9S_MB_2U(SCH_1):PAGE253
     2 SW_PVCCIN_CPU0_BOOTR1 @S9S_MB_2U_LIB.S9S_MB_2U(SCH_1):SW_PVCCIN_CPU0_BOOTR1    I48 @S9S_MB_2U_LIB.S9S_MB_2U(SCH_1):PAGE253

PC302_P0_2 Q_CAP_C0805-22UF,16V,20%,X6S,CA
     1 SW_P12V_PVCCIN_CPU0_FLT @S9S_MB_2U_LIB.S9S_MB_2U(SCH_1):SW_P12V_PVCCIN_CPU0_FLT    I23 @S9S_MB_2U_LIB.S9S_MB_2U(SCH_1):PAGE253
     2    GND @S9S_MB_2U_LIB.S9S_MB_2U(SCH_1):GND    I23 @S9S_MB_2U_LIB.S9S_MB_2U(SCH_1):PAGE253

PC303_P0_1 Q_CAP_C0805-22UF,16V,20%,X6S,CA
     1 SW_P12V_PVCCIN_CPU0_FLT @S9S_MB_2U_LIB.S9S_MB_2U(SCH_1):SW_P12V_PVCCIN_CPU0_FLT    I49 @S9S_MB_2U_LIB.S9S_MB_2U(SCH_1):PAGE253
     2    GND @S9S_MB_2U_LIB.S9S_MB_2U(SCH_1):GND    I49 @S9S_MB_2U_LIB.S9S_MB_2U(SCH_1):PAGE253

PC304_P0_2 Q_CAP_C0805-22UF,16V,20%,X6S,CA
     1 SW_P12V_PVCCIN_CPU0_FLT @S9S_MB_2U_LIB.S9S_MB_2U(SCH_1):SW_P12V_PVCCIN_CPU0_FLT    I24 @S9S_MB_2U_LIB.S9S_MB_2U(SCH_1):PAGE253
     2    GND @S9S_MB_2U_LIB.S9S_MB_2U(SCH_1):GND    I24 @S9S_MB_2U_LIB.S9S_MB_2U(SCH_1):PAGE253

PC305_P0_1 Q_CAP_C0805-22UF,16V,20%,X6S,CA
     1 SW_P12V_PVCCIN_CPU0_FLT @S9S_MB_2U_LIB.S9S_MB_2U(SCH_1):SW_P12V_PVCCIN_CPU0_FLT    I50 @S9S_MB_2U_LIB.S9S_MB_2U(SCH_1):PAGE253
     2    GND @S9S_MB_2U_LIB.S9S_MB_2U(SCH_1):GND    I50 @S9S_MB_2U_LIB.S9S_MB_2U(SCH_1):PAGE253

PC306_P0_2 Q_CAP_C0805-22UF,16V,20%,X6S,CA
     1 SW_P12V_PVCCIN_CPU0_FLT @S9S_MB_2U_LIB.S9S_MB_2U(SCH_1):SW_P12V_PVCCIN_CPU0_FLT    I54 @S9S_MB_2U_LIB.S9S_MB_2U(SCH_1):PAGE253
     2    GND @S9S_MB_2U_LIB.S9S_MB_2U(SCH_1):GND    I54 @S9S_MB_2U_LIB.S9S_MB_2U(SCH_1):PAGE253

PC307_P0_1 Q_CAP_C0805-22UF,16V,20%,X6S,CA
     1 SW_P12V_PVCCIN_CPU0_FLT @S9S_MB_2U_LIB.S9S_MB_2U(SCH_1):SW_P12V_PVCCIN_CPU0_FLT    I75 @S9S_MB_2U_LIB.S9S_MB_2U(SCH_1):PAGE253
     2    GND @S9S_MB_2U_LIB.S9S_MB_2U(SCH_1):GND    I75 @S9S_MB_2U_LIB.S9S_MB_2U(SCH_1):PAGE253

PC308_P0_1 Q_CAP_C0402-100NF,50V,10%,X7R,A
     1 PVCCIN_CPU0 @S9S_MB_2U_LIB.S9S_MB_2U(SCH_1):PVCCIN_CPU0    I83 @S9S_MB_2U_LIB.S9S_MB_2U(SCH_1):PAGE253
     2    GND @S9S_MB_2U_LIB.S9S_MB_2U(SCH_1):GND    I83 @S9S_MB_2U_LIB.S9S_MB_2U(SCH_1):PAGE253

PC310_P0_1 Q_CAP_C0402-1UF,16V,10%,X6S,CHA
     1 PVCCIN_CPU0 @S9S_MB_2U_LIB.S9S_MB_2U(SCH_1):PVCCIN_CPU0    I84 @S9S_MB_2U_LIB.S9S_MB_2U(SCH_1):PAGE253
     2    GND @S9S_MB_2U_LIB.S9S_MB_2U(SCH_1):GND    I84 @S9S_MB_2U_LIB.S9S_MB_2U(SCH_1):PAGE253

PC311_P0_2 Q_CAP_C0805-22UF,4V,20%,X6S,CHA
     1 PVCCIN_CPU0 @S9S_MB_2U_LIB.S9S_MB_2U(SCH_1):PVCCIN_CPU0    I57 @S9S_MB_2U_LIB.S9S_MB_2U(SCH_1):PAGE253
     2    GND @S9S_MB_2U_LIB.S9S_MB_2U(SCH_1):GND    I57 @S9S_MB_2U_LIB.S9S_MB_2U(SCH_1):PAGE253

PC312_P0_1 Q_CAP_C0805-22UF,4V,20%,X6S,CHA
     1 PVCCIN_CPU0 @S9S_MB_2U_LIB.S9S_MB_2U(SCH_1):PVCCIN_CPU0    I85 @S9S_MB_2U_LIB.S9S_MB_2U(SCH_1):PAGE253
     2    GND @S9S_MB_2U_LIB.S9S_MB_2U(SCH_1):GND    I85 @S9S_MB_2U_LIB.S9S_MB_2U(SCH_1):PAGE253

PC313_P0_2 Q_CAP_C0805-22UF,4V,20%,X6S,CHA
     1 PVCCIN_CPU0 @S9S_MB_2U_LIB.S9S_MB_2U(SCH_1):PVCCIN_CPU0    I58 @S9S_MB_2U_LIB.S9S_MB_2U(SCH_1):PAGE253
     2    GND @S9S_MB_2U_LIB.S9S_MB_2U(SCH_1):GND    I58 @S9S_MB_2U_LIB.S9S_MB_2U(SCH_1):PAGE253

PC314_P0_1 Q_CAP_C0805-22UF,4V,20%,X6S,CHA
     1 PVCCIN_CPU0 @S9S_MB_2U_LIB.S9S_MB_2U(SCH_1):PVCCIN_CPU0    I86 @S9S_MB_2U_LIB.S9S_MB_2U(SCH_1):PAGE253
     2    GND @S9S_MB_2U_LIB.S9S_MB_2U(SCH_1):GND    I86 @S9S_MB_2U_LIB.S9S_MB_2U(SCH_1):PAGE253

PC315 Q_CAPP_THLF-270UF,16V,20%,OSCOA
     1 SW_P12V_PVCCIN_CPU0_FLT @S9S_MB_2U_LIB.S9S_MB_2U(SCH_1):SW_P12V_PVCCIN_CPU0_FLT    I91 @S9S_MB_2U_LIB.S9S_MB_2U(SCH_1):PAGE253
     2    GND @S9S_MB_2U_LIB.S9S_MB_2U(SCH_1):GND    I91 @S9S_MB_2U_LIB.S9S_MB_2U(SCH_1):PAGE253

PC316 Q_CAPP_THLF-560UF,2.5V,20%,OSCA
     1 PVCCIN_CPU0 @S9S_MB_2U_LIB.S9S_MB_2U(SCH_1):PVCCIN_CPU0    I61 @S9S_MB_2U_LIB.S9S_MB_2U(SCH_1):PAGE253
     2    GND @S9S_MB_2U_LIB.S9S_MB_2U(SCH_1):GND    I61 @S9S_MB_2U_LIB.S9S_MB_2U(SCH_1):PAGE253

PC318 Q_CAPP_THLF-270UF,16V,20%,OSCOA
     1 SW_P12V_PVCCIN_CPU0_FLT @S9S_MB_2U_LIB.S9S_MB_2U(SCH_1):SW_P12V_PVCCIN_CPU0_FLT    I92 @S9S_MB_2U_LIB.S9S_MB_2U(SCH_1):PAGE253
     2    GND @S9S_MB_2U_LIB.S9S_MB_2U(SCH_1):GND    I92 @S9S_MB_2U_LIB.S9S_MB_2U(SCH_1):PAGE253

PC319 Q_CAPP_THLF-560UF,2.5V,20%,OSCA
     1 PVCCIN_CPU0 @S9S_MB_2U_LIB.S9S_MB_2U(SCH_1):PVCCIN_CPU0    I62 @S9S_MB_2U_LIB.S9S_MB_2U(SCH_1):PAGE253
     2    GND @S9S_MB_2U_LIB.S9S_MB_2U(SCH_1):GND    I62 @S9S_MB_2U_LIB.S9S_MB_2U(SCH_1):PAGE253

PC321 Q_CAPP_THLF-270UF,16V,20%,OSCOA
     1 SW_P12V_PVCCIN_CPU0_FLT @S9S_MB_2U_LIB.S9S_MB_2U(SCH_1):SW_P12V_PVCCIN_CPU0_FLT    I93 @S9S_MB_2U_LIB.S9S_MB_2U(SCH_1):PAGE253
     2    GND @S9S_MB_2U_LIB.S9S_MB_2U(SCH_1):GND    I93 @S9S_MB_2U_LIB.S9S_MB_2U(SCH_1):PAGE253

PC322 Q_CAPP_THLF-560UF,2.5V,20%,OSCA
     1 PVCCIN_CPU0 @S9S_MB_2U_LIB.S9S_MB_2U(SCH_1):PVCCIN_CPU0    I67 @S9S_MB_2U_LIB.S9S_MB_2U(SCH_1):PAGE253
     2    GND @S9S_MB_2U_LIB.S9S_MB_2U(SCH_1):GND    I67 @S9S_MB_2U_LIB.S9S_MB_2U(SCH_1):PAGE253

PC323 Q_CAPP_SMLF-330UF,2.5V,+10/-35A
     1 PVCCIN_CPU0 @S9S_MB_2U_LIB.S9S_MB_2U(SCH_1):PVCCIN_CPU0    I64 @S9S_MB_2U_LIB.S9S_MB_2U(SCH_1):PAGE253
     2    GND @S9S_MB_2U_LIB.S9S_MB_2U(SCH_1):GND    I64 @S9S_MB_2U_LIB.S9S_MB_2U(SCH_1):PAGE253

PC324 Q_CAPP_THLF-270UF,16V,20%,OSCOA
     1 SW_P12V_PVCCIN_CPU0_FLT @S9S_MB_2U_LIB.S9S_MB_2U(SCH_1):SW_P12V_PVCCIN_CPU0_FLT    I94 @S9S_MB_2U_LIB.S9S_MB_2U(SCH_1):PAGE253
     2    GND @S9S_MB_2U_LIB.S9S_MB_2U(SCH_1):GND    I94 @S9S_MB_2U_LIB.S9S_MB_2U(SCH_1):PAGE253

PC325 Q_CAPP_THLF-560UF,2.5V,20%,OSCA
     1 PVCCIN_CPU0 @S9S_MB_2U_LIB.S9S_MB_2U(SCH_1):PVCCIN_CPU0    I70 @S9S_MB_2U_LIB.S9S_MB_2U(SCH_1):PAGE253
     2    GND @S9S_MB_2U_LIB.S9S_MB_2U(SCH_1):GND    I70 @S9S_MB_2U_LIB.S9S_MB_2U(SCH_1):PAGE253

PC326 Q_CAPP_SMLF-330UF,2.5V,+10/-35A
     1 PVCCIN_CPU0 @S9S_MB_2U_LIB.S9S_MB_2U(SCH_1):PVCCIN_CPU0    I66 @S9S_MB_2U_LIB.S9S_MB_2U(SCH_1):PAGE253
     2    GND @S9S_MB_2U_LIB.S9S_MB_2U(SCH_1):GND    I66 @S9S_MB_2U_LIB.S9S_MB_2U(SCH_1):PAGE253

PC329 Q_CAP_0402-0.1UF,25V,10%,EMPTYA
     1 PVCCIN_CPU0_CSPIN @S9S_MB_2U_LIB.S9S_MB_2U(SCH_1):PVCCIN_CPU0_CSPIN    I53 @S9S_MB_2U_LIB.S9S_MB_2U(SCH_1):PAGE252
     2    GND @S9S_MB_2U_LIB.S9S_MB_2U(SCH_1):GND    I53 @S9S_MB_2U_LIB.S9S_MB_2U(SCH_1):PAGE252

PC330 Q_CAP_0402-0.1UF,25V,10%,X7R,CA
     1 PVCCIN_CPU0_VIN_CSNIN @S9S_MB_2U_LIB.S9S_MB_2U(SCH_1):PVCCIN_CPU0_VIN_CSNIN    I61 @S9S_MB_2U_LIB.S9S_MB_2U(SCH_1):PAGE252
     2    GND @S9S_MB_2U_LIB.S9S_MB_2U(SCH_1):GND    I61 @S9S_MB_2U_LIB.S9S_MB_2U(SCH_1):PAGE252

PC331 Q_CAP_0402-3300PF,50V,10%,X7R,A
     1 SH_PVCCIN_CPU0_R @S9S_MB_2U_LIB.S9S_MB_2U(SCH_1):SH_PVCCIN_CPU0_R    I79 @S9S_MB_2U_LIB.S9S_MB_2U(SCH_1):PAGE252
     2 VSENSE_PVCCIN_CPU0_DN @S9S_MB_2U_LIB.S9S_MB_2U(SCH_1):VSENSE_PVCCIN_CPU0_DN    I79 @S9S_MB_2U_LIB.S9S_MB_2U(SCH_1):PAGE252

PC334 Q_CAP_0402-0.1UF,25V,10%,EMPTYA
     1 PVCCIN_CPU0_VCC @S9S_MB_2U_LIB.S9S_MB_2U(SCH_1):PVCCIN_CPU0_VCC    I88 @S9S_MB_2U_LIB.S9S_MB_2U(SCH_1):PAGE252
     2    GND @S9S_MB_2U_LIB.S9S_MB_2U(SCH_1):GND    I88 @S9S_MB_2U_LIB.S9S_MB_2U(SCH_1):PAGE252

PC335 Q_CAP_C0402-10UF,6.3V,20%,X6S,B
     1 PVCCIN_CPU0_VREF @S9S_MB_2U_LIB.S9S_MB_2U(SCH_1):PVCCIN_CPU0_VREF    I86 @S9S_MB_2U_LIB.S9S_MB_2U(SCH_1):PAGE252
     2    GND @S9S_MB_2U_LIB.S9S_MB_2U(SCH_1):GND    I86 @S9S_MB_2U_LIB.S9S_MB_2U(SCH_1):PAGE252

PC336 Q_CAP_0402-470PF,50V,10%,X7R,TA
     1 PVCCIN_CPU0_ATSEN @S9S_MB_2U_LIB.S9S_MB_2U(SCH_1):PVCCIN_CPU0_ATSEN    I70 @S9S_MB_2U_LIB.S9S_MB_2U(SCH_1):PAGE252
     2    GND @S9S_MB_2U_LIB.S9S_MB_2U(SCH_1):GND    I70 @S9S_MB_2U_LIB.S9S_MB_2U(SCH_1):PAGE252

PC337 Q_CAP_C0402-1UF,16V,10%,X6S,CHA
     1 PVCCIN_CPU0_VCC @S9S_MB_2U_LIB.S9S_MB_2U(SCH_1):PVCCIN_CPU0_VCC    I89 @S9S_MB_2U_LIB.S9S_MB_2U(SCH_1):PAGE252
     2    GND @S9S_MB_2U_LIB.S9S_MB_2U(SCH_1):GND    I89 @S9S_MB_2U_LIB.S9S_MB_2U(SCH_1):PAGE252

PC373 Q_CAP_C0402-2.2UF,10V,10%,X6S,A
     1 PVCCD_HV_CPU1_VDD1 @S9S_MB_2U_LIB.S9S_MB_2U(SCH_1):PVCCD_HV_CPU1_VDD1    I15 @S9S_MB_2U_LIB.S9S_MB_2U(SCH_1):PAGE283
     2    GND @S9S_MB_2U_LIB.S9S_MB_2U(SCH_1):GND    I15 @S9S_MB_2U_LIB.S9S_MB_2U(SCH_1):PAGE283

PC374 Q_CAP_0402-3300PF,50V,10%,X7R,A
     1 SW_P12V_PVCCINFAON_CPU1_FLT @S9S_MB_2U_LIB.S9S_MB_2U(SCH_1):SW_P12V_PVCCINFAON_CPU1_FLT    I20 @S9S_MB_2U_LIB.S9S_MB_2U(SCH_1):PAGE283
     2    GND @S9S_MB_2U_LIB.S9S_MB_2U(SCH_1):GND    I20 @S9S_MB_2U_LIB.S9S_MB_2U(SCH_1):PAGE283

PC375 Q_CAP_C0402-1UF,16V,10%,X6S,CHA
     1 SW_P12V_PVCCINFAON_CPU1_FLT @S9S_MB_2U_LIB.S9S_MB_2U(SCH_1):SW_P12V_PVCCINFAON_CPU1_FLT    I22 @S9S_MB_2U_LIB.S9S_MB_2U(SCH_1):PAGE283
     2    GND @S9S_MB_2U_LIB.S9S_MB_2U(SCH_1):GND    I22 @S9S_MB_2U_LIB.S9S_MB_2U(SCH_1):PAGE283

PC376 Q_CAP_C0402-100NF,50V,10%,X7R,A
     1 SW_PVCCD_HV_CPU1_BOOT1_R @S9S_MB_2U_LIB.S9S_MB_2U(SCH_1):SW_PVCCD_HV_CPU1_BOOT1_R    I13 @S9S_MB_2U_LIB.S9S_MB_2U(SCH_1):PAGE283
     2 SW_PVCCD_HV_CPU1_BOOTR1 @S9S_MB_2U_LIB.S9S_MB_2U(SCH_1):SW_PVCCD_HV_CPU1_BOOTR1    I13 @S9S_MB_2U_LIB.S9S_MB_2U(SCH_1):PAGE283

PC377 Q_CAP_C0805-22UF,16V,20%,X6S,CA
     1 SW_P12V_PVCCINFAON_CPU1_FLT @S9S_MB_2U_LIB.S9S_MB_2U(SCH_1):SW_P12V_PVCCINFAON_CPU1_FLT    I23 @S9S_MB_2U_LIB.S9S_MB_2U(SCH_1):PAGE283
     2    GND @S9S_MB_2U_LIB.S9S_MB_2U(SCH_1):GND    I23 @S9S_MB_2U_LIB.S9S_MB_2U(SCH_1):PAGE283

PC378 Q_CAP_C0805-22UF,16V,20%,X6S,CA
     1 SW_P12V_PVCCINFAON_CPU1_FLT @S9S_MB_2U_LIB.S9S_MB_2U(SCH_1):SW_P12V_PVCCINFAON_CPU1_FLT    I24 @S9S_MB_2U_LIB.S9S_MB_2U(SCH_1):PAGE283
     2    GND @S9S_MB_2U_LIB.S9S_MB_2U(SCH_1):GND    I24 @S9S_MB_2U_LIB.S9S_MB_2U(SCH_1):PAGE283

PC379 Q_CAP_C0402-100NF,50V,10%,X7R,A
     1 PVCCD_HV_CPU1 @S9S_MB_2U_LIB.S9S_MB_2U(SCH_1):PVCCD_HV_CPU1    I27 @S9S_MB_2U_LIB.S9S_MB_2U(SCH_1):PAGE283
     2    GND @S9S_MB_2U_LIB.S9S_MB_2U(SCH_1):GND    I27 @S9S_MB_2U_LIB.S9S_MB_2U(SCH_1):PAGE283

PC381 Q_CAP_C0805-22UF,4V,20%,X6S,CHA
     1 PVCCD_HV_CPU1 @S9S_MB_2U_LIB.S9S_MB_2U(SCH_1):PVCCD_HV_CPU1    I28 @S9S_MB_2U_LIB.S9S_MB_2U(SCH_1):PAGE283
     2    GND @S9S_MB_2U_LIB.S9S_MB_2U(SCH_1):GND    I28 @S9S_MB_2U_LIB.S9S_MB_2U(SCH_1):PAGE283

PC382 Q_CAP_C0805-22UF,4V,20%,X6S,CHA
     1 PVCCD_HV_CPU1 @S9S_MB_2U_LIB.S9S_MB_2U(SCH_1):PVCCD_HV_CPU1    I29 @S9S_MB_2U_LIB.S9S_MB_2U(SCH_1):PAGE283
     2    GND @S9S_MB_2U_LIB.S9S_MB_2U(SCH_1):GND    I29 @S9S_MB_2U_LIB.S9S_MB_2U(SCH_1):PAGE283

PC384 Q_CAPP_THLF-560UF,2.5V,20%,OSCA
     1 PVCCD_HV_CPU1 @S9S_MB_2U_LIB.S9S_MB_2U(SCH_1):PVCCD_HV_CPU1    I26 @S9S_MB_2U_LIB.S9S_MB_2U(SCH_1):PAGE283
     2    GND @S9S_MB_2U_LIB.S9S_MB_2U(SCH_1):GND    I26 @S9S_MB_2U_LIB.S9S_MB_2U(SCH_1):PAGE283

PC385 Q_CAPP_THLF-560UF,2.5V,20%,OSCA
     1 PVCCD_HV_CPU1 @S9S_MB_2U_LIB.S9S_MB_2U(SCH_1):PVCCD_HV_CPU1    I32 @S9S_MB_2U_LIB.S9S_MB_2U(SCH_1):PAGE283
     2    GND @S9S_MB_2U_LIB.S9S_MB_2U(SCH_1):GND    I32 @S9S_MB_2U_LIB.S9S_MB_2U(SCH_1):PAGE283

PC386 Q_CAP_0402-0.1UF,25V,10%,X7R,CA
     1 PVCCD_HV_CPU1_ISENSE_P @S9S_MB_2U_LIB.S9S_MB_2U(SCH_1):PVCCD_HV_CPU1_ISENSE_P    I13 @S9S_MB_2U_LIB.S9S_MB_2U(SCH_1):PAGE282
     2    GND @S9S_MB_2U_LIB.S9S_MB_2U(SCH_1):GND    I13 @S9S_MB_2U_LIB.S9S_MB_2U(SCH_1):PAGE282

PC389 Q_CAP_0402-3300PF,50V,10%,X7R,A
     1 SH_PVCCD_HV_CPU1_R @S9S_MB_2U_LIB.S9S_MB_2U(SCH_1):SH_PVCCD_HV_CPU1_R    I22 @S9S_MB_2U_LIB.S9S_MB_2U(SCH_1):PAGE282
     2 VSENSE_PVCCD_HV_CPU1_DN @S9S_MB_2U_LIB.S9S_MB_2U(SCH_1):VSENSE_PVCCD_HV_CPU1_DN    I22 @S9S_MB_2U_LIB.S9S_MB_2U(SCH_1):PAGE282

PC390 Q_CAP_0402-0.1UF,25V,10%,X7R,CA
     1 PVCCD_HV_CPU1_ISENSE_N @S9S_MB_2U_LIB.S9S_MB_2U(SCH_1):PVCCD_HV_CPU1_ISENSE_N    I50 @S9S_MB_2U_LIB.S9S_MB_2U(SCH_1):PAGE282
     2    GND @S9S_MB_2U_LIB.S9S_MB_2U(SCH_1):GND    I50 @S9S_MB_2U_LIB.S9S_MB_2U(SCH_1):PAGE282

PC391 Q_CAP_C0402-100NF,50V,10%,EMPTA
     1 PVCCD_HV_CPU1_VCC @S9S_MB_2U_LIB.S9S_MB_2U(SCH_1):PVCCD_HV_CPU1_VCC    I69 @S9S_MB_2U_LIB.S9S_MB_2U(SCH_1):PAGE282
     2    GND @S9S_MB_2U_LIB.S9S_MB_2U(SCH_1):GND    I69 @S9S_MB_2U_LIB.S9S_MB_2U(SCH_1):PAGE282

PC392 Q_CAP_C0402-10UF,6.3V,20%,X6S,B
     1 PVCCD_HV_CPU1_VREF @S9S_MB_2U_LIB.S9S_MB_2U(SCH_1):PVCCD_HV_CPU1_VREF    I68 @S9S_MB_2U_LIB.S9S_MB_2U(SCH_1):PAGE282
     2    GND @S9S_MB_2U_LIB.S9S_MB_2U(SCH_1):GND    I68 @S9S_MB_2U_LIB.S9S_MB_2U(SCH_1):PAGE282

PC393 Q_CAP_0402-470PF,50V,10%,X7R,TA
     1 PVCCD_HV_CPU1_ATSEN @S9S_MB_2U_LIB.S9S_MB_2U(SCH_1):PVCCD_HV_CPU1_ATSEN    I57 @S9S_MB_2U_LIB.S9S_MB_2U(SCH_1):PAGE282
     2    GND @S9S_MB_2U_LIB.S9S_MB_2U(SCH_1):GND    I57 @S9S_MB_2U_LIB.S9S_MB_2U(SCH_1):PAGE282

PC394 Q_CAP_C0402-1UF,16V,10%,X6S,CHA
     1 PVCCD_HV_CPU1_VCC @S9S_MB_2U_LIB.S9S_MB_2U(SCH_1):PVCCD_HV_CPU1_VCC    I77 @S9S_MB_2U_LIB.S9S_MB_2U(SCH_1):PAGE282
     2    GND @S9S_MB_2U_LIB.S9S_MB_2U(SCH_1):GND    I77 @S9S_MB_2U_LIB.S9S_MB_2U(SCH_1):PAGE282

PC395 Q_CAP_C0402-2.2UF,10V,10%,X6S,A
     1 PVCCFA_EHV_FIVRA_CPU1_VDD1 @S9S_MB_2U_LIB.S9S_MB_2U(SCH_1):PVCCFA_EHV_FIVRA_CPU1_VDD1    I27 @S9S_MB_2U_LIB.S9S_MB_2U(SCH_1):PAGE275
     2    GND @S9S_MB_2U_LIB.S9S_MB_2U(SCH_1):GND    I27 @S9S_MB_2U_LIB.S9S_MB_2U(SCH_1):PAGE275

PC396 Q_CAP_C0402-2.2UF,10V,10%,X6S,A
     1 PVCCFA_EHV_FIVRA_CPU1_VDD2 @S9S_MB_2U_LIB.S9S_MB_2U(SCH_1):PVCCFA_EHV_FIVRA_CPU1_VDD2    I11 @S9S_MB_2U_LIB.S9S_MB_2U(SCH_1):PAGE275
     2    GND @S9S_MB_2U_LIB.S9S_MB_2U(SCH_1):GND    I11 @S9S_MB_2U_LIB.S9S_MB_2U(SCH_1):PAGE275

PC397_P1_1 Q_CAP_0402-3300PF,50V,10%,X7R,A
     1 SW_P12V_PVCCFA_EHV_FIVRA_CPU1_R @S9S_MB_2U_LIB.S9S_MB_2U(SCH_1):SW_P12V_PVCCFA_EHV_FIVRA_CPU1_R    I49 @S9S_MB_2U_LIB.S9S_MB_2U(SCH_1):PAGE275
     2    GND @S9S_MB_2U_LIB.S9S_MB_2U(SCH_1):GND    I49 @S9S_MB_2U_LIB.S9S_MB_2U(SCH_1):PAGE275

PC398_P1_2 Q_CAP_0402-3300PF,50V,10%,X7R,A
     1 SW_P12V_PVCCFA_EHV_FIVRA_CPU1_L @S9S_MB_2U_LIB.S9S_MB_2U(SCH_1):SW_P12V_PVCCFA_EHV_FIVRA_CPU1_L    I37 @S9S_MB_2U_LIB.S9S_MB_2U(SCH_1):PAGE275
     2    GND @S9S_MB_2U_LIB.S9S_MB_2U(SCH_1):GND    I37 @S9S_MB_2U_LIB.S9S_MB_2U(SCH_1):PAGE275

PC399_P1_1 Q_CAP_C0402-1UF,16V,10%,X6S,CHA
     1 SW_P12V_PVCCFA_EHV_FIVRA_CPU1_R @S9S_MB_2U_LIB.S9S_MB_2U(SCH_1):SW_P12V_PVCCFA_EHV_FIVRA_CPU1_R    I51 @S9S_MB_2U_LIB.S9S_MB_2U(SCH_1):PAGE275
     2    GND @S9S_MB_2U_LIB.S9S_MB_2U(SCH_1):GND    I51 @S9S_MB_2U_LIB.S9S_MB_2U(SCH_1):PAGE275

PC400_P1_2 Q_CAP_C0402-1UF,16V,10%,X6S,CHA
     1 SW_P12V_PVCCFA_EHV_FIVRA_CPU1_L @S9S_MB_2U_LIB.S9S_MB_2U(SCH_1):SW_P12V_PVCCFA_EHV_FIVRA_CPU1_L    I39 @S9S_MB_2U_LIB.S9S_MB_2U(SCH_1):PAGE275
     2    GND @S9S_MB_2U_LIB.S9S_MB_2U(SCH_1):GND    I39 @S9S_MB_2U_LIB.S9S_MB_2U(SCH_1):PAGE275

PC401 Q_CAP_C0402-100NF,50V,10%,X7R,A
     1 SW_PVCCFA_EHV_FIVRA_CPU1_BOOT1_ @S9S_MB_2U_LIB.S9S_MB_2U(SCH_1):SW_PVCCFA_EHV_FIVRA_CPU1_BOOT1_R    I54 @S9S_MB_2U_LIB.S9S_MB_2U(SCH_1):PAGE275
     2 SW_PVCCFA_EHV_FIVRA_CPU1_BOOTR1 @S9S_MB_2U_LIB.S9S_MB_2U(SCH_1):SW_PVCCFA_EHV_FIVRA_CPU1_BOOTR1    I54 @S9S_MB_2U_LIB.S9S_MB_2U(SCH_1):PAGE275

PC402 Q_CAP_C0402-100NF,50V,10%,X7R,A
     1 SW_PVCCFA_EHV_FIVRA_CPU1_BOOT2_ @S9S_MB_2U_LIB.S9S_MB_2U(SCH_1):SW_PVCCFA_EHV_FIVRA_CPU1_BOOT2_R    I43 @S9S_MB_2U_LIB.S9S_MB_2U(SCH_1):PAGE275
     2 SW_PVCCFA_EHV_FIVRA_CPU1_BOOTR2 @S9S_MB_2U_LIB.S9S_MB_2U(SCH_1):SW_PVCCFA_EHV_FIVRA_CPU1_BOOTR2    I43 @S9S_MB_2U_LIB.S9S_MB_2U(SCH_1):PAGE275

PC403_P1_1 Q_CAP_C0805-22UF,16V,20%,X6S,CA
     1 SW_P12V_PVCCFA_EHV_FIVRA_CPU1_R @S9S_MB_2U_LIB.S9S_MB_2U(SCH_1):SW_P12V_PVCCFA_EHV_FIVRA_CPU1_R    I52 @S9S_MB_2U_LIB.S9S_MB_2U(SCH_1):PAGE275
     2    GND @S9S_MB_2U_LIB.S9S_MB_2U(SCH_1):GND    I52 @S9S_MB_2U_LIB.S9S_MB_2U(SCH_1):PAGE275

PC404_P1_2 Q_CAP_C0805-22UF,16V,20%,X6S,CA
     1 SW_P12V_PVCCFA_EHV_FIVRA_CPU1_L @S9S_MB_2U_LIB.S9S_MB_2U(SCH_1):SW_P12V_PVCCFA_EHV_FIVRA_CPU1_L    I40 @S9S_MB_2U_LIB.S9S_MB_2U(SCH_1):PAGE275
     2    GND @S9S_MB_2U_LIB.S9S_MB_2U(SCH_1):GND    I40 @S9S_MB_2U_LIB.S9S_MB_2U(SCH_1):PAGE275

PC405_P1_1 Q_CAP_C0805-22UF,16V,20%,X6S,CA
     1 SW_P12V_PVCCFA_EHV_FIVRA_CPU1_R @S9S_MB_2U_LIB.S9S_MB_2U(SCH_1):SW_P12V_PVCCFA_EHV_FIVRA_CPU1_R    I56 @S9S_MB_2U_LIB.S9S_MB_2U(SCH_1):PAGE275
     2    GND @S9S_MB_2U_LIB.S9S_MB_2U(SCH_1):GND    I56 @S9S_MB_2U_LIB.S9S_MB_2U(SCH_1):PAGE275

PC406_P1_2 Q_CAP_C0805-22UF,16V,20%,X6S,CA
     1 SW_P12V_PVCCFA_EHV_FIVRA_CPU1_L @S9S_MB_2U_LIB.S9S_MB_2U(SCH_1):SW_P12V_PVCCFA_EHV_FIVRA_CPU1_L    I42 @S9S_MB_2U_LIB.S9S_MB_2U(SCH_1):PAGE275
     2    GND @S9S_MB_2U_LIB.S9S_MB_2U(SCH_1):GND    I42 @S9S_MB_2U_LIB.S9S_MB_2U(SCH_1):PAGE275

PC408_P1_2 Q_CAP_C0402-1UF,16V,10%,X6S,CHA
     1 PVCCFA_EHV_FIVRA_CPU1 @S9S_MB_2U_LIB.S9S_MB_2U(SCH_1):PVCCFA_EHV_FIVRA_CPU1    I61 @S9S_MB_2U_LIB.S9S_MB_2U(SCH_1):PAGE275
     2    GND @S9S_MB_2U_LIB.S9S_MB_2U(SCH_1):GND    I61 @S9S_MB_2U_LIB.S9S_MB_2U(SCH_1):PAGE275

PC410_P1_1 Q_CAP_C0805-22UF,4V,20%,X6S,CHA
     1 PVCCFA_EHV_FIVRA_CPU1 @S9S_MB_2U_LIB.S9S_MB_2U(SCH_1):PVCCFA_EHV_FIVRA_CPU1    I74 @S9S_MB_2U_LIB.S9S_MB_2U(SCH_1):PAGE275
     2    GND @S9S_MB_2U_LIB.S9S_MB_2U(SCH_1):GND    I74 @S9S_MB_2U_LIB.S9S_MB_2U(SCH_1):PAGE275

PC411_P1_2 Q_CAP_C0805-22UF,4V,20%,X6S,CHA
     1 PVCCFA_EHV_FIVRA_CPU1 @S9S_MB_2U_LIB.S9S_MB_2U(SCH_1):PVCCFA_EHV_FIVRA_CPU1    I62 @S9S_MB_2U_LIB.S9S_MB_2U(SCH_1):PAGE275
     2    GND @S9S_MB_2U_LIB.S9S_MB_2U(SCH_1):GND    I62 @S9S_MB_2U_LIB.S9S_MB_2U(SCH_1):PAGE275

PC412_P1_1 Q_CAP_C0805-22UF,4V,20%,X6S,CHA
     1 PVCCFA_EHV_FIVRA_CPU1 @S9S_MB_2U_LIB.S9S_MB_2U(SCH_1):PVCCFA_EHV_FIVRA_CPU1    I75 @S9S_MB_2U_LIB.S9S_MB_2U(SCH_1):PAGE275
     2    GND @S9S_MB_2U_LIB.S9S_MB_2U(SCH_1):GND    I75 @S9S_MB_2U_LIB.S9S_MB_2U(SCH_1):PAGE275

PC413_P1_2 Q_CAP_C0805-22UF,4V,20%,X6S,CHA
     1 PVCCFA_EHV_FIVRA_CPU1 @S9S_MB_2U_LIB.S9S_MB_2U(SCH_1):PVCCFA_EHV_FIVRA_CPU1    I63 @S9S_MB_2U_LIB.S9S_MB_2U(SCH_1):PAGE275
     2    GND @S9S_MB_2U_LIB.S9S_MB_2U(SCH_1):GND    I63 @S9S_MB_2U_LIB.S9S_MB_2U(SCH_1):PAGE275

PC414 Q_CAPP_THLF-560UF,2.5V,20%,OSCA
     1 PVCCFA_EHV_FIVRA_CPU1 @S9S_MB_2U_LIB.S9S_MB_2U(SCH_1):PVCCFA_EHV_FIVRA_CPU1    I66 @S9S_MB_2U_LIB.S9S_MB_2U(SCH_1):PAGE275
     2    GND @S9S_MB_2U_LIB.S9S_MB_2U(SCH_1):GND    I66 @S9S_MB_2U_LIB.S9S_MB_2U(SCH_1):PAGE275

PC415 Q_CAPP_THLF-560UF,2.5V,20%,OSCA
     1 PVCCFA_EHV_FIVRA_CPU1 @S9S_MB_2U_LIB.S9S_MB_2U(SCH_1):PVCCFA_EHV_FIVRA_CPU1    I67 @S9S_MB_2U_LIB.S9S_MB_2U(SCH_1):PAGE275
     2    GND @S9S_MB_2U_LIB.S9S_MB_2U(SCH_1):GND    I67 @S9S_MB_2U_LIB.S9S_MB_2U(SCH_1):PAGE275

PC416 Q_CAPP_THLF-560UF,2.5V,20%,OSCA
     1 PVCCFA_EHV_FIVRA_CPU1 @S9S_MB_2U_LIB.S9S_MB_2U(SCH_1):PVCCFA_EHV_FIVRA_CPU1    I68 @S9S_MB_2U_LIB.S9S_MB_2U(SCH_1):PAGE275
     2    GND @S9S_MB_2U_LIB.S9S_MB_2U(SCH_1):GND    I68 @S9S_MB_2U_LIB.S9S_MB_2U(SCH_1):PAGE275

PC417 Q_CAPP_THLF-270UF,16V,20%,OSCOA
     1 SW_P12V_PVCCFA_EHV_FIVRA_CPU1_L @S9S_MB_2U_LIB.S9S_MB_2U(SCH_1):SW_P12V_PVCCFA_EHV_FIVRA_CPU1_L    I87 @S9S_MB_2U_LIB.S9S_MB_2U(SCH_1):PAGE275
     2    GND @S9S_MB_2U_LIB.S9S_MB_2U(SCH_1):GND    I87 @S9S_MB_2U_LIB.S9S_MB_2U(SCH_1):PAGE275

PC418 Q_CAPP_SMLF-330UF,2.5V,+10/-35B
     1 PVCCFA_EHV_FIVRA_CPU1 @S9S_MB_2U_LIB.S9S_MB_2U(SCH_1):PVCCFA_EHV_FIVRA_CPU1    I70 @S9S_MB_2U_LIB.S9S_MB_2U(SCH_1):PAGE275
     2    GND @S9S_MB_2U_LIB.S9S_MB_2U(SCH_1):GND    I70 @S9S_MB_2U_LIB.S9S_MB_2U(SCH_1):PAGE275

PC422 Q_CAP_0402-3300PF,50V,10%,X7R,A
     1 SH_PVCCFA_EHV_FIVRA_CPU1_R @S9S_MB_2U_LIB.S9S_MB_2U(SCH_1):SH_PVCCFA_EHV_FIVRA_CPU1_R    I38 @S9S_MB_2U_LIB.S9S_MB_2U(SCH_1):PAGE270
     2 VSENSE_PVCCFA_EHV_FIVRA_CPU1_DN @S9S_MB_2U_LIB.S9S_MB_2U(SCH_1):VSENSE_PVCCFA_EHV_FIVRA_CPU1_DN    I38 @S9S_MB_2U_LIB.S9S_MB_2U(SCH_1):PAGE270

PC428 Q_CAP_C0402-2.2UF,10V,10%,X6S,A
     1 PVCCFA_EHV_CPU1_VDD1 @S9S_MB_2U_LIB.S9S_MB_2U(SCH_1):PVCCFA_EHV_CPU1_VDD1    I11 @S9S_MB_2U_LIB.S9S_MB_2U(SCH_1):PAGE280
     2    GND @S9S_MB_2U_LIB.S9S_MB_2U(SCH_1):GND    I11 @S9S_MB_2U_LIB.S9S_MB_2U(SCH_1):PAGE280

PC429 Q_CAP_0402-3300PF,50V,10%,X7R,A
     1 SW_P12V_PVCCINFAON_CPU1_FLT @S9S_MB_2U_LIB.S9S_MB_2U(SCH_1):SW_P12V_PVCCINFAON_CPU1_FLT    I24 @S9S_MB_2U_LIB.S9S_MB_2U(SCH_1):PAGE280
     2    GND @S9S_MB_2U_LIB.S9S_MB_2U(SCH_1):GND    I24 @S9S_MB_2U_LIB.S9S_MB_2U(SCH_1):PAGE280

PC430 Q_CAP_C0402-1UF,16V,10%,X6S,CHA
     1 SW_P12V_PVCCINFAON_CPU1_FLT @S9S_MB_2U_LIB.S9S_MB_2U(SCH_1):SW_P12V_PVCCINFAON_CPU1_FLT    I26 @S9S_MB_2U_LIB.S9S_MB_2U(SCH_1):PAGE280
     2    GND @S9S_MB_2U_LIB.S9S_MB_2U(SCH_1):GND    I26 @S9S_MB_2U_LIB.S9S_MB_2U(SCH_1):PAGE280

PC431 Q_CAP_C0402-100NF,50V,10%,X7R,A
     1 SW_PVCCFA_EHV_CPU1_BOOT1_R @S9S_MB_2U_LIB.S9S_MB_2U(SCH_1):SW_PVCCFA_EHV_CPU1_BOOT1_R    I22 @S9S_MB_2U_LIB.S9S_MB_2U(SCH_1):PAGE280
     2 SW_PVCCFA_EHV_CPU1_BOOTR1 @S9S_MB_2U_LIB.S9S_MB_2U(SCH_1):SW_PVCCFA_EHV_CPU1_BOOTR1    I22 @S9S_MB_2U_LIB.S9S_MB_2U(SCH_1):PAGE280

PC432 Q_CAP_C0805-22UF,16V,20%,X6S,CA
     1 SW_P12V_PVCCINFAON_CPU1_FLT @S9S_MB_2U_LIB.S9S_MB_2U(SCH_1):SW_P12V_PVCCINFAON_CPU1_FLT    I27 @S9S_MB_2U_LIB.S9S_MB_2U(SCH_1):PAGE280
     2    GND @S9S_MB_2U_LIB.S9S_MB_2U(SCH_1):GND    I27 @S9S_MB_2U_LIB.S9S_MB_2U(SCH_1):PAGE280

PC433 Q_CAP_C0805-22UF,16V,20%,X6S,CA
     1 SW_P12V_PVCCINFAON_CPU1_FLT @S9S_MB_2U_LIB.S9S_MB_2U(SCH_1):SW_P12V_PVCCINFAON_CPU1_FLT    I28 @S9S_MB_2U_LIB.S9S_MB_2U(SCH_1):PAGE280
     2    GND @S9S_MB_2U_LIB.S9S_MB_2U(SCH_1):GND    I28 @S9S_MB_2U_LIB.S9S_MB_2U(SCH_1):PAGE280

PC434 Q_CAP_C0402-100NF,50V,10%,X7R,A
     1 PVCCFA_EHV_CPU1 @S9S_MB_2U_LIB.S9S_MB_2U(SCH_1):PVCCFA_EHV_CPU1    I29 @S9S_MB_2U_LIB.S9S_MB_2U(SCH_1):PAGE280
     2    GND @S9S_MB_2U_LIB.S9S_MB_2U(SCH_1):GND    I29 @S9S_MB_2U_LIB.S9S_MB_2U(SCH_1):PAGE280

PC435 Q_CAP_C0805-22UF,4V,20%,X6S,CHA
     1 PVCCFA_EHV_CPU1 @S9S_MB_2U_LIB.S9S_MB_2U(SCH_1):PVCCFA_EHV_CPU1    I30 @S9S_MB_2U_LIB.S9S_MB_2U(SCH_1):PAGE280
     2    GND @S9S_MB_2U_LIB.S9S_MB_2U(SCH_1):GND    I30 @S9S_MB_2U_LIB.S9S_MB_2U(SCH_1):PAGE280

PC437 Q_CAP_C0805-22UF,4V,20%,X6S,CHA
     1 PVCCFA_EHV_CPU1 @S9S_MB_2U_LIB.S9S_MB_2U(SCH_1):PVCCFA_EHV_CPU1    I31 @S9S_MB_2U_LIB.S9S_MB_2U(SCH_1):PAGE280
     2    GND @S9S_MB_2U_LIB.S9S_MB_2U(SCH_1):GND    I31 @S9S_MB_2U_LIB.S9S_MB_2U(SCH_1):PAGE280

PC440 Q_CAP_C0402-2.2UF,10V,10%,X6S,A
     1 PVCCINFAON_CPU1_VDD1 @S9S_MB_2U_LIB.S9S_MB_2U(SCH_1):PVCCINFAON_CPU1_VDD1    I24 @S9S_MB_2U_LIB.S9S_MB_2U(SCH_1):PAGE279
     2    GND @S9S_MB_2U_LIB.S9S_MB_2U(SCH_1):GND    I24 @S9S_MB_2U_LIB.S9S_MB_2U(SCH_1):PAGE279

PC441 Q_CAP_C0402-2.2UF,10V,10%,X6S,A
     1 PVCCINFAON_CPU1_VDD2 @S9S_MB_2U_LIB.S9S_MB_2U(SCH_1):PVCCINFAON_CPU1_VDD2    I10 @S9S_MB_2U_LIB.S9S_MB_2U(SCH_1):PAGE279
     2    GND @S9S_MB_2U_LIB.S9S_MB_2U(SCH_1):GND    I10 @S9S_MB_2U_LIB.S9S_MB_2U(SCH_1):PAGE279

PC442_P1_1 Q_CAP_0402-3300PF,50V,10%,X7R,A
     1 SW_P12V_PVCCINFAON_CPU1_FLT @S9S_MB_2U_LIB.S9S_MB_2U(SCH_1):SW_P12V_PVCCINFAON_CPU1_FLT    I40 @S9S_MB_2U_LIB.S9S_MB_2U(SCH_1):PAGE279
     2    GND @S9S_MB_2U_LIB.S9S_MB_2U(SCH_1):GND    I40 @S9S_MB_2U_LIB.S9S_MB_2U(SCH_1):PAGE279

PC443_P1_2 Q_CAP_0402-3300PF,50V,10%,X7R,A
     1 SW_P12V_PVCCINFAON_CPU1_FLT @S9S_MB_2U_LIB.S9S_MB_2U(SCH_1):SW_P12V_PVCCINFAON_CPU1_FLT    I36 @S9S_MB_2U_LIB.S9S_MB_2U(SCH_1):PAGE279
     2    GND @S9S_MB_2U_LIB.S9S_MB_2U(SCH_1):GND    I36 @S9S_MB_2U_LIB.S9S_MB_2U(SCH_1):PAGE279

PC444_P1_1 Q_CAP_C0402-1UF,16V,10%,X6S,CHA
     1 SW_P12V_PVCCINFAON_CPU1_FLT @S9S_MB_2U_LIB.S9S_MB_2U(SCH_1):SW_P12V_PVCCINFAON_CPU1_FLT    I41 @S9S_MB_2U_LIB.S9S_MB_2U(SCH_1):PAGE279
     2    GND @S9S_MB_2U_LIB.S9S_MB_2U(SCH_1):GND    I41 @S9S_MB_2U_LIB.S9S_MB_2U(SCH_1):PAGE279

PC445_P1_2 Q_CAP_C0402-1UF,16V,10%,X6S,CHA
     1 SW_P12V_PVCCINFAON_CPU1_FLT @S9S_MB_2U_LIB.S9S_MB_2U(SCH_1):SW_P12V_PVCCINFAON_CPU1_FLT    I37 @S9S_MB_2U_LIB.S9S_MB_2U(SCH_1):PAGE279
     2    GND @S9S_MB_2U_LIB.S9S_MB_2U(SCH_1):GND    I37 @S9S_MB_2U_LIB.S9S_MB_2U(SCH_1):PAGE279

PC446 Q_CAP_C0402-100NF,50V,10%,X7R,A
     1 SW_PVCCINFAON_CPU1_BOOT1_R @S9S_MB_2U_LIB.S9S_MB_2U(SCH_1):SW_PVCCINFAON_CPU1_BOOT1_R    I52 @S9S_MB_2U_LIB.S9S_MB_2U(SCH_1):PAGE279
     2 SW_PVCCINFAON_CPU1_BOOTR1 @S9S_MB_2U_LIB.S9S_MB_2U(SCH_1):SW_PVCCINFAON_CPU1_BOOTR1    I52 @S9S_MB_2U_LIB.S9S_MB_2U(SCH_1):PAGE279

PC447 Q_CAP_C0402-100NF,50V,10%,X7R,A
     1 SW_PVCCINFAON_CPU1_BOOT2_R @S9S_MB_2U_LIB.S9S_MB_2U(SCH_1):SW_PVCCINFAON_CPU1_BOOT2_R    I44 @S9S_MB_2U_LIB.S9S_MB_2U(SCH_1):PAGE279
     2 SW_PVCCINFAON_CPU1_BOOTR2 @S9S_MB_2U_LIB.S9S_MB_2U(SCH_1):SW_PVCCINFAON_CPU1_BOOTR2    I44 @S9S_MB_2U_LIB.S9S_MB_2U(SCH_1):PAGE279

PC448_P1_1 Q_CAP_C0805-22UF,16V,20%,X6S,CA
     1 SW_P12V_PVCCINFAON_CPU1_FLT @S9S_MB_2U_LIB.S9S_MB_2U(SCH_1):SW_P12V_PVCCINFAON_CPU1_FLT    I51 @S9S_MB_2U_LIB.S9S_MB_2U(SCH_1):PAGE279
     2    GND @S9S_MB_2U_LIB.S9S_MB_2U(SCH_1):GND    I51 @S9S_MB_2U_LIB.S9S_MB_2U(SCH_1):PAGE279

PC449_P1_2 Q_CAP_C0805-22UF,16V,20%,X6S,CA
     1 SW_P12V_PVCCINFAON_CPU1_FLT @S9S_MB_2U_LIB.S9S_MB_2U(SCH_1):SW_P12V_PVCCINFAON_CPU1_FLT    I43 @S9S_MB_2U_LIB.S9S_MB_2U(SCH_1):PAGE279
     2    GND @S9S_MB_2U_LIB.S9S_MB_2U(SCH_1):GND    I43 @S9S_MB_2U_LIB.S9S_MB_2U(SCH_1):PAGE279

PC450_P1_1 Q_CAP_C0805-22UF,16V,20%,X6S,CA
     1 SW_P12V_PVCCINFAON_CPU1_FLT @S9S_MB_2U_LIB.S9S_MB_2U(SCH_1):SW_P12V_PVCCINFAON_CPU1_FLT    I53 @S9S_MB_2U_LIB.S9S_MB_2U(SCH_1):PAGE279
     2    GND @S9S_MB_2U_LIB.S9S_MB_2U(SCH_1):GND    I53 @S9S_MB_2U_LIB.S9S_MB_2U(SCH_1):PAGE279

PC451_P1_2 Q_CAP_C0805-22UF,16V,20%,X6S,CA
     1 SW_P12V_PVCCINFAON_CPU1_FLT @S9S_MB_2U_LIB.S9S_MB_2U(SCH_1):SW_P12V_PVCCINFAON_CPU1_FLT    I45 @S9S_MB_2U_LIB.S9S_MB_2U(SCH_1):PAGE279
     2    GND @S9S_MB_2U_LIB.S9S_MB_2U(SCH_1):GND    I45 @S9S_MB_2U_LIB.S9S_MB_2U(SCH_1):PAGE279

PC452_P1_1 Q_CAP_C0402-100NF,50V,10%,X7R,A
     1 PVCCINFAON_CPU1 @S9S_MB_2U_LIB.S9S_MB_2U(SCH_1):PVCCINFAON_CPU1    I55 @S9S_MB_2U_LIB.S9S_MB_2U(SCH_1):PAGE279
     2    GND @S9S_MB_2U_LIB.S9S_MB_2U(SCH_1):GND    I55 @S9S_MB_2U_LIB.S9S_MB_2U(SCH_1):PAGE279

PC455_P1_1 Q_CAP_C0805-22UF,4V,20%,X6S,CHA
     1 PVCCINFAON_CPU1 @S9S_MB_2U_LIB.S9S_MB_2U(SCH_1):PVCCINFAON_CPU1    I63 @S9S_MB_2U_LIB.S9S_MB_2U(SCH_1):PAGE279
     2    GND @S9S_MB_2U_LIB.S9S_MB_2U(SCH_1):GND    I63 @S9S_MB_2U_LIB.S9S_MB_2U(SCH_1):PAGE279

PC456_P1_2 Q_CAP_C0805-22UF,4V,20%,X6S,CHA
     1 PVCCINFAON_CPU1 @S9S_MB_2U_LIB.S9S_MB_2U(SCH_1):PVCCINFAON_CPU1    I32 @S9S_MB_2U_LIB.S9S_MB_2U(SCH_1):PAGE279
     2    GND @S9S_MB_2U_LIB.S9S_MB_2U(SCH_1):GND    I32 @S9S_MB_2U_LIB.S9S_MB_2U(SCH_1):PAGE279

PC457_P1_1 Q_CAP_C0805-22UF,4V,20%,X6S,CHA
     1 PVCCINFAON_CPU1 @S9S_MB_2U_LIB.S9S_MB_2U(SCH_1):PVCCINFAON_CPU1    I65 @S9S_MB_2U_LIB.S9S_MB_2U(SCH_1):PAGE279
     2    GND @S9S_MB_2U_LIB.S9S_MB_2U(SCH_1):GND    I65 @S9S_MB_2U_LIB.S9S_MB_2U(SCH_1):PAGE279

PC458_P1_2 Q_CAP_C0805-22UF,4V,20%,X6S,CHA
     1 PVCCINFAON_CPU1 @S9S_MB_2U_LIB.S9S_MB_2U(SCH_1):PVCCINFAON_CPU1    I33 @S9S_MB_2U_LIB.S9S_MB_2U(SCH_1):PAGE279
     2    GND @S9S_MB_2U_LIB.S9S_MB_2U(SCH_1):GND    I33 @S9S_MB_2U_LIB.S9S_MB_2U(SCH_1):PAGE279

PC460 Q_CAPP_THLF-270UF,16V,20%,OSCOA
     1 SW_P12V_PVCCINFAON_CPU1_FLT @S9S_MB_2U_LIB.S9S_MB_2U(SCH_1):SW_P12V_PVCCINFAON_CPU1_FLT    I69 @S9S_MB_2U_LIB.S9S_MB_2U(SCH_1):PAGE279
     2    GND @S9S_MB_2U_LIB.S9S_MB_2U(SCH_1):GND    I69 @S9S_MB_2U_LIB.S9S_MB_2U(SCH_1):PAGE279

PC461 Q_CAPP_THLF-270UF,16V,20%,OSCOA
     1 SW_P12V_PVCCINFAON_CPU1_FLT @S9S_MB_2U_LIB.S9S_MB_2U(SCH_1):SW_P12V_PVCCINFAON_CPU1_FLT    I70 @S9S_MB_2U_LIB.S9S_MB_2U(SCH_1):PAGE279
     2    GND @S9S_MB_2U_LIB.S9S_MB_2U(SCH_1):GND    I70 @S9S_MB_2U_LIB.S9S_MB_2U(SCH_1):PAGE279

PC467 Q_CAP_0402-0.1UF,25V,10%,EMPTYA
     1 PVCCINFAON_CPU1_CSPIN @S9S_MB_2U_LIB.S9S_MB_2U(SCH_1):PVCCINFAON_CPU1_CSPIN    I28 @S9S_MB_2U_LIB.S9S_MB_2U(SCH_1):PAGE278
     2    GND @S9S_MB_2U_LIB.S9S_MB_2U(SCH_1):GND    I28 @S9S_MB_2U_LIB.S9S_MB_2U(SCH_1):PAGE278

PC468 Q_CAP_0402-3300PF,50V,10%,X7R,A
     1 SH_PVCCINFAON_CPU1_R @S9S_MB_2U_LIB.S9S_MB_2U(SCH_1):SH_PVCCINFAON_CPU1_R    I53 @S9S_MB_2U_LIB.S9S_MB_2U(SCH_1):PAGE278
     2 VSENSE_PVCCINFAON_CPU1_DN @S9S_MB_2U_LIB.S9S_MB_2U(SCH_1):VSENSE_PVCCINFAON_CPU1_DN    I53 @S9S_MB_2U_LIB.S9S_MB_2U(SCH_1):PAGE278

PC469 Q_CAP_0402-3300PF,50V,10%,X7R,A
     1 SH_PVCCFA_EHV_CPU1_R @S9S_MB_2U_LIB.S9S_MB_2U(SCH_1):SH_PVCCFA_EHV_CPU1_R    I51 @S9S_MB_2U_LIB.S9S_MB_2U(SCH_1):PAGE278
     2 VSENSE_PVCCFA_EHV_CPU1_DN @S9S_MB_2U_LIB.S9S_MB_2U(SCH_1):VSENSE_PVCCFA_EHV_CPU1_DN    I51 @S9S_MB_2U_LIB.S9S_MB_2U(SCH_1):PAGE278

PC474 Q_CAP_0402-0.1UF,25V,10%,X7R,CA
     1 PVCCINFAON_CPU1_VIN_CSNIN @S9S_MB_2U_LIB.S9S_MB_2U(SCH_1):PVCCINFAON_CPU1_VIN_CSNIN    I36 @S9S_MB_2U_LIB.S9S_MB_2U(SCH_1):PAGE278
     2    GND @S9S_MB_2U_LIB.S9S_MB_2U(SCH_1):GND    I36 @S9S_MB_2U_LIB.S9S_MB_2U(SCH_1):PAGE278

PC475 Q_CAP_0402-470PF,50V,10%,X7R,TA
     1 PVCCINFAON_CPU1_ATSEN @S9S_MB_2U_LIB.S9S_MB_2U(SCH_1):PVCCINFAON_CPU1_ATSEN    I66 @S9S_MB_2U_LIB.S9S_MB_2U(SCH_1):PAGE278
     2    GND @S9S_MB_2U_LIB.S9S_MB_2U(SCH_1):GND    I66 @S9S_MB_2U_LIB.S9S_MB_2U(SCH_1):PAGE278

PC476 Q_CAP_C0402-100NF,50V,10%,EMPTA
     1 PVCCINFAON_CPU1_VCC @S9S_MB_2U_LIB.S9S_MB_2U(SCH_1):PVCCINFAON_CPU1_VCC    I93 @S9S_MB_2U_LIB.S9S_MB_2U(SCH_1):PAGE278
     2    GND @S9S_MB_2U_LIB.S9S_MB_2U(SCH_1):GND    I93 @S9S_MB_2U_LIB.S9S_MB_2U(SCH_1):PAGE278

PC477 Q_CAP_C0402-10UF,6.3V,20%,X6S,B
     1 PVCCINFAON_CPU1_VREF @S9S_MB_2U_LIB.S9S_MB_2U(SCH_1):PVCCINFAON_CPU1_VREF    I92 @S9S_MB_2U_LIB.S9S_MB_2U(SCH_1):PAGE278
     2    GND @S9S_MB_2U_LIB.S9S_MB_2U(SCH_1):GND    I92 @S9S_MB_2U_LIB.S9S_MB_2U(SCH_1):PAGE278

PC478 Q_CAP_C0402-1UF,16V,10%,X6S,CHA
     1 PVCCINFAON_CPU1_VCC @S9S_MB_2U_LIB.S9S_MB_2U(SCH_1):PVCCINFAON_CPU1_VCC    I97 @S9S_MB_2U_LIB.S9S_MB_2U(SCH_1):PAGE278
     2    GND @S9S_MB_2U_LIB.S9S_MB_2U(SCH_1):GND    I97 @S9S_MB_2U_LIB.S9S_MB_2U(SCH_1):PAGE278

PC479 Q_CAP_C0402-2.2UF,10V,10%,X6S,A
     1 PVCCIN_CPU1_VDD8 @S9S_MB_2U_LIB.S9S_MB_2U(SCH_1):PVCCIN_CPU1_VDD8     I9 @S9S_MB_2U_LIB.S9S_MB_2U(SCH_1):PAGE274
     2    GND @S9S_MB_2U_LIB.S9S_MB_2U(SCH_1):GND     I9 @S9S_MB_2U_LIB.S9S_MB_2U(SCH_1):PAGE274

PC480 Q_CAP_C0402-2.2UF,10V,10%,X6S,A
     1 PVCCIN_CPU1_VDD7 @S9S_MB_2U_LIB.S9S_MB_2U(SCH_1):PVCCIN_CPU1_VDD7    I34 @S9S_MB_2U_LIB.S9S_MB_2U(SCH_1):PAGE274
     2    GND @S9S_MB_2U_LIB.S9S_MB_2U(SCH_1):GND    I34 @S9S_MB_2U_LIB.S9S_MB_2U(SCH_1):PAGE274

PC481_P1_8 Q_CAP_C0402-2.2UF,10V,10%,X6S,A
     1 PVCCIN_CPU1_PVCC @S9S_MB_2U_LIB.S9S_MB_2U(SCH_1):PVCCIN_CPU1_PVCC    I18 @S9S_MB_2U_LIB.S9S_MB_2U(SCH_1):PAGE274
     2    GND @S9S_MB_2U_LIB.S9S_MB_2U(SCH_1):GND    I18 @S9S_MB_2U_LIB.S9S_MB_2U(SCH_1):PAGE274

PC482_P1_7 Q_CAP_C0402-2.2UF,10V,10%,X6S,A
     1 PVCCIN_CPU1_PVCC @S9S_MB_2U_LIB.S9S_MB_2U(SCH_1):PVCCIN_CPU1_PVCC    I69 @S9S_MB_2U_LIB.S9S_MB_2U(SCH_1):PAGE274
     2    GND @S9S_MB_2U_LIB.S9S_MB_2U(SCH_1):GND    I69 @S9S_MB_2U_LIB.S9S_MB_2U(SCH_1):PAGE274

PC483_P1_8 Q_CAP_0402-3300PF,50V,10%,X7R,A
     1 SW_P12V_PVCCIN_CPU1_FLT @S9S_MB_2U_LIB.S9S_MB_2U(SCH_1):SW_P12V_PVCCIN_CPU1_FLT    I24 @S9S_MB_2U_LIB.S9S_MB_2U(SCH_1):PAGE274
     2    GND @S9S_MB_2U_LIB.S9S_MB_2U(SCH_1):GND    I24 @S9S_MB_2U_LIB.S9S_MB_2U(SCH_1):PAGE274

PC484_P1_7 Q_CAP_0402-3300PF,50V,10%,X7R,A
     1 SW_P12V_PVCCIN_CPU1_FLT @S9S_MB_2U_LIB.S9S_MB_2U(SCH_1):SW_P12V_PVCCIN_CPU1_FLT    I37 @S9S_MB_2U_LIB.S9S_MB_2U(SCH_1):PAGE274
     2    GND @S9S_MB_2U_LIB.S9S_MB_2U(SCH_1):GND    I37 @S9S_MB_2U_LIB.S9S_MB_2U(SCH_1):PAGE274

PC485_P1_8 Q_CAP_C0402-1UF,16V,10%,X6S,CHA
     1 SW_P12V_PVCCIN_CPU1_FLT @S9S_MB_2U_LIB.S9S_MB_2U(SCH_1):SW_P12V_PVCCIN_CPU1_FLT    I27 @S9S_MB_2U_LIB.S9S_MB_2U(SCH_1):PAGE274
     2    GND @S9S_MB_2U_LIB.S9S_MB_2U(SCH_1):GND    I27 @S9S_MB_2U_LIB.S9S_MB_2U(SCH_1):PAGE274

PC486_P1_7 Q_CAP_C0402-1UF,16V,10%,X6S,CHA
     1 SW_P12V_PVCCIN_CPU1_FLT @S9S_MB_2U_LIB.S9S_MB_2U(SCH_1):SW_P12V_PVCCIN_CPU1_FLT    I40 @S9S_MB_2U_LIB.S9S_MB_2U(SCH_1):PAGE274
     2    GND @S9S_MB_2U_LIB.S9S_MB_2U(SCH_1):GND    I40 @S9S_MB_2U_LIB.S9S_MB_2U(SCH_1):PAGE274

PC487 Q_CAP_C0402-100NF,50V,10%,X7R,A
     1 SW_PVCCIN_CPU1_BOOT8_R @S9S_MB_2U_LIB.S9S_MB_2U(SCH_1):SW_PVCCIN_CPU1_BOOT8_R    I42 @S9S_MB_2U_LIB.S9S_MB_2U(SCH_1):PAGE274
     2 SW_PVCCIN_CPU1_BOOTR8 @S9S_MB_2U_LIB.S9S_MB_2U(SCH_1):SW_PVCCIN_CPU1_BOOTR8    I42 @S9S_MB_2U_LIB.S9S_MB_2U(SCH_1):PAGE274

PC488 Q_CAP_C0402-100NF,50V,10%,X7R,A
     1 SW_PVCCIN_CPU1_BOOT7_R @S9S_MB_2U_LIB.S9S_MB_2U(SCH_1):SW_PVCCIN_CPU1_BOOT7_R    I59 @S9S_MB_2U_LIB.S9S_MB_2U(SCH_1):PAGE274
     2 SW_PVCCIN_CPU1_BOOTR7 @S9S_MB_2U_LIB.S9S_MB_2U(SCH_1):SW_PVCCIN_CPU1_BOOTR7    I59 @S9S_MB_2U_LIB.S9S_MB_2U(SCH_1):PAGE274

PC489_P1_8 Q_CAP_C0805-22UF,16V,20%,X6S,CA
     1 SW_P12V_PVCCIN_CPU1_FLT @S9S_MB_2U_LIB.S9S_MB_2U(SCH_1):SW_P12V_PVCCIN_CPU1_FLT    I28 @S9S_MB_2U_LIB.S9S_MB_2U(SCH_1):PAGE274
     2    GND @S9S_MB_2U_LIB.S9S_MB_2U(SCH_1):GND    I28 @S9S_MB_2U_LIB.S9S_MB_2U(SCH_1):PAGE274

PC490_P1_7 Q_CAP_C0805-22UF,16V,20%,X6S,CA
     1 SW_P12V_PVCCIN_CPU1_FLT @S9S_MB_2U_LIB.S9S_MB_2U(SCH_1):SW_P12V_PVCCIN_CPU1_FLT    I41 @S9S_MB_2U_LIB.S9S_MB_2U(SCH_1):PAGE274
     2    GND @S9S_MB_2U_LIB.S9S_MB_2U(SCH_1):GND    I41 @S9S_MB_2U_LIB.S9S_MB_2U(SCH_1):PAGE274

PC491_P1_8 Q_CAP_C0805-22UF,16V,20%,X6S,CA
     1 SW_P12V_PVCCIN_CPU1_FLT @S9S_MB_2U_LIB.S9S_MB_2U(SCH_1):SW_P12V_PVCCIN_CPU1_FLT    I46 @S9S_MB_2U_LIB.S9S_MB_2U(SCH_1):PAGE274
     2    GND @S9S_MB_2U_LIB.S9S_MB_2U(SCH_1):GND    I46 @S9S_MB_2U_LIB.S9S_MB_2U(SCH_1):PAGE274

PC492_P1_7 Q_CAP_C0805-22UF,16V,20%,X6S,CA
     1 SW_P12V_PVCCIN_CPU1_FLT @S9S_MB_2U_LIB.S9S_MB_2U(SCH_1):SW_P12V_PVCCIN_CPU1_FLT    I61 @S9S_MB_2U_LIB.S9S_MB_2U(SCH_1):PAGE274
     2    GND @S9S_MB_2U_LIB.S9S_MB_2U(SCH_1):GND    I61 @S9S_MB_2U_LIB.S9S_MB_2U(SCH_1):PAGE274

PC493_P1_8 Q_CAP_C0805-22UF,16V,20%,X6S,CA
     1 SW_P12V_PVCCIN_CPU1_FLT @S9S_MB_2U_LIB.S9S_MB_2U(SCH_1):SW_P12V_PVCCIN_CPU1_FLT    I47 @S9S_MB_2U_LIB.S9S_MB_2U(SCH_1):PAGE274
     2    GND @S9S_MB_2U_LIB.S9S_MB_2U(SCH_1):GND    I47 @S9S_MB_2U_LIB.S9S_MB_2U(SCH_1):PAGE274

PC494_P1_7 Q_CAP_C0805-22UF,16V,20%,X6S,CA
     1 SW_P12V_PVCCIN_CPU1_FLT @S9S_MB_2U_LIB.S9S_MB_2U(SCH_1):SW_P12V_PVCCIN_CPU1_FLT    I62 @S9S_MB_2U_LIB.S9S_MB_2U(SCH_1):PAGE274
     2    GND @S9S_MB_2U_LIB.S9S_MB_2U(SCH_1):GND    I62 @S9S_MB_2U_LIB.S9S_MB_2U(SCH_1):PAGE274

PC495_P1_8 Q_CAP_C0402-1UF,16V,10%,X6S,CHA
     1 PVCCIN_CPU1 @S9S_MB_2U_LIB.S9S_MB_2U(SCH_1):PVCCIN_CPU1    I52 @S9S_MB_2U_LIB.S9S_MB_2U(SCH_1):PAGE274
     2    GND @S9S_MB_2U_LIB.S9S_MB_2U(SCH_1):GND    I52 @S9S_MB_2U_LIB.S9S_MB_2U(SCH_1):PAGE274

PC496_P1_7 Q_CAP_C0402-1UF,16V,10%,X6S,CHA
     1 PVCCIN_CPU1 @S9S_MB_2U_LIB.S9S_MB_2U(SCH_1):PVCCIN_CPU1    I64 @S9S_MB_2U_LIB.S9S_MB_2U(SCH_1):PAGE274
     2    GND @S9S_MB_2U_LIB.S9S_MB_2U(SCH_1):GND    I64 @S9S_MB_2U_LIB.S9S_MB_2U(SCH_1):PAGE274

PC497_P1_8 Q_CAP_C0805-22UF,4V,20%,X6S,CHA
     1 PVCCIN_CPU1 @S9S_MB_2U_LIB.S9S_MB_2U(SCH_1):PVCCIN_CPU1    I53 @S9S_MB_2U_LIB.S9S_MB_2U(SCH_1):PAGE274
     2    GND @S9S_MB_2U_LIB.S9S_MB_2U(SCH_1):GND    I53 @S9S_MB_2U_LIB.S9S_MB_2U(SCH_1):PAGE274

PC498_P1_7 Q_CAP_C0805-22UF,4V,20%,X6S,CHA
     1 PVCCIN_CPU1 @S9S_MB_2U_LIB.S9S_MB_2U(SCH_1):PVCCIN_CPU1    I65 @S9S_MB_2U_LIB.S9S_MB_2U(SCH_1):PAGE274
     2    GND @S9S_MB_2U_LIB.S9S_MB_2U(SCH_1):GND    I65 @S9S_MB_2U_LIB.S9S_MB_2U(SCH_1):PAGE274

PC499_P1_8 Q_CAP_C0805-22UF,4V,20%,X6S,CHA
     1 PVCCIN_CPU1 @S9S_MB_2U_LIB.S9S_MB_2U(SCH_1):PVCCIN_CPU1    I54 @S9S_MB_2U_LIB.S9S_MB_2U(SCH_1):PAGE274
     2    GND @S9S_MB_2U_LIB.S9S_MB_2U(SCH_1):GND    I54 @S9S_MB_2U_LIB.S9S_MB_2U(SCH_1):PAGE274

PC500_P1_7 Q_CAP_C0805-22UF,4V,20%,X6S,CHA
     1 PVCCIN_CPU1 @S9S_MB_2U_LIB.S9S_MB_2U(SCH_1):PVCCIN_CPU1    I66 @S9S_MB_2U_LIB.S9S_MB_2U(SCH_1):PAGE274
     2    GND @S9S_MB_2U_LIB.S9S_MB_2U(SCH_1):GND    I66 @S9S_MB_2U_LIB.S9S_MB_2U(SCH_1):PAGE274

PC501 Q_CAP_C0402-2.2UF,10V,10%,X6S,A
     1 PVCCIN_CPU1_VDD6 @S9S_MB_2U_LIB.S9S_MB_2U(SCH_1):PVCCIN_CPU1_VDD6    I17 @S9S_MB_2U_LIB.S9S_MB_2U(SCH_1):PAGE273
     2    GND @S9S_MB_2U_LIB.S9S_MB_2U(SCH_1):GND    I17 @S9S_MB_2U_LIB.S9S_MB_2U(SCH_1):PAGE273

PC502 Q_CAP_C0402-2.2UF,10V,10%,X6S,A
     1 PVCCIN_CPU1_VDD5 @S9S_MB_2U_LIB.S9S_MB_2U(SCH_1):PVCCIN_CPU1_VDD5    I37 @S9S_MB_2U_LIB.S9S_MB_2U(SCH_1):PAGE273
     2    GND @S9S_MB_2U_LIB.S9S_MB_2U(SCH_1):GND    I37 @S9S_MB_2U_LIB.S9S_MB_2U(SCH_1):PAGE273

PC503_P1_6 Q_CAP_C0402-2.2UF,10V,10%,X6S,A
     1 PVCCIN_CPU1_PVCC @S9S_MB_2U_LIB.S9S_MB_2U(SCH_1):PVCCIN_CPU1_PVCC    I21 @S9S_MB_2U_LIB.S9S_MB_2U(SCH_1):PAGE273
     2    GND @S9S_MB_2U_LIB.S9S_MB_2U(SCH_1):GND    I21 @S9S_MB_2U_LIB.S9S_MB_2U(SCH_1):PAGE273

PC504_P1_5 Q_CAP_C0402-2.2UF,10V,10%,X6S,A
     1 PVCCIN_CPU1_PVCC @S9S_MB_2U_LIB.S9S_MB_2U(SCH_1):PVCCIN_CPU1_PVCC    I41 @S9S_MB_2U_LIB.S9S_MB_2U(SCH_1):PAGE273
     2    GND @S9S_MB_2U_LIB.S9S_MB_2U(SCH_1):GND    I41 @S9S_MB_2U_LIB.S9S_MB_2U(SCH_1):PAGE273

PC505_P1_6 Q_CAP_0402-3300PF,50V,10%,X7R,A
     1 SW_P12V_PVCCIN_CPU1_FLT @S9S_MB_2U_LIB.S9S_MB_2U(SCH_1):SW_P12V_PVCCIN_CPU1_FLT    I29 @S9S_MB_2U_LIB.S9S_MB_2U(SCH_1):PAGE273
     2    GND @S9S_MB_2U_LIB.S9S_MB_2U(SCH_1):GND    I29 @S9S_MB_2U_LIB.S9S_MB_2U(SCH_1):PAGE273

PC506_P1_5 Q_CAP_0402-3300PF,50V,10%,X7R,A
     1 SW_P12V_PVCCIN_CPU1_FLT @S9S_MB_2U_LIB.S9S_MB_2U(SCH_1):SW_P12V_PVCCIN_CPU1_FLT    I45 @S9S_MB_2U_LIB.S9S_MB_2U(SCH_1):PAGE273
     2    GND @S9S_MB_2U_LIB.S9S_MB_2U(SCH_1):GND    I45 @S9S_MB_2U_LIB.S9S_MB_2U(SCH_1):PAGE273

PC507_P1_6 Q_CAP_C0402-1UF,16V,10%,X6S,CHA
     1 SW_P12V_PVCCIN_CPU1_FLT @S9S_MB_2U_LIB.S9S_MB_2U(SCH_1):SW_P12V_PVCCIN_CPU1_FLT    I31 @S9S_MB_2U_LIB.S9S_MB_2U(SCH_1):PAGE273
     2    GND @S9S_MB_2U_LIB.S9S_MB_2U(SCH_1):GND    I31 @S9S_MB_2U_LIB.S9S_MB_2U(SCH_1):PAGE273

PC508_P1_5 Q_CAP_C0402-1UF,16V,10%,X6S,CHA
     1 SW_P12V_PVCCIN_CPU1_FLT @S9S_MB_2U_LIB.S9S_MB_2U(SCH_1):SW_P12V_PVCCIN_CPU1_FLT    I46 @S9S_MB_2U_LIB.S9S_MB_2U(SCH_1):PAGE273
     2    GND @S9S_MB_2U_LIB.S9S_MB_2U(SCH_1):GND    I46 @S9S_MB_2U_LIB.S9S_MB_2U(SCH_1):PAGE273

PC509 Q_CAP_C0402-100NF,50V,10%,X7R,A
     1 SW_PVCCIN_CPU1_BOOT6_R @S9S_MB_2U_LIB.S9S_MB_2U(SCH_1):SW_PVCCIN_CPU1_BOOT6_R    I26 @S9S_MB_2U_LIB.S9S_MB_2U(SCH_1):PAGE273
     2 SW_PVCCIN_CPU1_BOOTR6 @S9S_MB_2U_LIB.S9S_MB_2U(SCH_1):SW_PVCCIN_CPU1_BOOTR6    I26 @S9S_MB_2U_LIB.S9S_MB_2U(SCH_1):PAGE273

PC510 Q_CAP_C0402-100NF,50V,10%,X7R,A
     1 SW_PVCCIN_CPU1_BOOT5_R @S9S_MB_2U_LIB.S9S_MB_2U(SCH_1):SW_PVCCIN_CPU1_BOOT5_R    I47 @S9S_MB_2U_LIB.S9S_MB_2U(SCH_1):PAGE273
     2 SW_PVCCIN_CPU1_BOOTR5 @S9S_MB_2U_LIB.S9S_MB_2U(SCH_1):SW_PVCCIN_CPU1_BOOTR5    I47 @S9S_MB_2U_LIB.S9S_MB_2U(SCH_1):PAGE273

PC511_P1_6 Q_CAP_C0805-22UF,16V,20%,X6S,CA
     1 SW_P12V_PVCCIN_CPU1_FLT @S9S_MB_2U_LIB.S9S_MB_2U(SCH_1):SW_P12V_PVCCIN_CPU1_FLT    I33 @S9S_MB_2U_LIB.S9S_MB_2U(SCH_1):PAGE273
     2    GND @S9S_MB_2U_LIB.S9S_MB_2U(SCH_1):GND    I33 @S9S_MB_2U_LIB.S9S_MB_2U(SCH_1):PAGE273

PC512_P1_5 Q_CAP_C0805-22UF,16V,20%,X6S,CA
     1 SW_P12V_PVCCIN_CPU1_FLT @S9S_MB_2U_LIB.S9S_MB_2U(SCH_1):SW_P12V_PVCCIN_CPU1_FLT    I50 @S9S_MB_2U_LIB.S9S_MB_2U(SCH_1):PAGE273
     2    GND @S9S_MB_2U_LIB.S9S_MB_2U(SCH_1):GND    I50 @S9S_MB_2U_LIB.S9S_MB_2U(SCH_1):PAGE273

PC513_P1_6 Q_CAP_C0805-22UF,16V,20%,X6S,CA
     1 SW_P12V_PVCCIN_CPU1_FLT @S9S_MB_2U_LIB.S9S_MB_2U(SCH_1):SW_P12V_PVCCIN_CPU1_FLT    I34 @S9S_MB_2U_LIB.S9S_MB_2U(SCH_1):PAGE273
     2    GND @S9S_MB_2U_LIB.S9S_MB_2U(SCH_1):GND    I34 @S9S_MB_2U_LIB.S9S_MB_2U(SCH_1):PAGE273

PC514_P1_5 Q_CAP_C0805-22UF,16V,20%,X6S,CA
     1 SW_P12V_PVCCIN_CPU1_FLT @S9S_MB_2U_LIB.S9S_MB_2U(SCH_1):SW_P12V_PVCCIN_CPU1_FLT    I51 @S9S_MB_2U_LIB.S9S_MB_2U(SCH_1):PAGE273
     2    GND @S9S_MB_2U_LIB.S9S_MB_2U(SCH_1):GND    I51 @S9S_MB_2U_LIB.S9S_MB_2U(SCH_1):PAGE273

PC515_P1_6 Q_CAP_C0805-22UF,16V,20%,X6S,CA
     1 SW_P12V_PVCCIN_CPU1_FLT @S9S_MB_2U_LIB.S9S_MB_2U(SCH_1):SW_P12V_PVCCIN_CPU1_FLT    I35 @S9S_MB_2U_LIB.S9S_MB_2U(SCH_1):PAGE273
     2    GND @S9S_MB_2U_LIB.S9S_MB_2U(SCH_1):GND    I35 @S9S_MB_2U_LIB.S9S_MB_2U(SCH_1):PAGE273

PC516_P1_5 Q_CAP_C0805-22UF,16V,20%,X6S,CA
     1 SW_P12V_PVCCIN_CPU1_FLT @S9S_MB_2U_LIB.S9S_MB_2U(SCH_1):SW_P12V_PVCCIN_CPU1_FLT    I52 @S9S_MB_2U_LIB.S9S_MB_2U(SCH_1):PAGE273
     2    GND @S9S_MB_2U_LIB.S9S_MB_2U(SCH_1):GND    I52 @S9S_MB_2U_LIB.S9S_MB_2U(SCH_1):PAGE273

PC519_P1_6 Q_CAP_C0805-22UF,4V,20%,X6S,CHA
     1 PVCCIN_CPU1 @S9S_MB_2U_LIB.S9S_MB_2U(SCH_1):PVCCIN_CPU1    I54 @S9S_MB_2U_LIB.S9S_MB_2U(SCH_1):PAGE273
     2    GND @S9S_MB_2U_LIB.S9S_MB_2U(SCH_1):GND    I54 @S9S_MB_2U_LIB.S9S_MB_2U(SCH_1):PAGE273

PC520_P1_5 Q_CAP_C0805-22UF,4V,20%,X6S,CHA
     1 PVCCIN_CPU1 @S9S_MB_2U_LIB.S9S_MB_2U(SCH_1):PVCCIN_CPU1    I64 @S9S_MB_2U_LIB.S9S_MB_2U(SCH_1):PAGE273
     2    GND @S9S_MB_2U_LIB.S9S_MB_2U(SCH_1):GND    I64 @S9S_MB_2U_LIB.S9S_MB_2U(SCH_1):PAGE273

PC521_P1_6 Q_CAP_C0805-22UF,4V,20%,X6S,CHA
     1 PVCCIN_CPU1 @S9S_MB_2U_LIB.S9S_MB_2U(SCH_1):PVCCIN_CPU1    I57 @S9S_MB_2U_LIB.S9S_MB_2U(SCH_1):PAGE273
     2    GND @S9S_MB_2U_LIB.S9S_MB_2U(SCH_1):GND    I57 @S9S_MB_2U_LIB.S9S_MB_2U(SCH_1):PAGE273

PC522_P1_5 Q_CAP_C0805-22UF,4V,20%,X6S,CHA
     1 PVCCIN_CPU1 @S9S_MB_2U_LIB.S9S_MB_2U(SCH_1):PVCCIN_CPU1    I65 @S9S_MB_2U_LIB.S9S_MB_2U(SCH_1):PAGE273
     2    GND @S9S_MB_2U_LIB.S9S_MB_2U(SCH_1):GND    I65 @S9S_MB_2U_LIB.S9S_MB_2U(SCH_1):PAGE273

PC523 Q_CAP_C0402-2.2UF,10V,10%,X6S,A
     1 PVCCIN_CPU1_VDD4 @S9S_MB_2U_LIB.S9S_MB_2U(SCH_1):PVCCIN_CPU1_VDD4    I11 @S9S_MB_2U_LIB.S9S_MB_2U(SCH_1):PAGE272
     2    GND @S9S_MB_2U_LIB.S9S_MB_2U(SCH_1):GND    I11 @S9S_MB_2U_LIB.S9S_MB_2U(SCH_1):PAGE272

PC524 Q_CAP_C0402-2.2UF,10V,10%,X6S,A
     1 PVCCIN_CPU1_VDD3 @S9S_MB_2U_LIB.S9S_MB_2U(SCH_1):PVCCIN_CPU1_VDD3    I24 @S9S_MB_2U_LIB.S9S_MB_2U(SCH_1):PAGE272
     2    GND @S9S_MB_2U_LIB.S9S_MB_2U(SCH_1):GND    I24 @S9S_MB_2U_LIB.S9S_MB_2U(SCH_1):PAGE272

PC525_P1_4 Q_CAP_C0402-2.2UF,10V,10%,X6S,A
     1 PVCCIN_CPU1_PVCC @S9S_MB_2U_LIB.S9S_MB_2U(SCH_1):PVCCIN_CPU1_PVCC    I19 @S9S_MB_2U_LIB.S9S_MB_2U(SCH_1):PAGE272
     2    GND @S9S_MB_2U_LIB.S9S_MB_2U(SCH_1):GND    I19 @S9S_MB_2U_LIB.S9S_MB_2U(SCH_1):PAGE272

PC526_P1_3 Q_CAP_C0402-2.2UF,10V,10%,X6S,A
     1 PVCCIN_CPU1_PVCC @S9S_MB_2U_LIB.S9S_MB_2U(SCH_1):PVCCIN_CPU1_PVCC    I29 @S9S_MB_2U_LIB.S9S_MB_2U(SCH_1):PAGE272
     2    GND @S9S_MB_2U_LIB.S9S_MB_2U(SCH_1):GND    I29 @S9S_MB_2U_LIB.S9S_MB_2U(SCH_1):PAGE272

PC527_P1_4 Q_CAP_0402-3300PF,50V,10%,X7R,A
     1 SW_P12V_PVCCIN_CPU1_FLT @S9S_MB_2U_LIB.S9S_MB_2U(SCH_1):SW_P12V_PVCCIN_CPU1_FLT    I33 @S9S_MB_2U_LIB.S9S_MB_2U(SCH_1):PAGE272
     2    GND @S9S_MB_2U_LIB.S9S_MB_2U(SCH_1):GND    I33 @S9S_MB_2U_LIB.S9S_MB_2U(SCH_1):PAGE272

PC528_P1_3 Q_CAP_0402-3300PF,50V,10%,X7R,A
     1 SW_P12V_PVCCIN_CPU1_FLT @S9S_MB_2U_LIB.S9S_MB_2U(SCH_1):SW_P12V_PVCCIN_CPU1_FLT    I48 @S9S_MB_2U_LIB.S9S_MB_2U(SCH_1):PAGE272
     2    GND @S9S_MB_2U_LIB.S9S_MB_2U(SCH_1):GND    I48 @S9S_MB_2U_LIB.S9S_MB_2U(SCH_1):PAGE272

PC529_P1_4 Q_CAP_C0402-1UF,16V,10%,X6S,CHA
     1 SW_P12V_PVCCIN_CPU1_FLT @S9S_MB_2U_LIB.S9S_MB_2U(SCH_1):SW_P12V_PVCCIN_CPU1_FLT    I35 @S9S_MB_2U_LIB.S9S_MB_2U(SCH_1):PAGE272
     2    GND @S9S_MB_2U_LIB.S9S_MB_2U(SCH_1):GND    I35 @S9S_MB_2U_LIB.S9S_MB_2U(SCH_1):PAGE272

PC530_P1_3 Q_CAP_C0402-1UF,16V,10%,X6S,CHA
     1 SW_P12V_PVCCIN_CPU1_FLT @S9S_MB_2U_LIB.S9S_MB_2U(SCH_1):SW_P12V_PVCCIN_CPU1_FLT    I49 @S9S_MB_2U_LIB.S9S_MB_2U(SCH_1):PAGE272
     2    GND @S9S_MB_2U_LIB.S9S_MB_2U(SCH_1):GND    I49 @S9S_MB_2U_LIB.S9S_MB_2U(SCH_1):PAGE272

PC531 Q_CAP_C0402-100NF,50V,10%,X7R,A
     1 SW_PVCCIN_CPU1_BOOT4_R @S9S_MB_2U_LIB.S9S_MB_2U(SCH_1):SW_PVCCIN_CPU1_BOOT4_R    I39 @S9S_MB_2U_LIB.S9S_MB_2U(SCH_1):PAGE272
     2 SW_PVCCIN_CPU1_BOOTR4 @S9S_MB_2U_LIB.S9S_MB_2U(SCH_1):SW_PVCCIN_CPU1_BOOTR4    I39 @S9S_MB_2U_LIB.S9S_MB_2U(SCH_1):PAGE272

PC532 Q_CAP_C0402-100NF,50V,10%,X7R,A
     1 SW_PVCCIN_CPU1_BOOT3_R @S9S_MB_2U_LIB.S9S_MB_2U(SCH_1):SW_PVCCIN_CPU1_BOOT3_R    I52 @S9S_MB_2U_LIB.S9S_MB_2U(SCH_1):PAGE272
     2 SW_PVCCIN_CPU1_BOOTR3 @S9S_MB_2U_LIB.S9S_MB_2U(SCH_1):SW_PVCCIN_CPU1_BOOTR3    I52 @S9S_MB_2U_LIB.S9S_MB_2U(SCH_1):PAGE272

PC533_P1_4 Q_CAP_C0805-22UF,16V,20%,X6S,CA
     1 SW_P12V_PVCCIN_CPU1_FLT @S9S_MB_2U_LIB.S9S_MB_2U(SCH_1):SW_P12V_PVCCIN_CPU1_FLT    I36 @S9S_MB_2U_LIB.S9S_MB_2U(SCH_1):PAGE272
     2    GND @S9S_MB_2U_LIB.S9S_MB_2U(SCH_1):GND    I36 @S9S_MB_2U_LIB.S9S_MB_2U(SCH_1):PAGE272

PC534_P1_3 Q_CAP_C0805-22UF,16V,20%,X6S,CA
     1 SW_P12V_PVCCIN_CPU1_FLT @S9S_MB_2U_LIB.S9S_MB_2U(SCH_1):SW_P12V_PVCCIN_CPU1_FLT    I50 @S9S_MB_2U_LIB.S9S_MB_2U(SCH_1):PAGE272
     2    GND @S9S_MB_2U_LIB.S9S_MB_2U(SCH_1):GND    I50 @S9S_MB_2U_LIB.S9S_MB_2U(SCH_1):PAGE272

PC535_P1_4 Q_CAP_C0805-22UF,16V,20%,X6S,CA
     1 SW_P12V_PVCCIN_CPU1_FLT @S9S_MB_2U_LIB.S9S_MB_2U(SCH_1):SW_P12V_PVCCIN_CPU1_FLT    I41 @S9S_MB_2U_LIB.S9S_MB_2U(SCH_1):PAGE272
     2    GND @S9S_MB_2U_LIB.S9S_MB_2U(SCH_1):GND    I41 @S9S_MB_2U_LIB.S9S_MB_2U(SCH_1):PAGE272

PC536_P1_3 Q_CAP_C0805-22UF,16V,20%,X6S,CA
     1 SW_P12V_PVCCIN_CPU1_FLT @S9S_MB_2U_LIB.S9S_MB_2U(SCH_1):SW_P12V_PVCCIN_CPU1_FLT    I54 @S9S_MB_2U_LIB.S9S_MB_2U(SCH_1):PAGE272
     2    GND @S9S_MB_2U_LIB.S9S_MB_2U(SCH_1):GND    I54 @S9S_MB_2U_LIB.S9S_MB_2U(SCH_1):PAGE272

PC537_P1_4 Q_CAP_C0805-22UF,16V,20%,X6S,CA
     1 SW_P12V_PVCCIN_CPU1_FLT @S9S_MB_2U_LIB.S9S_MB_2U(SCH_1):SW_P12V_PVCCIN_CPU1_FLT    I42 @S9S_MB_2U_LIB.S9S_MB_2U(SCH_1):PAGE272
     2    GND @S9S_MB_2U_LIB.S9S_MB_2U(SCH_1):GND    I42 @S9S_MB_2U_LIB.S9S_MB_2U(SCH_1):PAGE272

PC538_P1_3 Q_CAP_C0805-22UF,16V,20%,X6S,CA
     1 SW_P12V_PVCCIN_CPU1_FLT @S9S_MB_2U_LIB.S9S_MB_2U(SCH_1):SW_P12V_PVCCIN_CPU1_FLT    I55 @S9S_MB_2U_LIB.S9S_MB_2U(SCH_1):PAGE272
     2    GND @S9S_MB_2U_LIB.S9S_MB_2U(SCH_1):GND    I55 @S9S_MB_2U_LIB.S9S_MB_2U(SCH_1):PAGE272

PC541_P1_4 Q_CAP_C0805-22UF,4V,20%,X6S,CHA
     1 PVCCIN_CPU1 @S9S_MB_2U_LIB.S9S_MB_2U(SCH_1):PVCCIN_CPU1    I58 @S9S_MB_2U_LIB.S9S_MB_2U(SCH_1):PAGE272
     2    GND @S9S_MB_2U_LIB.S9S_MB_2U(SCH_1):GND    I58 @S9S_MB_2U_LIB.S9S_MB_2U(SCH_1):PAGE272

PC542_P1_3 Q_CAP_C0805-22UF,4V,20%,X6S,CHA
     1 PVCCIN_CPU1 @S9S_MB_2U_LIB.S9S_MB_2U(SCH_1):PVCCIN_CPU1    I63 @S9S_MB_2U_LIB.S9S_MB_2U(SCH_1):PAGE272
     2    GND @S9S_MB_2U_LIB.S9S_MB_2U(SCH_1):GND    I63 @S9S_MB_2U_LIB.S9S_MB_2U(SCH_1):PAGE272

PC543_P1_4 Q_CAP_C0805-22UF,4V,20%,X6S,CHA
     1 PVCCIN_CPU1 @S9S_MB_2U_LIB.S9S_MB_2U(SCH_1):PVCCIN_CPU1    I59 @S9S_MB_2U_LIB.S9S_MB_2U(SCH_1):PAGE272
     2    GND @S9S_MB_2U_LIB.S9S_MB_2U(SCH_1):GND    I59 @S9S_MB_2U_LIB.S9S_MB_2U(SCH_1):PAGE272

PC544_P1_3 Q_CAP_C0805-22UF,4V,20%,X6S,CHA
     1 PVCCIN_CPU1 @S9S_MB_2U_LIB.S9S_MB_2U(SCH_1):PVCCIN_CPU1    I64 @S9S_MB_2U_LIB.S9S_MB_2U(SCH_1):PAGE272
     2    GND @S9S_MB_2U_LIB.S9S_MB_2U(SCH_1):GND    I64 @S9S_MB_2U_LIB.S9S_MB_2U(SCH_1):PAGE272

PC547 Q_CAP_0402-0.1UF,25V,10%,EMPTYA
     1 PVCCIN_CPU1_CSPIN @S9S_MB_2U_LIB.S9S_MB_2U(SCH_1):PVCCIN_CPU1_CSPIN    I28 @S9S_MB_2U_LIB.S9S_MB_2U(SCH_1):PAGE270
     2    GND @S9S_MB_2U_LIB.S9S_MB_2U(SCH_1):GND    I28 @S9S_MB_2U_LIB.S9S_MB_2U(SCH_1):PAGE270

PC548 Q_CAP_0402-0.1UF,25V,10%,X7R,CA
     1 PVCCIN_CPU1_VIN_CSNIN @S9S_MB_2U_LIB.S9S_MB_2U(SCH_1):PVCCIN_CPU1_VIN_CSNIN    I31 @S9S_MB_2U_LIB.S9S_MB_2U(SCH_1):PAGE270
     2    GND @S9S_MB_2U_LIB.S9S_MB_2U(SCH_1):GND    I31 @S9S_MB_2U_LIB.S9S_MB_2U(SCH_1):PAGE270

PC549 Q_CAP_0402-3300PF,50V,10%,X7R,A
     1 SH_PVCCIN_CPU1_R @S9S_MB_2U_LIB.S9S_MB_2U(SCH_1):SH_PVCCIN_CPU1_R    I64 @S9S_MB_2U_LIB.S9S_MB_2U(SCH_1):PAGE270
     2 VSENSE_PVCCIN_CPU1_DN @S9S_MB_2U_LIB.S9S_MB_2U(SCH_1):VSENSE_PVCCIN_CPU1_DN    I64 @S9S_MB_2U_LIB.S9S_MB_2U(SCH_1):PAGE270

PC552 Q_CAP_C0402-100NF,50V,10%,EMPTA
     1 PVCCIN_CPU1_VCC @S9S_MB_2U_LIB.S9S_MB_2U(SCH_1):PVCCIN_CPU1_VCC   I120 @S9S_MB_2U_LIB.S9S_MB_2U(SCH_1):PAGE270
     2    GND @S9S_MB_2U_LIB.S9S_MB_2U(SCH_1):GND   I120 @S9S_MB_2U_LIB.S9S_MB_2U(SCH_1):PAGE270

PC553 Q_CAP_C0402-10UF,6.3V,20%,X6S,B
     1 PVCCIN_CPU1_VREF @S9S_MB_2U_LIB.S9S_MB_2U(SCH_1):PVCCIN_CPU1_VREF   I119 @S9S_MB_2U_LIB.S9S_MB_2U(SCH_1):PAGE270
     2    GND @S9S_MB_2U_LIB.S9S_MB_2U(SCH_1):GND   I119 @S9S_MB_2U_LIB.S9S_MB_2U(SCH_1):PAGE270

PC554 Q_CAP_0402-470PF,50V,10%,X7R,TA
     1 PVCCIN_CPU1_ATSEN @S9S_MB_2U_LIB.S9S_MB_2U(SCH_1):PVCCIN_CPU1_ATSEN    I72 @S9S_MB_2U_LIB.S9S_MB_2U(SCH_1):PAGE270
     2    GND @S9S_MB_2U_LIB.S9S_MB_2U(SCH_1):GND    I72 @S9S_MB_2U_LIB.S9S_MB_2U(SCH_1):PAGE270

PC555 Q_CAP_C0402-1UF,16V,10%,X6S,CHA
     1 PVCCIN_CPU1_VCC @S9S_MB_2U_LIB.S9S_MB_2U(SCH_1):PVCCIN_CPU1_VCC   I122 @S9S_MB_2U_LIB.S9S_MB_2U(SCH_1):PAGE270
     2    GND @S9S_MB_2U_LIB.S9S_MB_2U(SCH_1):GND   I122 @S9S_MB_2U_LIB.S9S_MB_2U(SCH_1):PAGE270

PC556 Q_CAP_C0402-2.2UF,10V,10%,X6S,A
     1 PVCCIN_CPU1_VDD2 @S9S_MB_2U_LIB.S9S_MB_2U(SCH_1):PVCCIN_CPU1_VDD2    I11 @S9S_MB_2U_LIB.S9S_MB_2U(SCH_1):PAGE271
     2    GND @S9S_MB_2U_LIB.S9S_MB_2U(SCH_1):GND    I11 @S9S_MB_2U_LIB.S9S_MB_2U(SCH_1):PAGE271

PC557 Q_CAP_C0402-2.2UF,10V,10%,X6S,A
     1 PVCCIN_CPU1_VDD1 @S9S_MB_2U_LIB.S9S_MB_2U(SCH_1):PVCCIN_CPU1_VDD1    I36 @S9S_MB_2U_LIB.S9S_MB_2U(SCH_1):PAGE271
     2    GND @S9S_MB_2U_LIB.S9S_MB_2U(SCH_1):GND    I36 @S9S_MB_2U_LIB.S9S_MB_2U(SCH_1):PAGE271

PC558_P1_2 Q_CAP_C0402-2.2UF,10V,10%,X6S,A
     1 PVCCIN_CPU1_PVCC @S9S_MB_2U_LIB.S9S_MB_2U(SCH_1):PVCCIN_CPU1_PVCC    I15 @S9S_MB_2U_LIB.S9S_MB_2U(SCH_1):PAGE271
     2    GND @S9S_MB_2U_LIB.S9S_MB_2U(SCH_1):GND    I15 @S9S_MB_2U_LIB.S9S_MB_2U(SCH_1):PAGE271

PC559_P1_1 Q_CAP_C0402-2.2UF,10V,10%,X6S,A
     1 PVCCIN_CPU1_PVCC @S9S_MB_2U_LIB.S9S_MB_2U(SCH_1):PVCCIN_CPU1_PVCC    I39 @S9S_MB_2U_LIB.S9S_MB_2U(SCH_1):PAGE271
     2    GND @S9S_MB_2U_LIB.S9S_MB_2U(SCH_1):GND    I39 @S9S_MB_2U_LIB.S9S_MB_2U(SCH_1):PAGE271

PC560_P1_2 Q_CAP_0402-3300PF,50V,10%,X7R,A
     1 SW_P12V_PVCCIN_CPU1_FLT @S9S_MB_2U_LIB.S9S_MB_2U(SCH_1):SW_P12V_PVCCIN_CPU1_FLT    I19 @S9S_MB_2U_LIB.S9S_MB_2U(SCH_1):PAGE271
     2    GND @S9S_MB_2U_LIB.S9S_MB_2U(SCH_1):GND    I19 @S9S_MB_2U_LIB.S9S_MB_2U(SCH_1):PAGE271

PC561_P1_1 Q_CAP_0402-3300PF,50V,10%,X7R,A
     1 SW_P12V_PVCCIN_CPU1_FLT @S9S_MB_2U_LIB.S9S_MB_2U(SCH_1):SW_P12V_PVCCIN_CPU1_FLT    I44 @S9S_MB_2U_LIB.S9S_MB_2U(SCH_1):PAGE271
     2    GND @S9S_MB_2U_LIB.S9S_MB_2U(SCH_1):GND    I44 @S9S_MB_2U_LIB.S9S_MB_2U(SCH_1):PAGE271

PC562_P1_2 Q_CAP_C0402-1UF,16V,10%,X6S,CHA
     1 SW_P12V_PVCCIN_CPU1_FLT @S9S_MB_2U_LIB.S9S_MB_2U(SCH_1):SW_P12V_PVCCIN_CPU1_FLT    I21 @S9S_MB_2U_LIB.S9S_MB_2U(SCH_1):PAGE271
     2    GND @S9S_MB_2U_LIB.S9S_MB_2U(SCH_1):GND    I21 @S9S_MB_2U_LIB.S9S_MB_2U(SCH_1):PAGE271

PC563_P1_1 Q_CAP_C0402-1UF,16V,10%,X6S,CHA
     1 SW_P12V_PVCCIN_CPU1_FLT @S9S_MB_2U_LIB.S9S_MB_2U(SCH_1):SW_P12V_PVCCIN_CPU1_FLT    I47 @S9S_MB_2U_LIB.S9S_MB_2U(SCH_1):PAGE271
     2    GND @S9S_MB_2U_LIB.S9S_MB_2U(SCH_1):GND    I47 @S9S_MB_2U_LIB.S9S_MB_2U(SCH_1):PAGE271

PC564 Q_CAP_C0402-100NF,50V,10%,X7R,A
     1 SW_PVCCIN_CPU1_BOOT2_R @S9S_MB_2U_LIB.S9S_MB_2U(SCH_1):SW_PVCCIN_CPU1_BOOT2_R    I23 @S9S_MB_2U_LIB.S9S_MB_2U(SCH_1):PAGE271
     2 SW_PVCCIN_CPU1_BOOTR2 @S9S_MB_2U_LIB.S9S_MB_2U(SCH_1):SW_PVCCIN_CPU1_BOOTR2    I23 @S9S_MB_2U_LIB.S9S_MB_2U(SCH_1):PAGE271

PC565 Q_CAP_C0402-100NF,50V,10%,X7R,A
     1 SW_PVCCIN_CPU1_BOOT1_R @S9S_MB_2U_LIB.S9S_MB_2U(SCH_1):SW_PVCCIN_CPU1_BOOT1_R    I49 @S9S_MB_2U_LIB.S9S_MB_2U(SCH_1):PAGE271
     2 SW_PVCCIN_CPU1_BOOTR1 @S9S_MB_2U_LIB.S9S_MB_2U(SCH_1):SW_PVCCIN_CPU1_BOOTR1    I49 @S9S_MB_2U_LIB.S9S_MB_2U(SCH_1):PAGE271

PC566 Q_CAPP_THLF-270UF,16V,20%,OSCOA
     1 SW_P3V3_AUX_FLT @S9S_MB_2U_LIB.S9S_MB_2U(SCH_1):SW_P3V3_AUX_FLT   I104 @S9S_MB_2U_LIB.S9S_MB_2U(SCH_1):PAGE245
     2    GND @S9S_MB_2U_LIB.S9S_MB_2U(SCH_1):GND   I104 @S9S_MB_2U_LIB.S9S_MB_2U(SCH_1):PAGE245

PC566_P1_2 Q_CAP_C0805-22UF,16V,20%,X6S,CA
     1 SW_P12V_PVCCIN_CPU1_FLT @S9S_MB_2U_LIB.S9S_MB_2U(SCH_1):SW_P12V_PVCCIN_CPU1_FLT    I22 @S9S_MB_2U_LIB.S9S_MB_2U(SCH_1):PAGE271
     2    GND @S9S_MB_2U_LIB.S9S_MB_2U(SCH_1):GND    I22 @S9S_MB_2U_LIB.S9S_MB_2U(SCH_1):PAGE271

PC567 Q_CAP_C0805-22UF,16V,20%,X6S,CA
     1 SW_P3V3_AUX_FLT @S9S_MB_2U_LIB.S9S_MB_2U(SCH_1):SW_P3V3_AUX_FLT   I106 @S9S_MB_2U_LIB.S9S_MB_2U(SCH_1):PAGE245
     2    GND @S9S_MB_2U_LIB.S9S_MB_2U(SCH_1):GND   I106 @S9S_MB_2U_LIB.S9S_MB_2U(SCH_1):PAGE245

PC567_P1_1 Q_CAP_C0805-22UF,16V,20%,X6S,CA
     1 SW_P12V_PVCCIN_CPU1_FLT @S9S_MB_2U_LIB.S9S_MB_2U(SCH_1):SW_P12V_PVCCIN_CPU1_FLT    I48 @S9S_MB_2U_LIB.S9S_MB_2U(SCH_1):PAGE271
     2    GND @S9S_MB_2U_LIB.S9S_MB_2U(SCH_1):GND    I48 @S9S_MB_2U_LIB.S9S_MB_2U(SCH_1):PAGE271

PC568 Q_CAP_C0402-0.22UF,25V,10%,X7RA
     1 SW_P3V3_AUX_BOOTR @S9S_MB_2U_LIB.S9S_MB_2U(SCH_1):SW_P3V3_AUX_BOOTR   I122 @S9S_MB_2U_LIB.S9S_MB_2U(SCH_1):PAGE245
     2 SW_P3V3_AUX_BOOT_R @S9S_MB_2U_LIB.S9S_MB_2U(SCH_1):SW_P3V3_AUX_BOOT_R   I122 @S9S_MB_2U_LIB.S9S_MB_2U(SCH_1):PAGE245

PC568_P1_2 Q_CAP_C0805-22UF,16V,20%,X6S,CA
     1 SW_P12V_PVCCIN_CPU1_FLT @S9S_MB_2U_LIB.S9S_MB_2U(SCH_1):SW_P12V_PVCCIN_CPU1_FLT    I24 @S9S_MB_2U_LIB.S9S_MB_2U(SCH_1):PAGE271
     2    GND @S9S_MB_2U_LIB.S9S_MB_2U(SCH_1):GND    I24 @S9S_MB_2U_LIB.S9S_MB_2U(SCH_1):PAGE271

PC569 Q_CAP_0402-220PF,50V,10%,X7R,TA
     1 P3V3_AUX_FB @S9S_MB_2U_LIB.S9S_MB_2U(SCH_1):P3V3_AUX_FB   I127 @S9S_MB_2U_LIB.S9S_MB_2U(SCH_1):PAGE245
     2 P3V3_AUX @S9S_MB_2U_LIB.S9S_MB_2U(SCH_1):P3V3_AUX   I127 @S9S_MB_2U_LIB.S9S_MB_2U(SCH_1):PAGE245

PC569_P1_1 Q_CAP_C0805-22UF,16V,20%,X6S,CA
     1 SW_P12V_PVCCIN_CPU1_FLT @S9S_MB_2U_LIB.S9S_MB_2U(SCH_1):SW_P12V_PVCCIN_CPU1_FLT    I50 @S9S_MB_2U_LIB.S9S_MB_2U(SCH_1):PAGE271
     2    GND @S9S_MB_2U_LIB.S9S_MB_2U(SCH_1):GND    I50 @S9S_MB_2U_LIB.S9S_MB_2U(SCH_1):PAGE271

PC570 Q_CAP_C0805-22UF,16V,20%,X6S,CA
     1 SW_P3V3_AUX_FLT @S9S_MB_2U_LIB.S9S_MB_2U(SCH_1):SW_P3V3_AUX_FLT   I109 @S9S_MB_2U_LIB.S9S_MB_2U(SCH_1):PAGE245
     2    GND @S9S_MB_2U_LIB.S9S_MB_2U(SCH_1):GND   I109 @S9S_MB_2U_LIB.S9S_MB_2U(SCH_1):PAGE245

PC570_P1_2 Q_CAP_C0805-22UF,16V,20%,X6S,CA
     1 SW_P12V_PVCCIN_CPU1_FLT @S9S_MB_2U_LIB.S9S_MB_2U(SCH_1):SW_P12V_PVCCIN_CPU1_FLT    I53 @S9S_MB_2U_LIB.S9S_MB_2U(SCH_1):PAGE271
     2    GND @S9S_MB_2U_LIB.S9S_MB_2U(SCH_1):GND    I53 @S9S_MB_2U_LIB.S9S_MB_2U(SCH_1):PAGE271

PC571 Q_CAP_C0805-22UF,16V,20%,X6S,CA
     1 SW_P3V3_AUX_FLT @S9S_MB_2U_LIB.S9S_MB_2U(SCH_1):SW_P3V3_AUX_FLT   I110 @S9S_MB_2U_LIB.S9S_MB_2U(SCH_1):PAGE245
     2    GND @S9S_MB_2U_LIB.S9S_MB_2U(SCH_1):GND   I110 @S9S_MB_2U_LIB.S9S_MB_2U(SCH_1):PAGE245

PC571_P1_1 Q_CAP_C0805-22UF,16V,20%,X6S,CA
     1 SW_P12V_PVCCIN_CPU1_FLT @S9S_MB_2U_LIB.S9S_MB_2U(SCH_1):SW_P12V_PVCCIN_CPU1_FLT    I76 @S9S_MB_2U_LIB.S9S_MB_2U(SCH_1):PAGE271
     2    GND @S9S_MB_2U_LIB.S9S_MB_2U(SCH_1):GND    I76 @S9S_MB_2U_LIB.S9S_MB_2U(SCH_1):PAGE271

PC572_P1_1 Q_CAP_C0402-100NF,50V,10%,X7R,A
     1 PVCCIN_CPU1 @S9S_MB_2U_LIB.S9S_MB_2U(SCH_1):PVCCIN_CPU1    I84 @S9S_MB_2U_LIB.S9S_MB_2U(SCH_1):PAGE271
     2    GND @S9S_MB_2U_LIB.S9S_MB_2U(SCH_1):GND    I84 @S9S_MB_2U_LIB.S9S_MB_2U(SCH_1):PAGE271

PC574_P1_1 Q_CAP_C0402-1UF,16V,10%,X6S,CHA
     1 PVCCIN_CPU1 @S9S_MB_2U_LIB.S9S_MB_2U(SCH_1):PVCCIN_CPU1    I85 @S9S_MB_2U_LIB.S9S_MB_2U(SCH_1):PAGE271
     2    GND @S9S_MB_2U_LIB.S9S_MB_2U(SCH_1):GND    I85 @S9S_MB_2U_LIB.S9S_MB_2U(SCH_1):PAGE271

PC575_P1_2 Q_CAP_C0805-22UF,4V,20%,X6S,CHA
     1 PVCCIN_CPU1 @S9S_MB_2U_LIB.S9S_MB_2U(SCH_1):PVCCIN_CPU1    I57 @S9S_MB_2U_LIB.S9S_MB_2U(SCH_1):PAGE271
     2    GND @S9S_MB_2U_LIB.S9S_MB_2U(SCH_1):GND    I57 @S9S_MB_2U_LIB.S9S_MB_2U(SCH_1):PAGE271

PC576 Q_CAP_C0805-22UF,16V,20%,X6S,CA
     1 SW_P3V3_AUX_FLT @S9S_MB_2U_LIB.S9S_MB_2U(SCH_1):SW_P3V3_AUX_FLT   I113 @S9S_MB_2U_LIB.S9S_MB_2U(SCH_1):PAGE245
     2    GND @S9S_MB_2U_LIB.S9S_MB_2U(SCH_1):GND   I113 @S9S_MB_2U_LIB.S9S_MB_2U(SCH_1):PAGE245

PC576_P1_1 Q_CAP_C0805-22UF,4V,20%,X6S,CHA
     1 PVCCIN_CPU1 @S9S_MB_2U_LIB.S9S_MB_2U(SCH_1):PVCCIN_CPU1    I88 @S9S_MB_2U_LIB.S9S_MB_2U(SCH_1):PAGE271
     2    GND @S9S_MB_2U_LIB.S9S_MB_2U(SCH_1):GND    I88 @S9S_MB_2U_LIB.S9S_MB_2U(SCH_1):PAGE271

PC577 Q_CAP_0402-0.1UF,25V,10%,X7R,CA
     1 SW_P3V3_AUX_FLT @S9S_MB_2U_LIB.S9S_MB_2U(SCH_1):SW_P3V3_AUX_FLT   I115 @S9S_MB_2U_LIB.S9S_MB_2U(SCH_1):PAGE245
     2    GND @S9S_MB_2U_LIB.S9S_MB_2U(SCH_1):GND   I115 @S9S_MB_2U_LIB.S9S_MB_2U(SCH_1):PAGE245

PC577_P1_2 Q_CAP_C0805-22UF,4V,20%,X6S,CHA
     1 PVCCIN_CPU1 @S9S_MB_2U_LIB.S9S_MB_2U(SCH_1):PVCCIN_CPU1    I58 @S9S_MB_2U_LIB.S9S_MB_2U(SCH_1):PAGE271
     2    GND @S9S_MB_2U_LIB.S9S_MB_2U(SCH_1):GND    I58 @S9S_MB_2U_LIB.S9S_MB_2U(SCH_1):PAGE271

PC578_P1_1 Q_CAP_C0805-22UF,4V,20%,X6S,CHA
     1 PVCCIN_CPU1 @S9S_MB_2U_LIB.S9S_MB_2U(SCH_1):PVCCIN_CPU1    I91 @S9S_MB_2U_LIB.S9S_MB_2U(SCH_1):PAGE271
     2    GND @S9S_MB_2U_LIB.S9S_MB_2U(SCH_1):GND    I91 @S9S_MB_2U_LIB.S9S_MB_2U(SCH_1):PAGE271

PC579 Q_CAPP_THLF-270UF,16V,20%,OSCOA
     1 SW_P12V_PVCCIN_CPU1_FLT @S9S_MB_2U_LIB.S9S_MB_2U(SCH_1):SW_P12V_PVCCIN_CPU1_FLT    I86 @S9S_MB_2U_LIB.S9S_MB_2U(SCH_1):PAGE271
     2    GND @S9S_MB_2U_LIB.S9S_MB_2U(SCH_1):GND    I86 @S9S_MB_2U_LIB.S9S_MB_2U(SCH_1):PAGE271

PC580 Q_CAPP_THLF-560UF,2.5V,20%,OSCA
     1 PVCCIN_CPU1 @S9S_MB_2U_LIB.S9S_MB_2U(SCH_1):PVCCIN_CPU1    I63 @S9S_MB_2U_LIB.S9S_MB_2U(SCH_1):PAGE271
     2    GND @S9S_MB_2U_LIB.S9S_MB_2U(SCH_1):GND    I63 @S9S_MB_2U_LIB.S9S_MB_2U(SCH_1):PAGE271

PC581 Q_CAP_C0603-4.7UF,16V,10%,X6S,A
     1 P3V3_AUX_VDRV @S9S_MB_2U_LIB.S9S_MB_2U(SCH_1):P3V3_AUX_VDRV    I86 @S9S_MB_2U_LIB.S9S_MB_2U(SCH_1):PAGE245
     2    GND @S9S_MB_2U_LIB.S9S_MB_2U(SCH_1):GND    I86 @S9S_MB_2U_LIB.S9S_MB_2U(SCH_1):PAGE245

PC582 Q_CAPP_THLF-270UF,16V,20%,OSCOA
     1 SW_P12V_PVCCIN_CPU1_FLT @S9S_MB_2U_LIB.S9S_MB_2U(SCH_1):SW_P12V_PVCCIN_CPU1_FLT    I87 @S9S_MB_2U_LIB.S9S_MB_2U(SCH_1):PAGE271
     2    GND @S9S_MB_2U_LIB.S9S_MB_2U(SCH_1):GND    I87 @S9S_MB_2U_LIB.S9S_MB_2U(SCH_1):PAGE271

PC583 Q_CAPP_THLF-560UF,2.5V,20%,OSCA
     1 PVCCIN_CPU1 @S9S_MB_2U_LIB.S9S_MB_2U(SCH_1):PVCCIN_CPU1    I64 @S9S_MB_2U_LIB.S9S_MB_2U(SCH_1):PAGE271
     2    GND @S9S_MB_2U_LIB.S9S_MB_2U(SCH_1):GND    I64 @S9S_MB_2U_LIB.S9S_MB_2U(SCH_1):PAGE271

PC585 Q_CAPP_THLF-270UF,16V,20%,OSCOA
     1 SW_P12V_PVCCIN_CPU1_FLT @S9S_MB_2U_LIB.S9S_MB_2U(SCH_1):SW_P12V_PVCCIN_CPU1_FLT    I92 @S9S_MB_2U_LIB.S9S_MB_2U(SCH_1):PAGE271
     2    GND @S9S_MB_2U_LIB.S9S_MB_2U(SCH_1):GND    I92 @S9S_MB_2U_LIB.S9S_MB_2U(SCH_1):PAGE271

PC586 Q_CAPP_THLF-560UF,2.5V,20%,OSCA
     1 PVCCIN_CPU1 @S9S_MB_2U_LIB.S9S_MB_2U(SCH_1):PVCCIN_CPU1    I69 @S9S_MB_2U_LIB.S9S_MB_2U(SCH_1):PAGE271
     2    GND @S9S_MB_2U_LIB.S9S_MB_2U(SCH_1):GND    I69 @S9S_MB_2U_LIB.S9S_MB_2U(SCH_1):PAGE271

PC587 Q_CAPP_SMLF-330UF,2.5V,+10/-35A
     1 PVCCIN_CPU1 @S9S_MB_2U_LIB.S9S_MB_2U(SCH_1):PVCCIN_CPU1    I65 @S9S_MB_2U_LIB.S9S_MB_2U(SCH_1):PAGE271
     2    GND @S9S_MB_2U_LIB.S9S_MB_2U(SCH_1):GND    I65 @S9S_MB_2U_LIB.S9S_MB_2U(SCH_1):PAGE271

PC588 Q_CAPP_THLF-270UF,16V,20%,OSCOA
     1 SW_P12V_PVCCIN_CPU1_FLT @S9S_MB_2U_LIB.S9S_MB_2U(SCH_1):SW_P12V_PVCCIN_CPU1_FLT    I94 @S9S_MB_2U_LIB.S9S_MB_2U(SCH_1):PAGE271
     2    GND @S9S_MB_2U_LIB.S9S_MB_2U(SCH_1):GND    I94 @S9S_MB_2U_LIB.S9S_MB_2U(SCH_1):PAGE271

PC589 Q_CAPP_THLF-560UF,2.5V,20%,OSCA
     1 PVCCIN_CPU1 @S9S_MB_2U_LIB.S9S_MB_2U(SCH_1):PVCCIN_CPU1    I72 @S9S_MB_2U_LIB.S9S_MB_2U(SCH_1):PAGE271
     2    GND @S9S_MB_2U_LIB.S9S_MB_2U(SCH_1):GND    I72 @S9S_MB_2U_LIB.S9S_MB_2U(SCH_1):PAGE271

PC590 Q_CAPP_SMLF-330UF,2.5V,+10/-35A
     1 PVCCIN_CPU1 @S9S_MB_2U_LIB.S9S_MB_2U(SCH_1):PVCCIN_CPU1    I68 @S9S_MB_2U_LIB.S9S_MB_2U(SCH_1):PAGE271
     2    GND @S9S_MB_2U_LIB.S9S_MB_2U(SCH_1):GND    I68 @S9S_MB_2U_LIB.S9S_MB_2U(SCH_1):PAGE271

PC591 Q_CAP_C0603-2.2UF,16V,10%,X6S,A
     1 P3V3_AUX_VCC @S9S_MB_2U_LIB.S9S_MB_2U(SCH_1):P3V3_AUX_VCC    I93 @S9S_MB_2U_LIB.S9S_MB_2U(SCH_1):PAGE245
     2    GND @S9S_MB_2U_LIB.S9S_MB_2U(SCH_1):GND    I93 @S9S_MB_2U_LIB.S9S_MB_2U(SCH_1):PAGE245

PC594 Q_CAP_0402-3300PF,50V,10%,X7R,A
     1 SH_PVCCFA_EHV_FIVRA_CPU0_R @S9S_MB_2U_LIB.S9S_MB_2U(SCH_1):SH_PVCCFA_EHV_FIVRA_CPU0_R    I67 @S9S_MB_2U_LIB.S9S_MB_2U(SCH_1):PAGE252
     2 VSENSE_PVCCFA_EHV_FIVRA_CPU0_DN @S9S_MB_2U_LIB.S9S_MB_2U(SCH_1):VSENSE_PVCCFA_EHV_FIVRA_CPU0_DN    I67 @S9S_MB_2U_LIB.S9S_MB_2U(SCH_1):PAGE252

PC600 Q_CAP_C0402-2.2UF,10V,10%,X6S,A
     1 PVCCFA_EHV_FIVRA_CPU0_VDD1 @S9S_MB_2U_LIB.S9S_MB_2U(SCH_1):PVCCFA_EHV_FIVRA_CPU0_VDD1    I37 @S9S_MB_2U_LIB.S9S_MB_2U(SCH_1):PAGE257
     2    GND @S9S_MB_2U_LIB.S9S_MB_2U(SCH_1):GND    I37 @S9S_MB_2U_LIB.S9S_MB_2U(SCH_1):PAGE257

PC601 Q_CAP_C0402-2.2UF,10V,10%,X6S,A
     1 PVCCFA_EHV_FIVRA_CPU0_VDD2 @S9S_MB_2U_LIB.S9S_MB_2U(SCH_1):PVCCFA_EHV_FIVRA_CPU0_VDD2    I18 @S9S_MB_2U_LIB.S9S_MB_2U(SCH_1):PAGE257
     2    GND @S9S_MB_2U_LIB.S9S_MB_2U(SCH_1):GND    I18 @S9S_MB_2U_LIB.S9S_MB_2U(SCH_1):PAGE257

PC602_P0_1 Q_CAP_0402-3300PF,50V,10%,X7R,A
     1 SW_P12V_PVCCFA_EHV_FIVRA_CPU0_R @S9S_MB_2U_LIB.S9S_MB_2U(SCH_1):SW_P12V_PVCCFA_EHV_FIVRA_CPU0_R    I44 @S9S_MB_2U_LIB.S9S_MB_2U(SCH_1):PAGE257
     2    GND @S9S_MB_2U_LIB.S9S_MB_2U(SCH_1):GND    I44 @S9S_MB_2U_LIB.S9S_MB_2U(SCH_1):PAGE257

PC603_P0_2 Q_CAP_0402-3300PF,50V,10%,X7R,A
     1 SW_P12V_PVCCFA_EHV_FIVRA_CPU0_L @S9S_MB_2U_LIB.S9S_MB_2U(SCH_1):SW_P12V_PVCCFA_EHV_FIVRA_CPU0_L    I27 @S9S_MB_2U_LIB.S9S_MB_2U(SCH_1):PAGE257
     2    GND @S9S_MB_2U_LIB.S9S_MB_2U(SCH_1):GND    I27 @S9S_MB_2U_LIB.S9S_MB_2U(SCH_1):PAGE257

PC604_P0_1 Q_CAP_C0402-1UF,16V,10%,X6S,CHA
     1 SW_P12V_PVCCFA_EHV_FIVRA_CPU0_R @S9S_MB_2U_LIB.S9S_MB_2U(SCH_1):SW_P12V_PVCCFA_EHV_FIVRA_CPU0_R    I45 @S9S_MB_2U_LIB.S9S_MB_2U(SCH_1):PAGE257
     2    GND @S9S_MB_2U_LIB.S9S_MB_2U(SCH_1):GND    I45 @S9S_MB_2U_LIB.S9S_MB_2U(SCH_1):PAGE257

PC605_P0_2 Q_CAP_C0402-1UF,16V,10%,X6S,CHA
     1 SW_P12V_PVCCFA_EHV_FIVRA_CPU0_L @S9S_MB_2U_LIB.S9S_MB_2U(SCH_1):SW_P12V_PVCCFA_EHV_FIVRA_CPU0_L    I28 @S9S_MB_2U_LIB.S9S_MB_2U(SCH_1):PAGE257
     2    GND @S9S_MB_2U_LIB.S9S_MB_2U(SCH_1):GND    I28 @S9S_MB_2U_LIB.S9S_MB_2U(SCH_1):PAGE257

PC606 Q_CAP_C0402-100NF,50V,10%,X7R,A
     1 SW_PVCCFA_EHV_FIVRA_CPU0_BOOT1_ @S9S_MB_2U_LIB.S9S_MB_2U(SCH_1):SW_PVCCFA_EHV_FIVRA_CPU0_BOOT1_R    I71 @S9S_MB_2U_LIB.S9S_MB_2U(SCH_1):PAGE257
     2 SW_PVCCFA_EHV_FIVRA_CPU0_BOOTR1 @S9S_MB_2U_LIB.S9S_MB_2U(SCH_1):SW_PVCCFA_EHV_FIVRA_CPU0_BOOTR1    I71 @S9S_MB_2U_LIB.S9S_MB_2U(SCH_1):PAGE257

PC607 Q_CAP_C0402-100NF,50V,10%,X7R,A
     1 SW_PVCCFA_EHV_FIVRA_CPU0_BOOT2_ @S9S_MB_2U_LIB.S9S_MB_2U(SCH_1):SW_PVCCFA_EHV_FIVRA_CPU0_BOOT2_R    I53 @S9S_MB_2U_LIB.S9S_MB_2U(SCH_1):PAGE257
     2 SW_PVCCFA_EHV_FIVRA_CPU0_BOOTR2 @S9S_MB_2U_LIB.S9S_MB_2U(SCH_1):SW_PVCCFA_EHV_FIVRA_CPU0_BOOTR2    I53 @S9S_MB_2U_LIB.S9S_MB_2U(SCH_1):PAGE257

PC608_P0_1 Q_CAP_C0805-22UF,16V,20%,X6S,CA
     1 SW_P12V_PVCCFA_EHV_FIVRA_CPU0_R @S9S_MB_2U_LIB.S9S_MB_2U(SCH_1):SW_P12V_PVCCFA_EHV_FIVRA_CPU0_R    I47 @S9S_MB_2U_LIB.S9S_MB_2U(SCH_1):PAGE257
     2    GND @S9S_MB_2U_LIB.S9S_MB_2U(SCH_1):GND    I47 @S9S_MB_2U_LIB.S9S_MB_2U(SCH_1):PAGE257

PC609_P0_2 Q_CAP_C0805-22UF,16V,20%,X6S,CA
     1 SW_P12V_PVCCFA_EHV_FIVRA_CPU0_L @S9S_MB_2U_LIB.S9S_MB_2U(SCH_1):SW_P12V_PVCCFA_EHV_FIVRA_CPU0_L    I31 @S9S_MB_2U_LIB.S9S_MB_2U(SCH_1):PAGE257
     2    GND @S9S_MB_2U_LIB.S9S_MB_2U(SCH_1):GND    I31 @S9S_MB_2U_LIB.S9S_MB_2U(SCH_1):PAGE257

PC610_P0_1 Q_CAP_C0805-22UF,16V,20%,X6S,CA
     1 SW_P12V_PVCCFA_EHV_FIVRA_CPU0_R @S9S_MB_2U_LIB.S9S_MB_2U(SCH_1):SW_P12V_PVCCFA_EHV_FIVRA_CPU0_R    I48 @S9S_MB_2U_LIB.S9S_MB_2U(SCH_1):PAGE257
     2    GND @S9S_MB_2U_LIB.S9S_MB_2U(SCH_1):GND    I48 @S9S_MB_2U_LIB.S9S_MB_2U(SCH_1):PAGE257

PC611_P0_2 Q_CAP_C0805-22UF,16V,20%,X6S,CA
     1 SW_P12V_PVCCFA_EHV_FIVRA_CPU0_L @S9S_MB_2U_LIB.S9S_MB_2U(SCH_1):SW_P12V_PVCCFA_EHV_FIVRA_CPU0_L    I32 @S9S_MB_2U_LIB.S9S_MB_2U(SCH_1):PAGE257
     2    GND @S9S_MB_2U_LIB.S9S_MB_2U(SCH_1):GND    I32 @S9S_MB_2U_LIB.S9S_MB_2U(SCH_1):PAGE257

PC612_P0_1 Q_CAP_C0402-100NF,50V,10%,X7R,A
     1 PVCCFA_EHV_FIVRA_CPU0 @S9S_MB_2U_LIB.S9S_MB_2U(SCH_1):PVCCFA_EHV_FIVRA_CPU0    I75 @S9S_MB_2U_LIB.S9S_MB_2U(SCH_1):PAGE257
     2    GND @S9S_MB_2U_LIB.S9S_MB_2U(SCH_1):GND    I75 @S9S_MB_2U_LIB.S9S_MB_2U(SCH_1):PAGE257

PC613_P0_2 Q_CAP_C0402-1UF,16V,10%,X6S,CHA
     1 PVCCFA_EHV_FIVRA_CPU0 @S9S_MB_2U_LIB.S9S_MB_2U(SCH_1):PVCCFA_EHV_FIVRA_CPU0    I51 @S9S_MB_2U_LIB.S9S_MB_2U(SCH_1):PAGE257
     2    GND @S9S_MB_2U_LIB.S9S_MB_2U(SCH_1):GND    I51 @S9S_MB_2U_LIB.S9S_MB_2U(SCH_1):PAGE257

PC615_P0_1 Q_CAP_C0805-22UF,4V,20%,X6S,CHA
     1 PVCCFA_EHV_FIVRA_CPU0 @S9S_MB_2U_LIB.S9S_MB_2U(SCH_1):PVCCFA_EHV_FIVRA_CPU0    I77 @S9S_MB_2U_LIB.S9S_MB_2U(SCH_1):PAGE257
     2    GND @S9S_MB_2U_LIB.S9S_MB_2U(SCH_1):GND    I77 @S9S_MB_2U_LIB.S9S_MB_2U(SCH_1):PAGE257

PC616_P0_2 Q_CAP_C0805-22UF,4V,20%,X6S,CHA
     1 PVCCFA_EHV_FIVRA_CPU0 @S9S_MB_2U_LIB.S9S_MB_2U(SCH_1):PVCCFA_EHV_FIVRA_CPU0    I52 @S9S_MB_2U_LIB.S9S_MB_2U(SCH_1):PAGE257
     2    GND @S9S_MB_2U_LIB.S9S_MB_2U(SCH_1):GND    I52 @S9S_MB_2U_LIB.S9S_MB_2U(SCH_1):PAGE257

PC617_P0_1 Q_CAP_C0805-22UF,4V,20%,X6S,CHA
     1 PVCCFA_EHV_FIVRA_CPU0 @S9S_MB_2U_LIB.S9S_MB_2U(SCH_1):PVCCFA_EHV_FIVRA_CPU0    I81 @S9S_MB_2U_LIB.S9S_MB_2U(SCH_1):PAGE257
     2    GND @S9S_MB_2U_LIB.S9S_MB_2U(SCH_1):GND    I81 @S9S_MB_2U_LIB.S9S_MB_2U(SCH_1):PAGE257

PC618_P0_2 Q_CAP_C0805-22UF,4V,20%,X6S,CHA
     1 PVCCFA_EHV_FIVRA_CPU0 @S9S_MB_2U_LIB.S9S_MB_2U(SCH_1):PVCCFA_EHV_FIVRA_CPU0    I59 @S9S_MB_2U_LIB.S9S_MB_2U(SCH_1):PAGE257
     2    GND @S9S_MB_2U_LIB.S9S_MB_2U(SCH_1):GND    I59 @S9S_MB_2U_LIB.S9S_MB_2U(SCH_1):PAGE257

PC619 Q_CAPP_THLF-560UF,2.5V,20%,OSCA
     1 PVCCFA_EHV_FIVRA_CPU0 @S9S_MB_2U_LIB.S9S_MB_2U(SCH_1):PVCCFA_EHV_FIVRA_CPU0    I57 @S9S_MB_2U_LIB.S9S_MB_2U(SCH_1):PAGE257
     2    GND @S9S_MB_2U_LIB.S9S_MB_2U(SCH_1):GND    I57 @S9S_MB_2U_LIB.S9S_MB_2U(SCH_1):PAGE257

PC620 Q_CAPP_THLF-560UF,2.5V,20%,OSCA
     1 PVCCFA_EHV_FIVRA_CPU0 @S9S_MB_2U_LIB.S9S_MB_2U(SCH_1):PVCCFA_EHV_FIVRA_CPU0    I58 @S9S_MB_2U_LIB.S9S_MB_2U(SCH_1):PAGE257
     2    GND @S9S_MB_2U_LIB.S9S_MB_2U(SCH_1):GND    I58 @S9S_MB_2U_LIB.S9S_MB_2U(SCH_1):PAGE257

PC621 Q_CAPP_THLF-560UF,2.5V,20%,OSCA
     1 PVCCFA_EHV_FIVRA_CPU0 @S9S_MB_2U_LIB.S9S_MB_2U(SCH_1):PVCCFA_EHV_FIVRA_CPU0    I62 @S9S_MB_2U_LIB.S9S_MB_2U(SCH_1):PAGE257
     2    GND @S9S_MB_2U_LIB.S9S_MB_2U(SCH_1):GND    I62 @S9S_MB_2U_LIB.S9S_MB_2U(SCH_1):PAGE257

PC621_P1_1 Q_CAP_C0402-100NF,50V,10%,X7R,A
     1 PVCCFA_EHV_FIVRA_CPU1 @S9S_MB_2U_LIB.S9S_MB_2U(SCH_1):PVCCFA_EHV_FIVRA_CPU1    I60 @S9S_MB_2U_LIB.S9S_MB_2U(SCH_1):PAGE275
     2    GND @S9S_MB_2U_LIB.S9S_MB_2U(SCH_1):GND    I60 @S9S_MB_2U_LIB.S9S_MB_2U(SCH_1):PAGE275

PC622 Q_CAPP_THLF-270UF,16V,20%,OSCOA
     1 SW_P12V_PVCCFA_EHV_FIVRA_CPU0_L @S9S_MB_2U_LIB.S9S_MB_2U(SCH_1):SW_P12V_PVCCFA_EHV_FIVRA_CPU0_L    I88 @S9S_MB_2U_LIB.S9S_MB_2U(SCH_1):PAGE257
     2    GND @S9S_MB_2U_LIB.S9S_MB_2U(SCH_1):GND    I88 @S9S_MB_2U_LIB.S9S_MB_2U(SCH_1):PAGE257

PC623 Q_CAPP_SMLF-330UF,2.5V,+10/-35B
     1 PVCCFA_EHV_FIVRA_CPU0 @S9S_MB_2U_LIB.S9S_MB_2U(SCH_1):PVCCFA_EHV_FIVRA_CPU0    I63 @S9S_MB_2U_LIB.S9S_MB_2U(SCH_1):PAGE257
     2    GND @S9S_MB_2U_LIB.S9S_MB_2U(SCH_1):GND    I63 @S9S_MB_2U_LIB.S9S_MB_2U(SCH_1):PAGE257

PC624 Q_CAP_0402-0.1UF,25V,10%,X7R,CA
     1 PVCCD_HV_CPU0_ISENSE_P @S9S_MB_2U_LIB.S9S_MB_2U(SCH_1):PVCCD_HV_CPU0_ISENSE_P     I9 @S9S_MB_2U_LIB.S9S_MB_2U(SCH_1):PAGE264
     2    GND @S9S_MB_2U_LIB.S9S_MB_2U(SCH_1):GND     I9 @S9S_MB_2U_LIB.S9S_MB_2U(SCH_1):PAGE264

PC627 Q_CAP_0402-3300PF,50V,10%,X7R,A
     1 SH_PVCCD_HV_CPU0_R @S9S_MB_2U_LIB.S9S_MB_2U(SCH_1):SH_PVCCD_HV_CPU0_R    I37 @S9S_MB_2U_LIB.S9S_MB_2U(SCH_1):PAGE264
     2 VSENSE_PVCCD_HV_CPU0_DN @S9S_MB_2U_LIB.S9S_MB_2U(SCH_1):VSENSE_PVCCD_HV_CPU0_DN    I37 @S9S_MB_2U_LIB.S9S_MB_2U(SCH_1):PAGE264

PC628 Q_CAP_0402-0.1UF,25V,10%,X7R,CA
     1 PVCCD_HV_CPU0_ISENSE_N @S9S_MB_2U_LIB.S9S_MB_2U(SCH_1):PVCCD_HV_CPU0_ISENSE_N    I50 @S9S_MB_2U_LIB.S9S_MB_2U(SCH_1):PAGE264
     2    GND @S9S_MB_2U_LIB.S9S_MB_2U(SCH_1):GND    I50 @S9S_MB_2U_LIB.S9S_MB_2U(SCH_1):PAGE264

PC629 Q_CAP_C0402-100NF,50V,10%,EMPTA
     1 PVCCD_HV_CPU0_VCC @S9S_MB_2U_LIB.S9S_MB_2U(SCH_1):PVCCD_HV_CPU0_VCC    I72 @S9S_MB_2U_LIB.S9S_MB_2U(SCH_1):PAGE264
     2    GND @S9S_MB_2U_LIB.S9S_MB_2U(SCH_1):GND    I72 @S9S_MB_2U_LIB.S9S_MB_2U(SCH_1):PAGE264

PC630 Q_CAP_C0402-10UF,6.3V,20%,X6S,B
     1 PVCCD_HV_CPU0_VREF @S9S_MB_2U_LIB.S9S_MB_2U(SCH_1):PVCCD_HV_CPU0_VREF    I70 @S9S_MB_2U_LIB.S9S_MB_2U(SCH_1):PAGE264
     2    GND @S9S_MB_2U_LIB.S9S_MB_2U(SCH_1):GND    I70 @S9S_MB_2U_LIB.S9S_MB_2U(SCH_1):PAGE264

PC631 Q_CAP_0402-470PF,50V,10%,X7R,TA
     1 PVCCD_HV_CPU0_ATSEN @S9S_MB_2U_LIB.S9S_MB_2U(SCH_1):PVCCD_HV_CPU0_ATSEN    I56 @S9S_MB_2U_LIB.S9S_MB_2U(SCH_1):PAGE264
     2    GND @S9S_MB_2U_LIB.S9S_MB_2U(SCH_1):GND    I56 @S9S_MB_2U_LIB.S9S_MB_2U(SCH_1):PAGE264

PC632 Q_CAP_C0402-1UF,16V,10%,X6S,CHA
     1 PVCCD_HV_CPU0_VCC @S9S_MB_2U_LIB.S9S_MB_2U(SCH_1):PVCCD_HV_CPU0_VCC    I73 @S9S_MB_2U_LIB.S9S_MB_2U(SCH_1):PAGE264
     2    GND @S9S_MB_2U_LIB.S9S_MB_2U(SCH_1):GND    I73 @S9S_MB_2U_LIB.S9S_MB_2U(SCH_1):PAGE264

PC633 Q_CAP_C0402-2.2UF,10V,10%,X6S,A
     1 PVCCD_HV_CPU0_VDD1 @S9S_MB_2U_LIB.S9S_MB_2U(SCH_1):PVCCD_HV_CPU0_VDD1    I11 @S9S_MB_2U_LIB.S9S_MB_2U(SCH_1):PAGE265
     2    GND @S9S_MB_2U_LIB.S9S_MB_2U(SCH_1):GND    I11 @S9S_MB_2U_LIB.S9S_MB_2U(SCH_1):PAGE265

PC634 Q_CAP_0402-3300PF,50V,10%,X7R,A
     1 SW_P12V_PVCCINFAON_CPU0_FLT @S9S_MB_2U_LIB.S9S_MB_2U(SCH_1):SW_P12V_PVCCINFAON_CPU0_FLT    I18 @S9S_MB_2U_LIB.S9S_MB_2U(SCH_1):PAGE265
     2    GND @S9S_MB_2U_LIB.S9S_MB_2U(SCH_1):GND    I18 @S9S_MB_2U_LIB.S9S_MB_2U(SCH_1):PAGE265

PC635 Q_CAP_C0402-1UF,16V,10%,X6S,CHA
     1 SW_P12V_PVCCINFAON_CPU0_FLT @S9S_MB_2U_LIB.S9S_MB_2U(SCH_1):SW_P12V_PVCCINFAON_CPU0_FLT    I20 @S9S_MB_2U_LIB.S9S_MB_2U(SCH_1):PAGE265
     2    GND @S9S_MB_2U_LIB.S9S_MB_2U(SCH_1):GND    I20 @S9S_MB_2U_LIB.S9S_MB_2U(SCH_1):PAGE265

PC636 Q_CAP_C0402-100NF,50V,10%,X7R,A
     1 SW_PVCCD_HV_CPU0_BOOT1_R @S9S_MB_2U_LIB.S9S_MB_2U(SCH_1):SW_PVCCD_HV_CPU0_BOOT1_R    I22 @S9S_MB_2U_LIB.S9S_MB_2U(SCH_1):PAGE265
     2 SW_PVCCD_HV_CPU0_BOOTR1 @S9S_MB_2U_LIB.S9S_MB_2U(SCH_1):SW_PVCCD_HV_CPU0_BOOTR1    I22 @S9S_MB_2U_LIB.S9S_MB_2U(SCH_1):PAGE265

PC637 Q_CAP_C0805-22UF,16V,20%,X6S,CA
     1 SW_P12V_PVCCINFAON_CPU0_FLT @S9S_MB_2U_LIB.S9S_MB_2U(SCH_1):SW_P12V_PVCCINFAON_CPU0_FLT    I21 @S9S_MB_2U_LIB.S9S_MB_2U(SCH_1):PAGE265
     2    GND @S9S_MB_2U_LIB.S9S_MB_2U(SCH_1):GND    I21 @S9S_MB_2U_LIB.S9S_MB_2U(SCH_1):PAGE265

PC638 Q_CAP_C0805-22UF,16V,20%,X6S,CA
     1 SW_P12V_PVCCINFAON_CPU0_FLT @S9S_MB_2U_LIB.S9S_MB_2U(SCH_1):SW_P12V_PVCCINFAON_CPU0_FLT    I23 @S9S_MB_2U_LIB.S9S_MB_2U(SCH_1):PAGE265
     2    GND @S9S_MB_2U_LIB.S9S_MB_2U(SCH_1):GND    I23 @S9S_MB_2U_LIB.S9S_MB_2U(SCH_1):PAGE265

PC639 Q_CAP_C0402-100NF,50V,10%,X7R,A
     1 PVCCD_HV_CPU0 @S9S_MB_2U_LIB.S9S_MB_2U(SCH_1):PVCCD_HV_CPU0    I24 @S9S_MB_2U_LIB.S9S_MB_2U(SCH_1):PAGE265
     2    GND @S9S_MB_2U_LIB.S9S_MB_2U(SCH_1):GND    I24 @S9S_MB_2U_LIB.S9S_MB_2U(SCH_1):PAGE265

PC641 Q_CAP_C0805-22UF,4V,20%,X6S,CHA
     1 PVCCD_HV_CPU0 @S9S_MB_2U_LIB.S9S_MB_2U(SCH_1):PVCCD_HV_CPU0    I25 @S9S_MB_2U_LIB.S9S_MB_2U(SCH_1):PAGE265
     2    GND @S9S_MB_2U_LIB.S9S_MB_2U(SCH_1):GND    I25 @S9S_MB_2U_LIB.S9S_MB_2U(SCH_1):PAGE265

PC642 Q_CAP_C0805-22UF,4V,20%,X6S,CHA
     1 PVCCD_HV_CPU0 @S9S_MB_2U_LIB.S9S_MB_2U(SCH_1):PVCCD_HV_CPU0    I28 @S9S_MB_2U_LIB.S9S_MB_2U(SCH_1):PAGE265
     2    GND @S9S_MB_2U_LIB.S9S_MB_2U(SCH_1):GND    I28 @S9S_MB_2U_LIB.S9S_MB_2U(SCH_1):PAGE265

PC644 Q_CAP_C0402-1UF,25V,10%,X6S,CHA
     1 PVPP_HBM_CPU1_VCC @S9S_MB_2U_LIB.S9S_MB_2U(SCH_1):PVPP_HBM_CPU1_VCC     I1 @S9S_MB_2U_LIB.S9S_MB_2U(SCH_1):PAGE285
     2    GND @S9S_MB_2U_LIB.S9S_MB_2U(SCH_1):GND     I1 @S9S_MB_2U_LIB.S9S_MB_2U(SCH_1):PAGE285

PC720_P0_1 Q_CAP_C0805-22UF,16V,20%,X6S,CA
     1 SW_P12V_PVCCFA_EHV_FIVRA_CPU0_R @S9S_MB_2U_LIB.S9S_MB_2U(SCH_1):SW_P12V_PVCCFA_EHV_FIVRA_CPU0_R    I73 @S9S_MB_2U_LIB.S9S_MB_2U(SCH_1):PAGE257
     2    GND @S9S_MB_2U_LIB.S9S_MB_2U(SCH_1):GND    I73 @S9S_MB_2U_LIB.S9S_MB_2U(SCH_1):PAGE257

PC721_P0_2 Q_CAP_C0805-22UF,16V,20%,X6S,CA
     1 SW_P12V_PVCCFA_EHV_FIVRA_CPU0_L @S9S_MB_2U_LIB.S9S_MB_2U(SCH_1):SW_P12V_PVCCFA_EHV_FIVRA_CPU0_L    I55 @S9S_MB_2U_LIB.S9S_MB_2U(SCH_1):PAGE257
     2    GND @S9S_MB_2U_LIB.S9S_MB_2U(SCH_1):GND    I55 @S9S_MB_2U_LIB.S9S_MB_2U(SCH_1):PAGE257

PC722_P0_3 Q_CAP_C0805-22UF,16V,20%,X6S,CA
     1 SW_P12V_PVCCFA_EHV_FIVRA_CPU0_R @S9S_MB_2U_LIB.S9S_MB_2U(SCH_1):SW_P12V_PVCCFA_EHV_FIVRA_CPU0_R    I53 @S9S_MB_2U_LIB.S9S_MB_2U(SCH_1):PAGE258
     2    GND @S9S_MB_2U_LIB.S9S_MB_2U(SCH_1):GND    I53 @S9S_MB_2U_LIB.S9S_MB_2U(SCH_1):PAGE258

PC723_P0_4 Q_CAP_C0805-22UF,16V,20%,X6S,CA
     1 SW_P12V_PVCCFA_EHV_FIVRA_CPU0_L @S9S_MB_2U_LIB.S9S_MB_2U(SCH_1):SW_P12V_PVCCFA_EHV_FIVRA_CPU0_L    I41 @S9S_MB_2U_LIB.S9S_MB_2U(SCH_1):PAGE258
     2    GND @S9S_MB_2U_LIB.S9S_MB_2U(SCH_1):GND    I41 @S9S_MB_2U_LIB.S9S_MB_2U(SCH_1):PAGE258

PC724_P1_1 Q_CAP_C0805-22UF,16V,20%,X6S,CA
     1 SW_P12V_PVCCFA_EHV_FIVRA_CPU1_R @S9S_MB_2U_LIB.S9S_MB_2U(SCH_1):SW_P12V_PVCCFA_EHV_FIVRA_CPU1_R    I58 @S9S_MB_2U_LIB.S9S_MB_2U(SCH_1):PAGE275
     2    GND @S9S_MB_2U_LIB.S9S_MB_2U(SCH_1):GND    I58 @S9S_MB_2U_LIB.S9S_MB_2U(SCH_1):PAGE275

PC725_P1_2 Q_CAP_C0805-22UF,16V,20%,X6S,CA
     1 SW_P12V_PVCCFA_EHV_FIVRA_CPU1_L @S9S_MB_2U_LIB.S9S_MB_2U(SCH_1):SW_P12V_PVCCFA_EHV_FIVRA_CPU1_L    I46 @S9S_MB_2U_LIB.S9S_MB_2U(SCH_1):PAGE275
     2    GND @S9S_MB_2U_LIB.S9S_MB_2U(SCH_1):GND    I46 @S9S_MB_2U_LIB.S9S_MB_2U(SCH_1):PAGE275

PC726_P1_3 Q_CAP_C0805-22UF,16V,20%,X6S,CA
     1 SW_P12V_PVCCFA_EHV_FIVRA_CPU1_R @S9S_MB_2U_LIB.S9S_MB_2U(SCH_1):SW_P12V_PVCCFA_EHV_FIVRA_CPU1_R    I60 @S9S_MB_2U_LIB.S9S_MB_2U(SCH_1):PAGE276
     2    GND @S9S_MB_2U_LIB.S9S_MB_2U(SCH_1):GND    I60 @S9S_MB_2U_LIB.S9S_MB_2U(SCH_1):PAGE276

PC727_P1_4 Q_CAP_C0805-22UF,16V,20%,X6S,CA
     1 SW_P12V_PVCCFA_EHV_FIVRA_CPU1_L @S9S_MB_2U_LIB.S9S_MB_2U(SCH_1):SW_P12V_PVCCFA_EHV_FIVRA_CPU1_L    I52 @S9S_MB_2U_LIB.S9S_MB_2U(SCH_1):PAGE276
     2    GND @S9S_MB_2U_LIB.S9S_MB_2U(SCH_1):GND    I52 @S9S_MB_2U_LIB.S9S_MB_2U(SCH_1):PAGE276

PC813 Q_CAP_C0402-1UF,16V,10%,X6S,CHA
     1 PVCCD_HV_CPU0_ISENSE_N @S9S_MB_2U_LIB.S9S_MB_2U(SCH_1):PVCCD_HV_CPU0_ISENSE_N    I51 @S9S_MB_2U_LIB.S9S_MB_2U(SCH_1):PAGE264
     2 PVCCD_HV_CPU0_ISENSE_P @S9S_MB_2U_LIB.S9S_MB_2U(SCH_1):PVCCD_HV_CPU0_ISENSE_P    I51 @S9S_MB_2U_LIB.S9S_MB_2U(SCH_1):PAGE264

PC814 Q_CAP_C0402-1UF,16V,10%,X6S,CHA
     1 PVCCD_HV_CPU1_ISENSE_N @S9S_MB_2U_LIB.S9S_MB_2U(SCH_1):PVCCD_HV_CPU1_ISENSE_N    I51 @S9S_MB_2U_LIB.S9S_MB_2U(SCH_1):PAGE282
     2 PVCCD_HV_CPU1_ISENSE_P @S9S_MB_2U_LIB.S9S_MB_2U(SCH_1):PVCCD_HV_CPU1_ISENSE_P    I51 @S9S_MB_2U_LIB.S9S_MB_2U(SCH_1):PAGE282

PC831 Q_CAP_C0805-22UF,16V,20%,X6S,CA
     1 SW_P12V_PVCCIN_CPU0_FLT @S9S_MB_2U_LIB.S9S_MB_2U(SCH_1):SW_P12V_PVCCIN_CPU0_FLT     I7 @S9S_MB_2U_LIB.S9S_MB_2U(SCH_1):PAGE267
     2    GND @S9S_MB_2U_LIB.S9S_MB_2U(SCH_1):GND     I7 @S9S_MB_2U_LIB.S9S_MB_2U(SCH_1):PAGE267

PC1171 Q_CAP_C0402-2.2UF,10V,10%,X6S,A
     1 PVCCFA_EHV_FIVRA_CPU0_VDD3 @S9S_MB_2U_LIB.S9S_MB_2U(SCH_1):PVCCFA_EHV_FIVRA_CPU0_VDD3    I23 @S9S_MB_2U_LIB.S9S_MB_2U(SCH_1):PAGE258
     2    GND @S9S_MB_2U_LIB.S9S_MB_2U(SCH_1):GND    I23 @S9S_MB_2U_LIB.S9S_MB_2U(SCH_1):PAGE258

PC1172 Q_CAP_C0402-2.2UF,10V,10%,X6S,A
     1 PVCCFA_EHV_FIVRA_CPU0_VDD4 @S9S_MB_2U_LIB.S9S_MB_2U(SCH_1):PVCCFA_EHV_FIVRA_CPU0_VDD4    I13 @S9S_MB_2U_LIB.S9S_MB_2U(SCH_1):PAGE258
     2    GND @S9S_MB_2U_LIB.S9S_MB_2U(SCH_1):GND    I13 @S9S_MB_2U_LIB.S9S_MB_2U(SCH_1):PAGE258

PC1173 Q_CAP_C0402-1UF,16V,10%,X6S,CHA
     1 PVCCIN_CPU0_VREF @S9S_MB_2U_LIB.S9S_MB_2U(SCH_1):PVCCIN_CPU0_VREF    I87 @S9S_MB_2U_LIB.S9S_MB_2U(SCH_1):PAGE252
     2    GND @S9S_MB_2U_LIB.S9S_MB_2U(SCH_1):GND    I87 @S9S_MB_2U_LIB.S9S_MB_2U(SCH_1):PAGE252

PC1173_P0_3 Q_CAP_0402-3300PF,50V,10%,X7R,A
     1 SW_P12V_PVCCFA_EHV_FIVRA_CPU0_R @S9S_MB_2U_LIB.S9S_MB_2U(SCH_1):SW_P12V_PVCCFA_EHV_FIVRA_CPU0_R    I44 @S9S_MB_2U_LIB.S9S_MB_2U(SCH_1):PAGE258
     2    GND @S9S_MB_2U_LIB.S9S_MB_2U(SCH_1):GND    I44 @S9S_MB_2U_LIB.S9S_MB_2U(SCH_1):PAGE258

PC1174_P0_4 Q_CAP_0402-3300PF,50V,10%,X7R,A
     1 SW_P12V_PVCCFA_EHV_FIVRA_CPU0_L @S9S_MB_2U_LIB.S9S_MB_2U(SCH_1):SW_P12V_PVCCFA_EHV_FIVRA_CPU0_L    I31 @S9S_MB_2U_LIB.S9S_MB_2U(SCH_1):PAGE258
     2    GND @S9S_MB_2U_LIB.S9S_MB_2U(SCH_1):GND    I31 @S9S_MB_2U_LIB.S9S_MB_2U(SCH_1):PAGE258

PC1175_P0_3 Q_CAP_C0402-1UF,16V,10%,X6S,CHA
     1 SW_P12V_PVCCFA_EHV_FIVRA_CPU0_R @S9S_MB_2U_LIB.S9S_MB_2U(SCH_1):SW_P12V_PVCCFA_EHV_FIVRA_CPU0_R    I46 @S9S_MB_2U_LIB.S9S_MB_2U(SCH_1):PAGE258
     2    GND @S9S_MB_2U_LIB.S9S_MB_2U(SCH_1):GND    I46 @S9S_MB_2U_LIB.S9S_MB_2U(SCH_1):PAGE258

PC1176_P0_4 Q_CAP_C0402-1UF,16V,10%,X6S,CHA
     1 SW_P12V_PVCCFA_EHV_FIVRA_CPU0_L @S9S_MB_2U_LIB.S9S_MB_2U(SCH_1):SW_P12V_PVCCFA_EHV_FIVRA_CPU0_L    I34 @S9S_MB_2U_LIB.S9S_MB_2U(SCH_1):PAGE258
     2    GND @S9S_MB_2U_LIB.S9S_MB_2U(SCH_1):GND    I34 @S9S_MB_2U_LIB.S9S_MB_2U(SCH_1):PAGE258

PC1177 Q_CAP_C0402-100NF,50V,10%,X7R,A
     1 SW_PVCCFA_EHV_FIVRA_CPU0_BOOT3_ @S9S_MB_2U_LIB.S9S_MB_2U(SCH_1):SW_PVCCFA_EHV_FIVRA_CPU0_BOOT3_R    I49 @S9S_MB_2U_LIB.S9S_MB_2U(SCH_1):PAGE258
     2 SW_PVCCFA_EHV_FIVRA_CPU0_BOOTR3 @S9S_MB_2U_LIB.S9S_MB_2U(SCH_1):SW_PVCCFA_EHV_FIVRA_CPU0_BOOTR3    I49 @S9S_MB_2U_LIB.S9S_MB_2U(SCH_1):PAGE258

PC1178 Q_CAP_C0402-100NF,50V,10%,X7R,A
     1 SW_PVCCFA_EHV_FIVRA_CPU0_BOOT4_ @S9S_MB_2U_LIB.S9S_MB_2U(SCH_1):SW_PVCCFA_EHV_FIVRA_CPU0_BOOT4_R    I37 @S9S_MB_2U_LIB.S9S_MB_2U(SCH_1):PAGE258
     2 SW_PVCCFA_EHV_FIVRA_CPU0_BOOTR4 @S9S_MB_2U_LIB.S9S_MB_2U(SCH_1):SW_PVCCFA_EHV_FIVRA_CPU0_BOOTR4    I37 @S9S_MB_2U_LIB.S9S_MB_2U(SCH_1):PAGE258

PC1179_P0_3 Q_CAP_C0805-22UF,16V,20%,X6S,CA
     1 SW_P12V_PVCCFA_EHV_FIVRA_CPU0_R @S9S_MB_2U_LIB.S9S_MB_2U(SCH_1):SW_P12V_PVCCFA_EHV_FIVRA_CPU0_R    I47 @S9S_MB_2U_LIB.S9S_MB_2U(SCH_1):PAGE258
     2    GND @S9S_MB_2U_LIB.S9S_MB_2U(SCH_1):GND    I47 @S9S_MB_2U_LIB.S9S_MB_2U(SCH_1):PAGE258

PC1180_P0_4 Q_CAP_C0805-22UF,16V,20%,X6S,CA
     1 SW_P12V_PVCCFA_EHV_FIVRA_CPU0_L @S9S_MB_2U_LIB.S9S_MB_2U(SCH_1):SW_P12V_PVCCFA_EHV_FIVRA_CPU0_L    I35 @S9S_MB_2U_LIB.S9S_MB_2U(SCH_1):PAGE258
     2    GND @S9S_MB_2U_LIB.S9S_MB_2U(SCH_1):GND    I35 @S9S_MB_2U_LIB.S9S_MB_2U(SCH_1):PAGE258

PC1181_P0_3 Q_CAP_C0805-22UF,16V,20%,X6S,CA
     1 SW_P12V_PVCCFA_EHV_FIVRA_CPU0_R @S9S_MB_2U_LIB.S9S_MB_2U(SCH_1):SW_P12V_PVCCFA_EHV_FIVRA_CPU0_R    I48 @S9S_MB_2U_LIB.S9S_MB_2U(SCH_1):PAGE258
     2    GND @S9S_MB_2U_LIB.S9S_MB_2U(SCH_1):GND    I48 @S9S_MB_2U_LIB.S9S_MB_2U(SCH_1):PAGE258

PC1182_P0_4 Q_CAP_C0805-22UF,16V,20%,X6S,CA
     1 SW_P12V_PVCCFA_EHV_FIVRA_CPU0_L @S9S_MB_2U_LIB.S9S_MB_2U(SCH_1):SW_P12V_PVCCFA_EHV_FIVRA_CPU0_L    I36 @S9S_MB_2U_LIB.S9S_MB_2U(SCH_1):PAGE258
     2    GND @S9S_MB_2U_LIB.S9S_MB_2U(SCH_1):GND    I36 @S9S_MB_2U_LIB.S9S_MB_2U(SCH_1):PAGE258

PC1183 Q_CAPP_THLF-560UF,2.5V,20%,OSCA
     1 PVCCFA_EHV_FIVRA_CPU0 @S9S_MB_2U_LIB.S9S_MB_2U(SCH_1):PVCCFA_EHV_FIVRA_CPU0    I64 @S9S_MB_2U_LIB.S9S_MB_2U(SCH_1):PAGE258
     2    GND @S9S_MB_2U_LIB.S9S_MB_2U(SCH_1):GND    I64 @S9S_MB_2U_LIB.S9S_MB_2U(SCH_1):PAGE258

PC1183_P0_3 Q_CAP_C0402-1UF,16V,10%,X6S,CHA
     1 PVCCFA_EHV_FIVRA_CPU0 @S9S_MB_2U_LIB.S9S_MB_2U(SCH_1):PVCCFA_EHV_FIVRA_CPU0    I55 @S9S_MB_2U_LIB.S9S_MB_2U(SCH_1):PAGE258
     2    GND @S9S_MB_2U_LIB.S9S_MB_2U(SCH_1):GND    I55 @S9S_MB_2U_LIB.S9S_MB_2U(SCH_1):PAGE258

PC1183_P0_4 Q_CAP_C0402-100NF,50V,10%,X7R,A
     1 PVCCFA_EHV_FIVRA_CPU0 @S9S_MB_2U_LIB.S9S_MB_2U(SCH_1):PVCCFA_EHV_FIVRA_CPU0    I40 @S9S_MB_2U_LIB.S9S_MB_2U(SCH_1):PAGE258
     2    GND @S9S_MB_2U_LIB.S9S_MB_2U(SCH_1):GND    I40 @S9S_MB_2U_LIB.S9S_MB_2U(SCH_1):PAGE258

PC1185 Q_CAPP_THLF-560UF,2.5V,20%,OSCA
     1 PVCCFA_EHV_FIVRA_CPU0 @S9S_MB_2U_LIB.S9S_MB_2U(SCH_1):PVCCFA_EHV_FIVRA_CPU0    I65 @S9S_MB_2U_LIB.S9S_MB_2U(SCH_1):PAGE258
     2    GND @S9S_MB_2U_LIB.S9S_MB_2U(SCH_1):GND    I65 @S9S_MB_2U_LIB.S9S_MB_2U(SCH_1):PAGE258

PC1185_P0_3 Q_CAP_C0805-22UF,4V,20%,X6S,CHA
     1 PVCCFA_EHV_FIVRA_CPU0 @S9S_MB_2U_LIB.S9S_MB_2U(SCH_1):PVCCFA_EHV_FIVRA_CPU0    I72 @S9S_MB_2U_LIB.S9S_MB_2U(SCH_1):PAGE258
     2    GND @S9S_MB_2U_LIB.S9S_MB_2U(SCH_1):GND    I72 @S9S_MB_2U_LIB.S9S_MB_2U(SCH_1):PAGE258

PC1186 Q_CAPP_THLF-560UF,2.5V,20%,OSCA
     1 PVCCFA_EHV_FIVRA_CPU0 @S9S_MB_2U_LIB.S9S_MB_2U(SCH_1):PVCCFA_EHV_FIVRA_CPU0    I68 @S9S_MB_2U_LIB.S9S_MB_2U(SCH_1):PAGE258
     2    GND @S9S_MB_2U_LIB.S9S_MB_2U(SCH_1):GND    I68 @S9S_MB_2U_LIB.S9S_MB_2U(SCH_1):PAGE258

PC1186_P0_4 Q_CAP_C0805-22UF,4V,20%,X6S,CHA
     1 PVCCFA_EHV_FIVRA_CPU0 @S9S_MB_2U_LIB.S9S_MB_2U(SCH_1):PVCCFA_EHV_FIVRA_CPU0    I60 @S9S_MB_2U_LIB.S9S_MB_2U(SCH_1):PAGE258
     2    GND @S9S_MB_2U_LIB.S9S_MB_2U(SCH_1):GND    I60 @S9S_MB_2U_LIB.S9S_MB_2U(SCH_1):PAGE258

PC1187 Q_CAPP_SMLF-330UF,2.5V,+10/-35B
     1 PVCCFA_EHV_FIVRA_CPU0 @S9S_MB_2U_LIB.S9S_MB_2U(SCH_1):PVCCFA_EHV_FIVRA_CPU0    I69 @S9S_MB_2U_LIB.S9S_MB_2U(SCH_1):PAGE258
     2    GND @S9S_MB_2U_LIB.S9S_MB_2U(SCH_1):GND    I69 @S9S_MB_2U_LIB.S9S_MB_2U(SCH_1):PAGE258

PC1187_P0_3 Q_CAP_C0805-22UF,4V,20%,X6S,CHA
     1 PVCCFA_EHV_FIVRA_CPU0 @S9S_MB_2U_LIB.S9S_MB_2U(SCH_1):PVCCFA_EHV_FIVRA_CPU0    I73 @S9S_MB_2U_LIB.S9S_MB_2U(SCH_1):PAGE258
     2    GND @S9S_MB_2U_LIB.S9S_MB_2U(SCH_1):GND    I73 @S9S_MB_2U_LIB.S9S_MB_2U(SCH_1):PAGE258

PC1188_P0_4 Q_CAP_C0805-22UF,4V,20%,X6S,CHA
     1 PVCCFA_EHV_FIVRA_CPU0 @S9S_MB_2U_LIB.S9S_MB_2U(SCH_1):PVCCFA_EHV_FIVRA_CPU0    I61 @S9S_MB_2U_LIB.S9S_MB_2U(SCH_1):PAGE258
     2    GND @S9S_MB_2U_LIB.S9S_MB_2U(SCH_1):GND    I61 @S9S_MB_2U_LIB.S9S_MB_2U(SCH_1):PAGE258

PC1189 Q_CAPP_THLF-270UF,16V,20%,OSCOA
     1 SW_P12V_PVCCFA_EHV_FIVRA_CPU0_R @S9S_MB_2U_LIB.S9S_MB_2U(SCH_1):SW_P12V_PVCCFA_EHV_FIVRA_CPU0_R    I80 @S9S_MB_2U_LIB.S9S_MB_2U(SCH_1):PAGE258
     2    GND @S9S_MB_2U_LIB.S9S_MB_2U(SCH_1):GND    I80 @S9S_MB_2U_LIB.S9S_MB_2U(SCH_1):PAGE258

PC1191 Q_CAP_C0402-2.2UF,10V,10%,X6S,A
     1 PVCCFA_EHV_FIVRA_CPU1_VDD3 @S9S_MB_2U_LIB.S9S_MB_2U(SCH_1):PVCCFA_EHV_FIVRA_CPU1_VDD3    I27 @S9S_MB_2U_LIB.S9S_MB_2U(SCH_1):PAGE276
     2    GND @S9S_MB_2U_LIB.S9S_MB_2U(SCH_1):GND    I27 @S9S_MB_2U_LIB.S9S_MB_2U(SCH_1):PAGE276

PC1192 Q_CAP_C0402-2.2UF,10V,10%,X6S,A
     1 PVCCFA_EHV_FIVRA_CPU1_VDD4 @S9S_MB_2U_LIB.S9S_MB_2U(SCH_1):PVCCFA_EHV_FIVRA_CPU1_VDD4    I12 @S9S_MB_2U_LIB.S9S_MB_2U(SCH_1):PAGE276
     2    GND @S9S_MB_2U_LIB.S9S_MB_2U(SCH_1):GND    I12 @S9S_MB_2U_LIB.S9S_MB_2U(SCH_1):PAGE276

PC1193 Q_CAP_C0402-1UF,16V,10%,X6S,CHA
     1 PVCCINFAON_CPU1_VREF @S9S_MB_2U_LIB.S9S_MB_2U(SCH_1):PVCCINFAON_CPU1_VREF    I96 @S9S_MB_2U_LIB.S9S_MB_2U(SCH_1):PAGE278
     2    GND @S9S_MB_2U_LIB.S9S_MB_2U(SCH_1):GND    I96 @S9S_MB_2U_LIB.S9S_MB_2U(SCH_1):PAGE278

PC1193_P1_3 Q_CAP_0402-3300PF,50V,10%,X7R,A
     1 SW_P12V_PVCCFA_EHV_FIVRA_CPU1_R @S9S_MB_2U_LIB.S9S_MB_2U(SCH_1):SW_P12V_PVCCFA_EHV_FIVRA_CPU1_R    I38 @S9S_MB_2U_LIB.S9S_MB_2U(SCH_1):PAGE276
     2    GND @S9S_MB_2U_LIB.S9S_MB_2U(SCH_1):GND    I38 @S9S_MB_2U_LIB.S9S_MB_2U(SCH_1):PAGE276

PC1194 Q_CAP_C0402-1UF,16V,10%,X6S,CHA
     1 PVCCIN_CPU1_VREF @S9S_MB_2U_LIB.S9S_MB_2U(SCH_1):PVCCIN_CPU1_VREF   I121 @S9S_MB_2U_LIB.S9S_MB_2U(SCH_1):PAGE270
     2    GND @S9S_MB_2U_LIB.S9S_MB_2U(SCH_1):GND   I121 @S9S_MB_2U_LIB.S9S_MB_2U(SCH_1):PAGE270

PC1194_P1_4 Q_CAP_0402-3300PF,50V,10%,X7R,A
     1 SW_P12V_PVCCFA_EHV_FIVRA_CPU1_L @S9S_MB_2U_LIB.S9S_MB_2U(SCH_1):SW_P12V_PVCCFA_EHV_FIVRA_CPU1_L    I33 @S9S_MB_2U_LIB.S9S_MB_2U(SCH_1):PAGE276
     2    GND @S9S_MB_2U_LIB.S9S_MB_2U(SCH_1):GND    I33 @S9S_MB_2U_LIB.S9S_MB_2U(SCH_1):PAGE276

PC1195_P1_3 Q_CAP_C0402-1UF,16V,10%,X6S,CHA
     1 SW_P12V_PVCCFA_EHV_FIVRA_CPU1_R @S9S_MB_2U_LIB.S9S_MB_2U(SCH_1):SW_P12V_PVCCFA_EHV_FIVRA_CPU1_R    I39 @S9S_MB_2U_LIB.S9S_MB_2U(SCH_1):PAGE276
     2    GND @S9S_MB_2U_LIB.S9S_MB_2U(SCH_1):GND    I39 @S9S_MB_2U_LIB.S9S_MB_2U(SCH_1):PAGE276

PC1196 Q_CAP_C0402-1UF,16V,10%,X6S,CHA
     1 PVCCD_HV_CPU0_VREF @S9S_MB_2U_LIB.S9S_MB_2U(SCH_1):PVCCD_HV_CPU0_VREF    I71 @S9S_MB_2U_LIB.S9S_MB_2U(SCH_1):PAGE264
     2    GND @S9S_MB_2U_LIB.S9S_MB_2U(SCH_1):GND    I71 @S9S_MB_2U_LIB.S9S_MB_2U(SCH_1):PAGE264

PC1196_P1_4 Q_CAP_C0402-1UF,16V,10%,X6S,CHA
     1 SW_P12V_PVCCFA_EHV_FIVRA_CPU1_L @S9S_MB_2U_LIB.S9S_MB_2U(SCH_1):SW_P12V_PVCCFA_EHV_FIVRA_CPU1_L    I35 @S9S_MB_2U_LIB.S9S_MB_2U(SCH_1):PAGE276
     2    GND @S9S_MB_2U_LIB.S9S_MB_2U(SCH_1):GND    I35 @S9S_MB_2U_LIB.S9S_MB_2U(SCH_1):PAGE276

PC1197 Q_CAP_C0402-100NF,50V,10%,X7R,A
     1 SW_PVCCFA_EHV_FIVRA_CPU1_BOOT3_ @S9S_MB_2U_LIB.S9S_MB_2U(SCH_1):SW_PVCCFA_EHV_FIVRA_CPU1_BOOT3_R    I58 @S9S_MB_2U_LIB.S9S_MB_2U(SCH_1):PAGE276
     2 SW_PVCCFA_EHV_FIVRA_CPU1_BOOTR3 @S9S_MB_2U_LIB.S9S_MB_2U(SCH_1):SW_PVCCFA_EHV_FIVRA_CPU1_BOOTR3    I58 @S9S_MB_2U_LIB.S9S_MB_2U(SCH_1):PAGE276

PC1198 Q_CAP_C0402-100NF,50V,10%,X7R,A
     1 SW_PVCCFA_EHV_FIVRA_CPU1_BOOT4_ @S9S_MB_2U_LIB.S9S_MB_2U(SCH_1):SW_PVCCFA_EHV_FIVRA_CPU1_BOOT4_R    I45 @S9S_MB_2U_LIB.S9S_MB_2U(SCH_1):PAGE276
     2 SW_PVCCFA_EHV_FIVRA_CPU1_BOOTR4 @S9S_MB_2U_LIB.S9S_MB_2U(SCH_1):SW_PVCCFA_EHV_FIVRA_CPU1_BOOTR4    I45 @S9S_MB_2U_LIB.S9S_MB_2U(SCH_1):PAGE276

PC1199_P1_3 Q_CAP_C0805-22UF,16V,20%,X6S,CA
     1 SW_P12V_PVCCFA_EHV_FIVRA_CPU1_R @S9S_MB_2U_LIB.S9S_MB_2U(SCH_1):SW_P12V_PVCCFA_EHV_FIVRA_CPU1_R    I41 @S9S_MB_2U_LIB.S9S_MB_2U(SCH_1):PAGE276
     2    GND @S9S_MB_2U_LIB.S9S_MB_2U(SCH_1):GND    I41 @S9S_MB_2U_LIB.S9S_MB_2U(SCH_1):PAGE276

PC1200_P1_4 Q_CAP_C0805-22UF,16V,20%,X6S,CA
     1 SW_P12V_PVCCFA_EHV_FIVRA_CPU1_L @S9S_MB_2U_LIB.S9S_MB_2U(SCH_1):SW_P12V_PVCCFA_EHV_FIVRA_CPU1_L    I36 @S9S_MB_2U_LIB.S9S_MB_2U(SCH_1):PAGE276
     2    GND @S9S_MB_2U_LIB.S9S_MB_2U(SCH_1):GND    I36 @S9S_MB_2U_LIB.S9S_MB_2U(SCH_1):PAGE276

PC1201 Q_CAPP_THLF-560UF,2.5V,20%,OSCA
     1 PVCCFA_EHV_FIVRA_CPU1 @S9S_MB_2U_LIB.S9S_MB_2U(SCH_1):PVCCFA_EHV_FIVRA_CPU1    I55 @S9S_MB_2U_LIB.S9S_MB_2U(SCH_1):PAGE276
     2    GND @S9S_MB_2U_LIB.S9S_MB_2U(SCH_1):GND    I55 @S9S_MB_2U_LIB.S9S_MB_2U(SCH_1):PAGE276

PC1201_P1_3 Q_CAP_C0805-22UF,16V,20%,X6S,CA
     1 SW_P12V_PVCCFA_EHV_FIVRA_CPU1_R @S9S_MB_2U_LIB.S9S_MB_2U(SCH_1):SW_P12V_PVCCFA_EHV_FIVRA_CPU1_R    I42 @S9S_MB_2U_LIB.S9S_MB_2U(SCH_1):PAGE276
     2    GND @S9S_MB_2U_LIB.S9S_MB_2U(SCH_1):GND    I42 @S9S_MB_2U_LIB.S9S_MB_2U(SCH_1):PAGE276

PC1202_P1_4 Q_CAP_C0805-22UF,16V,20%,X6S,CA
     1 SW_P12V_PVCCFA_EHV_FIVRA_CPU1_L @S9S_MB_2U_LIB.S9S_MB_2U(SCH_1):SW_P12V_PVCCFA_EHV_FIVRA_CPU1_L    I37 @S9S_MB_2U_LIB.S9S_MB_2U(SCH_1):PAGE276
     2    GND @S9S_MB_2U_LIB.S9S_MB_2U(SCH_1):GND    I37 @S9S_MB_2U_LIB.S9S_MB_2U(SCH_1):PAGE276

PC1203 Q_CAPP_THLF-560UF,2.5V,20%,OSCA
     1 PVCCFA_EHV_FIVRA_CPU1 @S9S_MB_2U_LIB.S9S_MB_2U(SCH_1):PVCCFA_EHV_FIVRA_CPU1    I67 @S9S_MB_2U_LIB.S9S_MB_2U(SCH_1):PAGE276
     2    GND @S9S_MB_2U_LIB.S9S_MB_2U(SCH_1):GND    I67 @S9S_MB_2U_LIB.S9S_MB_2U(SCH_1):PAGE276

PC1203_P1_4 Q_CAP_C0402-100NF,50V,10%,X7R,A
     1 PVCCFA_EHV_FIVRA_CPU1 @S9S_MB_2U_LIB.S9S_MB_2U(SCH_1):PVCCFA_EHV_FIVRA_CPU1    I47 @S9S_MB_2U_LIB.S9S_MB_2U(SCH_1):PAGE276
     2    GND @S9S_MB_2U_LIB.S9S_MB_2U(SCH_1):GND    I47 @S9S_MB_2U_LIB.S9S_MB_2U(SCH_1):PAGE276

PC1204 Q_CAPP_THLF-560UF,2.5V,20%,OSCA
     1 PVCCFA_EHV_FIVRA_CPU1 @S9S_MB_2U_LIB.S9S_MB_2U(SCH_1):PVCCFA_EHV_FIVRA_CPU1    I70 @S9S_MB_2U_LIB.S9S_MB_2U(SCH_1):PAGE276
     2    GND @S9S_MB_2U_LIB.S9S_MB_2U(SCH_1):GND    I70 @S9S_MB_2U_LIB.S9S_MB_2U(SCH_1):PAGE276

PC1204_P1_3 Q_CAP_C0402-1UF,16V,10%,X6S,CHA
     1 PVCCFA_EHV_FIVRA_CPU1 @S9S_MB_2U_LIB.S9S_MB_2U(SCH_1):PVCCFA_EHV_FIVRA_CPU1    I56 @S9S_MB_2U_LIB.S9S_MB_2U(SCH_1):PAGE276
     2    GND @S9S_MB_2U_LIB.S9S_MB_2U(SCH_1):GND    I56 @S9S_MB_2U_LIB.S9S_MB_2U(SCH_1):PAGE276

PC1205 Q_CAPP_SMLF-330UF,2.5V,+10/-35B
     1 PVCCFA_EHV_FIVRA_CPU1 @S9S_MB_2U_LIB.S9S_MB_2U(SCH_1):PVCCFA_EHV_FIVRA_CPU1    I72 @S9S_MB_2U_LIB.S9S_MB_2U(SCH_1):PAGE276
     2    GND @S9S_MB_2U_LIB.S9S_MB_2U(SCH_1):GND    I72 @S9S_MB_2U_LIB.S9S_MB_2U(SCH_1):PAGE276

PC1206 Q_CAP_C0805-22UF,4V,20%,X6S,CHA
     1 PVNN_MAIN_CPU0 @S9S_MB_2U_LIB.S9S_MB_2U(SCH_1):PVNN_MAIN_CPU0    I47 @S9S_MB_2U_LIB.S9S_MB_2U(SCH_1):PAGE268
     2    GND @S9S_MB_2U_LIB.S9S_MB_2U(SCH_1):GND    I47 @S9S_MB_2U_LIB.S9S_MB_2U(SCH_1):PAGE268

PC1206_P1_3 Q_CAP_C0805-22UF,4V,20%,X6S,CHA
     1 PVCCFA_EHV_FIVRA_CPU1 @S9S_MB_2U_LIB.S9S_MB_2U(SCH_1):PVCCFA_EHV_FIVRA_CPU1    I66 @S9S_MB_2U_LIB.S9S_MB_2U(SCH_1):PAGE276
     2    GND @S9S_MB_2U_LIB.S9S_MB_2U(SCH_1):GND    I66 @S9S_MB_2U_LIB.S9S_MB_2U(SCH_1):PAGE276

PC1207 Q_CAP_C0805-22UF,4V,20%,X6S,CHA
     1 PVNN_MAIN_CPU1 @S9S_MB_2U_LIB.S9S_MB_2U(SCH_1):PVNN_MAIN_CPU1    I45 @S9S_MB_2U_LIB.S9S_MB_2U(SCH_1):PAGE286
     2    GND @S9S_MB_2U_LIB.S9S_MB_2U(SCH_1):GND    I45 @S9S_MB_2U_LIB.S9S_MB_2U(SCH_1):PAGE286

PC1207_P1_4 Q_CAP_C0805-22UF,4V,20%,X6S,CHA
     1 PVCCFA_EHV_FIVRA_CPU1 @S9S_MB_2U_LIB.S9S_MB_2U(SCH_1):PVCCFA_EHV_FIVRA_CPU1    I48 @S9S_MB_2U_LIB.S9S_MB_2U(SCH_1):PAGE276
     2    GND @S9S_MB_2U_LIB.S9S_MB_2U(SCH_1):GND    I48 @S9S_MB_2U_LIB.S9S_MB_2U(SCH_1):PAGE276

PC1208_P1_3 Q_CAP_C0805-22UF,4V,20%,X6S,CHA
     1 PVCCFA_EHV_FIVRA_CPU1 @S9S_MB_2U_LIB.S9S_MB_2U(SCH_1):PVCCFA_EHV_FIVRA_CPU1    I68 @S9S_MB_2U_LIB.S9S_MB_2U(SCH_1):PAGE276
     2    GND @S9S_MB_2U_LIB.S9S_MB_2U(SCH_1):GND    I68 @S9S_MB_2U_LIB.S9S_MB_2U(SCH_1):PAGE276

PC1209_P1_4 Q_CAP_C0805-22UF,4V,20%,X6S,CHA
     1 PVCCFA_EHV_FIVRA_CPU1 @S9S_MB_2U_LIB.S9S_MB_2U(SCH_1):PVCCFA_EHV_FIVRA_CPU1    I50 @S9S_MB_2U_LIB.S9S_MB_2U(SCH_1):PAGE276
     2    GND @S9S_MB_2U_LIB.S9S_MB_2U(SCH_1):GND    I50 @S9S_MB_2U_LIB.S9S_MB_2U(SCH_1):PAGE276

PC1210 Q_CAPP_THLF-270UF,16V,20%,OSCOA
     1 SW_P12V_PVCCFA_EHV_FIVRA_CPU1_R @S9S_MB_2U_LIB.S9S_MB_2U(SCH_1):SW_P12V_PVCCFA_EHV_FIVRA_CPU1_R    I81 @S9S_MB_2U_LIB.S9S_MB_2U(SCH_1):PAGE276
     2    GND @S9S_MB_2U_LIB.S9S_MB_2U(SCH_1):GND    I81 @S9S_MB_2U_LIB.S9S_MB_2U(SCH_1):PAGE276

PC1211_P0_1 Q_CAP_C0402-2.2UF,10V,10%,X6S,A
     1 PVCCFA_EHV_FIVRA_CPU0_PVCC1 @S9S_MB_2U_LIB.S9S_MB_2U(SCH_1):PVCCFA_EHV_FIVRA_CPU0_PVCC1    I42 @S9S_MB_2U_LIB.S9S_MB_2U(SCH_1):PAGE257
     2    GND @S9S_MB_2U_LIB.S9S_MB_2U(SCH_1):GND    I42 @S9S_MB_2U_LIB.S9S_MB_2U(SCH_1):PAGE257

PC1212_P0_2 Q_CAP_C0402-2.2UF,10V,10%,X6S,A
     1 PVCCFA_EHV_FIVRA_CPU0_PVCC2 @S9S_MB_2U_LIB.S9S_MB_2U(SCH_1):PVCCFA_EHV_FIVRA_CPU0_PVCC2    I21 @S9S_MB_2U_LIB.S9S_MB_2U(SCH_1):PAGE257
     2    GND @S9S_MB_2U_LIB.S9S_MB_2U(SCH_1):GND    I21 @S9S_MB_2U_LIB.S9S_MB_2U(SCH_1):PAGE257

PC1213_P0_3 Q_CAP_C0402-2.2UF,10V,10%,X6S,A
     1 PVCCFA_EHV_FIVRA_CPU0_PVCC1 @S9S_MB_2U_LIB.S9S_MB_2U(SCH_1):PVCCFA_EHV_FIVRA_CPU0_PVCC1    I28 @S9S_MB_2U_LIB.S9S_MB_2U(SCH_1):PAGE258
     2    GND @S9S_MB_2U_LIB.S9S_MB_2U(SCH_1):GND    I28 @S9S_MB_2U_LIB.S9S_MB_2U(SCH_1):PAGE258

PC1214_P0_4 Q_CAP_C0402-2.2UF,10V,10%,X6S,A
     1 PVCCFA_EHV_FIVRA_CPU0_PVCC2 @S9S_MB_2U_LIB.S9S_MB_2U(SCH_1):PVCCFA_EHV_FIVRA_CPU0_PVCC2    I18 @S9S_MB_2U_LIB.S9S_MB_2U(SCH_1):PAGE258
     2    GND @S9S_MB_2U_LIB.S9S_MB_2U(SCH_1):GND    I18 @S9S_MB_2U_LIB.S9S_MB_2U(SCH_1):PAGE258

PC1215 Q_CAPP_SMLF-100UF,16V,20%,OSCOA
     1 SW_P12V_AUX_P1V05_PCH_AUX_FLT @S9S_MB_2U_LIB.S9S_MB_2U(SCH_1):SW_P12V_AUX_P1V05_PCH_AUX_FLT    I23 @S9S_MB_2U_LIB.S9S_MB_2U(SCH_1):PAGE248
     2    GND @S9S_MB_2U_LIB.S9S_MB_2U(SCH_1):GND    I23 @S9S_MB_2U_LIB.S9S_MB_2U(SCH_1):PAGE248

PC1216 Q_CAP_C0805-22UF,16V,20%,X6S,CA
     1 SW_P12V_AUX_P1V05_PCH_AUX_FLT @S9S_MB_2U_LIB.S9S_MB_2U(SCH_1):SW_P12V_AUX_P1V05_PCH_AUX_FLT    I25 @S9S_MB_2U_LIB.S9S_MB_2U(SCH_1):PAGE248
     2    GND @S9S_MB_2U_LIB.S9S_MB_2U(SCH_1):GND    I25 @S9S_MB_2U_LIB.S9S_MB_2U(SCH_1):PAGE248

PC1217 Q_CAP_C0805-22UF,16V,20%,X6S,CA
     1 SW_P12V_AUX_P1V05_PCH_AUX_FLT @S9S_MB_2U_LIB.S9S_MB_2U(SCH_1):SW_P12V_AUX_P1V05_PCH_AUX_FLT    I28 @S9S_MB_2U_LIB.S9S_MB_2U(SCH_1):PAGE248
     2    GND @S9S_MB_2U_LIB.S9S_MB_2U(SCH_1):GND    I28 @S9S_MB_2U_LIB.S9S_MB_2U(SCH_1):PAGE248

PC1218 Q_CAP_C0805-22UF,16V,20%,X6S,CA
     1 SW_P12V_AUX_P1V05_PCH_AUX_FLT @S9S_MB_2U_LIB.S9S_MB_2U(SCH_1):SW_P12V_AUX_P1V05_PCH_AUX_FLT    I29 @S9S_MB_2U_LIB.S9S_MB_2U(SCH_1):PAGE248
     2    GND @S9S_MB_2U_LIB.S9S_MB_2U(SCH_1):GND    I29 @S9S_MB_2U_LIB.S9S_MB_2U(SCH_1):PAGE248

PC1219 Q_CAP_C0402-1UF,16V,10%,X6S,CHA
     1 SW_P12V_AUX_P1V05_PCH_AUX_FLT @S9S_MB_2U_LIB.S9S_MB_2U(SCH_1):SW_P12V_AUX_P1V05_PCH_AUX_FLT    I30 @S9S_MB_2U_LIB.S9S_MB_2U(SCH_1):PAGE248
     2    GND @S9S_MB_2U_LIB.S9S_MB_2U(SCH_1):GND    I30 @S9S_MB_2U_LIB.S9S_MB_2U(SCH_1):PAGE248

PC1221 Q_CAP_0402-0.1UF,25V,10%,X7R,CA
     1 P1V05_PCH_AUX_REF @S9S_MB_2U_LIB.S9S_MB_2U(SCH_1):P1V05_PCH_AUX_REF    I16 @S9S_MB_2U_LIB.S9S_MB_2U(SCH_1):PAGE248
     2 SH_P1V05_PCH_AUX_N @S9S_MB_2U_LIB.S9S_MB_2U(SCH_1):SH_P1V05_PCH_AUX_N    I16 @S9S_MB_2U_LIB.S9S_MB_2U(SCH_1):PAGE248

PC1222 Q_CAP_C0402-0.22UF,25V,10%,X7RA
     1 SW_P1V05_PCH_AUX_BST @S9S_MB_2U_LIB.S9S_MB_2U(SCH_1):SW_P1V05_PCH_AUX_BST    I31 @S9S_MB_2U_LIB.S9S_MB_2U(SCH_1):PAGE248
     2 SW_P1V05_PCH_AUX_SW @S9S_MB_2U_LIB.S9S_MB_2U(SCH_1):SW_P1V05_PCH_AUX_SW    I31 @S9S_MB_2U_LIB.S9S_MB_2U(SCH_1):PAGE248

PC1223 Q_CAP_0402-680PF,50V,10%,X7R,TA
     1 P1V05_PCH_AUX_FB @S9S_MB_2U_LIB.S9S_MB_2U(SCH_1):P1V05_PCH_AUX_FB    I35 @S9S_MB_2U_LIB.S9S_MB_2U(SCH_1):PAGE248
     2 SH_P1V05_PCH_AUX_P @S9S_MB_2U_LIB.S9S_MB_2U(SCH_1):SH_P1V05_PCH_AUX_P    I35 @S9S_MB_2U_LIB.S9S_MB_2U(SCH_1):PAGE248

PC1224 Q_CAP_0402-0.1UF,25V,10%,X7R,CA
     1 P1V05_PCH_AUX @S9S_MB_2U_LIB.S9S_MB_2U(SCH_1):P1V05_PCH_AUX    I38 @S9S_MB_2U_LIB.S9S_MB_2U(SCH_1):PAGE248
     2    GND @S9S_MB_2U_LIB.S9S_MB_2U(SCH_1):GND    I38 @S9S_MB_2U_LIB.S9S_MB_2U(SCH_1):PAGE248

PC1225 Q_CAP_C0805-47UF,4V,20%,X6S,CHA
     1 P1V05_PCH_AUX @S9S_MB_2U_LIB.S9S_MB_2U(SCH_1):P1V05_PCH_AUX    I44 @S9S_MB_2U_LIB.S9S_MB_2U(SCH_1):PAGE248
     2    GND @S9S_MB_2U_LIB.S9S_MB_2U(SCH_1):GND    I44 @S9S_MB_2U_LIB.S9S_MB_2U(SCH_1):PAGE248

PC1226 Q_CAP_C0805-47UF,4V,20%,X6S,CHA
     1 P1V05_PCH_AUX @S9S_MB_2U_LIB.S9S_MB_2U(SCH_1):P1V05_PCH_AUX    I45 @S9S_MB_2U_LIB.S9S_MB_2U(SCH_1):PAGE248
     2    GND @S9S_MB_2U_LIB.S9S_MB_2U(SCH_1):GND    I45 @S9S_MB_2U_LIB.S9S_MB_2U(SCH_1):PAGE248

PC1227 Q_CAPP_THLF-560UF,2.5V,20%,OSCA
     1 P1V05_PCH_AUX @S9S_MB_2U_LIB.S9S_MB_2U(SCH_1):P1V05_PCH_AUX    I41 @S9S_MB_2U_LIB.S9S_MB_2U(SCH_1):PAGE248
     2    GND @S9S_MB_2U_LIB.S9S_MB_2U(SCH_1):GND    I41 @S9S_MB_2U_LIB.S9S_MB_2U(SCH_1):PAGE248

PC1229 Q_CAPP_SMLF-330UF,2V,35%,SPCAPA
     1 P1V05_PCH_AUX @S9S_MB_2U_LIB.S9S_MB_2U(SCH_1):P1V05_PCH_AUX    I47 @S9S_MB_2U_LIB.S9S_MB_2U(SCH_1):PAGE248
     2    GND @S9S_MB_2U_LIB.S9S_MB_2U(SCH_1):GND    I47 @S9S_MB_2U_LIB.S9S_MB_2U(SCH_1):PAGE248

PC1230 Q_CAPP_THLF-560UF,2.5V,20%,OSCA
     1 P1V05_PCH_AUX @S9S_MB_2U_LIB.S9S_MB_2U(SCH_1):P1V05_PCH_AUX    I48 @S9S_MB_2U_LIB.S9S_MB_2U(SCH_1):PAGE248
     2    GND @S9S_MB_2U_LIB.S9S_MB_2U(SCH_1):GND    I48 @S9S_MB_2U_LIB.S9S_MB_2U(SCH_1):PAGE248

PC1232 Q_CAP_C0805-10UF,16V,10%,X6S,CB
     1 SW_P1V8_PCH_AUX_FLT @S9S_MB_2U_LIB.S9S_MB_2U(SCH_1):SW_P1V8_PCH_AUX_FLT    I19 @S9S_MB_2U_LIB.S9S_MB_2U(SCH_1):PAGE249
     2    GND @S9S_MB_2U_LIB.S9S_MB_2U(SCH_1):GND    I19 @S9S_MB_2U_LIB.S9S_MB_2U(SCH_1):PAGE249

PC1233 Q_CAP_C0805-10UF,16V,10%,X6S,CB
     1 SW_P1V8_PCH_AUX_FLT @S9S_MB_2U_LIB.S9S_MB_2U(SCH_1):SW_P1V8_PCH_AUX_FLT    I20 @S9S_MB_2U_LIB.S9S_MB_2U(SCH_1):PAGE249
     2    GND @S9S_MB_2U_LIB.S9S_MB_2U(SCH_1):GND    I20 @S9S_MB_2U_LIB.S9S_MB_2U(SCH_1):PAGE249

PC1234 Q_CAP_C0402-100NF,50V,10%,X7R,A
     1 SW_P1V8_PCH_AUX_FLT @S9S_MB_2U_LIB.S9S_MB_2U(SCH_1):SW_P1V8_PCH_AUX_FLT    I21 @S9S_MB_2U_LIB.S9S_MB_2U(SCH_1):PAGE249
     2    GND @S9S_MB_2U_LIB.S9S_MB_2U(SCH_1):GND    I21 @S9S_MB_2U_LIB.S9S_MB_2U(SCH_1):PAGE249

PC1235 Q_CAP_C0402-0.22UF,25V,10%,X7RA
     1 SW_P1V8_PCH_AUX_BST @S9S_MB_2U_LIB.S9S_MB_2U(SCH_1):SW_P1V8_PCH_AUX_BST    I30 @S9S_MB_2U_LIB.S9S_MB_2U(SCH_1):PAGE249
     2 SW_P1V8_PCH_AUX_SW @S9S_MB_2U_LIB.S9S_MB_2U(SCH_1):SW_P1V8_PCH_AUX_SW    I30 @S9S_MB_2U_LIB.S9S_MB_2U(SCH_1):PAGE249

PC1236 Q_CAP_C0402-100NF,50V,10%,X7R,A
     1 P1V8_PCH_AUX @S9S_MB_2U_LIB.S9S_MB_2U(SCH_1):P1V8_PCH_AUX    I28 @S9S_MB_2U_LIB.S9S_MB_2U(SCH_1):PAGE249
     2    GND @S9S_MB_2U_LIB.S9S_MB_2U(SCH_1):GND    I28 @S9S_MB_2U_LIB.S9S_MB_2U(SCH_1):PAGE249

PC1237 Q_CAP_C0805-22UF,4V,20%,X6S,CHA
     1 P1V8_PCH_AUX @S9S_MB_2U_LIB.S9S_MB_2U(SCH_1):P1V8_PCH_AUX    I29 @S9S_MB_2U_LIB.S9S_MB_2U(SCH_1):PAGE249
     2    GND @S9S_MB_2U_LIB.S9S_MB_2U(SCH_1):GND    I29 @S9S_MB_2U_LIB.S9S_MB_2U(SCH_1):PAGE249

PC1238 Q_CAP_C0805-22UF,4V,20%,X6S,CHA
     1 P1V8_PCH_AUX @S9S_MB_2U_LIB.S9S_MB_2U(SCH_1):P1V8_PCH_AUX    I37 @S9S_MB_2U_LIB.S9S_MB_2U(SCH_1):PAGE249
     2    GND @S9S_MB_2U_LIB.S9S_MB_2U(SCH_1):GND    I37 @S9S_MB_2U_LIB.S9S_MB_2U(SCH_1):PAGE249

PC1239 Q_CAP_C0805-22UF,4V,20%,X6S,CHA
     1 P1V8_PCH_AUX @S9S_MB_2U_LIB.S9S_MB_2U(SCH_1):P1V8_PCH_AUX    I38 @S9S_MB_2U_LIB.S9S_MB_2U(SCH_1):PAGE249
     2    GND @S9S_MB_2U_LIB.S9S_MB_2U(SCH_1):GND    I38 @S9S_MB_2U_LIB.S9S_MB_2U(SCH_1):PAGE249

PC1240 Q_CAP_C0805-22UF,4V,20%,X6S,CHA
     1 P1V8_PCH_AUX @S9S_MB_2U_LIB.S9S_MB_2U(SCH_1):P1V8_PCH_AUX    I39 @S9S_MB_2U_LIB.S9S_MB_2U(SCH_1):PAGE249
     2    GND @S9S_MB_2U_LIB.S9S_MB_2U(SCH_1):GND    I39 @S9S_MB_2U_LIB.S9S_MB_2U(SCH_1):PAGE249

PC1241 Q_CAP_C0805-22UF,4V,20%,X6S,CHA
     1 P1V8_PCH_AUX @S9S_MB_2U_LIB.S9S_MB_2U(SCH_1):P1V8_PCH_AUX    I41 @S9S_MB_2U_LIB.S9S_MB_2U(SCH_1):PAGE249
     2    GND @S9S_MB_2U_LIB.S9S_MB_2U(SCH_1):GND    I41 @S9S_MB_2U_LIB.S9S_MB_2U(SCH_1):PAGE249

PC1242_P1_1 Q_CAP_C0402-2.2UF,10V,10%,X6S,A
     1 PVCCFA_EHV_FIVRA_CPU1_PVCC1 @S9S_MB_2U_LIB.S9S_MB_2U(SCH_1):PVCCFA_EHV_FIVRA_CPU1_PVCC1    I31 @S9S_MB_2U_LIB.S9S_MB_2U(SCH_1):PAGE275
     2    GND @S9S_MB_2U_LIB.S9S_MB_2U(SCH_1):GND    I31 @S9S_MB_2U_LIB.S9S_MB_2U(SCH_1):PAGE275

PC1243_P1_2 Q_CAP_C0402-2.2UF,10V,10%,X6S,A
     1 PVCCFA_EHV_FIVRA_CPU1_PVCC2 @S9S_MB_2U_LIB.S9S_MB_2U(SCH_1):PVCCFA_EHV_FIVRA_CPU1_PVCC2    I16 @S9S_MB_2U_LIB.S9S_MB_2U(SCH_1):PAGE275
     2    GND @S9S_MB_2U_LIB.S9S_MB_2U(SCH_1):GND    I16 @S9S_MB_2U_LIB.S9S_MB_2U(SCH_1):PAGE275

PC1244_P1_3 Q_CAP_C0402-2.2UF,10V,10%,X6S,A
     1 PVCCFA_EHV_FIVRA_CPU1_PVCC1 @S9S_MB_2U_LIB.S9S_MB_2U(SCH_1):PVCCFA_EHV_FIVRA_CPU1_PVCC1    I31 @S9S_MB_2U_LIB.S9S_MB_2U(SCH_1):PAGE276
     2    GND @S9S_MB_2U_LIB.S9S_MB_2U(SCH_1):GND    I31 @S9S_MB_2U_LIB.S9S_MB_2U(SCH_1):PAGE276

PC1245_P1_4 Q_CAP_C0402-2.2UF,10V,10%,X6S,A
     1 PVCCFA_EHV_FIVRA_CPU1_PVCC2 @S9S_MB_2U_LIB.S9S_MB_2U(SCH_1):PVCCFA_EHV_FIVRA_CPU1_PVCC2    I20 @S9S_MB_2U_LIB.S9S_MB_2U(SCH_1):PAGE276
     2    GND @S9S_MB_2U_LIB.S9S_MB_2U(SCH_1):GND    I20 @S9S_MB_2U_LIB.S9S_MB_2U(SCH_1):PAGE276

PC1247 Q_CAP_C0805-22UF,16V,20%,X6S,CA
     1 SW_P12V_PVCCIN_CPU0_FLT @S9S_MB_2U_LIB.S9S_MB_2U(SCH_1):SW_P12V_PVCCIN_CPU0_FLT    I10 @S9S_MB_2U_LIB.S9S_MB_2U(SCH_1):PAGE267
     2    GND @S9S_MB_2U_LIB.S9S_MB_2U(SCH_1):GND    I10 @S9S_MB_2U_LIB.S9S_MB_2U(SCH_1):PAGE267

PC1248 Q_CAP_C0805-22UF,16V,20%,X6S,CA
     1 SW_P12V_PVCCIN_CPU0_FLT @S9S_MB_2U_LIB.S9S_MB_2U(SCH_1):SW_P12V_PVCCIN_CPU0_FLT    I16 @S9S_MB_2U_LIB.S9S_MB_2U(SCH_1):PAGE267
     2    GND @S9S_MB_2U_LIB.S9S_MB_2U(SCH_1):GND    I16 @S9S_MB_2U_LIB.S9S_MB_2U(SCH_1):PAGE267

PC1249 Q_CAP_C0402-1UF,16V,10%,X6S,CHA
     1 SW_P12V_PVCCIN_CPU0_FLT @S9S_MB_2U_LIB.S9S_MB_2U(SCH_1):SW_P12V_PVCCIN_CPU0_FLT    I17 @S9S_MB_2U_LIB.S9S_MB_2U(SCH_1):PAGE267
     2    GND @S9S_MB_2U_LIB.S9S_MB_2U(SCH_1):GND    I17 @S9S_MB_2U_LIB.S9S_MB_2U(SCH_1):PAGE267

PC1251 Q_CAP_0402-0.1UF,25V,10%,X7R,CA
     1 PVPP_HBM_CPU0_REF @S9S_MB_2U_LIB.S9S_MB_2U(SCH_1):PVPP_HBM_CPU0_REF    I25 @S9S_MB_2U_LIB.S9S_MB_2U(SCH_1):PAGE267
     2 SH_PVPP_HBM_CPU0_N @S9S_MB_2U_LIB.S9S_MB_2U(SCH_1):SH_PVPP_HBM_CPU0_N    I25 @S9S_MB_2U_LIB.S9S_MB_2U(SCH_1):PAGE267

PC1252 Q_CAP_C0402-0.22UF,25V,10%,X7RA
     1 SW_PVPP_HBM_CPU0_BST @S9S_MB_2U_LIB.S9S_MB_2U(SCH_1):SW_PVPP_HBM_CPU0_BST    I27 @S9S_MB_2U_LIB.S9S_MB_2U(SCH_1):PAGE267
     2 SW_PVPP_HBM_CPU0_SW @S9S_MB_2U_LIB.S9S_MB_2U(SCH_1):SW_PVPP_HBM_CPU0_SW    I27 @S9S_MB_2U_LIB.S9S_MB_2U(SCH_1):PAGE267

PC1253 Q_CAP_C0402-680PF,50V,10%,X7R,A
     1 PVPP_HBM_CPU0_FB @S9S_MB_2U_LIB.S9S_MB_2U(SCH_1):PVPP_HBM_CPU0_FB    I35 @S9S_MB_2U_LIB.S9S_MB_2U(SCH_1):PAGE267
     2 SH_PVPP_HBM_CPU0_P @S9S_MB_2U_LIB.S9S_MB_2U(SCH_1):SH_PVPP_HBM_CPU0_P    I35 @S9S_MB_2U_LIB.S9S_MB_2U(SCH_1):PAGE267

PC1254 Q_CAP_0402-0.1UF,25V,10%,X7R,CA
     1 PVPP_HBM_CPU0 @S9S_MB_2U_LIB.S9S_MB_2U(SCH_1):PVPP_HBM_CPU0    I38 @S9S_MB_2U_LIB.S9S_MB_2U(SCH_1):PAGE267
     2    GND @S9S_MB_2U_LIB.S9S_MB_2U(SCH_1):GND    I38 @S9S_MB_2U_LIB.S9S_MB_2U(SCH_1):PAGE267

PC1255 Q_CAP_C0805-22UF,4V,20%,X6S,CHA
     1 PVPP_HBM_CPU0 @S9S_MB_2U_LIB.S9S_MB_2U(SCH_1):PVPP_HBM_CPU0    I42 @S9S_MB_2U_LIB.S9S_MB_2U(SCH_1):PAGE267
     2    GND @S9S_MB_2U_LIB.S9S_MB_2U(SCH_1):GND    I42 @S9S_MB_2U_LIB.S9S_MB_2U(SCH_1):PAGE267

PC1256 Q_CAP_C0805-22UF,4V,20%,X6S,CHA
     1 PVPP_HBM_CPU0 @S9S_MB_2U_LIB.S9S_MB_2U(SCH_1):PVPP_HBM_CPU0    I43 @S9S_MB_2U_LIB.S9S_MB_2U(SCH_1):PAGE267
     2    GND @S9S_MB_2U_LIB.S9S_MB_2U(SCH_1):GND    I43 @S9S_MB_2U_LIB.S9S_MB_2U(SCH_1):PAGE267

PC1257 Q_CAP_C0805-22UF,4V,20%,X6S,CHA
     1 PVPP_HBM_CPU0 @S9S_MB_2U_LIB.S9S_MB_2U(SCH_1):PVPP_HBM_CPU0    I44 @S9S_MB_2U_LIB.S9S_MB_2U(SCH_1):PAGE267
     2    GND @S9S_MB_2U_LIB.S9S_MB_2U(SCH_1):GND    I44 @S9S_MB_2U_LIB.S9S_MB_2U(SCH_1):PAGE267

PC1258 Q_CAPP_THLF-560UF,6.3V,20%,OSCA
     1 PVPP_HBM_CPU0 @S9S_MB_2U_LIB.S9S_MB_2U(SCH_1):PVPP_HBM_CPU0    I49 @S9S_MB_2U_LIB.S9S_MB_2U(SCH_1):PAGE267
     2    GND @S9S_MB_2U_LIB.S9S_MB_2U(SCH_1):GND    I49 @S9S_MB_2U_LIB.S9S_MB_2U(SCH_1):PAGE267

PC1259 Q_CAP_C0805-22UF,16V,20%,X6S,CA
     1 SW_P12V_PVCCIN_CPU1_FLT @S9S_MB_2U_LIB.S9S_MB_2U(SCH_1):SW_P12V_PVCCIN_CPU1_FLT     I8 @S9S_MB_2U_LIB.S9S_MB_2U(SCH_1):PAGE285
     2    GND @S9S_MB_2U_LIB.S9S_MB_2U(SCH_1):GND     I8 @S9S_MB_2U_LIB.S9S_MB_2U(SCH_1):PAGE285

PC1260 Q_CAP_C0805-22UF,16V,20%,X6S,CA
     1 SW_P12V_PVCCIN_CPU1_FLT @S9S_MB_2U_LIB.S9S_MB_2U(SCH_1):SW_P12V_PVCCIN_CPU1_FLT    I15 @S9S_MB_2U_LIB.S9S_MB_2U(SCH_1):PAGE285
     2    GND @S9S_MB_2U_LIB.S9S_MB_2U(SCH_1):GND    I15 @S9S_MB_2U_LIB.S9S_MB_2U(SCH_1):PAGE285

PC1261 Q_CAP_C0805-22UF,16V,20%,X6S,CA
     1 SW_P12V_PVCCIN_CPU1_FLT @S9S_MB_2U_LIB.S9S_MB_2U(SCH_1):SW_P12V_PVCCIN_CPU1_FLT    I16 @S9S_MB_2U_LIB.S9S_MB_2U(SCH_1):PAGE285
     2    GND @S9S_MB_2U_LIB.S9S_MB_2U(SCH_1):GND    I16 @S9S_MB_2U_LIB.S9S_MB_2U(SCH_1):PAGE285

PC1262 Q_CAP_C0402-1UF,16V,10%,X6S,CHA
     1 SW_P12V_PVCCIN_CPU1_FLT @S9S_MB_2U_LIB.S9S_MB_2U(SCH_1):SW_P12V_PVCCIN_CPU1_FLT    I17 @S9S_MB_2U_LIB.S9S_MB_2U(SCH_1):PAGE285
     2    GND @S9S_MB_2U_LIB.S9S_MB_2U(SCH_1):GND    I17 @S9S_MB_2U_LIB.S9S_MB_2U(SCH_1):PAGE285

PC1264 Q_CAP_0402-0.1UF,25V,10%,X7R,CA
     1 PVPP_HBM_CPU1_REF @S9S_MB_2U_LIB.S9S_MB_2U(SCH_1):PVPP_HBM_CPU1_REF    I24 @S9S_MB_2U_LIB.S9S_MB_2U(SCH_1):PAGE285
     2 SH_PVPP_HBM_CPU1_N @S9S_MB_2U_LIB.S9S_MB_2U(SCH_1):SH_PVPP_HBM_CPU1_N    I24 @S9S_MB_2U_LIB.S9S_MB_2U(SCH_1):PAGE285

PC1265 Q_CAP_C0402-0.22UF,25V,10%,X7RA
     1 SW_PVPP_HBM_CPU1_BST @S9S_MB_2U_LIB.S9S_MB_2U(SCH_1):SW_PVPP_HBM_CPU1_BST    I26 @S9S_MB_2U_LIB.S9S_MB_2U(SCH_1):PAGE285
     2 SW_PVPP_HBM_CPU1_SW @S9S_MB_2U_LIB.S9S_MB_2U(SCH_1):SW_PVPP_HBM_CPU1_SW    I26 @S9S_MB_2U_LIB.S9S_MB_2U(SCH_1):PAGE285

PC1266 Q_CAP_0402-680PF,50V,10%,X7R,TA
     1 PVPP_HBM_CPU1_FB @S9S_MB_2U_LIB.S9S_MB_2U(SCH_1):PVPP_HBM_CPU1_FB    I35 @S9S_MB_2U_LIB.S9S_MB_2U(SCH_1):PAGE285
     2 SH_PVPP_HBM_CPU1_P @S9S_MB_2U_LIB.S9S_MB_2U(SCH_1):SH_PVPP_HBM_CPU1_P    I35 @S9S_MB_2U_LIB.S9S_MB_2U(SCH_1):PAGE285

PC1267 Q_CAP_0402-0.1UF,25V,10%,X7R,CA
     1 PVPP_HBM_CPU1 @S9S_MB_2U_LIB.S9S_MB_2U(SCH_1):PVPP_HBM_CPU1    I39 @S9S_MB_2U_LIB.S9S_MB_2U(SCH_1):PAGE285
     2    GND @S9S_MB_2U_LIB.S9S_MB_2U(SCH_1):GND    I39 @S9S_MB_2U_LIB.S9S_MB_2U(SCH_1):PAGE285

PC1268 Q_CAP_C0805-22UF,4V,20%,X6S,CHA
     1 PVPP_HBM_CPU1 @S9S_MB_2U_LIB.S9S_MB_2U(SCH_1):PVPP_HBM_CPU1    I40 @S9S_MB_2U_LIB.S9S_MB_2U(SCH_1):PAGE285
     2    GND @S9S_MB_2U_LIB.S9S_MB_2U(SCH_1):GND    I40 @S9S_MB_2U_LIB.S9S_MB_2U(SCH_1):PAGE285

PC1269 Q_CAP_C0805-22UF,4V,20%,X6S,CHA
     1 PVPP_HBM_CPU1 @S9S_MB_2U_LIB.S9S_MB_2U(SCH_1):PVPP_HBM_CPU1    I41 @S9S_MB_2U_LIB.S9S_MB_2U(SCH_1):PAGE285
     2    GND @S9S_MB_2U_LIB.S9S_MB_2U(SCH_1):GND    I41 @S9S_MB_2U_LIB.S9S_MB_2U(SCH_1):PAGE285

PC1270 Q_CAP_C0805-22UF,4V,20%,X6S,CHA
     1 PVPP_HBM_CPU1 @S9S_MB_2U_LIB.S9S_MB_2U(SCH_1):PVPP_HBM_CPU1    I47 @S9S_MB_2U_LIB.S9S_MB_2U(SCH_1):PAGE285
     2    GND @S9S_MB_2U_LIB.S9S_MB_2U(SCH_1):GND    I47 @S9S_MB_2U_LIB.S9S_MB_2U(SCH_1):PAGE285

PC1271 Q_CAP_0402-470PF,50V,10%,X7R,TA
     1 PVCCFA_EHV_CPU0_BTSEN @S9S_MB_2U_LIB.S9S_MB_2U(SCH_1):PVCCFA_EHV_CPU0_BTSEN    I73 @S9S_MB_2U_LIB.S9S_MB_2U(SCH_1):PAGE260
     2    GND @S9S_MB_2U_LIB.S9S_MB_2U(SCH_1):GND    I73 @S9S_MB_2U_LIB.S9S_MB_2U(SCH_1):PAGE260

PC1272 Q_CAP_C0805-22UF,16V,20%,X6S,CA
     1 SW_P12V_PVCCINFAON_CPU0_FLT @S9S_MB_2U_LIB.S9S_MB_2U(SCH_1):SW_P12V_PVCCINFAON_CPU0_FLT    I13 @S9S_MB_2U_LIB.S9S_MB_2U(SCH_1):PAGE268
     2    GND @S9S_MB_2U_LIB.S9S_MB_2U(SCH_1):GND    I13 @S9S_MB_2U_LIB.S9S_MB_2U(SCH_1):PAGE268

PC1273 Q_CAP_C0805-22UF,16V,20%,X6S,CA
     1 SW_P12V_PVCCINFAON_CPU0_FLT @S9S_MB_2U_LIB.S9S_MB_2U(SCH_1):SW_P12V_PVCCINFAON_CPU0_FLT    I15 @S9S_MB_2U_LIB.S9S_MB_2U(SCH_1):PAGE268
     2    GND @S9S_MB_2U_LIB.S9S_MB_2U(SCH_1):GND    I15 @S9S_MB_2U_LIB.S9S_MB_2U(SCH_1):PAGE268

PC1274 Q_CAP_C0402-1UF,16V,10%,X6S,CHA
     1 SW_P12V_PVCCINFAON_CPU0_FLT @S9S_MB_2U_LIB.S9S_MB_2U(SCH_1):SW_P12V_PVCCINFAON_CPU0_FLT    I23 @S9S_MB_2U_LIB.S9S_MB_2U(SCH_1):PAGE268
     2    GND @S9S_MB_2U_LIB.S9S_MB_2U(SCH_1):GND    I23 @S9S_MB_2U_LIB.S9S_MB_2U(SCH_1):PAGE268

PC1275 Q_CAP_C0402-0.22UF,25V,10%,X7RA
     1 SW_PVNN_MAIN_CPU0_BST_R @S9S_MB_2U_LIB.S9S_MB_2U(SCH_1):SW_PVNN_MAIN_CPU0_BST_R    I26 @S9S_MB_2U_LIB.S9S_MB_2U(SCH_1):PAGE268
     2 SW_PVNN_MAIN_CPU0_SW @S9S_MB_2U_LIB.S9S_MB_2U(SCH_1):SW_PVNN_MAIN_CPU0_SW    I26 @S9S_MB_2U_LIB.S9S_MB_2U(SCH_1):PAGE268

PC1276 Q_CAP_C0402-100NF,50V,10%,X7R,A
     1 PVNN_MAIN_CPU0 @S9S_MB_2U_LIB.S9S_MB_2U(SCH_1):PVNN_MAIN_CPU0    I37 @S9S_MB_2U_LIB.S9S_MB_2U(SCH_1):PAGE268
     2    GND @S9S_MB_2U_LIB.S9S_MB_2U(SCH_1):GND    I37 @S9S_MB_2U_LIB.S9S_MB_2U(SCH_1):PAGE268

PC1277 Q_CAP_C0805-22UF,4V,20%,X6S,CHA
     1 PVNN_MAIN_CPU0 @S9S_MB_2U_LIB.S9S_MB_2U(SCH_1):PVNN_MAIN_CPU0    I38 @S9S_MB_2U_LIB.S9S_MB_2U(SCH_1):PAGE268
     2    GND @S9S_MB_2U_LIB.S9S_MB_2U(SCH_1):GND    I38 @S9S_MB_2U_LIB.S9S_MB_2U(SCH_1):PAGE268

PC1278 Q_CAP_C0805-22UF,4V,20%,X6S,CHA
     1 PVNN_MAIN_CPU0 @S9S_MB_2U_LIB.S9S_MB_2U(SCH_1):PVNN_MAIN_CPU0    I42 @S9S_MB_2U_LIB.S9S_MB_2U(SCH_1):PAGE268
     2    GND @S9S_MB_2U_LIB.S9S_MB_2U(SCH_1):GND    I42 @S9S_MB_2U_LIB.S9S_MB_2U(SCH_1):PAGE268

PC1279 Q_CAP_C0805-22UF,4V,20%,X6S,CHA
     1 PVNN_MAIN_CPU0 @S9S_MB_2U_LIB.S9S_MB_2U(SCH_1):PVNN_MAIN_CPU0    I43 @S9S_MB_2U_LIB.S9S_MB_2U(SCH_1):PAGE268
     2    GND @S9S_MB_2U_LIB.S9S_MB_2U(SCH_1):GND    I43 @S9S_MB_2U_LIB.S9S_MB_2U(SCH_1):PAGE268

PC1280 Q_CAP_C0805-22UF,16V,20%,X6S,CA
     1 SW_P12V_PVCCINFAON_CPU1_FLT @S9S_MB_2U_LIB.S9S_MB_2U(SCH_1):SW_P12V_PVCCINFAON_CPU1_FLT     I9 @S9S_MB_2U_LIB.S9S_MB_2U(SCH_1):PAGE286
     2    GND @S9S_MB_2U_LIB.S9S_MB_2U(SCH_1):GND     I9 @S9S_MB_2U_LIB.S9S_MB_2U(SCH_1):PAGE286

PC1281 Q_CAP_C0805-22UF,16V,20%,X6S,CA
     1 SW_P12V_PVCCINFAON_CPU1_FLT @S9S_MB_2U_LIB.S9S_MB_2U(SCH_1):SW_P12V_PVCCINFAON_CPU1_FLT    I14 @S9S_MB_2U_LIB.S9S_MB_2U(SCH_1):PAGE286
     2    GND @S9S_MB_2U_LIB.S9S_MB_2U(SCH_1):GND    I14 @S9S_MB_2U_LIB.S9S_MB_2U(SCH_1):PAGE286

PC1282 Q_CAP_C0402-1UF,16V,10%,X6S,CHA
     1 SW_P12V_PVCCINFAON_CPU1_FLT @S9S_MB_2U_LIB.S9S_MB_2U(SCH_1):SW_P12V_PVCCINFAON_CPU1_FLT    I16 @S9S_MB_2U_LIB.S9S_MB_2U(SCH_1):PAGE286
     2    GND @S9S_MB_2U_LIB.S9S_MB_2U(SCH_1):GND    I16 @S9S_MB_2U_LIB.S9S_MB_2U(SCH_1):PAGE286

PC1283 Q_CAP_C0402-0.22UF,25V,10%,X7RA
     1 SW_PVNN_MAIN_CPU1_BST_R @S9S_MB_2U_LIB.S9S_MB_2U(SCH_1):SW_PVNN_MAIN_CPU1_BST_R    I24 @S9S_MB_2U_LIB.S9S_MB_2U(SCH_1):PAGE286
     2 SW_PVNN_MAIN_CPU1_SW @S9S_MB_2U_LIB.S9S_MB_2U(SCH_1):SW_PVNN_MAIN_CPU1_SW    I24 @S9S_MB_2U_LIB.S9S_MB_2U(SCH_1):PAGE286

PC1284 Q_CAP_C0402-100NF,50V,10%,X7R,A
     1 PVNN_MAIN_CPU1 @S9S_MB_2U_LIB.S9S_MB_2U(SCH_1):PVNN_MAIN_CPU1    I28 @S9S_MB_2U_LIB.S9S_MB_2U(SCH_1):PAGE286
     2    GND @S9S_MB_2U_LIB.S9S_MB_2U(SCH_1):GND    I28 @S9S_MB_2U_LIB.S9S_MB_2U(SCH_1):PAGE286

PC1285 Q_CAP_C0805-22UF,4V,20%,X6S,CHA
     1 PVNN_MAIN_CPU1 @S9S_MB_2U_LIB.S9S_MB_2U(SCH_1):PVNN_MAIN_CPU1    I36 @S9S_MB_2U_LIB.S9S_MB_2U(SCH_1):PAGE286
     2    GND @S9S_MB_2U_LIB.S9S_MB_2U(SCH_1):GND    I36 @S9S_MB_2U_LIB.S9S_MB_2U(SCH_1):PAGE286

PC1286 Q_CAP_C0805-22UF,4V,20%,X6S,CHA
     1 PVNN_MAIN_CPU1 @S9S_MB_2U_LIB.S9S_MB_2U(SCH_1):PVNN_MAIN_CPU1    I38 @S9S_MB_2U_LIB.S9S_MB_2U(SCH_1):PAGE286
     2    GND @S9S_MB_2U_LIB.S9S_MB_2U(SCH_1):GND    I38 @S9S_MB_2U_LIB.S9S_MB_2U(SCH_1):PAGE286

PC1287 Q_CAP_C0805-22UF,4V,20%,X6S,CHA
     1 PVNN_MAIN_CPU1 @S9S_MB_2U_LIB.S9S_MB_2U(SCH_1):PVNN_MAIN_CPU1    I44 @S9S_MB_2U_LIB.S9S_MB_2U(SCH_1):PAGE286
     2    GND @S9S_MB_2U_LIB.S9S_MB_2U(SCH_1):GND    I44 @S9S_MB_2U_LIB.S9S_MB_2U(SCH_1):PAGE286

PC1289 Q_CAP_C0402-1UF,16V,10%,X6S,CHA
     1 PVCCD_HV_CPU1_VREF @S9S_MB_2U_LIB.S9S_MB_2U(SCH_1):PVCCD_HV_CPU1_VREF    I74 @S9S_MB_2U_LIB.S9S_MB_2U(SCH_1):PAGE282
     2    GND @S9S_MB_2U_LIB.S9S_MB_2U(SCH_1):GND    I74 @S9S_MB_2U_LIB.S9S_MB_2U(SCH_1):PAGE282

PC1292 Q_CAP_0402-470PF,50V,10%,X7R,TA
     1 PVCCFA_EHV_CPU1_BTSEN @S9S_MB_2U_LIB.S9S_MB_2U(SCH_1):PVCCFA_EHV_CPU1_BTSEN    I69 @S9S_MB_2U_LIB.S9S_MB_2U(SCH_1):PAGE278
     2    GND @S9S_MB_2U_LIB.S9S_MB_2U(SCH_1):GND    I69 @S9S_MB_2U_LIB.S9S_MB_2U(SCH_1):PAGE278

PC1320 Q_CAP_C0603-2.2UF,16V,20%,X7R,A
     1 P12V_OCP_AVIN_PD_2 @S9S_MB_2U_LIB.S9S_MB_2U(SCH_1):P12V_OCP_AVIN_PD_2    I95 @S9S_MB_2U_LIB.S9S_MB_2U(SCH_1):PAGE237
     2    GND @S9S_MB_2U_LIB.S9S_MB_2U(SCH_1):GND    I95 @S9S_MB_2U_LIB.S9S_MB_2U(SCH_1):PAGE237

PC1321 Q_CAP_0402-0.068UF,16V,10%,EMPA
     1 P3V3_OCP_DVDT_2 @S9S_MB_2U_LIB.S9S_MB_2U(SCH_1):P3V3_OCP_DVDT_2    I50 @S9S_MB_2U_LIB.S9S_MB_2U(SCH_1):PAGE237
     2    GND @S9S_MB_2U_LIB.S9S_MB_2U(SCH_1):GND    I50 @S9S_MB_2U_LIB.S9S_MB_2U(SCH_1):PAGE237

PC1322 Q_CAP_0402-100PF,50V,5%,EMPTY,A
     1 P3V3_OCP_GATE_PU207_2 @S9S_MB_2U_LIB.S9S_MB_2U(SCH_1):P3V3_OCP_GATE_PU207_2    I54 @S9S_MB_2U_LIB.S9S_MB_2U(SCH_1):PAGE237
     2    GND @S9S_MB_2U_LIB.S9S_MB_2U(SCH_1):GND    I54 @S9S_MB_2U_LIB.S9S_MB_2U(SCH_1):PAGE237

PC1338 Q_CAP_0402-0.1UF,25V,10%,X7R,CA
     1    GND @S9S_MB_2U_LIB.S9S_MB_2U(SCH_1):GND     I6 @S9S_MB_2U_LIB.S9S_MB_2U(SCH_1):PAGE271
     2 PVCCIN_CPU1_VREF @S9S_MB_2U_LIB.S9S_MB_2U(SCH_1):PVCCIN_CPU1_VREF     I6 @S9S_MB_2U_LIB.S9S_MB_2U(SCH_1):PAGE271

PC1339 Q_CAP_0402-0.1UF,25V,10%,X7R,CA
     1    GND @S9S_MB_2U_LIB.S9S_MB_2U(SCH_1):GND    I34 @S9S_MB_2U_LIB.S9S_MB_2U(SCH_1):PAGE271
     2 PVCCIN_CPU1_VREF @S9S_MB_2U_LIB.S9S_MB_2U(SCH_1):PVCCIN_CPU1_VREF    I34 @S9S_MB_2U_LIB.S9S_MB_2U(SCH_1):PAGE271

PC1340 Q_CAP_0402-0.1UF,25V,10%,X7R,CA
     1    GND @S9S_MB_2U_LIB.S9S_MB_2U(SCH_1):GND    I12 @S9S_MB_2U_LIB.S9S_MB_2U(SCH_1):PAGE254
     2 PVCCIN_CPU0_VREF @S9S_MB_2U_LIB.S9S_MB_2U(SCH_1):PVCCIN_CPU0_VREF    I12 @S9S_MB_2U_LIB.S9S_MB_2U(SCH_1):PAGE254

PC1341 Q_CAP_0402-0.1UF,25V,10%,X7R,CA
     1    GND @S9S_MB_2U_LIB.S9S_MB_2U(SCH_1):GND    I26 @S9S_MB_2U_LIB.S9S_MB_2U(SCH_1):PAGE254
     2 PVCCIN_CPU0_VREF @S9S_MB_2U_LIB.S9S_MB_2U(SCH_1):PVCCIN_CPU0_VREF    I26 @S9S_MB_2U_LIB.S9S_MB_2U(SCH_1):PAGE254

PC1342 Q_CAP_0402-0.1UF,25V,10%,X7R,CA
     1    GND @S9S_MB_2U_LIB.S9S_MB_2U(SCH_1):GND    I11 @S9S_MB_2U_LIB.S9S_MB_2U(SCH_1):PAGE255
     2 PVCCIN_CPU0_VREF @S9S_MB_2U_LIB.S9S_MB_2U(SCH_1):PVCCIN_CPU0_VREF    I11 @S9S_MB_2U_LIB.S9S_MB_2U(SCH_1):PAGE255

PC1343 Q_CAP_0402-0.1UF,25V,10%,X7R,CA
     1    GND @S9S_MB_2U_LIB.S9S_MB_2U(SCH_1):GND    I25 @S9S_MB_2U_LIB.S9S_MB_2U(SCH_1):PAGE255
     2 PVCCIN_CPU0_VREF @S9S_MB_2U_LIB.S9S_MB_2U(SCH_1):PVCCIN_CPU0_VREF    I25 @S9S_MB_2U_LIB.S9S_MB_2U(SCH_1):PAGE255

PC1344 Q_CAP_0402-0.1UF,25V,10%,X7R,CA
     1    GND @S9S_MB_2U_LIB.S9S_MB_2U(SCH_1):GND     I7 @S9S_MB_2U_LIB.S9S_MB_2U(SCH_1):PAGE256
     2 PVCCIN_CPU0_VREF @S9S_MB_2U_LIB.S9S_MB_2U(SCH_1):PVCCIN_CPU0_VREF     I7 @S9S_MB_2U_LIB.S9S_MB_2U(SCH_1):PAGE256

PC1345 Q_CAP_0402-0.1UF,25V,10%,X7R,CA
     1    GND @S9S_MB_2U_LIB.S9S_MB_2U(SCH_1):GND    I29 @S9S_MB_2U_LIB.S9S_MB_2U(SCH_1):PAGE256
     2 PVCCIN_CPU0_VREF @S9S_MB_2U_LIB.S9S_MB_2U(SCH_1):PVCCIN_CPU0_VREF    I29 @S9S_MB_2U_LIB.S9S_MB_2U(SCH_1):PAGE256

PC1346 Q_CAP_0402-0.1UF,25V,10%,X7R,CA
     1    GND @S9S_MB_2U_LIB.S9S_MB_2U(SCH_1):GND    I11 @S9S_MB_2U_LIB.S9S_MB_2U(SCH_1):PAGE261
     2 PVCCINFAON_CPU0_VREF @S9S_MB_2U_LIB.S9S_MB_2U(SCH_1):PVCCINFAON_CPU0_VREF    I11 @S9S_MB_2U_LIB.S9S_MB_2U(SCH_1):PAGE261

PC1347 Q_CAP_0402-0.1UF,25V,10%,X7R,CA
     1    GND @S9S_MB_2U_LIB.S9S_MB_2U(SCH_1):GND    I25 @S9S_MB_2U_LIB.S9S_MB_2U(SCH_1):PAGE261
     2 PVCCINFAON_CPU0_VREF @S9S_MB_2U_LIB.S9S_MB_2U(SCH_1):PVCCINFAON_CPU0_VREF    I25 @S9S_MB_2U_LIB.S9S_MB_2U(SCH_1):PAGE261

PC1348 Q_CAP_0402-0.1UF,25V,10%,X7R,CA
     1    GND @S9S_MB_2U_LIB.S9S_MB_2U(SCH_1):GND    I10 @S9S_MB_2U_LIB.S9S_MB_2U(SCH_1):PAGE262
     2 PVCCINFAON_CPU0_VREF @S9S_MB_2U_LIB.S9S_MB_2U(SCH_1):PVCCINFAON_CPU0_VREF    I10 @S9S_MB_2U_LIB.S9S_MB_2U(SCH_1):PAGE262

PC1349 Q_CAP_0402-0.1UF,25V,10%,X7R,CA
     1    GND @S9S_MB_2U_LIB.S9S_MB_2U(SCH_1):GND    I35 @S9S_MB_2U_LIB.S9S_MB_2U(SCH_1):PAGE257
     2 PVCCIN_CPU0_VREF @S9S_MB_2U_LIB.S9S_MB_2U(SCH_1):PVCCIN_CPU0_VREF    I35 @S9S_MB_2U_LIB.S9S_MB_2U(SCH_1):PAGE257

PC1350 Q_CAP_0402-0.1UF,25V,10%,X7R,CA
     1    GND @S9S_MB_2U_LIB.S9S_MB_2U(SCH_1):GND    I15 @S9S_MB_2U_LIB.S9S_MB_2U(SCH_1):PAGE257
     2 PVCCIN_CPU0_VREF @S9S_MB_2U_LIB.S9S_MB_2U(SCH_1):PVCCIN_CPU0_VREF    I15 @S9S_MB_2U_LIB.S9S_MB_2U(SCH_1):PAGE257

PC1351 Q_CAP_0402-0.1UF,25V,10%,X7R,CA
     1    GND @S9S_MB_2U_LIB.S9S_MB_2U(SCH_1):GND    I25 @S9S_MB_2U_LIB.S9S_MB_2U(SCH_1):PAGE258
     2 PVCCIN_CPU0_VREF @S9S_MB_2U_LIB.S9S_MB_2U(SCH_1):PVCCIN_CPU0_VREF    I25 @S9S_MB_2U_LIB.S9S_MB_2U(SCH_1):PAGE258

PC1352 Q_CAP_0402-0.1UF,25V,10%,X7R,CA
     1    GND @S9S_MB_2U_LIB.S9S_MB_2U(SCH_1):GND     I9 @S9S_MB_2U_LIB.S9S_MB_2U(SCH_1):PAGE258
     2 PVCCIN_CPU0_VREF @S9S_MB_2U_LIB.S9S_MB_2U(SCH_1):PVCCIN_CPU0_VREF     I9 @S9S_MB_2U_LIB.S9S_MB_2U(SCH_1):PAGE258

PC1354 Q_CAP_0402-0.1UF,25V,10%,X7R,CA
     1    GND @S9S_MB_2U_LIB.S9S_MB_2U(SCH_1):GND     I7 @S9S_MB_2U_LIB.S9S_MB_2U(SCH_1):PAGE265
     2 PVCCD_HV_CPU0_VREF @S9S_MB_2U_LIB.S9S_MB_2U(SCH_1):PVCCD_HV_CPU0_VREF     I7 @S9S_MB_2U_LIB.S9S_MB_2U(SCH_1):PAGE265

PC1355 Q_CAP_0402-0.1UF,25V,10%,X7R,CA
     1    GND @S9S_MB_2U_LIB.S9S_MB_2U(SCH_1):GND    I11 @S9S_MB_2U_LIB.S9S_MB_2U(SCH_1):PAGE253
     2 PVCCIN_CPU0_VREF @S9S_MB_2U_LIB.S9S_MB_2U(SCH_1):PVCCIN_CPU0_VREF    I11 @S9S_MB_2U_LIB.S9S_MB_2U(SCH_1):PAGE253

PC1356 Q_CAP_0402-0.1UF,25V,10%,X7R,CA
     1    GND @S9S_MB_2U_LIB.S9S_MB_2U(SCH_1):GND    I34 @S9S_MB_2U_LIB.S9S_MB_2U(SCH_1):PAGE253
     2 PVCCIN_CPU0_VREF @S9S_MB_2U_LIB.S9S_MB_2U(SCH_1):PVCCIN_CPU0_VREF    I34 @S9S_MB_2U_LIB.S9S_MB_2U(SCH_1):PAGE253

PC1358 Q_CAP_0402-0.1UF,25V,10%,X7R,CA
     1    GND @S9S_MB_2U_LIB.S9S_MB_2U(SCH_1):GND     I6 @S9S_MB_2U_LIB.S9S_MB_2U(SCH_1):PAGE272
     2 PVCCIN_CPU1_VREF @S9S_MB_2U_LIB.S9S_MB_2U(SCH_1):PVCCIN_CPU1_VREF     I6 @S9S_MB_2U_LIB.S9S_MB_2U(SCH_1):PAGE272

PC1359 Q_CAP_0402-0.1UF,25V,10%,X7R,CA
     1    GND @S9S_MB_2U_LIB.S9S_MB_2U(SCH_1):GND    I27 @S9S_MB_2U_LIB.S9S_MB_2U(SCH_1):PAGE272
     2 PVCCIN_CPU1_VREF @S9S_MB_2U_LIB.S9S_MB_2U(SCH_1):PVCCIN_CPU1_VREF    I27 @S9S_MB_2U_LIB.S9S_MB_2U(SCH_1):PAGE272

PC1360 Q_CAP_0402-0.1UF,25V,10%,X7R,CA
     1    GND @S9S_MB_2U_LIB.S9S_MB_2U(SCH_1):GND    I15 @S9S_MB_2U_LIB.S9S_MB_2U(SCH_1):PAGE273
     2 PVCCIN_CPU1_VREF @S9S_MB_2U_LIB.S9S_MB_2U(SCH_1):PVCCIN_CPU1_VREF    I15 @S9S_MB_2U_LIB.S9S_MB_2U(SCH_1):PAGE273

PC1361 Q_CAP_0402-0.1UF,25V,10%,X7R,CA
     1    GND @S9S_MB_2U_LIB.S9S_MB_2U(SCH_1):GND    I36 @S9S_MB_2U_LIB.S9S_MB_2U(SCH_1):PAGE273
     2 PVCCIN_CPU1_VREF @S9S_MB_2U_LIB.S9S_MB_2U(SCH_1):PVCCIN_CPU1_VREF    I36 @S9S_MB_2U_LIB.S9S_MB_2U(SCH_1):PAGE273

PC1362 Q_CAP_0402-0.1UF,25V,10%,X7R,CA
     1    GND @S9S_MB_2U_LIB.S9S_MB_2U(SCH_1):GND     I7 @S9S_MB_2U_LIB.S9S_MB_2U(SCH_1):PAGE274
     2 PVCCIN_CPU1_VREF @S9S_MB_2U_LIB.S9S_MB_2U(SCH_1):PVCCIN_CPU1_VREF     I7 @S9S_MB_2U_LIB.S9S_MB_2U(SCH_1):PAGE274

PC1363 Q_CAP_0402-0.1UF,25V,10%,X7R,CA
     1    GND @S9S_MB_2U_LIB.S9S_MB_2U(SCH_1):GND    I32 @S9S_MB_2U_LIB.S9S_MB_2U(SCH_1):PAGE274
     2 PVCCIN_CPU1_VREF @S9S_MB_2U_LIB.S9S_MB_2U(SCH_1):PVCCIN_CPU1_VREF    I32 @S9S_MB_2U_LIB.S9S_MB_2U(SCH_1):PAGE274

PC1364 Q_CAP_0402-0.1UF,25V,10%,X7R,CA
     1    GND @S9S_MB_2U_LIB.S9S_MB_2U(SCH_1):GND    I20 @S9S_MB_2U_LIB.S9S_MB_2U(SCH_1):PAGE279
     2 PVCCINFAON_CPU1_VREF @S9S_MB_2U_LIB.S9S_MB_2U(SCH_1):PVCCINFAON_CPU1_VREF    I20 @S9S_MB_2U_LIB.S9S_MB_2U(SCH_1):PAGE279

PC1365 Q_CAP_0402-0.1UF,25V,10%,X7R,CA
     1    GND @S9S_MB_2U_LIB.S9S_MB_2U(SCH_1):GND     I6 @S9S_MB_2U_LIB.S9S_MB_2U(SCH_1):PAGE279
     2 PVCCINFAON_CPU1_VREF @S9S_MB_2U_LIB.S9S_MB_2U(SCH_1):PVCCINFAON_CPU1_VREF     I6 @S9S_MB_2U_LIB.S9S_MB_2U(SCH_1):PAGE279

PC1366 Q_CAP_0402-0.1UF,25V,10%,X7R,CA
     1    GND @S9S_MB_2U_LIB.S9S_MB_2U(SCH_1):GND     I9 @S9S_MB_2U_LIB.S9S_MB_2U(SCH_1):PAGE280
     2 PVCCINFAON_CPU1_VREF @S9S_MB_2U_LIB.S9S_MB_2U(SCH_1):PVCCINFAON_CPU1_VREF     I9 @S9S_MB_2U_LIB.S9S_MB_2U(SCH_1):PAGE280

PC1367 Q_CAP_0402-0.1UF,25V,10%,X7R,CA
     1    GND @S9S_MB_2U_LIB.S9S_MB_2U(SCH_1):GND    I29 @S9S_MB_2U_LIB.S9S_MB_2U(SCH_1):PAGE275
     2 PVCCIN_CPU1_VREF @S9S_MB_2U_LIB.S9S_MB_2U(SCH_1):PVCCIN_CPU1_VREF    I29 @S9S_MB_2U_LIB.S9S_MB_2U(SCH_1):PAGE275

PC1368 Q_CAP_0402-0.1UF,25V,10%,X7R,CA
     1    GND @S9S_MB_2U_LIB.S9S_MB_2U(SCH_1):GND     I8 @S9S_MB_2U_LIB.S9S_MB_2U(SCH_1):PAGE275
     2 PVCCIN_CPU1_VREF @S9S_MB_2U_LIB.S9S_MB_2U(SCH_1):PVCCIN_CPU1_VREF     I8 @S9S_MB_2U_LIB.S9S_MB_2U(SCH_1):PAGE275

PC1369 Q_CAP_0402-0.1UF,25V,10%,X7R,CA
     1    GND @S9S_MB_2U_LIB.S9S_MB_2U(SCH_1):GND    I23 @S9S_MB_2U_LIB.S9S_MB_2U(SCH_1):PAGE276
     2 PVCCIN_CPU1_VREF @S9S_MB_2U_LIB.S9S_MB_2U(SCH_1):PVCCIN_CPU1_VREF    I23 @S9S_MB_2U_LIB.S9S_MB_2U(SCH_1):PAGE276

PC1370 Q_CAP_0402-0.1UF,25V,10%,X7R,CA
     1    GND @S9S_MB_2U_LIB.S9S_MB_2U(SCH_1):GND    I13 @S9S_MB_2U_LIB.S9S_MB_2U(SCH_1):PAGE276
     2 PVCCIN_CPU1_VREF @S9S_MB_2U_LIB.S9S_MB_2U(SCH_1):PVCCIN_CPU1_VREF    I13 @S9S_MB_2U_LIB.S9S_MB_2U(SCH_1):PAGE276

PC1371 Q_CAP_0402-0.1UF,25V,10%,X7R,CA
     1    GND @S9S_MB_2U_LIB.S9S_MB_2U(SCH_1):GND     I8 @S9S_MB_2U_LIB.S9S_MB_2U(SCH_1):PAGE283
     2 PVCCD_HV_CPU1_VREF @S9S_MB_2U_LIB.S9S_MB_2U(SCH_1):PVCCD_HV_CPU1_VREF     I8 @S9S_MB_2U_LIB.S9S_MB_2U(SCH_1):PAGE283

PC1372 Q_CAP_C0402-1UF,16V,10%,X6S,CHA
     1 PVCCINFAON_CPU0_VREF @S9S_MB_2U_LIB.S9S_MB_2U(SCH_1):PVCCINFAON_CPU0_VREF    I95 @S9S_MB_2U_LIB.S9S_MB_2U(SCH_1):PAGE260
     2    GND @S9S_MB_2U_LIB.S9S_MB_2U(SCH_1):GND    I95 @S9S_MB_2U_LIB.S9S_MB_2U(SCH_1):PAGE260

PC1420 Q_CAP_0402-0.01UF,25V,10%,X7R,A
     1 PVNN_MAIN_CPU0_FB_RC @S9S_MB_2U_LIB.S9S_MB_2U(SCH_1):PVNN_MAIN_CPU0_FB_RC    I39 @S9S_MB_2U_LIB.S9S_MB_2U(SCH_1):PAGE268
     2    GND @S9S_MB_2U_LIB.S9S_MB_2U(SCH_1):GND    I39 @S9S_MB_2U_LIB.S9S_MB_2U(SCH_1):PAGE268

PC1421 Q_CAP_0402-0.01UF,25V,10%,X7R,A
     1 SH_PVPP_HBM_CPU0_P @S9S_MB_2U_LIB.S9S_MB_2U(SCH_1):SH_PVPP_HBM_CPU0_P    I40 @S9S_MB_2U_LIB.S9S_MB_2U(SCH_1):PAGE267
     2 SH_PVPP_HBM_CPU0_N @S9S_MB_2U_LIB.S9S_MB_2U(SCH_1):SH_PVPP_HBM_CPU0_N    I40 @S9S_MB_2U_LIB.S9S_MB_2U(SCH_1):PAGE267

PC1525 Q_CAP_C0402-1UF,25V,10%,X6S,CHA
     1 HSC_VDD_R_1 @S9S_MB_2U_LIB.S9S_MB_2U(SCH_1):HSC_VDD_R_1    I20 @S9S_MB_2U_LIB.S9S_MB_2U(SCH_1):PAGE301
     2 AGND_HSC @S9S_MB_2U_LIB.S9S_MB_2U(SCH_1):AGND_HSC    I20 @S9S_MB_2U_LIB.S9S_MB_2U(SCH_1):PAGE301

PC1573 Q_CAPP_SMLF-330UF,2V,35%,SPCAPA
     1 PVCCINFAON_CPU0 @S9S_MB_2U_LIB.S9S_MB_2U(SCH_1):PVCCINFAON_CPU0    I68 @S9S_MB_2U_LIB.S9S_MB_2U(SCH_1):PAGE261
     2    GND @S9S_MB_2U_LIB.S9S_MB_2U(SCH_1):GND    I68 @S9S_MB_2U_LIB.S9S_MB_2U(SCH_1):PAGE261

PC1574 Q_CAPP_THLF-560UF,2.5V,20%,OSCA
     1 PVCCINFAON_CPU0 @S9S_MB_2U_LIB.S9S_MB_2U(SCH_1):PVCCINFAON_CPU0    I66 @S9S_MB_2U_LIB.S9S_MB_2U(SCH_1):PAGE261
     2    GND @S9S_MB_2U_LIB.S9S_MB_2U(SCH_1):GND    I66 @S9S_MB_2U_LIB.S9S_MB_2U(SCH_1):PAGE261

PC1575 Q_CAPP_SMLF-330UF,2V,35%,SPCAPA
     1 PVCCINFAON_CPU0 @S9S_MB_2U_LIB.S9S_MB_2U(SCH_1):PVCCINFAON_CPU0    I69 @S9S_MB_2U_LIB.S9S_MB_2U(SCH_1):PAGE261
     2    GND @S9S_MB_2U_LIB.S9S_MB_2U(SCH_1):GND    I69 @S9S_MB_2U_LIB.S9S_MB_2U(SCH_1):PAGE261

PC1576 Q_CAPP_THLF-560UF,2.5V,20%,OSCA
     1 PVCCINFAON_CPU0 @S9S_MB_2U_LIB.S9S_MB_2U(SCH_1):PVCCINFAON_CPU0    I67 @S9S_MB_2U_LIB.S9S_MB_2U(SCH_1):PAGE261
     2    GND @S9S_MB_2U_LIB.S9S_MB_2U(SCH_1):GND    I67 @S9S_MB_2U_LIB.S9S_MB_2U(SCH_1):PAGE261

PC1579 Q_CAPP_THLF-560UF,2.5V,20%,OSCA
     1 PVCCINFAON_CPU0 @S9S_MB_2U_LIB.S9S_MB_2U(SCH_1):PVCCINFAON_CPU0    I70 @S9S_MB_2U_LIB.S9S_MB_2U(SCH_1):PAGE261
     2    GND @S9S_MB_2U_LIB.S9S_MB_2U(SCH_1):GND    I70 @S9S_MB_2U_LIB.S9S_MB_2U(SCH_1):PAGE261

PC1588 Q_CAPP_SMLF-330UF,2V,35%,SPCAPA
     1 PVCCINFAON_CPU1 @S9S_MB_2U_LIB.S9S_MB_2U(SCH_1):PVCCINFAON_CPU1    I61 @S9S_MB_2U_LIB.S9S_MB_2U(SCH_1):PAGE279
     2    GND @S9S_MB_2U_LIB.S9S_MB_2U(SCH_1):GND    I61 @S9S_MB_2U_LIB.S9S_MB_2U(SCH_1):PAGE279

PC1593 Q_CAPP_THLF-560UF,2.5V,20%,OSCA
     1 PVCCINFAON_CPU1 @S9S_MB_2U_LIB.S9S_MB_2U(SCH_1):PVCCINFAON_CPU1    I59 @S9S_MB_2U_LIB.S9S_MB_2U(SCH_1):PAGE279
     2    GND @S9S_MB_2U_LIB.S9S_MB_2U(SCH_1):GND    I59 @S9S_MB_2U_LIB.S9S_MB_2U(SCH_1):PAGE279

PC1594 Q_CAPP_SMLF-330UF,2V,35%,SPCAPA
     1 PVCCINFAON_CPU1 @S9S_MB_2U_LIB.S9S_MB_2U(SCH_1):PVCCINFAON_CPU1    I62 @S9S_MB_2U_LIB.S9S_MB_2U(SCH_1):PAGE279
     2    GND @S9S_MB_2U_LIB.S9S_MB_2U(SCH_1):GND    I62 @S9S_MB_2U_LIB.S9S_MB_2U(SCH_1):PAGE279

PC1595 Q_CAPP_THLF-560UF,2.5V,20%,OSCA
     1 PVCCINFAON_CPU1 @S9S_MB_2U_LIB.S9S_MB_2U(SCH_1):PVCCINFAON_CPU1    I60 @S9S_MB_2U_LIB.S9S_MB_2U(SCH_1):PAGE279
     2    GND @S9S_MB_2U_LIB.S9S_MB_2U(SCH_1):GND    I60 @S9S_MB_2U_LIB.S9S_MB_2U(SCH_1):PAGE279

PC1596 Q_CAPP_THLF-560UF,2.5V,20%,OSCA
     1 PVCCINFAON_CPU1 @S9S_MB_2U_LIB.S9S_MB_2U(SCH_1):PVCCINFAON_CPU1    I71 @S9S_MB_2U_LIB.S9S_MB_2U(SCH_1):PAGE279
     2    GND @S9S_MB_2U_LIB.S9S_MB_2U(SCH_1):GND    I71 @S9S_MB_2U_LIB.S9S_MB_2U(SCH_1):PAGE279

PC1599 Q_CAP_C0805-22UF,10V,20%,X6S,CA
     1 P3V3_AUX @S9S_MB_2U_LIB.S9S_MB_2U(SCH_1):P3V3_AUX   I134 @S9S_MB_2U_LIB.S9S_MB_2U(SCH_1):PAGE245
     2    GND @S9S_MB_2U_LIB.S9S_MB_2U(SCH_1):GND   I134 @S9S_MB_2U_LIB.S9S_MB_2U(SCH_1):PAGE245

PC1600 Q_CAP_C0805-22UF,10V,20%,X6S,CA
     1 P3V3_AUX @S9S_MB_2U_LIB.S9S_MB_2U(SCH_1):P3V3_AUX   I136 @S9S_MB_2U_LIB.S9S_MB_2U(SCH_1):PAGE245
     2    GND @S9S_MB_2U_LIB.S9S_MB_2U(SCH_1):GND   I136 @S9S_MB_2U_LIB.S9S_MB_2U(SCH_1):PAGE245

PC1642 Q_CAP_C0402-1UF,25V,10%,X6S,CHA
     1 P1V8_PCH_AUX_VCC @S9S_MB_2U_LIB.S9S_MB_2U(SCH_1):P1V8_PCH_AUX_VCC     I4 @S9S_MB_2U_LIB.S9S_MB_2U(SCH_1):PAGE249
     2    GND @S9S_MB_2U_LIB.S9S_MB_2U(SCH_1):GND     I4 @S9S_MB_2U_LIB.S9S_MB_2U(SCH_1):PAGE249

PC1644 Q_CAPP_THLF-560UF,2.5V,20%,OSCA
     1 PVCCD_HV_CPU0 @S9S_MB_2U_LIB.S9S_MB_2U(SCH_1):PVCCD_HV_CPU0    I27 @S9S_MB_2U_LIB.S9S_MB_2U(SCH_1):PAGE265
     2    GND @S9S_MB_2U_LIB.S9S_MB_2U(SCH_1):GND    I27 @S9S_MB_2U_LIB.S9S_MB_2U(SCH_1):PAGE265

PC1645 Q_CAPP_THLF-560UF,2.5V,20%,OSCA
     1 PVCCD_HV_CPU0 @S9S_MB_2U_LIB.S9S_MB_2U(SCH_1):PVCCD_HV_CPU0    I34 @S9S_MB_2U_LIB.S9S_MB_2U(SCH_1):PAGE265
     2    GND @S9S_MB_2U_LIB.S9S_MB_2U(SCH_1):GND    I34 @S9S_MB_2U_LIB.S9S_MB_2U(SCH_1):PAGE265

PC1648 Q_CAP_C0402-100NF,50V,10%,X7R,A
     1 P12V_AUX @S9S_MB_2U_LIB.S9S_MB_2U(SCH_1):P12V_AUX     I2 @S9S_MB_2U_LIB.S9S_MB_2U(SCH_1):PAGE244
     2    GND @S9S_MB_2U_LIB.S9S_MB_2U(SCH_1):GND     I2 @S9S_MB_2U_LIB.S9S_MB_2U(SCH_1):PAGE244

PC1649 Q_CAP_C0402-100NF,50V,10%,X7R,A
     1 P12V_AUX @S9S_MB_2U_LIB.S9S_MB_2U(SCH_1):P12V_AUX    I97 @S9S_MB_2U_LIB.S9S_MB_2U(SCH_1):PAGE245
     2    GND @S9S_MB_2U_LIB.S9S_MB_2U(SCH_1):GND    I97 @S9S_MB_2U_LIB.S9S_MB_2U(SCH_1):PAGE245

PC1650 Q_CAP_C0402-100NF,50V,10%,X7R,A
     1 P12V_AUX @S9S_MB_2U_LIB.S9S_MB_2U(SCH_1):P12V_AUX    I18 @S9S_MB_2U_LIB.S9S_MB_2U(SCH_1):PAGE248
     2    GND @S9S_MB_2U_LIB.S9S_MB_2U(SCH_1):GND    I18 @S9S_MB_2U_LIB.S9S_MB_2U(SCH_1):PAGE248

PC1651 Q_CAP_C0402-100NF,50V,10%,X7R,A
     1 P12V_AUX @S9S_MB_2U_LIB.S9S_MB_2U(SCH_1):P12V_AUX    I14 @S9S_MB_2U_LIB.S9S_MB_2U(SCH_1):PAGE249
     2    GND @S9S_MB_2U_LIB.S9S_MB_2U(SCH_1):GND    I14 @S9S_MB_2U_LIB.S9S_MB_2U(SCH_1):PAGE249

PC1652 Q_CAP_C0402-100NF,50V,10%,X7R,A
     1 P12V_AUX @S9S_MB_2U_LIB.S9S_MB_2U(SCH_1):P12V_AUX    I80 @S9S_MB_2U_LIB.S9S_MB_2U(SCH_1):PAGE253
     2    GND @S9S_MB_2U_LIB.S9S_MB_2U(SCH_1):GND    I80 @S9S_MB_2U_LIB.S9S_MB_2U(SCH_1):PAGE253

PC1653 Q_CAP_C0402-100NF,50V,10%,X7R,A
     1 P12V_AUX @S9S_MB_2U_LIB.S9S_MB_2U(SCH_1):P12V_AUX    I78 @S9S_MB_2U_LIB.S9S_MB_2U(SCH_1):PAGE257
     2    GND @S9S_MB_2U_LIB.S9S_MB_2U(SCH_1):GND    I78 @S9S_MB_2U_LIB.S9S_MB_2U(SCH_1):PAGE257

PC1654 Q_CAP_C0402-100NF,50V,10%,X7R,A
     1 P12V_AUX @S9S_MB_2U_LIB.S9S_MB_2U(SCH_1):P12V_AUX    I57 @S9S_MB_2U_LIB.S9S_MB_2U(SCH_1):PAGE258
     2    GND @S9S_MB_2U_LIB.S9S_MB_2U(SCH_1):GND    I57 @S9S_MB_2U_LIB.S9S_MB_2U(SCH_1):PAGE258

PC1655 Q_CAP_C0402-100NF,50V,10%,X7R,A
     1 P12V_AUX @S9S_MB_2U_LIB.S9S_MB_2U(SCH_1):P12V_AUX    I60 @S9S_MB_2U_LIB.S9S_MB_2U(SCH_1):PAGE261
     2    GND @S9S_MB_2U_LIB.S9S_MB_2U(SCH_1):GND    I60 @S9S_MB_2U_LIB.S9S_MB_2U(SCH_1):PAGE261

PC1656 Q_CAP_C0402-100NF,50V,10%,X7R,A
     1 P12V_AUX @S9S_MB_2U_LIB.S9S_MB_2U(SCH_1):P12V_AUX    I79 @S9S_MB_2U_LIB.S9S_MB_2U(SCH_1):PAGE271
     2    GND @S9S_MB_2U_LIB.S9S_MB_2U(SCH_1):GND    I79 @S9S_MB_2U_LIB.S9S_MB_2U(SCH_1):PAGE271

PC1657 Q_CAP_C0402-100NF,50V,10%,X7R,A
     1 P12V_AUX @S9S_MB_2U_LIB.S9S_MB_2U(SCH_1):P12V_AUX    I77 @S9S_MB_2U_LIB.S9S_MB_2U(SCH_1):PAGE275
     2    GND @S9S_MB_2U_LIB.S9S_MB_2U(SCH_1):GND    I77 @S9S_MB_2U_LIB.S9S_MB_2U(SCH_1):PAGE275

PC1658 Q_CAP_C0402-100NF,50V,10%,X7R,A
     1 P12V_AUX @S9S_MB_2U_LIB.S9S_MB_2U(SCH_1):P12V_AUX    I62 @S9S_MB_2U_LIB.S9S_MB_2U(SCH_1):PAGE276
     2    GND @S9S_MB_2U_LIB.S9S_MB_2U(SCH_1):GND    I62 @S9S_MB_2U_LIB.S9S_MB_2U(SCH_1):PAGE276

PC1659 Q_CAP_C0402-100NF,50V,10%,X7R,A
     1 P12V_AUX @S9S_MB_2U_LIB.S9S_MB_2U(SCH_1):P12V_AUX    I68 @S9S_MB_2U_LIB.S9S_MB_2U(SCH_1):PAGE279
     2    GND @S9S_MB_2U_LIB.S9S_MB_2U(SCH_1):GND    I68 @S9S_MB_2U_LIB.S9S_MB_2U(SCH_1):PAGE279

PC1669 Q_CAP_C0805-22UF,16V,20%,X6S,CA
     1 SW_P12V_PVCCFA_EHV_FIVRA_CPU0_L @S9S_MB_2U_LIB.S9S_MB_2U(SCH_1):SW_P12V_PVCCFA_EHV_FIVRA_CPU0_L    I83 @S9S_MB_2U_LIB.S9S_MB_2U(SCH_1):PAGE257
     2    GND @S9S_MB_2U_LIB.S9S_MB_2U(SCH_1):GND    I83 @S9S_MB_2U_LIB.S9S_MB_2U(SCH_1):PAGE257

PC1670 Q_CAP_C0805-22UF,16V,20%,X6S,CA
     1 SW_P12V_PVCCFA_EHV_FIVRA_CPU0_L @S9S_MB_2U_LIB.S9S_MB_2U(SCH_1):SW_P12V_PVCCFA_EHV_FIVRA_CPU0_L    I84 @S9S_MB_2U_LIB.S9S_MB_2U(SCH_1):PAGE257
     2    GND @S9S_MB_2U_LIB.S9S_MB_2U(SCH_1):GND    I84 @S9S_MB_2U_LIB.S9S_MB_2U(SCH_1):PAGE257

PC1671 Q_CAP_C0805-22UF,16V,20%,X6S,CA
     1 SW_P12V_PVCCFA_EHV_FIVRA_CPU0_L @S9S_MB_2U_LIB.S9S_MB_2U(SCH_1):SW_P12V_PVCCFA_EHV_FIVRA_CPU0_L    I85 @S9S_MB_2U_LIB.S9S_MB_2U(SCH_1):PAGE257
     2    GND @S9S_MB_2U_LIB.S9S_MB_2U(SCH_1):GND    I85 @S9S_MB_2U_LIB.S9S_MB_2U(SCH_1):PAGE257

PC1672 Q_CAP_C0805-22UF,16V,20%,X6S,CA
     1 SW_P12V_PVCCFA_EHV_FIVRA_CPU0_L @S9S_MB_2U_LIB.S9S_MB_2U(SCH_1):SW_P12V_PVCCFA_EHV_FIVRA_CPU0_L    I86 @S9S_MB_2U_LIB.S9S_MB_2U(SCH_1):PAGE257
     2    GND @S9S_MB_2U_LIB.S9S_MB_2U(SCH_1):GND    I86 @S9S_MB_2U_LIB.S9S_MB_2U(SCH_1):PAGE257

PC1673 Q_CAP_C0805-22UF,16V,20%,X6S,CA
     1 SW_P12V_PVCCFA_EHV_FIVRA_CPU0_R @S9S_MB_2U_LIB.S9S_MB_2U(SCH_1):SW_P12V_PVCCFA_EHV_FIVRA_CPU0_R    I75 @S9S_MB_2U_LIB.S9S_MB_2U(SCH_1):PAGE258
     2    GND @S9S_MB_2U_LIB.S9S_MB_2U(SCH_1):GND    I75 @S9S_MB_2U_LIB.S9S_MB_2U(SCH_1):PAGE258

PC1674 Q_CAP_C0805-22UF,16V,20%,X6S,CA
     1 SW_P12V_PVCCFA_EHV_FIVRA_CPU0_R @S9S_MB_2U_LIB.S9S_MB_2U(SCH_1):SW_P12V_PVCCFA_EHV_FIVRA_CPU0_R    I76 @S9S_MB_2U_LIB.S9S_MB_2U(SCH_1):PAGE258
     2    GND @S9S_MB_2U_LIB.S9S_MB_2U(SCH_1):GND    I76 @S9S_MB_2U_LIB.S9S_MB_2U(SCH_1):PAGE258

PC1675 Q_CAP_C0805-22UF,16V,20%,X6S,CA
     1 SW_P12V_PVCCFA_EHV_FIVRA_CPU0_R @S9S_MB_2U_LIB.S9S_MB_2U(SCH_1):SW_P12V_PVCCFA_EHV_FIVRA_CPU0_R    I77 @S9S_MB_2U_LIB.S9S_MB_2U(SCH_1):PAGE258
     2    GND @S9S_MB_2U_LIB.S9S_MB_2U(SCH_1):GND    I77 @S9S_MB_2U_LIB.S9S_MB_2U(SCH_1):PAGE258

PC1676 Q_CAP_C0805-22UF,16V,20%,X6S,CA
     1 SW_P12V_PVCCFA_EHV_FIVRA_CPU0_R @S9S_MB_2U_LIB.S9S_MB_2U(SCH_1):SW_P12V_PVCCFA_EHV_FIVRA_CPU0_R    I79 @S9S_MB_2U_LIB.S9S_MB_2U(SCH_1):PAGE258
     2    GND @S9S_MB_2U_LIB.S9S_MB_2U(SCH_1):GND    I79 @S9S_MB_2U_LIB.S9S_MB_2U(SCH_1):PAGE258

PC1677 Q_CAP_C0805-22UF,16V,20%,X6S,CA
     1 SW_P12V_PVCCFA_EHV_FIVRA_CPU1_L @S9S_MB_2U_LIB.S9S_MB_2U(SCH_1):SW_P12V_PVCCFA_EHV_FIVRA_CPU1_L    I80 @S9S_MB_2U_LIB.S9S_MB_2U(SCH_1):PAGE275
     2    GND @S9S_MB_2U_LIB.S9S_MB_2U(SCH_1):GND    I80 @S9S_MB_2U_LIB.S9S_MB_2U(SCH_1):PAGE275

PC1678 Q_CAP_C0805-22UF,16V,20%,X6S,CA
     1 SW_P12V_PVCCFA_EHV_FIVRA_CPU1_L @S9S_MB_2U_LIB.S9S_MB_2U(SCH_1):SW_P12V_PVCCFA_EHV_FIVRA_CPU1_L    I83 @S9S_MB_2U_LIB.S9S_MB_2U(SCH_1):PAGE275
     2    GND @S9S_MB_2U_LIB.S9S_MB_2U(SCH_1):GND    I83 @S9S_MB_2U_LIB.S9S_MB_2U(SCH_1):PAGE275

PC1679 Q_CAP_C0805-22UF,16V,20%,X6S,CA
     1 SW_P12V_PVCCFA_EHV_FIVRA_CPU1_L @S9S_MB_2U_LIB.S9S_MB_2U(SCH_1):SW_P12V_PVCCFA_EHV_FIVRA_CPU1_L    I84 @S9S_MB_2U_LIB.S9S_MB_2U(SCH_1):PAGE275
     2    GND @S9S_MB_2U_LIB.S9S_MB_2U(SCH_1):GND    I84 @S9S_MB_2U_LIB.S9S_MB_2U(SCH_1):PAGE275

PC1680 Q_CAP_C0805-22UF,16V,20%,X6S,CA
     1 SW_P12V_PVCCFA_EHV_FIVRA_CPU1_L @S9S_MB_2U_LIB.S9S_MB_2U(SCH_1):SW_P12V_PVCCFA_EHV_FIVRA_CPU1_L    I85 @S9S_MB_2U_LIB.S9S_MB_2U(SCH_1):PAGE275
     2    GND @S9S_MB_2U_LIB.S9S_MB_2U(SCH_1):GND    I85 @S9S_MB_2U_LIB.S9S_MB_2U(SCH_1):PAGE275

PC1681 Q_CAP_C0805-22UF,16V,20%,X6S,CA
     1 SW_P12V_PVCCFA_EHV_FIVRA_CPU1_R @S9S_MB_2U_LIB.S9S_MB_2U(SCH_1):SW_P12V_PVCCFA_EHV_FIVRA_CPU1_R    I75 @S9S_MB_2U_LIB.S9S_MB_2U(SCH_1):PAGE276
     2    GND @S9S_MB_2U_LIB.S9S_MB_2U(SCH_1):GND    I75 @S9S_MB_2U_LIB.S9S_MB_2U(SCH_1):PAGE276

PC1682 Q_CAP_C0805-22UF,16V,20%,X6S,CA
     1 SW_P12V_PVCCFA_EHV_FIVRA_CPU1_R @S9S_MB_2U_LIB.S9S_MB_2U(SCH_1):SW_P12V_PVCCFA_EHV_FIVRA_CPU1_R    I77 @S9S_MB_2U_LIB.S9S_MB_2U(SCH_1):PAGE276
     2    GND @S9S_MB_2U_LIB.S9S_MB_2U(SCH_1):GND    I77 @S9S_MB_2U_LIB.S9S_MB_2U(SCH_1):PAGE276

PC1683 Q_CAP_C0805-22UF,16V,20%,X6S,CA
     1 SW_P12V_PVCCFA_EHV_FIVRA_CPU1_R @S9S_MB_2U_LIB.S9S_MB_2U(SCH_1):SW_P12V_PVCCFA_EHV_FIVRA_CPU1_R    I78 @S9S_MB_2U_LIB.S9S_MB_2U(SCH_1):PAGE276
     2    GND @S9S_MB_2U_LIB.S9S_MB_2U(SCH_1):GND    I78 @S9S_MB_2U_LIB.S9S_MB_2U(SCH_1):PAGE276

PC1684 Q_CAP_C0805-22UF,16V,20%,X6S,CA
     1 SW_P12V_PVCCFA_EHV_FIVRA_CPU1_R @S9S_MB_2U_LIB.S9S_MB_2U(SCH_1):SW_P12V_PVCCFA_EHV_FIVRA_CPU1_R    I80 @S9S_MB_2U_LIB.S9S_MB_2U(SCH_1):PAGE276
     2    GND @S9S_MB_2U_LIB.S9S_MB_2U(SCH_1):GND    I80 @S9S_MB_2U_LIB.S9S_MB_2U(SCH_1):PAGE276

PC1750 Q_CAP_C0402-33NF,25V,10%,EMPTYA
     1 P12V_AUX @S9S_MB_2U_LIB.S9S_MB_2U(SCH_1):P12V_AUX    I68 @S9S_MB_2U_LIB.S9S_MB_2U(SCH_1):PAGE328
     2 P12V_HSC_GATE2 @S9S_MB_2U_LIB.S9S_MB_2U(SCH_1):P12V_HSC_GATE2    I68 @S9S_MB_2U_LIB.S9S_MB_2U(SCH_1):PAGE328

PC1751 Q_CAP_0402-1NF,50V,10%,EMPTY,CA
     1 P12V_HSC_GATE_RC @S9S_MB_2U_LIB.S9S_MB_2U(SCH_1):P12V_HSC_GATE_RC    I69 @S9S_MB_2U_LIB.S9S_MB_2U(SCH_1):PAGE328
     2 P12V_HSC_GATE2 @S9S_MB_2U_LIB.S9S_MB_2U(SCH_1):P12V_HSC_GATE2    I69 @S9S_MB_2U_LIB.S9S_MB_2U(SCH_1):PAGE328

PC1771 Q_CAPP_THLF-560UF,6.3V,20%,OSCA
     1 PVPP_HBM_CPU1 @S9S_MB_2U_LIB.S9S_MB_2U(SCH_1):PVPP_HBM_CPU1    I49 @S9S_MB_2U_LIB.S9S_MB_2U(SCH_1):PAGE285
     2    GND @S9S_MB_2U_LIB.S9S_MB_2U(SCH_1):GND    I49 @S9S_MB_2U_LIB.S9S_MB_2U(SCH_1):PAGE285

PC1789 Q_CAP_0402-0.1UF,25V,10%,EMPTYA
     1 P12V_AUX @S9S_MB_2U_LIB.S9S_MB_2U(SCH_1):P12V_AUX    I38 @S9S_MB_2U_LIB.S9S_MB_2U(SCH_1):PAGE327
     2    GND @S9S_MB_2U_LIB.S9S_MB_2U(SCH_1):GND    I38 @S9S_MB_2U_LIB.S9S_MB_2U(SCH_1):PAGE327

PC1845 Q_CAPP_SMLF-220UF,6.3V,20%,ALUA
     1 P5V_AUX @S9S_MB_2U_LIB.S9S_MB_2U(SCH_1):P5V_AUX    I32 @S9S_MB_2U_LIB.S9S_MB_2U(SCH_1):PAGE244
     2    GND @S9S_MB_2U_LIB.S9S_MB_2U(SCH_1):GND    I32 @S9S_MB_2U_LIB.S9S_MB_2U(SCH_1):PAGE244

PC1846 Q_CAP_C0402-1UF,16V,10%,X6S,CHA
     1 SW_P5V_AUX_FLT @S9S_MB_2U_LIB.S9S_MB_2U(SCH_1):SW_P5V_AUX_FLT    I14 @S9S_MB_2U_LIB.S9S_MB_2U(SCH_1):PAGE244
     2    GND @S9S_MB_2U_LIB.S9S_MB_2U(SCH_1):GND    I14 @S9S_MB_2U_LIB.S9S_MB_2U(SCH_1):PAGE244

PC1847 Q_CAP_C0402-0.22UF,25V,10%,X7RA
     1 SW_P5V_AUX_BST @S9S_MB_2U_LIB.S9S_MB_2U(SCH_1):SW_P5V_AUX_BST    I26 @S9S_MB_2U_LIB.S9S_MB_2U(SCH_1):PAGE244
     2 SW_P5V_AUX_SW @S9S_MB_2U_LIB.S9S_MB_2U(SCH_1):SW_P5V_AUX_SW    I26 @S9S_MB_2U_LIB.S9S_MB_2U(SCH_1):PAGE244

PC1848 Q_CAP_C0402-1UF,25V,10%,X6S,CHA
     1 P5V_AUX_VCC @S9S_MB_2U_LIB.S9S_MB_2U(SCH_1):P5V_AUX_VCC     I8 @S9S_MB_2U_LIB.S9S_MB_2U(SCH_1):PAGE244
     2    GND @S9S_MB_2U_LIB.S9S_MB_2U(SCH_1):GND     I8 @S9S_MB_2U_LIB.S9S_MB_2U(SCH_1):PAGE244

PC1849 Q_CAP_C0805-22UF,16V,20%,X6S,CA
     1 SW_P5V_AUX_FLT @S9S_MB_2U_LIB.S9S_MB_2U(SCH_1):SW_P5V_AUX_FLT     I7 @S9S_MB_2U_LIB.S9S_MB_2U(SCH_1):PAGE244
     2    GND @S9S_MB_2U_LIB.S9S_MB_2U(SCH_1):GND     I7 @S9S_MB_2U_LIB.S9S_MB_2U(SCH_1):PAGE244

PC1850 Q_CAP_C0805-22UF,16V,20%,X6S,CA
     1 SW_P5V_AUX_FLT @S9S_MB_2U_LIB.S9S_MB_2U(SCH_1):SW_P5V_AUX_FLT    I11 @S9S_MB_2U_LIB.S9S_MB_2U(SCH_1):PAGE244
     2    GND @S9S_MB_2U_LIB.S9S_MB_2U(SCH_1):GND    I11 @S9S_MB_2U_LIB.S9S_MB_2U(SCH_1):PAGE244

PC1852 Q_CAP_0402-0.1UF,25V,10%,X7R,CA
     1 P5V_AUX @S9S_MB_2U_LIB.S9S_MB_2U(SCH_1):P5V_AUX    I36 @S9S_MB_2U_LIB.S9S_MB_2U(SCH_1):PAGE244
     2    GND @S9S_MB_2U_LIB.S9S_MB_2U(SCH_1):GND    I36 @S9S_MB_2U_LIB.S9S_MB_2U(SCH_1):PAGE244

PC1853 Q_CAP_0402-0.1UF,25V,10%,X7R,CA
     1 P5V_AUX_REF @S9S_MB_2U_LIB.S9S_MB_2U(SCH_1):P5V_AUX_REF    I21 @S9S_MB_2U_LIB.S9S_MB_2U(SCH_1):PAGE244
     2    GND @S9S_MB_2U_LIB.S9S_MB_2U(SCH_1):GND    I21 @S9S_MB_2U_LIB.S9S_MB_2U(SCH_1):PAGE244

PC1855 Q_CAP_C0805-22UF,10V,20%,X6S,CA
     1 P5V_AUX @S9S_MB_2U_LIB.S9S_MB_2U(SCH_1):P5V_AUX    I33 @S9S_MB_2U_LIB.S9S_MB_2U(SCH_1):PAGE244
     2    GND @S9S_MB_2U_LIB.S9S_MB_2U(SCH_1):GND    I33 @S9S_MB_2U_LIB.S9S_MB_2U(SCH_1):PAGE244

PC1856 Q_CAP_C0805-22UF,10V,20%,X6S,CA
     1 P5V_AUX @S9S_MB_2U_LIB.S9S_MB_2U(SCH_1):P5V_AUX    I34 @S9S_MB_2U_LIB.S9S_MB_2U(SCH_1):PAGE244
     2    GND @S9S_MB_2U_LIB.S9S_MB_2U(SCH_1):GND    I34 @S9S_MB_2U_LIB.S9S_MB_2U(SCH_1):PAGE244

PC1866 Q_CAPP_THLF-560UF,6.3V,20%,OSCA
     1 P3V3_AUX @S9S_MB_2U_LIB.S9S_MB_2U(SCH_1):P3V3_AUX   I131 @S9S_MB_2U_LIB.S9S_MB_2U(SCH_1):PAGE245
     2    GND @S9S_MB_2U_LIB.S9S_MB_2U(SCH_1):GND   I131 @S9S_MB_2U_LIB.S9S_MB_2U(SCH_1):PAGE245

PC1867 Q_CAPP_THLF-560UF,6.3V,20%,OSCA
     1 P3V3_AUX @S9S_MB_2U_LIB.S9S_MB_2U(SCH_1):P3V3_AUX   I132 @S9S_MB_2U_LIB.S9S_MB_2U(SCH_1):PAGE245
     2    GND @S9S_MB_2U_LIB.S9S_MB_2U(SCH_1):GND   I132 @S9S_MB_2U_LIB.S9S_MB_2U(SCH_1):PAGE245

PC1868 Q_CAP_C0805-22UF,10V,20%,X6S,CA
     1 P3V3_AUX @S9S_MB_2U_LIB.S9S_MB_2U(SCH_1):P3V3_AUX   I133 @S9S_MB_2U_LIB.S9S_MB_2U(SCH_1):PAGE245
     2    GND @S9S_MB_2U_LIB.S9S_MB_2U(SCH_1):GND   I133 @S9S_MB_2U_LIB.S9S_MB_2U(SCH_1):PAGE245

PC1869 Q_CAP_0402-0.1UF,25V,10%,X7R,CA
     1 P3V3_AUX @S9S_MB_2U_LIB.S9S_MB_2U(SCH_1):P3V3_AUX   I137 @S9S_MB_2U_LIB.S9S_MB_2U(SCH_1):PAGE245
     2    GND @S9S_MB_2U_LIB.S9S_MB_2U(SCH_1):GND   I137 @S9S_MB_2U_LIB.S9S_MB_2U(SCH_1):PAGE245

PC1877 Q_CAP_0402-47PF,50V,5%,NPO,TMPA
     1 P5V_AUX_FB @S9S_MB_2U_LIB.S9S_MB_2U(SCH_1):P5V_AUX_FB    I22 @S9S_MB_2U_LIB.S9S_MB_2U(SCH_1):PAGE244
     2 P5V_AUX @S9S_MB_2U_LIB.S9S_MB_2U(SCH_1):P5V_AUX    I22 @S9S_MB_2U_LIB.S9S_MB_2U(SCH_1):PAGE244

PC1898 Q_CAP_C0805-22UF,16V,20%,X6S,CA
     1 SW_P5V_AUX_FLT @S9S_MB_2U_LIB.S9S_MB_2U(SCH_1):SW_P5V_AUX_FLT    I12 @S9S_MB_2U_LIB.S9S_MB_2U(SCH_1):PAGE244
     2    GND @S9S_MB_2U_LIB.S9S_MB_2U(SCH_1):GND    I12 @S9S_MB_2U_LIB.S9S_MB_2U(SCH_1):PAGE244

PC1900 Q_CAPP_SMLF-330UF,2.5V,+10/-35B
     1 PVCCFA_EHV_CPU0 @S9S_MB_2U_LIB.S9S_MB_2U(SCH_1):PVCCFA_EHV_CPU0    I34 @S9S_MB_2U_LIB.S9S_MB_2U(SCH_1):PAGE262
     2    GND @S9S_MB_2U_LIB.S9S_MB_2U(SCH_1):GND    I34 @S9S_MB_2U_LIB.S9S_MB_2U(SCH_1):PAGE262

PC1910 Q_CAPP_SMLF-330UF,2V,35%,SPCAPA
     1 PVCCD_HV_CPU0 @S9S_MB_2U_LIB.S9S_MB_2U(SCH_1):PVCCD_HV_CPU0    I26 @S9S_MB_2U_LIB.S9S_MB_2U(SCH_1):PAGE265
     2    GND @S9S_MB_2U_LIB.S9S_MB_2U(SCH_1):GND    I26 @S9S_MB_2U_LIB.S9S_MB_2U(SCH_1):PAGE265

PC1920 Q_CAPP_SMLF-330UF,2.5V,+10/-35A
     1 PVCCIN_CPU0 @S9S_MB_2U_LIB.S9S_MB_2U(SCH_1):PVCCIN_CPU0    I63 @S9S_MB_2U_LIB.S9S_MB_2U(SCH_1):PAGE253
     2    GND @S9S_MB_2U_LIB.S9S_MB_2U(SCH_1):GND    I63 @S9S_MB_2U_LIB.S9S_MB_2U(SCH_1):PAGE253

PC1930 Q_CAPP_SMLF-330UF,2.5V,+10/-35B
     1 PVCCFA_EHV_CPU1 @S9S_MB_2U_LIB.S9S_MB_2U(SCH_1):PVCCFA_EHV_CPU1    I33 @S9S_MB_2U_LIB.S9S_MB_2U(SCH_1):PAGE280
     2    GND @S9S_MB_2U_LIB.S9S_MB_2U(SCH_1):GND    I33 @S9S_MB_2U_LIB.S9S_MB_2U(SCH_1):PAGE280

PC1940 Q_CAPP_SMLF-330UF,2V,35%,SPCAPA
     1 PVCCD_HV_CPU1 @S9S_MB_2U_LIB.S9S_MB_2U(SCH_1):PVCCD_HV_CPU1    I25 @S9S_MB_2U_LIB.S9S_MB_2U(SCH_1):PAGE283
     2    GND @S9S_MB_2U_LIB.S9S_MB_2U(SCH_1):GND    I25 @S9S_MB_2U_LIB.S9S_MB_2U(SCH_1):PAGE283

PC1990 Q_CAPP_SMLF-330UF,2.5V,+10/-35A
     1 PVCCIN_CPU1 @S9S_MB_2U_LIB.S9S_MB_2U(SCH_1):PVCCIN_CPU1    I61 @S9S_MB_2U_LIB.S9S_MB_2U(SCH_1):PAGE271
     2    GND @S9S_MB_2U_LIB.S9S_MB_2U(SCH_1):GND    I61 @S9S_MB_2U_LIB.S9S_MB_2U(SCH_1):PAGE271

PC2000 Q_CAP_0402-0.022UF,16V,10%,X7RA
     1 P1V05_PCH_AUX_REF @S9S_MB_2U_LIB.S9S_MB_2U(SCH_1):P1V05_PCH_AUX_REF    I14 @S9S_MB_2U_LIB.S9S_MB_2U(SCH_1):PAGE248
     2    GND @S9S_MB_2U_LIB.S9S_MB_2U(SCH_1):GND    I14 @S9S_MB_2U_LIB.S9S_MB_2U(SCH_1):PAGE248

PC2001 Q_CAP_0402-0.022UF,16V,10%,X7RA
     1 PVPP_HBM_CPU0_REF @S9S_MB_2U_LIB.S9S_MB_2U(SCH_1):PVPP_HBM_CPU0_REF    I23 @S9S_MB_2U_LIB.S9S_MB_2U(SCH_1):PAGE267
     2    GND @S9S_MB_2U_LIB.S9S_MB_2U(SCH_1):GND    I23 @S9S_MB_2U_LIB.S9S_MB_2U(SCH_1):PAGE267

PC2002 Q_CAP_0402-0.022UF,16V,10%,X7RA
     1 PVPP_HBM_CPU1_REF @S9S_MB_2U_LIB.S9S_MB_2U(SCH_1):PVPP_HBM_CPU1_REF    I23 @S9S_MB_2U_LIB.S9S_MB_2U(SCH_1):PAGE285
     2    GND @S9S_MB_2U_LIB.S9S_MB_2U(SCH_1):GND    I23 @S9S_MB_2U_LIB.S9S_MB_2U(SCH_1):PAGE285

PC2079 Q_CAP_C0402-1UF,25V,10%,X6S,CHA
     1 P12V_AUX @S9S_MB_2U_LIB.S9S_MB_2U(SCH_1):P12V_AUX    I44 @S9S_MB_2U_LIB.S9S_MB_2U(SCH_1):PAGE153
     2    GND @S9S_MB_2U_LIB.S9S_MB_2U(SCH_1):GND    I44 @S9S_MB_2U_LIB.S9S_MB_2U(SCH_1):PAGE153

PC2080 Q_CAP_C0805-22UF,16V,20%,X6S,CC
     1 P12V_OCP_SFF @S9S_MB_2U_LIB.S9S_MB_2U(SCH_1):P12V_OCP_SFF    I94 @S9S_MB_2U_LIB.S9S_MB_2U(SCH_1):PAGE153
     2    GND @S9S_MB_2U_LIB.S9S_MB_2U(SCH_1):GND    I94 @S9S_MB_2U_LIB.S9S_MB_2U(SCH_1):PAGE153

PC2081 Q_CAP_C0805-10UF,16V,10%,X6S,CB
     1 P3V3_OCP_SFF_R @S9S_MB_2U_LIB.S9S_MB_2U(SCH_1):P3V3_OCP_SFF_R   I113 @S9S_MB_2U_LIB.S9S_MB_2U(SCH_1):PAGE153
     2    GND @S9S_MB_2U_LIB.S9S_MB_2U(SCH_1):GND   I113 @S9S_MB_2U_LIB.S9S_MB_2U(SCH_1):PAGE153

PC2082 Q_CAP_C0805-10UF,16V,10%,X6S,CC
     1 P12V_OCP_SFF @S9S_MB_2U_LIB.S9S_MB_2U(SCH_1):P12V_OCP_SFF    I96 @S9S_MB_2U_LIB.S9S_MB_2U(SCH_1):PAGE153
     2    GND @S9S_MB_2U_LIB.S9S_MB_2U(SCH_1):GND    I96 @S9S_MB_2U_LIB.S9S_MB_2U(SCH_1):PAGE153

PC2085 Q_CAP_C0402-1UF,25V,10%,EMPTY,A
     1 P12V_OCP_VCC_1 @S9S_MB_2U_LIB.S9S_MB_2U(SCH_1):P12V_OCP_VCC_1    I55 @S9S_MB_2U_LIB.S9S_MB_2U(SCH_1):PAGE153
     2    GND @S9S_MB_2U_LIB.S9S_MB_2U(SCH_1):GND    I55 @S9S_MB_2U_LIB.S9S_MB_2U(SCH_1):PAGE153

PC2086 Q_CAP_C0402-1UF,25V,10%,X6S,CHA
     1 P3V3_OCP_VCC_1 @S9S_MB_2U_LIB.S9S_MB_2U(SCH_1):P3V3_OCP_VCC_1    I71 @S9S_MB_2U_LIB.S9S_MB_2U(SCH_1):PAGE153
     2    GND @S9S_MB_2U_LIB.S9S_MB_2U(SCH_1):GND    I71 @S9S_MB_2U_LIB.S9S_MB_2U(SCH_1):PAGE153

PC2087 Q_CAP_C0402-1UF,25V,10%,EMPTY,A
     1    GND @S9S_MB_2U_LIB.S9S_MB_2U(SCH_1):GND    I54 @S9S_MB_2U_LIB.S9S_MB_2U(SCH_1):PAGE153
     2 P12V_OCP_REG_1 @S9S_MB_2U_LIB.S9S_MB_2U(SCH_1):P12V_OCP_REG_1    I54 @S9S_MB_2U_LIB.S9S_MB_2U(SCH_1):PAGE153

PC2088 Q_CAP_C0402-0.01UF,50V,10%,EMPA
     1 P12V_OCP_SFF @S9S_MB_2U_LIB.S9S_MB_2U(SCH_1):P12V_OCP_SFF    I81 @S9S_MB_2U_LIB.S9S_MB_2U(SCH_1):PAGE153
     2 P12V_OCP_GATE_1 @S9S_MB_2U_LIB.S9S_MB_2U(SCH_1):P12V_OCP_GATE_1    I81 @S9S_MB_2U_LIB.S9S_MB_2U(SCH_1):PAGE153

PC2089 Q_CAP_C0402-6800PF,50V,10%,X7RA
     1 P3V3_OCP_GATE_PU202_1 @S9S_MB_2U_LIB.S9S_MB_2U(SCH_1):P3V3_OCP_GATE_PU202_1   I107 @S9S_MB_2U_LIB.S9S_MB_2U(SCH_1):PAGE153
     2    GND @S9S_MB_2U_LIB.S9S_MB_2U(SCH_1):GND   I107 @S9S_MB_2U_LIB.S9S_MB_2U(SCH_1):PAGE153

PC2091 Q_CAP_0402-0.1UF,25V,10%,X7R,CA
     1 P3V3_OCP_SFF_R @S9S_MB_2U_LIB.S9S_MB_2U(SCH_1):P3V3_OCP_SFF_R   I111 @S9S_MB_2U_LIB.S9S_MB_2U(SCH_1):PAGE153
     2    GND @S9S_MB_2U_LIB.S9S_MB_2U(SCH_1):GND   I111 @S9S_MB_2U_LIB.S9S_MB_2U(SCH_1):PAGE153

PC2092 Q_CAP_0402-0.1UF,25V,10%,X7R,CA
     1 P12V_OCP_SFF @S9S_MB_2U_LIB.S9S_MB_2U(SCH_1):P12V_OCP_SFF    I93 @S9S_MB_2U_LIB.S9S_MB_2U(SCH_1):PAGE153
     2    GND @S9S_MB_2U_LIB.S9S_MB_2U(SCH_1):GND    I93 @S9S_MB_2U_LIB.S9S_MB_2U(SCH_1):PAGE153

PC2093 Q_CAP_C0402-1UF,25V,10%,X6S,CHA
     1    GND @S9S_MB_2U_LIB.S9S_MB_2U(SCH_1):GND    I72 @S9S_MB_2U_LIB.S9S_MB_2U(SCH_1):PAGE153
     2 P3V3_OCP_REG_1 @S9S_MB_2U_LIB.S9S_MB_2U(SCH_1):P3V3_OCP_REG_1    I72 @S9S_MB_2U_LIB.S9S_MB_2U(SCH_1):PAGE153

PC2098 Q_CAP_C0402-1UF,25V,10%,EMPTY,A
     1 P12V_OCP_VCC_2 @S9S_MB_2U_LIB.S9S_MB_2U(SCH_1):P12V_OCP_VCC_2    I61 @S9S_MB_2U_LIB.S9S_MB_2U(SCH_1):PAGE131
     2    GND @S9S_MB_2U_LIB.S9S_MB_2U(SCH_1):GND    I61 @S9S_MB_2U_LIB.S9S_MB_2U(SCH_1):PAGE131

PC2103 Q_CAP_C0402-1UF,25V,10%,X6S,CHA
     1 HSC_VDD18 @S9S_MB_2U_LIB.S9S_MB_2U(SCH_1):HSC_VDD18    I35 @S9S_MB_2U_LIB.S9S_MB_2U(SCH_1):PAGE303
     2 AGND_HSC @S9S_MB_2U_LIB.S9S_MB_2U(SCH_1):AGND_HSC    I35 @S9S_MB_2U_LIB.S9S_MB_2U(SCH_1):PAGE303

PC2137 Q_CAP_0402-0.1UF,25V,10%,X7R,CA
     1 P3V3_OCP_V3_2_R @S9S_MB_2U_LIB.S9S_MB_2U(SCH_1):P3V3_OCP_V3_2_R   I109 @S9S_MB_2U_LIB.S9S_MB_2U(SCH_1):PAGE131
     2    GND @S9S_MB_2U_LIB.S9S_MB_2U(SCH_1):GND   I109 @S9S_MB_2U_LIB.S9S_MB_2U(SCH_1):PAGE131

PC2139 Q_CAP_C0402-1UF,25V,10%,X6S,CHA
     1 P12V_AUX @S9S_MB_2U_LIB.S9S_MB_2U(SCH_1):P12V_AUX    I46 @S9S_MB_2U_LIB.S9S_MB_2U(SCH_1):PAGE131
     2    GND @S9S_MB_2U_LIB.S9S_MB_2U(SCH_1):GND    I46 @S9S_MB_2U_LIB.S9S_MB_2U(SCH_1):PAGE131

PC2140 Q_CAP_C0402-1UF,25V,10%,X6S,CHA
     1 P3V3_AUX @S9S_MB_2U_LIB.S9S_MB_2U(SCH_1):P3V3_AUX    I52 @S9S_MB_2U_LIB.S9S_MB_2U(SCH_1):PAGE131
     2    GND @S9S_MB_2U_LIB.S9S_MB_2U(SCH_1):GND    I52 @S9S_MB_2U_LIB.S9S_MB_2U(SCH_1):PAGE131

PC2141 Q_CAP_C0805-22UF,16V,20%,X6S,CC
     1 P12V_OCP_V3_2 @S9S_MB_2U_LIB.S9S_MB_2U(SCH_1):P12V_OCP_V3_2   I100 @S9S_MB_2U_LIB.S9S_MB_2U(SCH_1):PAGE131
     2    GND @S9S_MB_2U_LIB.S9S_MB_2U(SCH_1):GND   I100 @S9S_MB_2U_LIB.S9S_MB_2U(SCH_1):PAGE131

PC2142 Q_CAP_C0805-10UF,16V,10%,X6S,CB
     1 P3V3_OCP_V3_2_R @S9S_MB_2U_LIB.S9S_MB_2U(SCH_1):P3V3_OCP_V3_2_R   I113 @S9S_MB_2U_LIB.S9S_MB_2U(SCH_1):PAGE131
     2    GND @S9S_MB_2U_LIB.S9S_MB_2U(SCH_1):GND   I113 @S9S_MB_2U_LIB.S9S_MB_2U(SCH_1):PAGE131

PC2143 Q_CAP_C0805-10UF,16V,10%,X6S,CC
     1 P12V_OCP_V3_2 @S9S_MB_2U_LIB.S9S_MB_2U(SCH_1):P12V_OCP_V3_2   I102 @S9S_MB_2U_LIB.S9S_MB_2U(SCH_1):PAGE131
     2    GND @S9S_MB_2U_LIB.S9S_MB_2U(SCH_1):GND   I102 @S9S_MB_2U_LIB.S9S_MB_2U(SCH_1):PAGE131

PC2144 Q_CAP_C0402-0.01UF,50V,10%,EMPA
     1 P3V3_OCP_SFF_R @S9S_MB_2U_LIB.S9S_MB_2U(SCH_1):P3V3_OCP_SFF_R   I101 @S9S_MB_2U_LIB.S9S_MB_2U(SCH_1):PAGE153
     2 P3V3_OCP_GATE_PU202_1 @S9S_MB_2U_LIB.S9S_MB_2U(SCH_1):P3V3_OCP_GATE_PU202_1   I101 @S9S_MB_2U_LIB.S9S_MB_2U(SCH_1):PAGE153

PC2146 Q_CAP_C0402-1UF,25V,10%,EMPTY,A
     1    GND @S9S_MB_2U_LIB.S9S_MB_2U(SCH_1):GND    I62 @S9S_MB_2U_LIB.S9S_MB_2U(SCH_1):PAGE131
     2 P12V_OCP_REG_2 @S9S_MB_2U_LIB.S9S_MB_2U(SCH_1):P12V_OCP_REG_2    I62 @S9S_MB_2U_LIB.S9S_MB_2U(SCH_1):PAGE131

PC2147 Q_CAP_C0402-1UF,25V,10%,X6S,CHA
     1    GND @S9S_MB_2U_LIB.S9S_MB_2U(SCH_1):GND    I87 @S9S_MB_2U_LIB.S9S_MB_2U(SCH_1):PAGE131
     2 P3V3_OCP_REG_2 @S9S_MB_2U_LIB.S9S_MB_2U(SCH_1):P3V3_OCP_REG_2    I87 @S9S_MB_2U_LIB.S9S_MB_2U(SCH_1):PAGE131

PC2149 Q_CAP_C0402-0.01UF,50V,10%,EMPA
     1 P3V3_OCP_V3_2_R @S9S_MB_2U_LIB.S9S_MB_2U(SCH_1):P3V3_OCP_V3_2_R   I105 @S9S_MB_2U_LIB.S9S_MB_2U(SCH_1):PAGE131
     2 P3V3_OCP_GATE_2 @S9S_MB_2U_LIB.S9S_MB_2U(SCH_1):P3V3_OCP_GATE_2   I105 @S9S_MB_2U_LIB.S9S_MB_2U(SCH_1):PAGE131

PC2150 Q_CAP_C0402-3900PF,50V,10%,EMPA
     1 P12V_OCP_GATE_2 @S9S_MB_2U_LIB.S9S_MB_2U(SCH_1):P12V_OCP_GATE_2    I76 @S9S_MB_2U_LIB.S9S_MB_2U(SCH_1):PAGE131
     2    GND @S9S_MB_2U_LIB.S9S_MB_2U(SCH_1):GND    I76 @S9S_MB_2U_LIB.S9S_MB_2U(SCH_1):PAGE131

PC2151 Q_CAP_C0402-6800PF,50V,10%,X7RA
     1 P3V3_OCP_GATE_2 @S9S_MB_2U_LIB.S9S_MB_2U(SCH_1):P3V3_OCP_GATE_2    I96 @S9S_MB_2U_LIB.S9S_MB_2U(SCH_1):PAGE131
     2    GND @S9S_MB_2U_LIB.S9S_MB_2U(SCH_1):GND    I96 @S9S_MB_2U_LIB.S9S_MB_2U(SCH_1):PAGE131

PC2152 Q_CAP_0402-0.1UF,25V,10%,X7R,CA
     1 P12V_OCP_V3_2 @S9S_MB_2U_LIB.S9S_MB_2U(SCH_1):P12V_OCP_V3_2    I98 @S9S_MB_2U_LIB.S9S_MB_2U(SCH_1):PAGE131
     2    GND @S9S_MB_2U_LIB.S9S_MB_2U(SCH_1):GND    I98 @S9S_MB_2U_LIB.S9S_MB_2U(SCH_1):PAGE131

PC2153 Q_CAP_0402-0.22UF,16V,10%,X7R,A
     1 P12V_OCP_TIMER_1 @S9S_MB_2U_LIB.S9S_MB_2U(SCH_1):P12V_OCP_TIMER_1    I60 @S9S_MB_2U_LIB.S9S_MB_2U(SCH_1):PAGE236
     2    GND @S9S_MB_2U_LIB.S9S_MB_2U(SCH_1):GND    I60 @S9S_MB_2U_LIB.S9S_MB_2U(SCH_1):PAGE236

PC2154 Q_CAP_C0402-1UF,25V,10%,X6S,CHA
     1 P12V_AUX @S9S_MB_2U_LIB.S9S_MB_2U(SCH_1):P12V_AUX    I68 @S9S_MB_2U_LIB.S9S_MB_2U(SCH_1):PAGE236
     2    GND @S9S_MB_2U_LIB.S9S_MB_2U(SCH_1):GND    I68 @S9S_MB_2U_LIB.S9S_MB_2U(SCH_1):PAGE236

PC2155 Q_CAP_C0402-0.047UF,25V,10%,X7A
     1 P12V_OCP_SS_1 @S9S_MB_2U_LIB.S9S_MB_2U(SCH_1):P12V_OCP_SS_1    I63 @S9S_MB_2U_LIB.S9S_MB_2U(SCH_1):PAGE236
     2    GND @S9S_MB_2U_LIB.S9S_MB_2U(SCH_1):GND    I63 @S9S_MB_2U_LIB.S9S_MB_2U(SCH_1):PAGE236

PC2156 Q_CAP_C0402-100NF,50V,10%,X7R,A
     1 P12V_OCP_IMON_1 @S9S_MB_2U_LIB.S9S_MB_2U(SCH_1):P12V_OCP_IMON_1    I74 @S9S_MB_2U_LIB.S9S_MB_2U(SCH_1):PAGE236
     2    GND @S9S_MB_2U_LIB.S9S_MB_2U(SCH_1):GND    I74 @S9S_MB_2U_LIB.S9S_MB_2U(SCH_1):PAGE236

PC2157 Q_CAP_C0402-39PF,50V,5%,EMPTY,A
     1 P3V3_OCP_MODE_1 @S9S_MB_2U_LIB.S9S_MB_2U(SCH_1):P3V3_OCP_MODE_1    I42 @S9S_MB_2U_LIB.S9S_MB_2U(SCH_1):PAGE236
     2    GND @S9S_MB_2U_LIB.S9S_MB_2U(SCH_1):GND    I42 @S9S_MB_2U_LIB.S9S_MB_2U(SCH_1):PAGE236

PC2158 Q_CAP_C0603-2.2UF,16V,20%,X7R,A
     1 P12V_OCP_AVIN_PD_1 @S9S_MB_2U_LIB.S9S_MB_2U(SCH_1):P12V_OCP_AVIN_PD_1    I88 @S9S_MB_2U_LIB.S9S_MB_2U(SCH_1):PAGE236
     2    GND @S9S_MB_2U_LIB.S9S_MB_2U(SCH_1):GND    I88 @S9S_MB_2U_LIB.S9S_MB_2U(SCH_1):PAGE236

PC2159 Q_CAP_C0402-1UF,25V,10%,EMPTY,A
     1 P3V3_AUX @S9S_MB_2U_LIB.S9S_MB_2U(SCH_1):P3V3_AUX    I55 @S9S_MB_2U_LIB.S9S_MB_2U(SCH_1):PAGE236
     2    GND @S9S_MB_2U_LIB.S9S_MB_2U(SCH_1):GND    I55 @S9S_MB_2U_LIB.S9S_MB_2U(SCH_1):PAGE236

PC2160 Q_CAP_0402-0.1UF,25V,10%,X7R,CA
     1 P12V_OCP_SFF @S9S_MB_2U_LIB.S9S_MB_2U(SCH_1):P12V_OCP_SFF    I91 @S9S_MB_2U_LIB.S9S_MB_2U(SCH_1):PAGE236
     2    GND @S9S_MB_2U_LIB.S9S_MB_2U(SCH_1):GND    I91 @S9S_MB_2U_LIB.S9S_MB_2U(SCH_1):PAGE236

PC2161 Q_CAP_0402-0.068UF,16V,10%,EMPA
     1 P3V3_OCP_DVDT_1 @S9S_MB_2U_LIB.S9S_MB_2U(SCH_1):P3V3_OCP_DVDT_1    I49 @S9S_MB_2U_LIB.S9S_MB_2U(SCH_1):PAGE236
     2    GND @S9S_MB_2U_LIB.S9S_MB_2U(SCH_1):GND    I49 @S9S_MB_2U_LIB.S9S_MB_2U(SCH_1):PAGE236

PC2162 Q_CAP_0402-100PF,50V,5%,EMPTY,A
     1 P3V3_OCP_GATE_1 @S9S_MB_2U_LIB.S9S_MB_2U(SCH_1):P3V3_OCP_GATE_1    I52 @S9S_MB_2U_LIB.S9S_MB_2U(SCH_1):PAGE236
     2    GND @S9S_MB_2U_LIB.S9S_MB_2U(SCH_1):GND    I52 @S9S_MB_2U_LIB.S9S_MB_2U(SCH_1):PAGE236

PC2163 Q_CAP_C0805-10UF,16V,10%,EMPTYB
     1 P3V3_OCP_SFF_R @S9S_MB_2U_LIB.S9S_MB_2U(SCH_1):P3V3_OCP_SFF_R    I54 @S9S_MB_2U_LIB.S9S_MB_2U(SCH_1):PAGE236
     2    GND @S9S_MB_2U_LIB.S9S_MB_2U(SCH_1):GND    I54 @S9S_MB_2U_LIB.S9S_MB_2U(SCH_1):PAGE236

PC2164 Q_CAP_0402-0.22UF,16V,10%,X7R,A
     1 P12V_OCP_TIMER_2 @S9S_MB_2U_LIB.S9S_MB_2U(SCH_1):P12V_OCP_TIMER_2    I62 @S9S_MB_2U_LIB.S9S_MB_2U(SCH_1):PAGE237
     2    GND @S9S_MB_2U_LIB.S9S_MB_2U(SCH_1):GND    I62 @S9S_MB_2U_LIB.S9S_MB_2U(SCH_1):PAGE237

PC2165 Q_CAP_C0402-1UF,25V,10%,X6S,CHA
     1 P12V_AUX @S9S_MB_2U_LIB.S9S_MB_2U(SCH_1):P12V_AUX    I68 @S9S_MB_2U_LIB.S9S_MB_2U(SCH_1):PAGE237
     2    GND @S9S_MB_2U_LIB.S9S_MB_2U(SCH_1):GND    I68 @S9S_MB_2U_LIB.S9S_MB_2U(SCH_1):PAGE237

PC2166 Q_CAP_C0402-0.047UF,25V,10%,X7A
     1 P12V_OCP_SS_2 @S9S_MB_2U_LIB.S9S_MB_2U(SCH_1):P12V_OCP_SS_2    I65 @S9S_MB_2U_LIB.S9S_MB_2U(SCH_1):PAGE237
     2    GND @S9S_MB_2U_LIB.S9S_MB_2U(SCH_1):GND    I65 @S9S_MB_2U_LIB.S9S_MB_2U(SCH_1):PAGE237

PC2167 Q_CAP_0402-100PF,50V,5%,X7R,CHA
     1 P12V_OCP_IMON_2 @S9S_MB_2U_LIB.S9S_MB_2U(SCH_1):P12V_OCP_IMON_2    I73 @S9S_MB_2U_LIB.S9S_MB_2U(SCH_1):PAGE237
     2    GND @S9S_MB_2U_LIB.S9S_MB_2U(SCH_1):GND    I73 @S9S_MB_2U_LIB.S9S_MB_2U(SCH_1):PAGE237

PC2168 Q_CAP_C0402-39PF,50V,5%,EMPTY,A
     1 P3V3_OCP_MODE_2 @S9S_MB_2U_LIB.S9S_MB_2U(SCH_1):P3V3_OCP_MODE_2    I35 @S9S_MB_2U_LIB.S9S_MB_2U(SCH_1):PAGE237
     2    GND @S9S_MB_2U_LIB.S9S_MB_2U(SCH_1):GND    I35 @S9S_MB_2U_LIB.S9S_MB_2U(SCH_1):PAGE237

PC2169 Q_CAP_C0402-1UF,25V,10%,EMPTY,A
     1 P3V3_AUX @S9S_MB_2U_LIB.S9S_MB_2U(SCH_1):P3V3_AUX    I48 @S9S_MB_2U_LIB.S9S_MB_2U(SCH_1):PAGE237
     2    GND @S9S_MB_2U_LIB.S9S_MB_2U(SCH_1):GND    I48 @S9S_MB_2U_LIB.S9S_MB_2U(SCH_1):PAGE237

PC2170 Q_CAPP_SMLF-330UF,2.5V,+10/-35B
     1 PVCCFA_EHV_FIVRA_CPU0 @S9S_MB_2U_LIB.S9S_MB_2U(SCH_1):PVCCFA_EHV_FIVRA_CPU0    I70 @S9S_MB_2U_LIB.S9S_MB_2U(SCH_1):PAGE258
     2    GND @S9S_MB_2U_LIB.S9S_MB_2U(SCH_1):GND    I70 @S9S_MB_2U_LIB.S9S_MB_2U(SCH_1):PAGE258

PC2171 Q_CAPP_SMLF-330UF,2.5V,+10/-35B
     1 PVCCFA_EHV_FIVRA_CPU1 @S9S_MB_2U_LIB.S9S_MB_2U(SCH_1):PVCCFA_EHV_FIVRA_CPU1    I73 @S9S_MB_2U_LIB.S9S_MB_2U(SCH_1):PAGE276
     2    GND @S9S_MB_2U_LIB.S9S_MB_2U(SCH_1):GND    I73 @S9S_MB_2U_LIB.S9S_MB_2U(SCH_1):PAGE276

PC2172 Q_CAPP_SMLF-330UF,2.5V,+10/-35B
     1 PVCCFA_EHV_FIVRA_CPU1 @S9S_MB_2U_LIB.S9S_MB_2U(SCH_1):PVCCFA_EHV_FIVRA_CPU1    I72 @S9S_MB_2U_LIB.S9S_MB_2U(SCH_1):PAGE275
     2    GND @S9S_MB_2U_LIB.S9S_MB_2U(SCH_1):GND    I72 @S9S_MB_2U_LIB.S9S_MB_2U(SCH_1):PAGE275

PC2173 Q_CAP_C0805-10UF,16V,10%,EMPTYB
     1 P3V3_OCP_V3_2_R @S9S_MB_2U_LIB.S9S_MB_2U(SCH_1):P3V3_OCP_V3_2_R    I56 @S9S_MB_2U_LIB.S9S_MB_2U(SCH_1):PAGE237
     2    GND @S9S_MB_2U_LIB.S9S_MB_2U(SCH_1):GND    I56 @S9S_MB_2U_LIB.S9S_MB_2U(SCH_1):PAGE237

PC2174 Q_CAP_0402-0.1UF,25V,10%,X7R,CA
     1 P12V_OCP_V3_2 @S9S_MB_2U_LIB.S9S_MB_2U(SCH_1):P12V_OCP_V3_2    I91 @S9S_MB_2U_LIB.S9S_MB_2U(SCH_1):PAGE237
     2    GND @S9S_MB_2U_LIB.S9S_MB_2U(SCH_1):GND    I91 @S9S_MB_2U_LIB.S9S_MB_2U(SCH_1):PAGE237

PC2180 Q_CAPP_THLF-560UF,2.5V,20%,OSCA
     1 PVCCFA_EHV_CPU0 @S9S_MB_2U_LIB.S9S_MB_2U(SCH_1):PVCCFA_EHV_CPU0    I33 @S9S_MB_2U_LIB.S9S_MB_2U(SCH_1):PAGE262
     2    GND @S9S_MB_2U_LIB.S9S_MB_2U(SCH_1):GND    I33 @S9S_MB_2U_LIB.S9S_MB_2U(SCH_1):PAGE262

PC2181 Q_CAP_C0402-1UF,25V,10%,X6S,CHA
     1 HSC_VDD_R_2 @S9S_MB_2U_LIB.S9S_MB_2U(SCH_1):HSC_VDD_R_2     I4 @S9S_MB_2U_LIB.S9S_MB_2U(SCH_1):PAGE301
     2 AGND_HSC @S9S_MB_2U_LIB.S9S_MB_2U(SCH_1):AGND_HSC     I4 @S9S_MB_2U_LIB.S9S_MB_2U(SCH_1):PAGE301

PC2182 Q_CAP_0402-220PF,50V,10%,X7R,TA
     1 HSC_ON @S9S_MB_2U_LIB.S9S_MB_2U(SCH_1):HSC_ON    I23 @S9S_MB_2U_LIB.S9S_MB_2U(SCH_1):PAGE301
     2 AGND_HSC @S9S_MB_2U_LIB.S9S_MB_2U(SCH_1):AGND_HSC    I23 @S9S_MB_2U_LIB.S9S_MB_2U(SCH_1):PAGE301

PC2183 Q_CAP_0402-220PF,50V,10%,EMPTYA
     1 HSC_ON @S9S_MB_2U_LIB.S9S_MB_2U(SCH_1):HSC_ON     I2 @S9S_MB_2U_LIB.S9S_MB_2U(SCH_1):PAGE301
     2 AGND_HSC @S9S_MB_2U_LIB.S9S_MB_2U(SCH_1):AGND_HSC     I2 @S9S_MB_2U_LIB.S9S_MB_2U(SCH_1):PAGE301

PC2184 Q_CAP_0402-0.068UF,16V,10%,X7RA
     1 HSC_SS @S9S_MB_2U_LIB.S9S_MB_2U(SCH_1):HSC_SS    I47 @S9S_MB_2U_LIB.S9S_MB_2U(SCH_1):PAGE301
     2 AGND_HSC @S9S_MB_2U_LIB.S9S_MB_2U(SCH_1):AGND_HSC    I47 @S9S_MB_2U_LIB.S9S_MB_2U(SCH_1):PAGE301

PC2185 Q_CAP_0402-0.068UF,16V,10%,X7RA
     1 HSC_SS @S9S_MB_2U_LIB.S9S_MB_2U(SCH_1):HSC_SS    I37 @S9S_MB_2U_LIB.S9S_MB_2U(SCH_1):PAGE301
     2 AGND_HSC @S9S_MB_2U_LIB.S9S_MB_2U(SCH_1):AGND_HSC    I37 @S9S_MB_2U_LIB.S9S_MB_2U(SCH_1):PAGE301

PC2186 Q_CAP_C0402-1UF,25V,10%,X6S,CHA
     1 HSC_VDD_R @S9S_MB_2U_LIB.S9S_MB_2U(SCH_1):HSC_VDD_R    I14 @S9S_MB_2U_LIB.S9S_MB_2U(SCH_1):PAGE303
     2 AGND_HSC @S9S_MB_2U_LIB.S9S_MB_2U(SCH_1):AGND_HSC    I14 @S9S_MB_2U_LIB.S9S_MB_2U(SCH_1):PAGE303

PC2187 Q_CAP_C0402-1UF,25V,10%,X6S,CHA
     1 HSC_VDD_R @S9S_MB_2U_LIB.S9S_MB_2U(SCH_1):HSC_VDD_R    I23 @S9S_MB_2U_LIB.S9S_MB_2U(SCH_1):PAGE303
     2 AGND_HSC @S9S_MB_2U_LIB.S9S_MB_2U(SCH_1):AGND_HSC    I23 @S9S_MB_2U_LIB.S9S_MB_2U(SCH_1):PAGE303

PC2188 Q_CAP_C0402-1UF,25V,10%,X6S,CHA
     1 P12V_PSU @S9S_MB_2U_LIB.S9S_MB_2U(SCH_1):P12V_PSU    I51 @S9S_MB_2U_LIB.S9S_MB_2U(SCH_1):PAGE303
     2    GND @S9S_MB_2U_LIB.S9S_MB_2U(SCH_1):GND    I51 @S9S_MB_2U_LIB.S9S_MB_2U(SCH_1):PAGE303

PC2189 Q_CAP_C0402-0.01UF,50V,10%,X7RA
     1 HSC_VSENSE @S9S_MB_2U_LIB.S9S_MB_2U(SCH_1):HSC_VSENSE    I45 @S9S_MB_2U_LIB.S9S_MB_2U(SCH_1):PAGE303
     2 AGND_HSC @S9S_MB_2U_LIB.S9S_MB_2U(SCH_1):AGND_HSC    I45 @S9S_MB_2U_LIB.S9S_MB_2U(SCH_1):PAGE303

PC2190 Q_CAP_C0402-0.01UF,50V,10%,X7RA
     1 HSC_VOSEN @S9S_MB_2U_LIB.S9S_MB_2U(SCH_1):HSC_VOSEN    I75 @S9S_MB_2U_LIB.S9S_MB_2U(SCH_1):PAGE303
     2 AGND_HSC @S9S_MB_2U_LIB.S9S_MB_2U(SCH_1):AGND_HSC    I75 @S9S_MB_2U_LIB.S9S_MB_2U(SCH_1):PAGE303

PC2191 Q_CAP_0402-0.068UF,16V,10%,X7RA
     1 HSC_SS @S9S_MB_2U_LIB.S9S_MB_2U(SCH_1):HSC_SS    I69 @S9S_MB_2U_LIB.S9S_MB_2U(SCH_1):PAGE303
     2 AGND_HSC @S9S_MB_2U_LIB.S9S_MB_2U(SCH_1):AGND_HSC    I69 @S9S_MB_2U_LIB.S9S_MB_2U(SCH_1):PAGE303

PC2192 Q_CAP_C0402-0.001UF,50V,10%,X7A
     1 HSC_VTEMP @S9S_MB_2U_LIB.S9S_MB_2U(SCH_1):HSC_VTEMP    I77 @S9S_MB_2U_LIB.S9S_MB_2U(SCH_1):PAGE303
     2 AGND_HSC @S9S_MB_2U_LIB.S9S_MB_2U(SCH_1):AGND_HSC    I77 @S9S_MB_2U_LIB.S9S_MB_2U(SCH_1):PAGE303

PC2193 Q_CAP_C0402-0.047UF,25V,10%,X7A
     1 HSC_IMON @S9S_MB_2U_LIB.S9S_MB_2U(SCH_1):HSC_IMON    I89 @S9S_MB_2U_LIB.S9S_MB_2U(SCH_1):PAGE303
     2 AGND_HSC @S9S_MB_2U_LIB.S9S_MB_2U(SCH_1):AGND_HSC    I89 @S9S_MB_2U_LIB.S9S_MB_2U(SCH_1):PAGE303

PC2196 Q_CAP_0402-0.22UF,16V,10%,X7R,A
     1 P12V_E1S_TIMER_0 @S9S_MB_2U_LIB.S9S_MB_2U(SCH_1):P12V_E1S_TIMER_0    I37 @S9S_MB_2U_LIB.S9S_MB_2U(SCH_1):PAGE323
     2    GND @S9S_MB_2U_LIB.S9S_MB_2U(SCH_1):GND    I37 @S9S_MB_2U_LIB.S9S_MB_2U(SCH_1):PAGE323

PC2197 Q_CAP_C0402-39PF,50V,5%,EMPTY,A
     1 P3V3_E1S_MODE_0 @S9S_MB_2U_LIB.S9S_MB_2U(SCH_1):P3V3_E1S_MODE_0     I3 @S9S_MB_2U_LIB.S9S_MB_2U(SCH_1):PAGE323
     2    GND @S9S_MB_2U_LIB.S9S_MB_2U(SCH_1):GND     I3 @S9S_MB_2U_LIB.S9S_MB_2U(SCH_1):PAGE323

PC2198 Q_CAP_C0402-1UF,25V,10%,X6S,CHA
     1 P12V_AUX @S9S_MB_2U_LIB.S9S_MB_2U(SCH_1):P12V_AUX    I51 @S9S_MB_2U_LIB.S9S_MB_2U(SCH_1):PAGE323
     2    GND @S9S_MB_2U_LIB.S9S_MB_2U(SCH_1):GND    I51 @S9S_MB_2U_LIB.S9S_MB_2U(SCH_1):PAGE323

PC2199 Q_CAPP_THLF-560UF,2.5V,20%,OSCA
     1 PVCCFA_EHV_CPU1 @S9S_MB_2U_LIB.S9S_MB_2U(SCH_1):PVCCFA_EHV_CPU1    I32 @S9S_MB_2U_LIB.S9S_MB_2U(SCH_1):PAGE280
     2    GND @S9S_MB_2U_LIB.S9S_MB_2U(SCH_1):GND    I32 @S9S_MB_2U_LIB.S9S_MB_2U(SCH_1):PAGE280

PC2200 Q_CAP_C0402-1UF,25V,10%,EMPTY,A
     1 P3V3_AUX @S9S_MB_2U_LIB.S9S_MB_2U(SCH_1):P3V3_AUX     I9 @S9S_MB_2U_LIB.S9S_MB_2U(SCH_1):PAGE323
     2    GND @S9S_MB_2U_LIB.S9S_MB_2U(SCH_1):GND     I9 @S9S_MB_2U_LIB.S9S_MB_2U(SCH_1):PAGE323

PC2201 Q_CAP_0402-0.068UF,16V,10%,EMPA
     1 P3V3_E1S_DVDT_0 @S9S_MB_2U_LIB.S9S_MB_2U(SCH_1):P3V3_E1S_DVDT_0    I30 @S9S_MB_2U_LIB.S9S_MB_2U(SCH_1):PAGE323
     2    GND @S9S_MB_2U_LIB.S9S_MB_2U(SCH_1):GND    I30 @S9S_MB_2U_LIB.S9S_MB_2U(SCH_1):PAGE323

PC2202 Q_CAP_C0402-100NF,50V,10%,X7R,A
     1 P12V_E1S_IMON_0 @S9S_MB_2U_LIB.S9S_MB_2U(SCH_1):P12V_E1S_IMON_0    I56 @S9S_MB_2U_LIB.S9S_MB_2U(SCH_1):PAGE323
     2    GND @S9S_MB_2U_LIB.S9S_MB_2U(SCH_1):GND    I56 @S9S_MB_2U_LIB.S9S_MB_2U(SCH_1):PAGE323

PC2203 Q_CAP_0402-100PF,50V,5%,EMPTY,A
     1 P3V3_E1S_GATE_0_PU293 @S9S_MB_2U_LIB.S9S_MB_2U(SCH_1):P3V3_E1S_GATE_0_PU293    I32 @S9S_MB_2U_LIB.S9S_MB_2U(SCH_1):PAGE323
     2    GND @S9S_MB_2U_LIB.S9S_MB_2U(SCH_1):GND    I32 @S9S_MB_2U_LIB.S9S_MB_2U(SCH_1):PAGE323

PC2204 Q_CAP_C0805-10UF,16V,10%,EMPTYB
     1 P3V3_E1S_0_R @S9S_MB_2U_LIB.S9S_MB_2U(SCH_1):P3V3_E1S_0_R    I34 @S9S_MB_2U_LIB.S9S_MB_2U(SCH_1):PAGE323
     2    GND @S9S_MB_2U_LIB.S9S_MB_2U(SCH_1):GND    I34 @S9S_MB_2U_LIB.S9S_MB_2U(SCH_1):PAGE323

PC2205 Q_CAP_C0603-2.2UF,16V,20%,X7R,A
     1 P12V_E1S_AVIN_PD_0 @S9S_MB_2U_LIB.S9S_MB_2U(SCH_1):P12V_E1S_AVIN_PD_0    I69 @S9S_MB_2U_LIB.S9S_MB_2U(SCH_1):PAGE323
     2    GND @S9S_MB_2U_LIB.S9S_MB_2U(SCH_1):GND    I69 @S9S_MB_2U_LIB.S9S_MB_2U(SCH_1):PAGE323

PC2206 Q_CAP_0402-0.1UF,25V,10%,X7R,CA
     1 P12V_E1S_0 @S9S_MB_2U_LIB.S9S_MB_2U(SCH_1):P12V_E1S_0    I73 @S9S_MB_2U_LIB.S9S_MB_2U(SCH_1):PAGE323
     2    GND @S9S_MB_2U_LIB.S9S_MB_2U(SCH_1):GND    I73 @S9S_MB_2U_LIB.S9S_MB_2U(SCH_1):PAGE323

PC2207 Q_CAP_C0402-1UF,25V,10%,X6S,CHA
     1 P12V_AUX @S9S_MB_2U_LIB.S9S_MB_2U(SCH_1):P12V_AUX    I31 @S9S_MB_2U_LIB.S9S_MB_2U(SCH_1):PAGE324
     2    GND @S9S_MB_2U_LIB.S9S_MB_2U(SCH_1):GND    I31 @S9S_MB_2U_LIB.S9S_MB_2U(SCH_1):PAGE324

PC2208 Q_CAP_C0402-1UF,25V,10%,X6S,CHA
     1 P3V3_AUX @S9S_MB_2U_LIB.S9S_MB_2U(SCH_1):P3V3_AUX    I17 @S9S_MB_2U_LIB.S9S_MB_2U(SCH_1):PAGE324
     2    GND @S9S_MB_2U_LIB.S9S_MB_2U(SCH_1):GND    I17 @S9S_MB_2U_LIB.S9S_MB_2U(SCH_1):PAGE324

PC2209 Q_CAP_C0402-1UF,25V,10%,EMPTY,A
     1 P12V_E1S_VCC_0 @S9S_MB_2U_LIB.S9S_MB_2U(SCH_1):P12V_E1S_VCC_0    I60 @S9S_MB_2U_LIB.S9S_MB_2U(SCH_1):PAGE324
     2    GND @S9S_MB_2U_LIB.S9S_MB_2U(SCH_1):GND    I60 @S9S_MB_2U_LIB.S9S_MB_2U(SCH_1):PAGE324

PC2210 Q_CAP_C0402-1UF,25V,10%,X6S,CHA
     1 P3V3_E1S_VCC_0 @S9S_MB_2U_LIB.S9S_MB_2U(SCH_1):P3V3_E1S_VCC_0    I37 @S9S_MB_2U_LIB.S9S_MB_2U(SCH_1):PAGE324
     2    GND @S9S_MB_2U_LIB.S9S_MB_2U(SCH_1):GND    I37 @S9S_MB_2U_LIB.S9S_MB_2U(SCH_1):PAGE324

PC2211 Q_CAP_C0402-1UF,25V,10%,EMPTY,A
     1    GND @S9S_MB_2U_LIB.S9S_MB_2U(SCH_1):GND    I57 @S9S_MB_2U_LIB.S9S_MB_2U(SCH_1):PAGE324
     2 P12V_E1S_REG_0 @S9S_MB_2U_LIB.S9S_MB_2U(SCH_1):P12V_E1S_REG_0    I57 @S9S_MB_2U_LIB.S9S_MB_2U(SCH_1):PAGE324

PC2212 Q_CAP_C0402-1UF,25V,10%,X6S,CHA
     1    GND @S9S_MB_2U_LIB.S9S_MB_2U(SCH_1):GND    I38 @S9S_MB_2U_LIB.S9S_MB_2U(SCH_1):PAGE324
     2 P3V3_E1S_REG_0 @S9S_MB_2U_LIB.S9S_MB_2U(SCH_1):P3V3_E1S_REG_0    I38 @S9S_MB_2U_LIB.S9S_MB_2U(SCH_1):PAGE324

PC2213 Q_CAP_C0402-0.01UF,50V,10%,EMPA
     1 P3V3_E1S_0_R @S9S_MB_2U_LIB.S9S_MB_2U(SCH_1):P3V3_E1S_0_R    I42 @S9S_MB_2U_LIB.S9S_MB_2U(SCH_1):PAGE324
     2 P3V3_E1S_GATE_0 @S9S_MB_2U_LIB.S9S_MB_2U(SCH_1):P3V3_E1S_GATE_0    I42 @S9S_MB_2U_LIB.S9S_MB_2U(SCH_1):PAGE324

PC2214 Q_CAP_C0402-0.01UF,50V,10%,EMPA
     1 P12V_E1S_0 @S9S_MB_2U_LIB.S9S_MB_2U(SCH_1):P12V_E1S_0    I69 @S9S_MB_2U_LIB.S9S_MB_2U(SCH_1):PAGE324
     2 P12V_E1S_GATE_0 @S9S_MB_2U_LIB.S9S_MB_2U(SCH_1):P12V_E1S_GATE_0    I69 @S9S_MB_2U_LIB.S9S_MB_2U(SCH_1):PAGE324

PC2215 Q_CAP_C0402-3900PF,50V,10%,EMPA
     1 P12V_E1S_GATE_0 @S9S_MB_2U_LIB.S9S_MB_2U(SCH_1):P12V_E1S_GATE_0    I66 @S9S_MB_2U_LIB.S9S_MB_2U(SCH_1):PAGE324
     2    GND @S9S_MB_2U_LIB.S9S_MB_2U(SCH_1):GND    I66 @S9S_MB_2U_LIB.S9S_MB_2U(SCH_1):PAGE324

PC2216 Q_CAP_C0402-6800PF,50V,10%,X7RA
     1 P3V3_E1S_GATE_0 @S9S_MB_2U_LIB.S9S_MB_2U(SCH_1):P3V3_E1S_GATE_0    I45 @S9S_MB_2U_LIB.S9S_MB_2U(SCH_1):PAGE324
     2    GND @S9S_MB_2U_LIB.S9S_MB_2U(SCH_1):GND    I45 @S9S_MB_2U_LIB.S9S_MB_2U(SCH_1):PAGE324

PC2217 Q_CAP_0402-0.1UF,25V,10%,X7R,CA
     1 P12V_E1S_0 @S9S_MB_2U_LIB.S9S_MB_2U(SCH_1):P12V_E1S_0    I75 @S9S_MB_2U_LIB.S9S_MB_2U(SCH_1):PAGE324
     2    GND @S9S_MB_2U_LIB.S9S_MB_2U(SCH_1):GND    I75 @S9S_MB_2U_LIB.S9S_MB_2U(SCH_1):PAGE324

PC2218 Q_CAP_0402-0.1UF,25V,10%,X7R,CA
     1 P3V3_E1S_0_R @S9S_MB_2U_LIB.S9S_MB_2U(SCH_1):P3V3_E1S_0_R    I52 @S9S_MB_2U_LIB.S9S_MB_2U(SCH_1):PAGE324
     2    GND @S9S_MB_2U_LIB.S9S_MB_2U(SCH_1):GND    I52 @S9S_MB_2U_LIB.S9S_MB_2U(SCH_1):PAGE324

PC2219 Q_CAP_C0805-10UF,16V,10%,X6S,CC
     1 P12V_E1S_0 @S9S_MB_2U_LIB.S9S_MB_2U(SCH_1):P12V_E1S_0    I78 @S9S_MB_2U_LIB.S9S_MB_2U(SCH_1):PAGE324
     2    GND @S9S_MB_2U_LIB.S9S_MB_2U(SCH_1):GND    I78 @S9S_MB_2U_LIB.S9S_MB_2U(SCH_1):PAGE324

PC2220 Q_CAP_C0805-10UF,16V,10%,X6S,CB
     1 P3V3_E1S_0_R @S9S_MB_2U_LIB.S9S_MB_2U(SCH_1):P3V3_E1S_0_R    I53 @S9S_MB_2U_LIB.S9S_MB_2U(SCH_1):PAGE324
     2    GND @S9S_MB_2U_LIB.S9S_MB_2U(SCH_1):GND    I53 @S9S_MB_2U_LIB.S9S_MB_2U(SCH_1):PAGE324

PC2221 Q_CAP_C0402-1UF,25V,10%,X6S,CHA
     1 PVNN_MAIN_CPU0_VCC @S9S_MB_2U_LIB.S9S_MB_2U(SCH_1):PVNN_MAIN_CPU0_VCC     I7 @S9S_MB_2U_LIB.S9S_MB_2U(SCH_1):PAGE268
     2    GND @S9S_MB_2U_LIB.S9S_MB_2U(SCH_1):GND     I7 @S9S_MB_2U_LIB.S9S_MB_2U(SCH_1):PAGE268

PC2222 Q_CAP_C0402-1UF,25V,10%,X6S,CHA
     1 PVNN_MAIN_CPU1_VCC @S9S_MB_2U_LIB.S9S_MB_2U(SCH_1):PVNN_MAIN_CPU1_VCC    I10 @S9S_MB_2U_LIB.S9S_MB_2U(SCH_1):PAGE286
     2    GND @S9S_MB_2U_LIB.S9S_MB_2U(SCH_1):GND    I10 @S9S_MB_2U_LIB.S9S_MB_2U(SCH_1):PAGE286

PC2223 Q_CAP_C0402-1UF,25V,10%,X6S,CHA
     1 HSC_VDD_R_4 @S9S_MB_2U_LIB.S9S_MB_2U(SCH_1):HSC_VDD_R_4     I4 @S9S_MB_2U_LIB.S9S_MB_2U(SCH_1):PAGE325
     2 AGND_HSC @S9S_MB_2U_LIB.S9S_MB_2U(SCH_1):AGND_HSC     I4 @S9S_MB_2U_LIB.S9S_MB_2U(SCH_1):PAGE325

PC2224 Q_CAP_0402-220PF,50V,10%,EMPTYA
     1 HSC_ON @S9S_MB_2U_LIB.S9S_MB_2U(SCH_1):HSC_ON    I23 @S9S_MB_2U_LIB.S9S_MB_2U(SCH_1):PAGE325
     2 AGND_HSC @S9S_MB_2U_LIB.S9S_MB_2U(SCH_1):AGND_HSC    I23 @S9S_MB_2U_LIB.S9S_MB_2U(SCH_1):PAGE325

PC2225 Q_CAP_0402-220PF,50V,10%,EMPTYA
     1 HSC_ON @S9S_MB_2U_LIB.S9S_MB_2U(SCH_1):HSC_ON     I2 @S9S_MB_2U_LIB.S9S_MB_2U(SCH_1):PAGE325
     2 AGND_HSC @S9S_MB_2U_LIB.S9S_MB_2U(SCH_1):AGND_HSC     I2 @S9S_MB_2U_LIB.S9S_MB_2U(SCH_1):PAGE325

PC2226 Q_CAP_0402-0.068UF,16V,10%,X7RA
     1 HSC_SS @S9S_MB_2U_LIB.S9S_MB_2U(SCH_1):HSC_SS    I48 @S9S_MB_2U_LIB.S9S_MB_2U(SCH_1):PAGE325
     2 AGND_HSC @S9S_MB_2U_LIB.S9S_MB_2U(SCH_1):AGND_HSC    I48 @S9S_MB_2U_LIB.S9S_MB_2U(SCH_1):PAGE325

PC2227 Q_CAP_0402-0.068UF,16V,10%,X7RA
     1 HSC_SS @S9S_MB_2U_LIB.S9S_MB_2U(SCH_1):HSC_SS    I38 @S9S_MB_2U_LIB.S9S_MB_2U(SCH_1):PAGE325
     2 AGND_HSC @S9S_MB_2U_LIB.S9S_MB_2U(SCH_1):AGND_HSC    I38 @S9S_MB_2U_LIB.S9S_MB_2U(SCH_1):PAGE325

PC2229 Q_CAP_0402-0.22UF,16V,10%,X7R,A
     1 P12V_SCM_TIMER @S9S_MB_2U_LIB.S9S_MB_2U(SCH_1):P12V_SCM_TIMER     I8 @S9S_MB_2U_LIB.S9S_MB_2U(SCH_1):PAGE229
     2    GND @S9S_MB_2U_LIB.S9S_MB_2U(SCH_1):GND     I8 @S9S_MB_2U_LIB.S9S_MB_2U(SCH_1):PAGE229

PC2230 Q_CAP_C0402-1UF,25V,10%,X6S,CHA
     1 P12V_AUX @S9S_MB_2U_LIB.S9S_MB_2U(SCH_1):P12V_AUX    I31 @S9S_MB_2U_LIB.S9S_MB_2U(SCH_1):PAGE229
     2    GND @S9S_MB_2U_LIB.S9S_MB_2U(SCH_1):GND    I31 @S9S_MB_2U_LIB.S9S_MB_2U(SCH_1):PAGE229

PC2231 Q_CAP_C0402-1UF,25V,10%,X6S,CHA
     1 P12V_AUX @S9S_MB_2U_LIB.S9S_MB_2U(SCH_1):P12V_AUX    I37 @S9S_MB_2U_LIB.S9S_MB_2U(SCH_1):PAGE229
     2    GND @S9S_MB_2U_LIB.S9S_MB_2U(SCH_1):GND    I37 @S9S_MB_2U_LIB.S9S_MB_2U(SCH_1):PAGE229

PC2232 Q_CAP_C0402-0.047UF,25V,10%,X7A
     1 P12V_SCM_SS @S9S_MB_2U_LIB.S9S_MB_2U(SCH_1):P12V_SCM_SS    I33 @S9S_MB_2U_LIB.S9S_MB_2U(SCH_1):PAGE229
     2    GND @S9S_MB_2U_LIB.S9S_MB_2U(SCH_1):GND    I33 @S9S_MB_2U_LIB.S9S_MB_2U(SCH_1):PAGE229

PC2233 Q_CAP_C0402-1UF,25V,10%,EMPTY,A
     1 P12V_SCM_VCC @S9S_MB_2U_LIB.S9S_MB_2U(SCH_1):P12V_SCM_VCC    I68 @S9S_MB_2U_LIB.S9S_MB_2U(SCH_1):PAGE229
     2    GND @S9S_MB_2U_LIB.S9S_MB_2U(SCH_1):GND    I68 @S9S_MB_2U_LIB.S9S_MB_2U(SCH_1):PAGE229

PC2234 Q_CAP_C0402-1UF,25V,10%,EMPTY,A
     1    GND @S9S_MB_2U_LIB.S9S_MB_2U(SCH_1):GND    I66 @S9S_MB_2U_LIB.S9S_MB_2U(SCH_1):PAGE229
     2 P12V_SCM_REG @S9S_MB_2U_LIB.S9S_MB_2U(SCH_1):P12V_SCM_REG    I66 @S9S_MB_2U_LIB.S9S_MB_2U(SCH_1):PAGE229

PC2235 Q_CAP_C0402-100NF,50V,10%,X7R,A
     1 P12V_SCM_IMON @S9S_MB_2U_LIB.S9S_MB_2U(SCH_1):P12V_SCM_IMON    I42 @S9S_MB_2U_LIB.S9S_MB_2U(SCH_1):PAGE229
     2    GND @S9S_MB_2U_LIB.S9S_MB_2U(SCH_1):GND    I42 @S9S_MB_2U_LIB.S9S_MB_2U(SCH_1):PAGE229

PC2236 Q_CAP_C0402-0.01UF,50V,10%,EMPA
     1 P12V_SCM_R @S9S_MB_2U_LIB.S9S_MB_2U(SCH_1):P12V_SCM_R    I73 @S9S_MB_2U_LIB.S9S_MB_2U(SCH_1):PAGE229
     2 P12V_SCM_GATE @S9S_MB_2U_LIB.S9S_MB_2U(SCH_1):P12V_SCM_GATE    I73 @S9S_MB_2U_LIB.S9S_MB_2U(SCH_1):PAGE229

PC2237 Q_CAP_C0402-3900PF,50V,10%,EMPA
     1 P12V_SCM_GATE @S9S_MB_2U_LIB.S9S_MB_2U(SCH_1):P12V_SCM_GATE    I75 @S9S_MB_2U_LIB.S9S_MB_2U(SCH_1):PAGE229
     2    GND @S9S_MB_2U_LIB.S9S_MB_2U(SCH_1):GND    I75 @S9S_MB_2U_LIB.S9S_MB_2U(SCH_1):PAGE229

PC2238 Q_CAP_0402-0.1UF,25V,10%,X7R,CA
     1 P12V_SCM_R @S9S_MB_2U_LIB.S9S_MB_2U(SCH_1):P12V_SCM_R    I83 @S9S_MB_2U_LIB.S9S_MB_2U(SCH_1):PAGE229
     2    GND @S9S_MB_2U_LIB.S9S_MB_2U(SCH_1):GND    I83 @S9S_MB_2U_LIB.S9S_MB_2U(SCH_1):PAGE229

PC2239 Q_CAP_C0603-2.2UF,16V,20%,X7R,A
     1 P12V_SCM_AVIN_PD @S9S_MB_2U_LIB.S9S_MB_2U(SCH_1):P12V_SCM_AVIN_PD    I53 @S9S_MB_2U_LIB.S9S_MB_2U(SCH_1):PAGE229
     2    GND @S9S_MB_2U_LIB.S9S_MB_2U(SCH_1):GND    I53 @S9S_MB_2U_LIB.S9S_MB_2U(SCH_1):PAGE229

PC2240 Q_CAP_C0805-10UF,16V,10%,X6S,CC
     1 P12V_SCM_R @S9S_MB_2U_LIB.S9S_MB_2U(SCH_1):P12V_SCM_R    I84 @S9S_MB_2U_LIB.S9S_MB_2U(SCH_1):PAGE229
     2    GND @S9S_MB_2U_LIB.S9S_MB_2U(SCH_1):GND    I84 @S9S_MB_2U_LIB.S9S_MB_2U(SCH_1):PAGE229

PC2241 Q_CAP_0402-0.1UF,25V,10%,X7R,CA
     1 P12V_SCM_R @S9S_MB_2U_LIB.S9S_MB_2U(SCH_1):P12V_SCM_R    I57 @S9S_MB_2U_LIB.S9S_MB_2U(SCH_1):PAGE229
     2    GND @S9S_MB_2U_LIB.S9S_MB_2U(SCH_1):GND    I57 @S9S_MB_2U_LIB.S9S_MB_2U(SCH_1):PAGE229

PC2242 Q_CAP_C0805-22UF,16V,20%,X6S,CC
     1 P12V_SCM_R @S9S_MB_2U_LIB.S9S_MB_2U(SCH_1):P12V_SCM_R    I88 @S9S_MB_2U_LIB.S9S_MB_2U(SCH_1):PAGE229
     2    GND @S9S_MB_2U_LIB.S9S_MB_2U(SCH_1):GND    I88 @S9S_MB_2U_LIB.S9S_MB_2U(SCH_1):PAGE229

PC2260 Q_CAP_C0805-22UF,16V,20%,X6S,CA
     1 SW_P3V3_AUX_FLT @S9S_MB_2U_LIB.S9S_MB_2U(SCH_1):SW_P3V3_AUX_FLT   I100 @S9S_MB_2U_LIB.S9S_MB_2U(SCH_1):PAGE245
     2    GND @S9S_MB_2U_LIB.S9S_MB_2U(SCH_1):GND   I100 @S9S_MB_2U_LIB.S9S_MB_2U(SCH_1):PAGE245

PC2261 Q_CAP_C0805-22UF,16V,20%,X6S,CA
     1 SW_P3V3_AUX_FLT @S9S_MB_2U_LIB.S9S_MB_2U(SCH_1):SW_P3V3_AUX_FLT   I101 @S9S_MB_2U_LIB.S9S_MB_2U(SCH_1):PAGE245
     2    GND @S9S_MB_2U_LIB.S9S_MB_2U(SCH_1):GND   I101 @S9S_MB_2U_LIB.S9S_MB_2U(SCH_1):PAGE245

PC2262 Q_CAP_C0805-22UF,16V,20%,X6S,CA
     1 SW_P3V3_AUX_FLT @S9S_MB_2U_LIB.S9S_MB_2U(SCH_1):SW_P3V3_AUX_FLT   I105 @S9S_MB_2U_LIB.S9S_MB_2U(SCH_1):PAGE245
     2    GND @S9S_MB_2U_LIB.S9S_MB_2U(SCH_1):GND   I105 @S9S_MB_2U_LIB.S9S_MB_2U(SCH_1):PAGE245

PC2263 Q_CAP_C0805-22UF,16V,20%,X6S,CA
     1 SW_P3V3_AUX_FLT @S9S_MB_2U_LIB.S9S_MB_2U(SCH_1):SW_P3V3_AUX_FLT   I107 @S9S_MB_2U_LIB.S9S_MB_2U(SCH_1):PAGE245
     2    GND @S9S_MB_2U_LIB.S9S_MB_2U(SCH_1):GND   I107 @S9S_MB_2U_LIB.S9S_MB_2U(SCH_1):PAGE245

PC2277 Q_CAP_0402-0.01UF,25V,10%,X7R,A
     1 PVNN_MAIN_CPU1_FB_RC @S9S_MB_2U_LIB.S9S_MB_2U(SCH_1):PVNN_MAIN_CPU1_FB_RC    I40 @S9S_MB_2U_LIB.S9S_MB_2U(SCH_1):PAGE286
     2    GND @S9S_MB_2U_LIB.S9S_MB_2U(SCH_1):GND    I40 @S9S_MB_2U_LIB.S9S_MB_2U(SCH_1):PAGE286

PC2279 Q_CAP_0402-0.01UF,25V,10%,X7R,A
     1 SH_P1V05_PCH_AUX_P @S9S_MB_2U_LIB.S9S_MB_2U(SCH_1):SH_P1V05_PCH_AUX_P    I37 @S9S_MB_2U_LIB.S9S_MB_2U(SCH_1):PAGE248
     2 SH_P1V05_PCH_AUX_N @S9S_MB_2U_LIB.S9S_MB_2U(SCH_1):SH_P1V05_PCH_AUX_N    I37 @S9S_MB_2U_LIB.S9S_MB_2U(SCH_1):PAGE248

PC2280 Q_CAP_C0805-10UF,16V,10%,X6S,CC
     1 P12V_E1S_0 @S9S_MB_2U_LIB.S9S_MB_2U(SCH_1):P12V_E1S_0    I79 @S9S_MB_2U_LIB.S9S_MB_2U(SCH_1):PAGE324
     2    GND @S9S_MB_2U_LIB.S9S_MB_2U(SCH_1):GND    I79 @S9S_MB_2U_LIB.S9S_MB_2U(SCH_1):PAGE324

PC2281 Q_CAP_C0402-0.047UF,25V,10%,X7A
     1 P12V_E1S_SS_0 @S9S_MB_2U_LIB.S9S_MB_2U(SCH_1):P12V_E1S_SS_0    I47 @S9S_MB_2U_LIB.S9S_MB_2U(SCH_1):PAGE323
     2    GND @S9S_MB_2U_LIB.S9S_MB_2U(SCH_1):GND    I47 @S9S_MB_2U_LIB.S9S_MB_2U(SCH_1):PAGE323

PC2282 Q_CAP_0402-0.01UF,25V,10%,X7R,A
     1 SH_PVPP_HBM_CPU1_P @S9S_MB_2U_LIB.S9S_MB_2U(SCH_1):SH_PVPP_HBM_CPU1_P    I32 @S9S_MB_2U_LIB.S9S_MB_2U(SCH_1):PAGE285
     2 SH_PVPP_HBM_CPU1_N @S9S_MB_2U_LIB.S9S_MB_2U(SCH_1):SH_PVPP_HBM_CPU1_N    I32 @S9S_MB_2U_LIB.S9S_MB_2U(SCH_1):PAGE285

PC2286 Q_CAP_0402-1000PF,50V,5%,EMPTYA
     1 FM_P1V05_PCH_AUX_R_EN @S9S_MB_2U_LIB.S9S_MB_2U(SCH_1):FM_P1V05_PCH_AUX_R_EN     I8 @S9S_MB_2U_LIB.S9S_MB_2U(SCH_1):PAGE248
     2    GND @S9S_MB_2U_LIB.S9S_MB_2U(SCH_1):GND     I8 @S9S_MB_2U_LIB.S9S_MB_2U(SCH_1):PAGE248

PC2336 Q_CAPP_SMLF-330UF,2.5V,+10/-35A
     1 PVCCIN_CPU0 @S9S_MB_2U_LIB.S9S_MB_2U(SCH_1):PVCCIN_CPU0    I60 @S9S_MB_2U_LIB.S9S_MB_2U(SCH_1):PAGE253
     2    GND @S9S_MB_2U_LIB.S9S_MB_2U(SCH_1):GND    I60 @S9S_MB_2U_LIB.S9S_MB_2U(SCH_1):PAGE253

PC2340 Q_CAP_C0402-560PF,50V,10%,X7R,A
     1 P12V_SCM_ISET_R @S9S_MB_2U_LIB.S9S_MB_2U(SCH_1):P12V_SCM_ISET_R     I7 @S9S_MB_2U_LIB.S9S_MB_2U(SCH_1):PAGE229
     2    GND @S9S_MB_2U_LIB.S9S_MB_2U(SCH_1):GND     I7 @S9S_MB_2U_LIB.S9S_MB_2U(SCH_1):PAGE229

PC2341 Q_CAP_C0402-560PF,50V,10%,X7R,A
     1 P12V_E1S_ISET_0_R @S9S_MB_2U_LIB.S9S_MB_2U(SCH_1):P12V_E1S_ISET_0_R    I42 @S9S_MB_2U_LIB.S9S_MB_2U(SCH_1):PAGE323
     2    GND @S9S_MB_2U_LIB.S9S_MB_2U(SCH_1):GND    I42 @S9S_MB_2U_LIB.S9S_MB_2U(SCH_1):PAGE323

PC2342 Q_CAP_C0805-22UF,16V,20%,X6S,CA
     1 SW_P3V3_AUX_FLT @S9S_MB_2U_LIB.S9S_MB_2U(SCH_1):SW_P3V3_AUX_FLT   I108 @S9S_MB_2U_LIB.S9S_MB_2U(SCH_1):PAGE245
     2    GND @S9S_MB_2U_LIB.S9S_MB_2U(SCH_1):GND   I108 @S9S_MB_2U_LIB.S9S_MB_2U(SCH_1):PAGE245

PC2343 Q_CAP_C0805-22UF,16V,20%,X6S,CA
     1 SW_P3V3_AUX_FLT @S9S_MB_2U_LIB.S9S_MB_2U(SCH_1):SW_P3V3_AUX_FLT   I111 @S9S_MB_2U_LIB.S9S_MB_2U(SCH_1):PAGE245
     2    GND @S9S_MB_2U_LIB.S9S_MB_2U(SCH_1):GND   I111 @S9S_MB_2U_LIB.S9S_MB_2U(SCH_1):PAGE245

PC2344 Q_CAP_C0805-22UF,16V,20%,X6S,CA
     1 SW_P3V3_AUX_FLT @S9S_MB_2U_LIB.S9S_MB_2U(SCH_1):SW_P3V3_AUX_FLT   I112 @S9S_MB_2U_LIB.S9S_MB_2U(SCH_1):PAGE245
     2    GND @S9S_MB_2U_LIB.S9S_MB_2U(SCH_1):GND   I112 @S9S_MB_2U_LIB.S9S_MB_2U(SCH_1):PAGE245

PC2345 Q_CAPP_THLF-270UF,16V,20%,OSCOA
     1 SW_P12V_PVCCIN_CPU0_FLT @S9S_MB_2U_LIB.S9S_MB_2U(SCH_1):SW_P12V_PVCCIN_CPU0_FLT    I95 @S9S_MB_2U_LIB.S9S_MB_2U(SCH_1):PAGE253
     2    GND @S9S_MB_2U_LIB.S9S_MB_2U(SCH_1):GND    I95 @S9S_MB_2U_LIB.S9S_MB_2U(SCH_1):PAGE253

PC2346 Q_CAPP_THLF-270UF,16V,20%,OSCOA
     1 SW_P12V_PVCCIN_CPU1_FLT @S9S_MB_2U_LIB.S9S_MB_2U(SCH_1):SW_P12V_PVCCIN_CPU1_FLT    I96 @S9S_MB_2U_LIB.S9S_MB_2U(SCH_1):PAGE271
     2    GND @S9S_MB_2U_LIB.S9S_MB_2U(SCH_1):GND    I96 @S9S_MB_2U_LIB.S9S_MB_2U(SCH_1):PAGE271

PC2347 Q_CAP_0402-1NF,50V,10%,EMPTY,CA
     1 HSC_OCREF @S9S_MB_2U_LIB.S9S_MB_2U(SCH_1):HSC_OCREF    I29 @S9S_MB_2U_LIB.S9S_MB_2U(SCH_1):PAGE301
     2 AGND_HSC @S9S_MB_2U_LIB.S9S_MB_2U(SCH_1):AGND_HSC    I29 @S9S_MB_2U_LIB.S9S_MB_2U(SCH_1):PAGE301

PC2348 Q_CAP_0402-1NF,50V,10%,EMPTY,CA
     1 HSC_OCREF @S9S_MB_2U_LIB.S9S_MB_2U(SCH_1):HSC_OCREF    I11 @S9S_MB_2U_LIB.S9S_MB_2U(SCH_1):PAGE301
     2 AGND_HSC @S9S_MB_2U_LIB.S9S_MB_2U(SCH_1):AGND_HSC    I11 @S9S_MB_2U_LIB.S9S_MB_2U(SCH_1):PAGE301

PC2349 Q_CAP_0402-1NF,50V,10%,EMPTY,CA
     1 HSC_OCREF @S9S_MB_2U_LIB.S9S_MB_2U(SCH_1):HSC_OCREF    I11 @S9S_MB_2U_LIB.S9S_MB_2U(SCH_1):PAGE325
     2 AGND_HSC @S9S_MB_2U_LIB.S9S_MB_2U(SCH_1):AGND_HSC    I11 @S9S_MB_2U_LIB.S9S_MB_2U(SCH_1):PAGE325

PC2350 Q_CAP_0402-1NF,50V,10%,EMPTY,CA
     1 HSC_OCREF @S9S_MB_2U_LIB.S9S_MB_2U(SCH_1):HSC_OCREF    I29 @S9S_MB_2U_LIB.S9S_MB_2U(SCH_1):PAGE325
     2 AGND_HSC @S9S_MB_2U_LIB.S9S_MB_2U(SCH_1):AGND_HSC    I29 @S9S_MB_2U_LIB.S9S_MB_2U(SCH_1):PAGE325

PC2361 Q_CAP_0402-0.1UF,25V,10%,EMPTYA
     1 PVCCIN_CPU0_VCC @S9S_MB_2U_LIB.S9S_MB_2U(SCH_1):PVCCIN_CPU0_VCC   I136 @S9S_MB_2U_LIB.S9S_MB_2U(SCH_1):PAGE252
     2    GND @S9S_MB_2U_LIB.S9S_MB_2U(SCH_1):GND   I136 @S9S_MB_2U_LIB.S9S_MB_2U(SCH_1):PAGE252

PC2362 Q_CAP_0402-0.1UF,25V,10%,EMPTYA
     1 PVCCINFAON_CPU0_VCC @S9S_MB_2U_LIB.S9S_MB_2U(SCH_1):PVCCINFAON_CPU0_VCC   I110 @S9S_MB_2U_LIB.S9S_MB_2U(SCH_1):PAGE260
     2    GND @S9S_MB_2U_LIB.S9S_MB_2U(SCH_1):GND   I110 @S9S_MB_2U_LIB.S9S_MB_2U(SCH_1):PAGE260

PC2365 Q_CAP_0402-0.1UF,25V,10%,EMPTYA
     1 PVCCD_HV_CPU0_VCC @S9S_MB_2U_LIB.S9S_MB_2U(SCH_1):PVCCD_HV_CPU0_VCC    I96 @S9S_MB_2U_LIB.S9S_MB_2U(SCH_1):PAGE264
     2    GND @S9S_MB_2U_LIB.S9S_MB_2U(SCH_1):GND    I96 @S9S_MB_2U_LIB.S9S_MB_2U(SCH_1):PAGE264

PC2366 Q_CAP_0402-0.1UF,25V,10%,EMPTYA
     1 PVCCIN_CPU1_VCC @S9S_MB_2U_LIB.S9S_MB_2U(SCH_1):PVCCIN_CPU1_VCC   I128 @S9S_MB_2U_LIB.S9S_MB_2U(SCH_1):PAGE270
     2    GND @S9S_MB_2U_LIB.S9S_MB_2U(SCH_1):GND   I128 @S9S_MB_2U_LIB.S9S_MB_2U(SCH_1):PAGE270

PC2367 Q_CAP_0402-0.1UF,25V,10%,EMPTYA
     1 PVCCINFAON_CPU1_VCC @S9S_MB_2U_LIB.S9S_MB_2U(SCH_1):PVCCINFAON_CPU1_VCC   I111 @S9S_MB_2U_LIB.S9S_MB_2U(SCH_1):PAGE278
     2    GND @S9S_MB_2U_LIB.S9S_MB_2U(SCH_1):GND   I111 @S9S_MB_2U_LIB.S9S_MB_2U(SCH_1):PAGE278

PC2368 Q_CAP_0402-0.1UF,25V,10%,EMPTYA
     1 PVCCD_HV_CPU1_VCC @S9S_MB_2U_LIB.S9S_MB_2U(SCH_1):PVCCD_HV_CPU1_VCC    I96 @S9S_MB_2U_LIB.S9S_MB_2U(SCH_1):PAGE282
     2    GND @S9S_MB_2U_LIB.S9S_MB_2U(SCH_1):GND    I96 @S9S_MB_2U_LIB.S9S_MB_2U(SCH_1):PAGE282

PC2643 Q_CAP_C0402-1UF,25V,10%,X6S,CHA
     1 PVPP_HBM_CPU0_VCC @S9S_MB_2U_LIB.S9S_MB_2U(SCH_1):PVPP_HBM_CPU0_VCC     I4 @S9S_MB_2U_LIB.S9S_MB_2U(SCH_1):PAGE267
     2    GND @S9S_MB_2U_LIB.S9S_MB_2U(SCH_1):GND     I4 @S9S_MB_2U_LIB.S9S_MB_2U(SCH_1):PAGE267

PC2645 Q_CAPP_SMLF-330UF,2.5V,+10/-35B
     1 PVCCFA_EHV_FIVRA_CPU0 @S9S_MB_2U_LIB.S9S_MB_2U(SCH_1):PVCCFA_EHV_FIVRA_CPU0    I67 @S9S_MB_2U_LIB.S9S_MB_2U(SCH_1):PAGE257
     2    GND @S9S_MB_2U_LIB.S9S_MB_2U(SCH_1):GND    I67 @S9S_MB_2U_LIB.S9S_MB_2U(SCH_1):PAGE257

PC2946 Q_CAP_C0402-2.2UF,10V,10%,X6S,A
     1 PVCCFA_EHV_CPU0_PVCC @S9S_MB_2U_LIB.S9S_MB_2U(SCH_1):PVCCFA_EHV_CPU0_PVCC    I16 @S9S_MB_2U_LIB.S9S_MB_2U(SCH_1):PAGE261
     2    GND @S9S_MB_2U_LIB.S9S_MB_2U(SCH_1):GND    I16 @S9S_MB_2U_LIB.S9S_MB_2U(SCH_1):PAGE261

PC2947 Q_CAP_C0402-2.2UF,10V,10%,X6S,A
     1 PVCCFA_EHV_CPU0_PVCC @S9S_MB_2U_LIB.S9S_MB_2U(SCH_1):PVCCFA_EHV_CPU0_PVCC    I29 @S9S_MB_2U_LIB.S9S_MB_2U(SCH_1):PAGE261
     2    GND @S9S_MB_2U_LIB.S9S_MB_2U(SCH_1):GND    I29 @S9S_MB_2U_LIB.S9S_MB_2U(SCH_1):PAGE261

PC2948 Q_CAP_C0402-2.2UF,10V,10%,X6S,A
     1 PVCCFA_EHV_CPU0_PVCC @S9S_MB_2U_LIB.S9S_MB_2U(SCH_1):PVCCFA_EHV_CPU0_PVCC    I14 @S9S_MB_2U_LIB.S9S_MB_2U(SCH_1):PAGE265
     2    GND @S9S_MB_2U_LIB.S9S_MB_2U(SCH_1):GND    I14 @S9S_MB_2U_LIB.S9S_MB_2U(SCH_1):PAGE265

PC2949 Q_CAP_C0402-2.2UF,10V,10%,X6S,A
     1 PVCCFA_EHV_CPU1_PVCC @S9S_MB_2U_LIB.S9S_MB_2U(SCH_1):PVCCFA_EHV_CPU1_PVCC    I13 @S9S_MB_2U_LIB.S9S_MB_2U(SCH_1):PAGE279
     2    GND @S9S_MB_2U_LIB.S9S_MB_2U(SCH_1):GND    I13 @S9S_MB_2U_LIB.S9S_MB_2U(SCH_1):PAGE279

PC2950 Q_CAP_C0402-2.2UF,10V,10%,X6S,A
     1 PVCCFA_EHV_CPU1_PVCC @S9S_MB_2U_LIB.S9S_MB_2U(SCH_1):PVCCFA_EHV_CPU1_PVCC    I26 @S9S_MB_2U_LIB.S9S_MB_2U(SCH_1):PAGE279
     2    GND @S9S_MB_2U_LIB.S9S_MB_2U(SCH_1):GND    I26 @S9S_MB_2U_LIB.S9S_MB_2U(SCH_1):PAGE279

PC2951 Q_CAP_C0402-2.2UF,10V,10%,X6S,A
     1 PVCCFA_EHV_CPU1_PVCC @S9S_MB_2U_LIB.S9S_MB_2U(SCH_1):PVCCFA_EHV_CPU1_PVCC    I18 @S9S_MB_2U_LIB.S9S_MB_2U(SCH_1):PAGE283
     2    GND @S9S_MB_2U_LIB.S9S_MB_2U(SCH_1):GND    I18 @S9S_MB_2U_LIB.S9S_MB_2U(SCH_1):PAGE283

PC3272 Q_CAP_C0402-1UF,25V,10%,X6S,CHA
     1 HSC_VDD_R_3 @S9S_MB_2U_LIB.S9S_MB_2U(SCH_1):HSC_VDD_R_3    I19 @S9S_MB_2U_LIB.S9S_MB_2U(SCH_1):PAGE325
     2 AGND_HSC @S9S_MB_2U_LIB.S9S_MB_2U(SCH_1):AGND_HSC    I19 @S9S_MB_2U_LIB.S9S_MB_2U(SCH_1):PAGE325

PC4056 Q_CAP_C0402-3900PF,50V,10%,EMPA
     1 P12V_OCP_GATE_1 @S9S_MB_2U_LIB.S9S_MB_2U(SCH_1):P12V_OCP_GATE_1    I83 @S9S_MB_2U_LIB.S9S_MB_2U(SCH_1):PAGE153
     2    GND @S9S_MB_2U_LIB.S9S_MB_2U(SCH_1):GND    I83 @S9S_MB_2U_LIB.S9S_MB_2U(SCH_1):PAGE153

PC5328 Q_CAP_C0402-1UF,25V,10%,X6S,CHA
     1 P3V3_AUX @S9S_MB_2U_LIB.S9S_MB_2U(SCH_1):P3V3_AUX    I66 @S9S_MB_2U_LIB.S9S_MB_2U(SCH_1):PAGE153
     2    GND @S9S_MB_2U_LIB.S9S_MB_2U(SCH_1):GND    I66 @S9S_MB_2U_LIB.S9S_MB_2U(SCH_1):PAGE153

PD15 ZENER_AC-5.0SMDJ14A,SMLF,IC,BCA
     A    GND @S9S_MB_2U_LIB.S9S_MB_2U(SCH_1):GND    I51 @S9S_MB_2U_LIB.S9S_MB_2U(SCH_1):PAGE328
     C P12V_PSU_FUSE @S9S_MB_2U_LIB.S9S_MB_2U(SCH_1):P12V_PSU_FUSE    I51 @S9S_MB_2U_LIB.S9S_MB_2U(SCH_1):PAGE328

PD16 ZENER_AC-5.0SMDJ14A,SMLF,IC,BCA
     A    GND @S9S_MB_2U_LIB.S9S_MB_2U(SCH_1):GND    I53 @S9S_MB_2U_LIB.S9S_MB_2U(SCH_1):PAGE328
     C P12V_PSU_FUSE @S9S_MB_2U_LIB.S9S_MB_2U(SCH_1):P12V_PSU_FUSE    I53 @S9S_MB_2U_LIB.S9S_MB_2U(SCH_1):PAGE328

PD17 SS15P3SM386A-SS15P3S-M3/86A,SMA
     1    GND @S9S_MB_2U_LIB.S9S_MB_2U(SCH_1):GND    I72 @S9S_MB_2U_LIB.S9S_MB_2U(SCH_1):PAGE328
     K P12V_AUX @S9S_MB_2U_LIB.S9S_MB_2U(SCH_1):P12V_AUX    I72 @S9S_MB_2U_LIB.S9S_MB_2U(SCH_1):PAGE328
     2    GND @S9S_MB_2U_LIB.S9S_MB_2U(SCH_1):GND    I72 @S9S_MB_2U_LIB.S9S_MB_2U(SCH_1):PAGE328

PD101 DIODE_TVS-SMF14A,SMLF,IC,BCSMFA
     A    GND @S9S_MB_2U_LIB.S9S_MB_2U(SCH_1):GND    I38 @S9S_MB_2U_LIB.S9S_MB_2U(SCH_1):PAGE153
     C P12V_AUX @S9S_MB_2U_LIB.S9S_MB_2U(SCH_1):P12V_AUX    I38 @S9S_MB_2U_LIB.S9S_MB_2U(SCH_1):PAGE153

PD102 SCHOTTKY_AC-B340A-13-F,SMLF,ICA
     A    GND @S9S_MB_2U_LIB.S9S_MB_2U(SCH_1):GND    I86 @S9S_MB_2U_LIB.S9S_MB_2U(SCH_1):PAGE153
     C P12V_OCP_SFF @S9S_MB_2U_LIB.S9S_MB_2U(SCH_1):P12V_OCP_SFF    I86 @S9S_MB_2U_LIB.S9S_MB_2U(SCH_1):PAGE153

PD103 SCHOTTKY_AC-B340A-13-F,SMLF,ICA
     A    GND @S9S_MB_2U_LIB.S9S_MB_2U(SCH_1):GND   I104 @S9S_MB_2U_LIB.S9S_MB_2U(SCH_1):PAGE153
     C P3V3_OCP_SFF_R @S9S_MB_2U_LIB.S9S_MB_2U(SCH_1):P3V3_OCP_SFF_R   I104 @S9S_MB_2U_LIB.S9S_MB_2U(SCH_1):PAGE153

PD107 DIODE_TVS-SMF14A,SMLF,IC,BCSMFA
     A    GND @S9S_MB_2U_LIB.S9S_MB_2U(SCH_1):GND    I44 @S9S_MB_2U_LIB.S9S_MB_2U(SCH_1):PAGE131
     C P12V_AUX @S9S_MB_2U_LIB.S9S_MB_2U(SCH_1):P12V_AUX    I44 @S9S_MB_2U_LIB.S9S_MB_2U(SCH_1):PAGE131

PD108 SCHOTTKY_AC-B340A-13-F,SMLF,ICA
     A    GND @S9S_MB_2U_LIB.S9S_MB_2U(SCH_1):GND    I93 @S9S_MB_2U_LIB.S9S_MB_2U(SCH_1):PAGE131
     C P12V_OCP_V3_2 @S9S_MB_2U_LIB.S9S_MB_2U(SCH_1):P12V_OCP_V3_2    I93 @S9S_MB_2U_LIB.S9S_MB_2U(SCH_1):PAGE131

PD109 SCHOTTKY_AC-B340A-13-F,SMLF,ICA
     A    GND @S9S_MB_2U_LIB.S9S_MB_2U(SCH_1):GND   I107 @S9S_MB_2U_LIB.S9S_MB_2U(SCH_1):PAGE131
     C P3V3_OCP_V3_2_R @S9S_MB_2U_LIB.S9S_MB_2U(SCH_1):P3V3_OCP_V3_2_R   I107 @S9S_MB_2U_LIB.S9S_MB_2U(SCH_1):PAGE131

PD112 SCHOTTKY_AC-B340A-13-F,SMLF,ICA
     A    GND @S9S_MB_2U_LIB.S9S_MB_2U(SCH_1):GND    I71 @S9S_MB_2U_LIB.S9S_MB_2U(SCH_1):PAGE324
     C P12V_E1S_0 @S9S_MB_2U_LIB.S9S_MB_2U(SCH_1):P12V_E1S_0    I71 @S9S_MB_2U_LIB.S9S_MB_2U(SCH_1):PAGE324

PD113 SCHOTTKY_AC-B340A-13-F,SMLF,ICA
     A    GND @S9S_MB_2U_LIB.S9S_MB_2U(SCH_1):GND    I46 @S9S_MB_2U_LIB.S9S_MB_2U(SCH_1):PAGE324
     C P3V3_E1S_0_R @S9S_MB_2U_LIB.S9S_MB_2U(SCH_1):P3V3_E1S_0_R    I46 @S9S_MB_2U_LIB.S9S_MB_2U(SCH_1):PAGE324

PD114 DIODE_TVS-SMF14A,SMLF,IC,BCSMFA
     A    GND @S9S_MB_2U_LIB.S9S_MB_2U(SCH_1):GND    I84 @S9S_MB_2U_LIB.S9S_MB_2U(SCH_1):PAGE324
     C P12V_AUX @S9S_MB_2U_LIB.S9S_MB_2U(SCH_1):P12V_AUX    I84 @S9S_MB_2U_LIB.S9S_MB_2U(SCH_1):PAGE324

PD115 DIODE_TVS-SMF14A,SMLF,IC,BCSMFA
     A    GND @S9S_MB_2U_LIB.S9S_MB_2U(SCH_1):GND    I29 @S9S_MB_2U_LIB.S9S_MB_2U(SCH_1):PAGE229
     C P12V_AUX @S9S_MB_2U_LIB.S9S_MB_2U(SCH_1):P12V_AUX    I29 @S9S_MB_2U_LIB.S9S_MB_2U(SCH_1):PAGE229

PD116 SCHOTTKY_AC-B340A-13-F,SMLF,ICA
     A    GND @S9S_MB_2U_LIB.S9S_MB_2U(SCH_1):GND    I82 @S9S_MB_2U_LIB.S9S_MB_2U(SCH_1):PAGE229
     C P12V_SCM_R @S9S_MB_2U_LIB.S9S_MB_2U(SCH_1):P12V_SCM_R    I82 @S9S_MB_2U_LIB.S9S_MB_2U(SCH_1):PAGE229

PJ42 SCONN21_9193031121LF-SCONN21_9A
     1 P12V_PSU @S9S_MB_2U_LIB.S9S_MB_2U(SCH_1):P12V_PSU    I34 @S9S_MB_2U_LIB.S9S_MB_2U(SCH_1):PAGE327
     3 P12V_HSC_SENSE1_N @S9S_MB_2U_LIB.S9S_MB_2U(SCH_1):P12V_HSC_SENSE1_N    I34 @S9S_MB_2U_LIB.S9S_MB_2U(SCH_1):PAGE327
     4 P12V_HSC_SENSE2_P @S9S_MB_2U_LIB.S9S_MB_2U(SCH_1):P12V_HSC_SENSE2_P    I34 @S9S_MB_2U_LIB.S9S_MB_2U(SCH_1):PAGE327
     5 P12V_HSC_SENSE2_N @S9S_MB_2U_LIB.S9S_MB_2U(SCH_1):P12V_HSC_SENSE2_N    I34 @S9S_MB_2U_LIB.S9S_MB_2U(SCH_1):PAGE327
     2 P12V_HSC_SENSE1_P @S9S_MB_2U_LIB.S9S_MB_2U(SCH_1):P12V_HSC_SENSE1_P    I34 @S9S_MB_2U_LIB.S9S_MB_2U(SCH_1):PAGE327
    G1    GND @S9S_MB_2U_LIB.S9S_MB_2U(SCH_1):GND    I34 @S9S_MB_2U_LIB.S9S_MB_2U(SCH_1):PAGE327
    G2    GND @S9S_MB_2U_LIB.S9S_MB_2U(SCH_1):GND    I34 @S9S_MB_2U_LIB.S9S_MB_2U(SCH_1):PAGE327
     6 P12V_HSC_ADC_N @S9S_MB_2U_LIB.S9S_MB_2U(SCH_1):P12V_HSC_ADC_N    I34 @S9S_MB_2U_LIB.S9S_MB_2U(SCH_1):PAGE327
     7 P12V_HSC_ADC_P @S9S_MB_2U_LIB.S9S_MB_2U(SCH_1):P12V_HSC_ADC_P    I34 @S9S_MB_2U_LIB.S9S_MB_2U(SCH_1):PAGE327
     8 P12V_HSC_GATE1 @S9S_MB_2U_LIB.S9S_MB_2U(SCH_1):P12V_HSC_GATE1    I34 @S9S_MB_2U_LIB.S9S_MB_2U(SCH_1):PAGE327
     9 P12V_HSC_GATE2 @S9S_MB_2U_LIB.S9S_MB_2U(SCH_1):P12V_HSC_GATE2    I34 @S9S_MB_2U_LIB.S9S_MB_2U(SCH_1):PAGE327
    10 P12V_AUX @S9S_MB_2U_LIB.S9S_MB_2U(SCH_1):P12V_AUX    I34 @S9S_MB_2U_LIB.S9S_MB_2U(SCH_1):PAGE327
    11    GND @S9S_MB_2U_LIB.S9S_MB_2U(SCH_1):GND    I34 @S9S_MB_2U_LIB.S9S_MB_2U(SCH_1):PAGE327
    12 P3V3_AUX @S9S_MB_2U_LIB.S9S_MB_2U(SCH_1):P3V3_AUX    I34 @S9S_MB_2U_LIB.S9S_MB_2U(SCH_1):PAGE327
    13 IRQ_HSC_FAULT_N @S9S_MB_2U_LIB.S9S_MB_2U(SCH_1):IRQ_HSC_FAULT_N    I34 @S9S_MB_2U_LIB.S9S_MB_2U(SCH_1):PAGE327
    14 HSC_EN @S9S_MB_2U_LIB.S9S_MB_2U(SCH_1):HSC_EN    I34 @S9S_MB_2U_LIB.S9S_MB_2U(SCH_1):PAGE327
    15 MB0_P12V_STBY_PWRGD @S9S_MB_2U_LIB.S9S_MB_2U(SCH_1):MB0_P12V_STBY_PWRGD    I34 @S9S_MB_2U_LIB.S9S_MB_2U(SCH_1):PAGE327
    16 HSC_CSOUT @S9S_MB_2U_LIB.S9S_MB_2U(SCH_1):HSC_CSOUT    I34 @S9S_MB_2U_LIB.S9S_MB_2U(SCH_1):PAGE327
    17 HSC_TYPE_ADC @S9S_MB_2U_LIB.S9S_MB_2U(SCH_1):HSC_TYPE_ADC    I34 @S9S_MB_2U_LIB.S9S_MB_2U(SCH_1):PAGE327
    18 SMB_SML1_PMBUS_HSC_MODULE_SCL @S9S_MB_2U_LIB.S9S_MB_2U(SCH_1):SMB_SML1_PMBUS_HSC_MODULE_SCL    I34 @S9S_MB_2U_LIB.S9S_MB_2U(SCH_1):PAGE327
    19 SMB_SML1_PMBUS_HSC_MODULE_SDA @S9S_MB_2U_LIB.S9S_MB_2U(SCH_1):SMB_SML1_PMBUS_HSC_MODULE_SDA    I34 @S9S_MB_2U_LIB.S9S_MB_2U(SCH_1):PAGE327
    20 IRQ_SML1_PMBUS_ALERT_N @S9S_MB_2U_LIB.S9S_MB_2U(SCH_1):IRQ_SML1_PMBUS_ALERT_N    I34 @S9S_MB_2U_LIB.S9S_MB_2U(SCH_1):PAGE327
    21    GND @S9S_MB_2U_LIB.S9S_MB_2U(SCH_1):GND    I34 @S9S_MB_2U_LIB.S9S_MB_2U(SCH_1):PAGE327

PJ45 Q_SHORT_SM-EMPTY,SHORT6
     1 VSENSE_PVCCINFAON_CPU0_DP @S9S_MB_2U_LIB.S9S_MB_2U(SCH_1):VSENSE_PVCCINFAON_CPU0_DP    I43 @S9S_MB_2U_LIB.S9S_MB_2U(SCH_1):PAGE260
     2 SH_PVCCINFAON_CPU0 @S9S_MB_2U_LIB.S9S_MB_2U(SCH_1):SH_PVCCINFAON_CPU0    I43 @S9S_MB_2U_LIB.S9S_MB_2U(SCH_1):PAGE260

PJ46 Q_SHORT_SM-EMPTY,SHORT6
     1 VSENSE_PVCCFA_EHV_CPU0_DP @S9S_MB_2U_LIB.S9S_MB_2U(SCH_1):VSENSE_PVCCFA_EHV_CPU0_DP    I39 @S9S_MB_2U_LIB.S9S_MB_2U(SCH_1):PAGE260
     2 SH_PVCCFA_EHV_CPU0 @S9S_MB_2U_LIB.S9S_MB_2U(SCH_1):SH_PVCCFA_EHV_CPU0    I39 @S9S_MB_2U_LIB.S9S_MB_2U(SCH_1):PAGE260

PJ47 Q_SHORT_SM-EMPTY,SHORT6
     1 VSENSE_PVCCIN_CPU0_DP @S9S_MB_2U_LIB.S9S_MB_2U(SCH_1):VSENSE_PVCCIN_CPU0_DP    I37 @S9S_MB_2U_LIB.S9S_MB_2U(SCH_1):PAGE252
     2 SH_PVCCIN_CPU0 @S9S_MB_2U_LIB.S9S_MB_2U(SCH_1):SH_PVCCIN_CPU0    I37 @S9S_MB_2U_LIB.S9S_MB_2U(SCH_1):PAGE252

PJ48 Q_SHORT_SM-EMPTY,SHORT6
     1 VSENSE_PVCCD_HV_CPU1_DP @S9S_MB_2U_LIB.S9S_MB_2U(SCH_1):VSENSE_PVCCD_HV_CPU1_DP    I16 @S9S_MB_2U_LIB.S9S_MB_2U(SCH_1):PAGE282
     2 SH_PVCCD_HV_CPU1 @S9S_MB_2U_LIB.S9S_MB_2U(SCH_1):SH_PVCCD_HV_CPU1    I16 @S9S_MB_2U_LIB.S9S_MB_2U(SCH_1):PAGE282

PJ49 Q_SHORT_SM-EMPTY,SHORT6
     1 VSENSE_PVCCFA_EHV_FIVRA_CPU1_DP @S9S_MB_2U_LIB.S9S_MB_2U(SCH_1):VSENSE_PVCCFA_EHV_FIVRA_CPU1_DP    I22 @S9S_MB_2U_LIB.S9S_MB_2U(SCH_1):PAGE270
     2 SH_PVCCFA_EHV_FIVRA_CPU1 @S9S_MB_2U_LIB.S9S_MB_2U(SCH_1):SH_PVCCFA_EHV_FIVRA_CPU1    I22 @S9S_MB_2U_LIB.S9S_MB_2U(SCH_1):PAGE270

PJ50 Q_SHORT_SM-EMPTY,SHORT6
     1 VSENSE_PVCCINFAON_CPU1_DP @S9S_MB_2U_LIB.S9S_MB_2U(SCH_1):VSENSE_PVCCINFAON_CPU1_DP    I54 @S9S_MB_2U_LIB.S9S_MB_2U(SCH_1):PAGE278
     2 SH_PVCCINFAON_CPU1 @S9S_MB_2U_LIB.S9S_MB_2U(SCH_1):SH_PVCCINFAON_CPU1    I54 @S9S_MB_2U_LIB.S9S_MB_2U(SCH_1):PAGE278

PJ51 Q_SHORT_SM-EMPTY,SHORT6
     1 VSENSE_PVCCFA_EHV_CPU1_DP @S9S_MB_2U_LIB.S9S_MB_2U(SCH_1):VSENSE_PVCCFA_EHV_CPU1_DP    I44 @S9S_MB_2U_LIB.S9S_MB_2U(SCH_1):PAGE278
     2 SH_PVCCFA_EHV_CPU1 @S9S_MB_2U_LIB.S9S_MB_2U(SCH_1):SH_PVCCFA_EHV_CPU1    I44 @S9S_MB_2U_LIB.S9S_MB_2U(SCH_1):PAGE278

PJ52 Q_SHORT_SM-EMPTY,SHORT6
     1 VSENSE_PVCCIN_CPU1_DP @S9S_MB_2U_LIB.S9S_MB_2U(SCH_1):VSENSE_PVCCIN_CPU1_DP    I46 @S9S_MB_2U_LIB.S9S_MB_2U(SCH_1):PAGE270
     2 SH_PVCCIN_CPU1 @S9S_MB_2U_LIB.S9S_MB_2U(SCH_1):SH_PVCCIN_CPU1    I46 @S9S_MB_2U_LIB.S9S_MB_2U(SCH_1):PAGE270

PJ53 Q_SHORT_SM-EMPTY,SHORT6
     1 VSENSE_PVCCFA_EHV_FIVRA_CPU0_DP @S9S_MB_2U_LIB.S9S_MB_2U(SCH_1):VSENSE_PVCCFA_EHV_FIVRA_CPU0_DP    I24 @S9S_MB_2U_LIB.S9S_MB_2U(SCH_1):PAGE252
     2 SH_PVCCFA_EHV_FIVRA_CPU0 @S9S_MB_2U_LIB.S9S_MB_2U(SCH_1):SH_PVCCFA_EHV_FIVRA_CPU0    I24 @S9S_MB_2U_LIB.S9S_MB_2U(SCH_1):PAGE252

PJ54 Q_SHORT_SM-EMPTY,SHORT6
     1 VSENSE_PVCCD_HV_CPU0_DP @S9S_MB_2U_LIB.S9S_MB_2U(SCH_1):VSENSE_PVCCD_HV_CPU0_DP    I32 @S9S_MB_2U_LIB.S9S_MB_2U(SCH_1):PAGE264
     2 SH_PVCCD_HV_CPU0 @S9S_MB_2U_LIB.S9S_MB_2U(SCH_1):SH_PVCCD_HV_CPU0    I32 @S9S_MB_2U_LIB.S9S_MB_2U(SCH_1):PAGE264

PJ62 Q_SHORT_SM-EMPTY,SHORT6
     1 SH_P1V05_PCH_AUX_P @S9S_MB_2U_LIB.S9S_MB_2U(SCH_1):SH_P1V05_PCH_AUX_P    I43 @S9S_MB_2U_LIB.S9S_MB_2U(SCH_1):PAGE248
     2 P1V05_PCH_AUX @S9S_MB_2U_LIB.S9S_MB_2U(SCH_1):P1V05_PCH_AUX    I43 @S9S_MB_2U_LIB.S9S_MB_2U(SCH_1):PAGE248

PJ63 Q_SHORT_SM-EMPTY,SHORT6
     1 SH_P1V05_PCH_AUX_N @S9S_MB_2U_LIB.S9S_MB_2U(SCH_1):SH_P1V05_PCH_AUX_N    I42 @S9S_MB_2U_LIB.S9S_MB_2U(SCH_1):PAGE248
     2    GND @S9S_MB_2U_LIB.S9S_MB_2U(SCH_1):GND    I42 @S9S_MB_2U_LIB.S9S_MB_2U(SCH_1):PAGE248

PJ64 Q_SHORT_SM-EMPTY,SHORT6
     1 SH_PVPP_HBM_CPU0_P @S9S_MB_2U_LIB.S9S_MB_2U(SCH_1):SH_PVPP_HBM_CPU0_P    I41 @S9S_MB_2U_LIB.S9S_MB_2U(SCH_1):PAGE267
     2 PVPP_HBM_CPU0 @S9S_MB_2U_LIB.S9S_MB_2U(SCH_1):PVPP_HBM_CPU0    I41 @S9S_MB_2U_LIB.S9S_MB_2U(SCH_1):PAGE267

PJ65 Q_SHORT_SM-EMPTY,SHORT6
     1 SH_PVPP_HBM_CPU0_N @S9S_MB_2U_LIB.S9S_MB_2U(SCH_1):SH_PVPP_HBM_CPU0_N    I33 @S9S_MB_2U_LIB.S9S_MB_2U(SCH_1):PAGE267
     2    GND @S9S_MB_2U_LIB.S9S_MB_2U(SCH_1):GND    I33 @S9S_MB_2U_LIB.S9S_MB_2U(SCH_1):PAGE267

PJ66 Q_SHORT_SM-EMPTY,SHORT6
     1 SH_PVPP_HBM_CPU1_P @S9S_MB_2U_LIB.S9S_MB_2U(SCH_1):SH_PVPP_HBM_CPU1_P    I46 @S9S_MB_2U_LIB.S9S_MB_2U(SCH_1):PAGE285
     2 PVPP_HBM_CPU1 @S9S_MB_2U_LIB.S9S_MB_2U(SCH_1):PVPP_HBM_CPU1    I46 @S9S_MB_2U_LIB.S9S_MB_2U(SCH_1):PAGE285

PJ67 Q_SHORT_SM-EMPTY,SHORT6
     1 SH_PVPP_HBM_CPU1_N @S9S_MB_2U_LIB.S9S_MB_2U(SCH_1):SH_PVPP_HBM_CPU1_N    I44 @S9S_MB_2U_LIB.S9S_MB_2U(SCH_1):PAGE285
     2    GND @S9S_MB_2U_LIB.S9S_MB_2U(SCH_1):GND    I44 @S9S_MB_2U_LIB.S9S_MB_2U(SCH_1):PAGE285

PJP1 CONN3_210HP1030BR1-CONN3_210-HB
     3 SMB_VR_3V3AUX_SDA_R3 @S9S_MB_2U_LIB.S9S_MB_2U(SCH_1):SMB_VR_3V3AUX_SDA_R3    I32 @S9S_MB_2U_LIB.S9S_MB_2U(SCH_1):PAGE252
     2    GND @S9S_MB_2U_LIB.S9S_MB_2U(SCH_1):GND    I32 @S9S_MB_2U_LIB.S9S_MB_2U(SCH_1):PAGE252
     1 SMB_VR_3V3AUX_SCL_R3 @S9S_MB_2U_LIB.S9S_MB_2U(SCH_1):SMB_VR_3V3AUX_SCL_R3    I32 @S9S_MB_2U_LIB.S9S_MB_2U(SCH_1):PAGE252

 PL2 Q_INDUCTOR_SMLF-130NH/106A,INDA
     2 PVCCFA_EHV_FIVRA_CPU0 @S9S_MB_2U_LIB.S9S_MB_2U(SCH_1):PVCCFA_EHV_FIVRA_CPU0    I51 @S9S_MB_2U_LIB.S9S_MB_2U(SCH_1):PAGE258
     1 SW_PVCCFA_EHV_FIVRA_CPU0_SW3 @S9S_MB_2U_LIB.S9S_MB_2U(SCH_1):SW_PVCCFA_EHV_FIVRA_CPU0_SW3    I51 @S9S_MB_2U_LIB.S9S_MB_2U(SCH_1):PAGE258

 PL3 Q_INDUCTOR_SMLF-300NH/33A,IND,A
     2 PVCCFA_EHV_CPU0 @S9S_MB_2U_LIB.S9S_MB_2U(SCH_1):PVCCFA_EHV_CPU0    I29 @S9S_MB_2U_LIB.S9S_MB_2U(SCH_1):PAGE262
     1 SW_PVCCFA_EHV_CPU0_SW1 @S9S_MB_2U_LIB.S9S_MB_2U(SCH_1):SW_PVCCFA_EHV_CPU0_SW1    I29 @S9S_MB_2U_LIB.S9S_MB_2U(SCH_1):PAGE262

 PL4 Q_INDUCTOR_SMLF-120NH/69A,IND,A
     2 PVCCINFAON_CPU0 @S9S_MB_2U_LIB.S9S_MB_2U(SCH_1):PVCCINFAON_CPU0    I52 @S9S_MB_2U_LIB.S9S_MB_2U(SCH_1):PAGE261
     1 SW_PVCCINFAON_CPU0_SW1 @S9S_MB_2U_LIB.S9S_MB_2U(SCH_1):SW_PVCCINFAON_CPU0_SW1    I52 @S9S_MB_2U_LIB.S9S_MB_2U(SCH_1):PAGE261

 PL5 Q_INDUCTOR_SMLF-120NH/69A,IND,A
     2 PVCCINFAON_CPU0 @S9S_MB_2U_LIB.S9S_MB_2U(SCH_1):PVCCINFAON_CPU0    I39 @S9S_MB_2U_LIB.S9S_MB_2U(SCH_1):PAGE261
     1 SW_PVCCINFAON_CPU0_SW2 @S9S_MB_2U_LIB.S9S_MB_2U(SCH_1):SW_PVCCINFAON_CPU0_SW2    I39 @S9S_MB_2U_LIB.S9S_MB_2U(SCH_1):PAGE261

 PL6 Q_INDUCTOR_SMLF-100NH/16A,IND,A
     2 SW_P12V_PVCCINFAON_CPU0_FLT @S9S_MB_2U_LIB.S9S_MB_2U(SCH_1):SW_P12V_PVCCINFAON_CPU0_FLT    I62 @S9S_MB_2U_LIB.S9S_MB_2U(SCH_1):PAGE261
     1 P12V_AUX @S9S_MB_2U_LIB.S9S_MB_2U(SCH_1):P12V_AUX    I62 @S9S_MB_2U_LIB.S9S_MB_2U(SCH_1):PAGE261

 PL7 Q_INDUCTOR4P_14-150NH,SMLF,INDA
     2 IND_P0_CPL8 @S9S_MB_2U_LIB.S9S_MB_2U(SCH_1):IND_P0_CPL8    I44 @S9S_MB_2U_LIB.S9S_MB_2U(SCH_1):PAGE256
     3    GND @S9S_MB_2U_LIB.S9S_MB_2U(SCH_1):GND    I44 @S9S_MB_2U_LIB.S9S_MB_2U(SCH_1):PAGE256
     4 PVCCIN_CPU0 @S9S_MB_2U_LIB.S9S_MB_2U(SCH_1):PVCCIN_CPU0    I44 @S9S_MB_2U_LIB.S9S_MB_2U(SCH_1):PAGE256
     1 SW_PVCCIN_CPU0_SW8 @S9S_MB_2U_LIB.S9S_MB_2U(SCH_1):SW_PVCCIN_CPU0_SW8    I44 @S9S_MB_2U_LIB.S9S_MB_2U(SCH_1):PAGE256

 PL8 Q_INDUCTOR4P_14-150NH,SMLF,INDA
     2 IND_P0_CPL7 @S9S_MB_2U_LIB.S9S_MB_2U(SCH_1):IND_P0_CPL7    I58 @S9S_MB_2U_LIB.S9S_MB_2U(SCH_1):PAGE256
     3 IND_P0_CPL6 @S9S_MB_2U_LIB.S9S_MB_2U(SCH_1):IND_P0_CPL6    I58 @S9S_MB_2U_LIB.S9S_MB_2U(SCH_1):PAGE256
     4 PVCCIN_CPU0 @S9S_MB_2U_LIB.S9S_MB_2U(SCH_1):PVCCIN_CPU0    I58 @S9S_MB_2U_LIB.S9S_MB_2U(SCH_1):PAGE256
     1 SW_PVCCIN_CPU0_SW7 @S9S_MB_2U_LIB.S9S_MB_2U(SCH_1):SW_PVCCIN_CPU0_SW7    I58 @S9S_MB_2U_LIB.S9S_MB_2U(SCH_1):PAGE256

 PL9 Q_INDUCTOR4P_14-150NH,SMLF,INDA
     2 IND_P0_CPL6 @S9S_MB_2U_LIB.S9S_MB_2U(SCH_1):IND_P0_CPL6    I32 @S9S_MB_2U_LIB.S9S_MB_2U(SCH_1):PAGE255
     3 IND_P0_CPL1 @S9S_MB_2U_LIB.S9S_MB_2U(SCH_1):IND_P0_CPL1    I32 @S9S_MB_2U_LIB.S9S_MB_2U(SCH_1):PAGE255
     4 PVCCIN_CPU0 @S9S_MB_2U_LIB.S9S_MB_2U(SCH_1):PVCCIN_CPU0    I32 @S9S_MB_2U_LIB.S9S_MB_2U(SCH_1):PAGE255
     1 SW_PVCCIN_CPU0_SW6 @S9S_MB_2U_LIB.S9S_MB_2U(SCH_1):SW_PVCCIN_CPU0_SW6    I32 @S9S_MB_2U_LIB.S9S_MB_2U(SCH_1):PAGE255

PL10 Q_INDUCTOR4P_14-150NH,SMLF,INDA
     2 IND_P0_CPL5 @S9S_MB_2U_LIB.S9S_MB_2U(SCH_1):IND_P0_CPL5    I50 @S9S_MB_2U_LIB.S9S_MB_2U(SCH_1):PAGE255
     3 IND_P0_CPL8 @S9S_MB_2U_LIB.S9S_MB_2U(SCH_1):IND_P0_CPL8    I50 @S9S_MB_2U_LIB.S9S_MB_2U(SCH_1):PAGE255
     4 PVCCIN_CPU0 @S9S_MB_2U_LIB.S9S_MB_2U(SCH_1):PVCCIN_CPU0    I50 @S9S_MB_2U_LIB.S9S_MB_2U(SCH_1):PAGE255
     1 SW_PVCCIN_CPU0_SW5 @S9S_MB_2U_LIB.S9S_MB_2U(SCH_1):SW_PVCCIN_CPU0_SW5    I50 @S9S_MB_2U_LIB.S9S_MB_2U(SCH_1):PAGE255

PL11 Q_INDUCTOR4P_14-150NH,SMLF,INDA
     2 IND_P0_CPL4 @S9S_MB_2U_LIB.S9S_MB_2U(SCH_1):IND_P0_CPL4    I33 @S9S_MB_2U_LIB.S9S_MB_2U(SCH_1):PAGE254
     3 IND_P0_CPL5 @S9S_MB_2U_LIB.S9S_MB_2U(SCH_1):IND_P0_CPL5    I33 @S9S_MB_2U_LIB.S9S_MB_2U(SCH_1):PAGE254
     4 PVCCIN_CPU0 @S9S_MB_2U_LIB.S9S_MB_2U(SCH_1):PVCCIN_CPU0    I33 @S9S_MB_2U_LIB.S9S_MB_2U(SCH_1):PAGE254
     1 SW_PVCCIN_CPU0_SW4 @S9S_MB_2U_LIB.S9S_MB_2U(SCH_1):SW_PVCCIN_CPU0_SW4    I33 @S9S_MB_2U_LIB.S9S_MB_2U(SCH_1):PAGE254

PL12 Q_INDUCTOR_SMLF-130NH/106A,INDA
     2 PVCCFA_EHV_FIVRA_CPU1 @S9S_MB_2U_LIB.S9S_MB_2U(SCH_1):PVCCFA_EHV_FIVRA_CPU1    I57 @S9S_MB_2U_LIB.S9S_MB_2U(SCH_1):PAGE276
     1 SW_PVCCFA_EHV_FIVRA_CPU1_SW3 @S9S_MB_2U_LIB.S9S_MB_2U(SCH_1):SW_PVCCFA_EHV_FIVRA_CPU1_SW3    I57 @S9S_MB_2U_LIB.S9S_MB_2U(SCH_1):PAGE276

PL13 Q_INDUCTOR4P_14-150NH,SMLF,INDA
     2 IND_P0_CPL2 @S9S_MB_2U_LIB.S9S_MB_2U(SCH_1):IND_P0_CPL2    I21 @S9S_MB_2U_LIB.S9S_MB_2U(SCH_1):PAGE253
     3 IND_P0_CPL3 @S9S_MB_2U_LIB.S9S_MB_2U(SCH_1):IND_P0_CPL3    I21 @S9S_MB_2U_LIB.S9S_MB_2U(SCH_1):PAGE253
     4 PVCCIN_CPU0 @S9S_MB_2U_LIB.S9S_MB_2U(SCH_1):PVCCIN_CPU0    I21 @S9S_MB_2U_LIB.S9S_MB_2U(SCH_1):PAGE253
     1 SW_PVCCIN_CPU0_SW2 @S9S_MB_2U_LIB.S9S_MB_2U(SCH_1):SW_PVCCIN_CPU0_SW2    I21 @S9S_MB_2U_LIB.S9S_MB_2U(SCH_1):PAGE253

PL14 Q_INDUCTOR_SMLF-100NH/16A,IND,A
     2 SW_P12V_PVCCFA_EHV_FIVRA_CPU1_R @S9S_MB_2U_LIB.S9S_MB_2U(SCH_1):SW_P12V_PVCCFA_EHV_FIVRA_CPU1_R    I64 @S9S_MB_2U_LIB.S9S_MB_2U(SCH_1):PAGE276
     1 P12V_AUX @S9S_MB_2U_LIB.S9S_MB_2U(SCH_1):P12V_AUX    I64 @S9S_MB_2U_LIB.S9S_MB_2U(SCH_1):PAGE276

PL15 Q_INDUCTOR_SMLF-50NH/148A,IND,A
     2 SW_P12V_PVCCIN_CPU0_FLT @S9S_MB_2U_LIB.S9S_MB_2U(SCH_1):SW_P12V_PVCCIN_CPU0_FLT    I82 @S9S_MB_2U_LIB.S9S_MB_2U(SCH_1):PAGE253
     1 P12V_AUX @S9S_MB_2U_LIB.S9S_MB_2U(SCH_1):P12V_AUX    I82 @S9S_MB_2U_LIB.S9S_MB_2U(SCH_1):PAGE253

PL16 Q_INDUCTOR_SMLF-BLM18SN220TN1DA
     2 SW_P1V8_PCH_AUX_FLT @S9S_MB_2U_LIB.S9S_MB_2U(SCH_1):SW_P1V8_PCH_AUX_FLT    I16 @S9S_MB_2U_LIB.S9S_MB_2U(SCH_1):PAGE249
     1 P12V_AUX @S9S_MB_2U_LIB.S9S_MB_2U(SCH_1):P12V_AUX    I16 @S9S_MB_2U_LIB.S9S_MB_2U(SCH_1):PAGE249

PL17 Q_INDUCTOR_SMLF-120NH/69A,IND,A
     2 PVCCD_HV_CPU1 @S9S_MB_2U_LIB.S9S_MB_2U(SCH_1):PVCCD_HV_CPU1    I14 @S9S_MB_2U_LIB.S9S_MB_2U(SCH_1):PAGE283
     1 SW_PVCCD_HV_CPU1_SW1 @S9S_MB_2U_LIB.S9S_MB_2U(SCH_1):SW_PVCCD_HV_CPU1_SW1    I14 @S9S_MB_2U_LIB.S9S_MB_2U(SCH_1):PAGE283

PL18 Q_INDUCTOR_SMLF-130NH/106A,INDA
     2 PVCCFA_EHV_FIVRA_CPU1 @S9S_MB_2U_LIB.S9S_MB_2U(SCH_1):PVCCFA_EHV_FIVRA_CPU1    I55 @S9S_MB_2U_LIB.S9S_MB_2U(SCH_1):PAGE275
     1 SW_PVCCFA_EHV_FIVRA_CPU1_SW1 @S9S_MB_2U_LIB.S9S_MB_2U(SCH_1):SW_PVCCFA_EHV_FIVRA_CPU1_SW1    I55 @S9S_MB_2U_LIB.S9S_MB_2U(SCH_1):PAGE275

PL19 Q_INDUCTOR_SMLF-130NH/106A,INDA
     2 PVCCFA_EHV_FIVRA_CPU1 @S9S_MB_2U_LIB.S9S_MB_2U(SCH_1):PVCCFA_EHV_FIVRA_CPU1    I44 @S9S_MB_2U_LIB.S9S_MB_2U(SCH_1):PAGE275
     1 SW_PVCCFA_EHV_FIVRA_CPU1_SW2 @S9S_MB_2U_LIB.S9S_MB_2U(SCH_1):SW_PVCCFA_EHV_FIVRA_CPU1_SW2    I44 @S9S_MB_2U_LIB.S9S_MB_2U(SCH_1):PAGE275

PL20 Q_INDUCTOR_SMLF-300NH/33A,IND,A
     2 PVCCFA_EHV_CPU1 @S9S_MB_2U_LIB.S9S_MB_2U(SCH_1):PVCCFA_EHV_CPU1    I23 @S9S_MB_2U_LIB.S9S_MB_2U(SCH_1):PAGE280
     1 SW_PVCCFA_EHV_CPU1_SW1 @S9S_MB_2U_LIB.S9S_MB_2U(SCH_1):SW_PVCCFA_EHV_CPU1_SW1    I23 @S9S_MB_2U_LIB.S9S_MB_2U(SCH_1):PAGE280

PL21 Q_INDUCTOR_SMLF-120NH/69A,IND,A
     2 PVCCINFAON_CPU1 @S9S_MB_2U_LIB.S9S_MB_2U(SCH_1):PVCCINFAON_CPU1    I54 @S9S_MB_2U_LIB.S9S_MB_2U(SCH_1):PAGE279
     1 SW_PVCCINFAON_CPU1_SW1 @S9S_MB_2U_LIB.S9S_MB_2U(SCH_1):SW_PVCCINFAON_CPU1_SW1    I54 @S9S_MB_2U_LIB.S9S_MB_2U(SCH_1):PAGE279

PL22 Q_INDUCTOR_SMLF-120NH/69A,IND,A
     2 PVCCINFAON_CPU1 @S9S_MB_2U_LIB.S9S_MB_2U(SCH_1):PVCCINFAON_CPU1    I46 @S9S_MB_2U_LIB.S9S_MB_2U(SCH_1):PAGE279
     1 SW_PVCCINFAON_CPU1_SW2 @S9S_MB_2U_LIB.S9S_MB_2U(SCH_1):SW_PVCCINFAON_CPU1_SW2    I46 @S9S_MB_2U_LIB.S9S_MB_2U(SCH_1):PAGE279

PL23 Q_INDUCTOR_SMLF-100NH/16A,IND,A
     2 SW_P12V_PVCCINFAON_CPU1_FLT @S9S_MB_2U_LIB.S9S_MB_2U(SCH_1):SW_P12V_PVCCINFAON_CPU1_FLT    I78 @S9S_MB_2U_LIB.S9S_MB_2U(SCH_1):PAGE279
     1 P12V_AUX @S9S_MB_2U_LIB.S9S_MB_2U(SCH_1):P12V_AUX    I78 @S9S_MB_2U_LIB.S9S_MB_2U(SCH_1):PAGE279

PL24 Q_INDUCTOR4P_14-150NH,SMLF,INDA
     2 IND_P1_CPL8 @S9S_MB_2U_LIB.S9S_MB_2U(SCH_1):IND_P1_CPL8    I43 @S9S_MB_2U_LIB.S9S_MB_2U(SCH_1):PAGE274
     3 IND_P1_CPL5 @S9S_MB_2U_LIB.S9S_MB_2U(SCH_1):IND_P1_CPL5    I43 @S9S_MB_2U_LIB.S9S_MB_2U(SCH_1):PAGE274
     4 PVCCIN_CPU1 @S9S_MB_2U_LIB.S9S_MB_2U(SCH_1):PVCCIN_CPU1    I43 @S9S_MB_2U_LIB.S9S_MB_2U(SCH_1):PAGE274
     1 SW_PVCCIN_CPU1_SW8 @S9S_MB_2U_LIB.S9S_MB_2U(SCH_1):SW_PVCCIN_CPU1_SW8    I43 @S9S_MB_2U_LIB.S9S_MB_2U(SCH_1):PAGE274

PL25 Q_INDUCTOR4P_14-150NH,SMLF,INDA
     2 IND_P1_CPL7 @S9S_MB_2U_LIB.S9S_MB_2U(SCH_1):IND_P1_CPL7    I58 @S9S_MB_2U_LIB.S9S_MB_2U(SCH_1):PAGE274
     3    GND @S9S_MB_2U_LIB.S9S_MB_2U(SCH_1):GND    I58 @S9S_MB_2U_LIB.S9S_MB_2U(SCH_1):PAGE274
     4 PVCCIN_CPU1 @S9S_MB_2U_LIB.S9S_MB_2U(SCH_1):PVCCIN_CPU1    I58 @S9S_MB_2U_LIB.S9S_MB_2U(SCH_1):PAGE274
     1 SW_PVCCIN_CPU1_SW7 @S9S_MB_2U_LIB.S9S_MB_2U(SCH_1):SW_PVCCIN_CPU1_SW7    I58 @S9S_MB_2U_LIB.S9S_MB_2U(SCH_1):PAGE274

PL26 Q_INDUCTOR4P_14-150NH,SMLF,INDA
     2 IND_P1_CPL6 @S9S_MB_2U_LIB.S9S_MB_2U(SCH_1):IND_P1_CPL6    I28 @S9S_MB_2U_LIB.S9S_MB_2U(SCH_1):PAGE273
     3 IND_P1_CPL7 @S9S_MB_2U_LIB.S9S_MB_2U(SCH_1):IND_P1_CPL7    I28 @S9S_MB_2U_LIB.S9S_MB_2U(SCH_1):PAGE273
     4 PVCCIN_CPU1 @S9S_MB_2U_LIB.S9S_MB_2U(SCH_1):PVCCIN_CPU1    I28 @S9S_MB_2U_LIB.S9S_MB_2U(SCH_1):PAGE273
     1 SW_PVCCIN_CPU1_SW6 @S9S_MB_2U_LIB.S9S_MB_2U(SCH_1):SW_PVCCIN_CPU1_SW6    I28 @S9S_MB_2U_LIB.S9S_MB_2U(SCH_1):PAGE273

PL27 Q_INDUCTOR4P_14-150NH,SMLF,INDA
     2 IND_P1_CPL5 @S9S_MB_2U_LIB.S9S_MB_2U(SCH_1):IND_P1_CPL5    I48 @S9S_MB_2U_LIB.S9S_MB_2U(SCH_1):PAGE273
     3 IND_P1_CPL4 @S9S_MB_2U_LIB.S9S_MB_2U(SCH_1):IND_P1_CPL4    I48 @S9S_MB_2U_LIB.S9S_MB_2U(SCH_1):PAGE273
     4 PVCCIN_CPU1 @S9S_MB_2U_LIB.S9S_MB_2U(SCH_1):PVCCIN_CPU1    I48 @S9S_MB_2U_LIB.S9S_MB_2U(SCH_1):PAGE273
     1 SW_PVCCIN_CPU1_SW5 @S9S_MB_2U_LIB.S9S_MB_2U(SCH_1):SW_PVCCIN_CPU1_SW5    I48 @S9S_MB_2U_LIB.S9S_MB_2U(SCH_1):PAGE273

PL28 Q_INDUCTOR4P_14-150NH,SMLF,INDA
     2 IND_P1_CPL4 @S9S_MB_2U_LIB.S9S_MB_2U(SCH_1):IND_P1_CPL4    I37 @S9S_MB_2U_LIB.S9S_MB_2U(SCH_1):PAGE272
     3 IND_P1_CPL3 @S9S_MB_2U_LIB.S9S_MB_2U(SCH_1):IND_P1_CPL3    I37 @S9S_MB_2U_LIB.S9S_MB_2U(SCH_1):PAGE272
     4 PVCCIN_CPU1 @S9S_MB_2U_LIB.S9S_MB_2U(SCH_1):PVCCIN_CPU1    I37 @S9S_MB_2U_LIB.S9S_MB_2U(SCH_1):PAGE272
     1 SW_PVCCIN_CPU1_SW4 @S9S_MB_2U_LIB.S9S_MB_2U(SCH_1):SW_PVCCIN_CPU1_SW4    I37 @S9S_MB_2U_LIB.S9S_MB_2U(SCH_1):PAGE272

PL29 Q_INDUCTOR4P_14-150NH,SMLF,INDA
     2 IND_P1_CPL3 @S9S_MB_2U_LIB.S9S_MB_2U(SCH_1):IND_P1_CPL3    I51 @S9S_MB_2U_LIB.S9S_MB_2U(SCH_1):PAGE272
     3 IND_P1_CPL2 @S9S_MB_2U_LIB.S9S_MB_2U(SCH_1):IND_P1_CPL2    I51 @S9S_MB_2U_LIB.S9S_MB_2U(SCH_1):PAGE272
     4 PVCCIN_CPU1 @S9S_MB_2U_LIB.S9S_MB_2U(SCH_1):PVCCIN_CPU1    I51 @S9S_MB_2U_LIB.S9S_MB_2U(SCH_1):PAGE272
     1 SW_PVCCIN_CPU1_SW3 @S9S_MB_2U_LIB.S9S_MB_2U(SCH_1):SW_PVCCIN_CPU1_SW3    I51 @S9S_MB_2U_LIB.S9S_MB_2U(SCH_1):PAGE272

PL30 Q_INDUCTOR4P_14-150NH,SMLF,INDA
     2 IND_P1_CPL2 @S9S_MB_2U_LIB.S9S_MB_2U(SCH_1):IND_P1_CPL2    I18 @S9S_MB_2U_LIB.S9S_MB_2U(SCH_1):PAGE271
     3 IND_P1_CPL1 @S9S_MB_2U_LIB.S9S_MB_2U(SCH_1):IND_P1_CPL1    I18 @S9S_MB_2U_LIB.S9S_MB_2U(SCH_1):PAGE271
     4 PVCCIN_CPU1 @S9S_MB_2U_LIB.S9S_MB_2U(SCH_1):PVCCIN_CPU1    I18 @S9S_MB_2U_LIB.S9S_MB_2U(SCH_1):PAGE271
     1 SW_PVCCIN_CPU1_SW2 @S9S_MB_2U_LIB.S9S_MB_2U(SCH_1):SW_PVCCIN_CPU1_SW2    I18 @S9S_MB_2U_LIB.S9S_MB_2U(SCH_1):PAGE271

PL31 Q_INDUCTOR4P_14-150NH,SMLF,INDA
     2 IND_P1_CPL1 @S9S_MB_2U_LIB.S9S_MB_2U(SCH_1):IND_P1_CPL1    I74 @S9S_MB_2U_LIB.S9S_MB_2U(SCH_1):PAGE271
     3 IND_P1_CPL6 @S9S_MB_2U_LIB.S9S_MB_2U(SCH_1):IND_P1_CPL6    I74 @S9S_MB_2U_LIB.S9S_MB_2U(SCH_1):PAGE271
     4 PVCCIN_CPU1 @S9S_MB_2U_LIB.S9S_MB_2U(SCH_1):PVCCIN_CPU1    I74 @S9S_MB_2U_LIB.S9S_MB_2U(SCH_1):PAGE271
     1 SW_PVCCIN_CPU1_SW1 @S9S_MB_2U_LIB.S9S_MB_2U(SCH_1):SW_PVCCIN_CPU1_SW1    I74 @S9S_MB_2U_LIB.S9S_MB_2U(SCH_1):PAGE271

PL32 Q_INDUCTOR_SMLF-50NH/148A,IND,A
     2 SW_P12V_PVCCIN_CPU1_FLT @S9S_MB_2U_LIB.S9S_MB_2U(SCH_1):SW_P12V_PVCCIN_CPU1_FLT    I83 @S9S_MB_2U_LIB.S9S_MB_2U(SCH_1):PAGE271
     1 P12V_AUX @S9S_MB_2U_LIB.S9S_MB_2U(SCH_1):P12V_AUX    I83 @S9S_MB_2U_LIB.S9S_MB_2U(SCH_1):PAGE271

PL33 Q_INDUCTOR_SMLF-130NH/106A,INDA
     2 PVCCFA_EHV_FIVRA_CPU0 @S9S_MB_2U_LIB.S9S_MB_2U(SCH_1):PVCCFA_EHV_FIVRA_CPU0    I70 @S9S_MB_2U_LIB.S9S_MB_2U(SCH_1):PAGE257
     1 SW_PVCCFA_EHV_FIVRA_CPU0_SW1 @S9S_MB_2U_LIB.S9S_MB_2U(SCH_1):SW_PVCCFA_EHV_FIVRA_CPU0_SW1    I70 @S9S_MB_2U_LIB.S9S_MB_2U(SCH_1):PAGE257

PL34 Q_INDUCTOR_SMLF-130NH/106A,INDA
     2 PVCCFA_EHV_FIVRA_CPU0 @S9S_MB_2U_LIB.S9S_MB_2U(SCH_1):PVCCFA_EHV_FIVRA_CPU0    I49 @S9S_MB_2U_LIB.S9S_MB_2U(SCH_1):PAGE257
     1 SW_PVCCFA_EHV_FIVRA_CPU0_SW2 @S9S_MB_2U_LIB.S9S_MB_2U(SCH_1):SW_PVCCFA_EHV_FIVRA_CPU0_SW2    I49 @S9S_MB_2U_LIB.S9S_MB_2U(SCH_1):PAGE257

PL35 Q_INDUCTOR_SMLF-120NH/69A,IND,A
     2 PVCCD_HV_CPU0 @S9S_MB_2U_LIB.S9S_MB_2U(SCH_1):PVCCD_HV_CPU0    I30 @S9S_MB_2U_LIB.S9S_MB_2U(SCH_1):PAGE265
     1 SW_PVCCD_HV_CPU0_SW1 @S9S_MB_2U_LIB.S9S_MB_2U(SCH_1):SW_PVCCD_HV_CPU0_SW1    I30 @S9S_MB_2U_LIB.S9S_MB_2U(SCH_1):PAGE265

PL43 Q_INDUCTOR_SMLF-100NH/16A,IND,A
     2 SW_P12V_PVCCFA_EHV_FIVRA_CPU1_L @S9S_MB_2U_LIB.S9S_MB_2U(SCH_1):SW_P12V_PVCCFA_EHV_FIVRA_CPU1_L    I79 @S9S_MB_2U_LIB.S9S_MB_2U(SCH_1):PAGE275
     1 P12V_AUX @S9S_MB_2U_LIB.S9S_MB_2U(SCH_1):P12V_AUX    I79 @S9S_MB_2U_LIB.S9S_MB_2U(SCH_1):PAGE275

PL44 Q_INDUCTOR_SMLF-100NH/16A,IND,A
     2 SW_P12V_PVCCFA_EHV_FIVRA_CPU0_L @S9S_MB_2U_LIB.S9S_MB_2U(SCH_1):SW_P12V_PVCCFA_EHV_FIVRA_CPU0_L    I80 @S9S_MB_2U_LIB.S9S_MB_2U(SCH_1):PAGE257
     1 P12V_AUX @S9S_MB_2U_LIB.S9S_MB_2U(SCH_1):P12V_AUX    I80 @S9S_MB_2U_LIB.S9S_MB_2U(SCH_1):PAGE257

PL45 Q_INDUCTOR_SMLF-100NH/16A,IND,A
     2 SW_P3V3_AUX_FLT @S9S_MB_2U_LIB.S9S_MB_2U(SCH_1):SW_P3V3_AUX_FLT    I98 @S9S_MB_2U_LIB.S9S_MB_2U(SCH_1):PAGE245
     1 P12V_AUX @S9S_MB_2U_LIB.S9S_MB_2U(SCH_1):P12V_AUX    I98 @S9S_MB_2U_LIB.S9S_MB_2U(SCH_1):PAGE245

PL64 Q_INDUCTOR_SMLF-BLM18SN220TN1DA
     2 SW_P5V_AUX_FLT @S9S_MB_2U_LIB.S9S_MB_2U(SCH_1):SW_P5V_AUX_FLT     I5 @S9S_MB_2U_LIB.S9S_MB_2U(SCH_1):PAGE244
     1 P12V_AUX @S9S_MB_2U_LIB.S9S_MB_2U(SCH_1):P12V_AUX     I5 @S9S_MB_2U_LIB.S9S_MB_2U(SCH_1):PAGE244

PL65 Q_INDUCTOR_SMLF-4.7UH,IND,CV-4A
     2 P5V_AUX @S9S_MB_2U_LIB.S9S_MB_2U(SCH_1):P5V_AUX    I30 @S9S_MB_2U_LIB.S9S_MB_2U(SCH_1):PAGE244
     1 SW_P5V_AUX_SW @S9S_MB_2U_LIB.S9S_MB_2U(SCH_1):SW_P5V_AUX_SW    I30 @S9S_MB_2U_LIB.S9S_MB_2U(SCH_1):PAGE244

PL66 Q_INDUCTOR_SMLF-1.5UH/53A,IND,A
     2 P3V3_AUX @S9S_MB_2U_LIB.S9S_MB_2U(SCH_1):P3V3_AUX   I129 @S9S_MB_2U_LIB.S9S_MB_2U(SCH_1):PAGE245
     1 SW_P3V3_AUX_SW @S9S_MB_2U_LIB.S9S_MB_2U(SCH_1):SW_P3V3_AUX_SW   I129 @S9S_MB_2U_LIB.S9S_MB_2U(SCH_1):PAGE245

PL101 Q_INDUCTOR_SMLF-100NH/16A,IND,A
     2 SW_P12V_PVCCFA_EHV_FIVRA_CPU0_R @S9S_MB_2U_LIB.S9S_MB_2U(SCH_1):SW_P12V_PVCCFA_EHV_FIVRA_CPU0_R    I59 @S9S_MB_2U_LIB.S9S_MB_2U(SCH_1):PAGE258
     1 P12V_AUX @S9S_MB_2U_LIB.S9S_MB_2U(SCH_1):P12V_AUX    I59 @S9S_MB_2U_LIB.S9S_MB_2U(SCH_1):PAGE258

PL105 Q_INDUCTOR_SMLF-120NH/69A,IND,A
     2    GND @S9S_MB_2U_LIB.S9S_MB_2U(SCH_1):GND    I39 @S9S_MB_2U_LIB.S9S_MB_2U(SCH_1):PAGE256
     1 IND_P0_CPL7 @S9S_MB_2U_LIB.S9S_MB_2U(SCH_1):IND_P0_CPL7    I39 @S9S_MB_2U_LIB.S9S_MB_2U(SCH_1):PAGE256

PL106 Q_INDUCTOR_SMLF-120NH/69A,IND,A
     2    GND @S9S_MB_2U_LIB.S9S_MB_2U(SCH_1):GND    I23 @S9S_MB_2U_LIB.S9S_MB_2U(SCH_1):PAGE274
     1 IND_P1_CPL8 @S9S_MB_2U_LIB.S9S_MB_2U(SCH_1):IND_P1_CPL8    I23 @S9S_MB_2U_LIB.S9S_MB_2U(SCH_1):PAGE274

PL110 Q_INDUCTOR_SMLF-100NH/16A,IND,A
     2 SW_P12V_AUX_P1V05_PCH_AUX_FLT @S9S_MB_2U_LIB.S9S_MB_2U(SCH_1):SW_P12V_AUX_P1V05_PCH_AUX_FLT    I19 @S9S_MB_2U_LIB.S9S_MB_2U(SCH_1):PAGE248
     1 P12V_AUX @S9S_MB_2U_LIB.S9S_MB_2U(SCH_1):P12V_AUX    I19 @S9S_MB_2U_LIB.S9S_MB_2U(SCH_1):PAGE248

PL112 Q_INDUCTOR4P_14-150NH,SMLF,INDA
     2 IND_P0_CPL3 @S9S_MB_2U_LIB.S9S_MB_2U(SCH_1):IND_P0_CPL3    I50 @S9S_MB_2U_LIB.S9S_MB_2U(SCH_1):PAGE254
     3 IND_P0_CPL4 @S9S_MB_2U_LIB.S9S_MB_2U(SCH_1):IND_P0_CPL4    I50 @S9S_MB_2U_LIB.S9S_MB_2U(SCH_1):PAGE254
     4 PVCCIN_CPU0 @S9S_MB_2U_LIB.S9S_MB_2U(SCH_1):PVCCIN_CPU0    I50 @S9S_MB_2U_LIB.S9S_MB_2U(SCH_1):PAGE254
     1 SW_PVCCIN_CPU0_SW3 @S9S_MB_2U_LIB.S9S_MB_2U(SCH_1):SW_PVCCIN_CPU0_SW3    I50 @S9S_MB_2U_LIB.S9S_MB_2U(SCH_1):PAGE254

PL113 Q_INDUCTOR_SMLF-130NH/106A,INDA
     2 PVCCFA_EHV_FIVRA_CPU1 @S9S_MB_2U_LIB.S9S_MB_2U(SCH_1):PVCCFA_EHV_FIVRA_CPU1    I44 @S9S_MB_2U_LIB.S9S_MB_2U(SCH_1):PAGE276
     1 SW_PVCCFA_EHV_FIVRA_CPU1_SW4 @S9S_MB_2U_LIB.S9S_MB_2U(SCH_1):SW_PVCCFA_EHV_FIVRA_CPU1_SW4    I44 @S9S_MB_2U_LIB.S9S_MB_2U(SCH_1):PAGE276

PL114 Q_INDUCTOR4P_14-150NH,SMLF,INDA
     2 IND_P0_CPL1 @S9S_MB_2U_LIB.S9S_MB_2U(SCH_1):IND_P0_CPL1    I46 @S9S_MB_2U_LIB.S9S_MB_2U(SCH_1):PAGE253
     3 IND_P0_CPL2 @S9S_MB_2U_LIB.S9S_MB_2U(SCH_1):IND_P0_CPL2    I46 @S9S_MB_2U_LIB.S9S_MB_2U(SCH_1):PAGE253
     4 PVCCIN_CPU0 @S9S_MB_2U_LIB.S9S_MB_2U(SCH_1):PVCCIN_CPU0    I46 @S9S_MB_2U_LIB.S9S_MB_2U(SCH_1):PAGE253
     1 SW_PVCCIN_CPU0_SW1 @S9S_MB_2U_LIB.S9S_MB_2U(SCH_1):SW_PVCCIN_CPU0_SW1    I46 @S9S_MB_2U_LIB.S9S_MB_2U(SCH_1):PAGE253

PL118 Q_INDUCTOR_SMLF-0.68UH,IND,CV+A
     2 PVPP_HBM_CPU0 @S9S_MB_2U_LIB.S9S_MB_2U(SCH_1):PVPP_HBM_CPU0    I28 @S9S_MB_2U_LIB.S9S_MB_2U(SCH_1):PAGE267
     1 SW_PVPP_HBM_CPU0_SW @S9S_MB_2U_LIB.S9S_MB_2U(SCH_1):SW_PVPP_HBM_CPU0_SW    I28 @S9S_MB_2U_LIB.S9S_MB_2U(SCH_1):PAGE267

PL119 Q_INDUCTOR_SMLF-0.68UH,IND,CV+A
     2 PVPP_HBM_CPU1 @S9S_MB_2U_LIB.S9S_MB_2U(SCH_1):PVPP_HBM_CPU1    I33 @S9S_MB_2U_LIB.S9S_MB_2U(SCH_1):PAGE285
     1 SW_PVPP_HBM_CPU1_SW @S9S_MB_2U_LIB.S9S_MB_2U(SCH_1):SW_PVPP_HBM_CPU1_SW    I33 @S9S_MB_2U_LIB.S9S_MB_2U(SCH_1):PAGE285

PL120 Q_INDUCTOR_SMLF-4.7UH,IND,CV-4B
     2 PVNN_MAIN_CPU0 @S9S_MB_2U_LIB.S9S_MB_2U(SCH_1):PVNN_MAIN_CPU0    I29 @S9S_MB_2U_LIB.S9S_MB_2U(SCH_1):PAGE268
     1 SW_PVNN_MAIN_CPU0_SW @S9S_MB_2U_LIB.S9S_MB_2U(SCH_1):SW_PVNN_MAIN_CPU0_SW    I29 @S9S_MB_2U_LIB.S9S_MB_2U(SCH_1):PAGE268

PL121 Q_INDUCTOR_SMLF-4.7UH,IND,CV-4B
     2 PVNN_MAIN_CPU1 @S9S_MB_2U_LIB.S9S_MB_2U(SCH_1):PVNN_MAIN_CPU1    I27 @S9S_MB_2U_LIB.S9S_MB_2U(SCH_1):PAGE286
     1 SW_PVNN_MAIN_CPU1_SW @S9S_MB_2U_LIB.S9S_MB_2U(SCH_1):SW_PVNN_MAIN_CPU1_SW    I27 @S9S_MB_2U_LIB.S9S_MB_2U(SCH_1):PAGE286

PL150 Q_INDUCTOR_SMLF-300NH/33A,IND,A
     2 P1V05_PCH_AUX @S9S_MB_2U_LIB.S9S_MB_2U(SCH_1):P1V05_PCH_AUX    I53 @S9S_MB_2U_LIB.S9S_MB_2U(SCH_1):PAGE248
     1 SW_P1V05_PCH_AUX_SW @S9S_MB_2U_LIB.S9S_MB_2U(SCH_1):SW_P1V05_PCH_AUX_SW    I53 @S9S_MB_2U_LIB.S9S_MB_2U(SCH_1):PAGE248

PL170 Q_INDUCTOR_SMLF-2.2UH,IND,CV-2A
     2 P1V8_PCH_AUX @S9S_MB_2U_LIB.S9S_MB_2U(SCH_1):P1V8_PCH_AUX    I45 @S9S_MB_2U_LIB.S9S_MB_2U(SCH_1):PAGE249
     1 SW_P1V8_PCH_AUX_SW @S9S_MB_2U_LIB.S9S_MB_2U(SCH_1):SW_P1V8_PCH_AUX_SW    I45 @S9S_MB_2U_LIB.S9S_MB_2U(SCH_1):PAGE249

PL210 Q_INDUCTOR_SMLF-130NH/106A,INDA
     2 PVCCFA_EHV_FIVRA_CPU0 @S9S_MB_2U_LIB.S9S_MB_2U(SCH_1):PVCCFA_EHV_FIVRA_CPU0    I39 @S9S_MB_2U_LIB.S9S_MB_2U(SCH_1):PAGE258
     1 SW_PVCCFA_EHV_FIVRA_CPU0_SW4 @S9S_MB_2U_LIB.S9S_MB_2U(SCH_1):SW_PVCCFA_EHV_FIVRA_CPU0_SW4    I39 @S9S_MB_2U_LIB.S9S_MB_2U(SCH_1):PAGE258

PPQ1 MOSFET_NCH_1D3S-PSMNR58-30YLH,B
     3 P12V_AUX @S9S_MB_2U_LIB.S9S_MB_2U(SCH_1):P12V_AUX    I65 @S9S_MB_2U_LIB.S9S_MB_2U(SCH_1):PAGE328
     5 P12V_MAIN_R @S9S_MB_2U_LIB.S9S_MB_2U(SCH_1):P12V_MAIN_R    I65 @S9S_MB_2U_LIB.S9S_MB_2U(SCH_1):PAGE328
     2 P12V_AUX @S9S_MB_2U_LIB.S9S_MB_2U(SCH_1):P12V_AUX    I65 @S9S_MB_2U_LIB.S9S_MB_2U(SCH_1):PAGE328
     4 P12V_HSC_GATE_G5 @S9S_MB_2U_LIB.S9S_MB_2U(SCH_1):P12V_HSC_GATE_G5    I65 @S9S_MB_2U_LIB.S9S_MB_2U(SCH_1):PAGE328
     1 P12V_AUX @S9S_MB_2U_LIB.S9S_MB_2U(SCH_1):P12V_AUX    I65 @S9S_MB_2U_LIB.S9S_MB_2U(SCH_1):PAGE328

PPQ2 MOSFET_NCH_1D3S-PSMNR58-30YLH,B
     3 P12V_AUX @S9S_MB_2U_LIB.S9S_MB_2U(SCH_1):P12V_AUX    I73 @S9S_MB_2U_LIB.S9S_MB_2U(SCH_1):PAGE328
     5 P12V_MAIN_R @S9S_MB_2U_LIB.S9S_MB_2U(SCH_1):P12V_MAIN_R    I73 @S9S_MB_2U_LIB.S9S_MB_2U(SCH_1):PAGE328
     2 P12V_AUX @S9S_MB_2U_LIB.S9S_MB_2U(SCH_1):P12V_AUX    I73 @S9S_MB_2U_LIB.S9S_MB_2U(SCH_1):PAGE328
     4 P12V_HSC_GATE_G6 @S9S_MB_2U_LIB.S9S_MB_2U(SCH_1):P12V_HSC_GATE_G6    I73 @S9S_MB_2U_LIB.S9S_MB_2U(SCH_1):PAGE328
     1 P12V_AUX @S9S_MB_2U_LIB.S9S_MB_2U(SCH_1):P12V_AUX    I73 @S9S_MB_2U_LIB.S9S_MB_2U(SCH_1):PAGE328

PPQ5 MOSFET_NCH_1D3S-PSMNR58-30YLH,B
     3 P12V_AUX @S9S_MB_2U_LIB.S9S_MB_2U(SCH_1):P12V_AUX    I35 @S9S_MB_2U_LIB.S9S_MB_2U(SCH_1):PAGE328
     5 P12V_MAIN_R @S9S_MB_2U_LIB.S9S_MB_2U(SCH_1):P12V_MAIN_R    I35 @S9S_MB_2U_LIB.S9S_MB_2U(SCH_1):PAGE328
     2 P12V_AUX @S9S_MB_2U_LIB.S9S_MB_2U(SCH_1):P12V_AUX    I35 @S9S_MB_2U_LIB.S9S_MB_2U(SCH_1):PAGE328
     4 P12V_HSC_GATE_G1 @S9S_MB_2U_LIB.S9S_MB_2U(SCH_1):P12V_HSC_GATE_G1    I35 @S9S_MB_2U_LIB.S9S_MB_2U(SCH_1):PAGE328
     1 P12V_AUX @S9S_MB_2U_LIB.S9S_MB_2U(SCH_1):P12V_AUX    I35 @S9S_MB_2U_LIB.S9S_MB_2U(SCH_1):PAGE328

PPQ6 MOSFET_NCH_1D3S-PSMNR58-30YLH,B
     3 P12V_AUX @S9S_MB_2U_LIB.S9S_MB_2U(SCH_1):P12V_AUX    I40 @S9S_MB_2U_LIB.S9S_MB_2U(SCH_1):PAGE328
     5 P12V_MAIN_R @S9S_MB_2U_LIB.S9S_MB_2U(SCH_1):P12V_MAIN_R    I40 @S9S_MB_2U_LIB.S9S_MB_2U(SCH_1):PAGE328
     2 P12V_AUX @S9S_MB_2U_LIB.S9S_MB_2U(SCH_1):P12V_AUX    I40 @S9S_MB_2U_LIB.S9S_MB_2U(SCH_1):PAGE328
     4 P12V_HSC_GATE_G2 @S9S_MB_2U_LIB.S9S_MB_2U(SCH_1):P12V_HSC_GATE_G2    I40 @S9S_MB_2U_LIB.S9S_MB_2U(SCH_1):PAGE328
     1 P12V_AUX @S9S_MB_2U_LIB.S9S_MB_2U(SCH_1):P12V_AUX    I40 @S9S_MB_2U_LIB.S9S_MB_2U(SCH_1):PAGE328

PPQ7 MOSFET_NCH_1D3S-PSMNR58-30YLH,B
     3 P12V_AUX @S9S_MB_2U_LIB.S9S_MB_2U(SCH_1):P12V_AUX    I41 @S9S_MB_2U_LIB.S9S_MB_2U(SCH_1):PAGE328
     5 P12V_MAIN_R @S9S_MB_2U_LIB.S9S_MB_2U(SCH_1):P12V_MAIN_R    I41 @S9S_MB_2U_LIB.S9S_MB_2U(SCH_1):PAGE328
     2 P12V_AUX @S9S_MB_2U_LIB.S9S_MB_2U(SCH_1):P12V_AUX    I41 @S9S_MB_2U_LIB.S9S_MB_2U(SCH_1):PAGE328
     4 P12V_HSC_GATE_G3 @S9S_MB_2U_LIB.S9S_MB_2U(SCH_1):P12V_HSC_GATE_G3    I41 @S9S_MB_2U_LIB.S9S_MB_2U(SCH_1):PAGE328
     1 P12V_AUX @S9S_MB_2U_LIB.S9S_MB_2U(SCH_1):P12V_AUX    I41 @S9S_MB_2U_LIB.S9S_MB_2U(SCH_1):PAGE328

PPQ8 MOSFET_NCH_1D3S-PSMNR58-30YLH,B
     3 P12V_AUX @S9S_MB_2U_LIB.S9S_MB_2U(SCH_1):P12V_AUX    I62 @S9S_MB_2U_LIB.S9S_MB_2U(SCH_1):PAGE328
     5 P12V_MAIN_R @S9S_MB_2U_LIB.S9S_MB_2U(SCH_1):P12V_MAIN_R    I62 @S9S_MB_2U_LIB.S9S_MB_2U(SCH_1):PAGE328
     2 P12V_AUX @S9S_MB_2U_LIB.S9S_MB_2U(SCH_1):P12V_AUX    I62 @S9S_MB_2U_LIB.S9S_MB_2U(SCH_1):PAGE328
     4 P12V_HSC_GATE_G4 @S9S_MB_2U_LIB.S9S_MB_2U(SCH_1):P12V_HSC_GATE_G4    I62 @S9S_MB_2U_LIB.S9S_MB_2U(SCH_1):PAGE328
     1 P12V_AUX @S9S_MB_2U_LIB.S9S_MB_2U(SCH_1):P12V_AUX    I62 @S9S_MB_2U_LIB.S9S_MB_2U(SCH_1):PAGE328

PPQ9 MOSFET_NCH_1D3S-PSMNR58-30YLH,B
     3 P12V_AUX @S9S_MB_2U_LIB.S9S_MB_2U(SCH_1):P12V_AUX    I77 @S9S_MB_2U_LIB.S9S_MB_2U(SCH_1):PAGE328
     5 P12V_MAIN_R_0 @S9S_MB_2U_LIB.S9S_MB_2U(SCH_1):P12V_MAIN_R_0    I77 @S9S_MB_2U_LIB.S9S_MB_2U(SCH_1):PAGE328
     2 P12V_AUX @S9S_MB_2U_LIB.S9S_MB_2U(SCH_1):P12V_AUX    I77 @S9S_MB_2U_LIB.S9S_MB_2U(SCH_1):PAGE328
     4 MB0_CM_GATE_G0 @S9S_MB_2U_LIB.S9S_MB_2U(SCH_1):MB0_CM_GATE_G0    I77 @S9S_MB_2U_LIB.S9S_MB_2U(SCH_1):PAGE328
     1 P12V_AUX @S9S_MB_2U_LIB.S9S_MB_2U(SCH_1):P12V_AUX    I77 @S9S_MB_2U_LIB.S9S_MB_2U(SCH_1):PAGE328

 PR1 Q_RES_0402LF-0,5%,1/16W,CHIP,CA
     1    GND @S9S_MB_2U_LIB.S9S_MB_2U(SCH_1):GND    I19 @S9S_MB_2U_LIB.S9S_MB_2U(SCH_1):PAGE268
     2    GND @S9S_MB_2U_LIB.S9S_MB_2U(SCH_1):GND    I19 @S9S_MB_2U_LIB.S9S_MB_2U(SCH_1):PAGE268

 PR2 Q_RES_0402LF-0,5%,1/16W,CHIP,CA
     1    GND @S9S_MB_2U_LIB.S9S_MB_2U(SCH_1):GND    I22 @S9S_MB_2U_LIB.S9S_MB_2U(SCH_1):PAGE286
     2    GND @S9S_MB_2U_LIB.S9S_MB_2U(SCH_1):GND    I22 @S9S_MB_2U_LIB.S9S_MB_2U(SCH_1):PAGE286

 PR3 Q_RES_4P_12-0.003,1%,3W,SMLF,EA
     1 P12V_PSU @S9S_MB_2U_LIB.S9S_MB_2U(SCH_1):P12V_PSU   I126 @S9S_MB_2U_LIB.S9S_MB_2U(SCH_1):PAGE328
     2 P12V_MAIN_R_0 @S9S_MB_2U_LIB.S9S_MB_2U(SCH_1):P12V_MAIN_R_0   I126 @S9S_MB_2U_LIB.S9S_MB_2U(SCH_1):PAGE328
     3 P12V_HSC_SENSE1_P @S9S_MB_2U_LIB.S9S_MB_2U(SCH_1):P12V_HSC_SENSE1_P   I126 @S9S_MB_2U_LIB.S9S_MB_2U(SCH_1):PAGE328
     4 P12V_HSC_SENSE1_N @S9S_MB_2U_LIB.S9S_MB_2U(SCH_1):P12V_HSC_SENSE1_N   I126 @S9S_MB_2U_LIB.S9S_MB_2U(SCH_1):PAGE328

 PR4 Q_SP_RES4P-0.0003,1%,4W,SMLF,EA
    2B P12V_HSC_SENSE2_R1_N @S9S_MB_2U_LIB.S9S_MB_2U(SCH_1):P12V_HSC_SENSE2_R1_N    I79 @S9S_MB_2U_LIB.S9S_MB_2U(SCH_1):PAGE328
    1B P12V_HSC_SENSE2_R1_P @S9S_MB_2U_LIB.S9S_MB_2U(SCH_1):P12V_HSC_SENSE2_R1_P    I79 @S9S_MB_2U_LIB.S9S_MB_2U(SCH_1):PAGE328
    2A P12V_MAIN_R @S9S_MB_2U_LIB.S9S_MB_2U(SCH_1):P12V_MAIN_R    I79 @S9S_MB_2U_LIB.S9S_MB_2U(SCH_1):PAGE328
    1A P12V_PSU @S9S_MB_2U_LIB.S9S_MB_2U(SCH_1):P12V_PSU    I79 @S9S_MB_2U_LIB.S9S_MB_2U(SCH_1):PAGE328

PR50 Q_RES_0402LF-12.4K,0.1%,1/16W,A
     1 PVNN_MAIN_CPU0_FB @S9S_MB_2U_LIB.S9S_MB_2U(SCH_1):PVNN_MAIN_CPU0_FB    I28 @S9S_MB_2U_LIB.S9S_MB_2U(SCH_1):PAGE268
     2    GND @S9S_MB_2U_LIB.S9S_MB_2U(SCH_1):GND    I28 @S9S_MB_2U_LIB.S9S_MB_2U(SCH_1):PAGE268

PR51 Q_RES_0402LF-12.4K,0.1%,1/16W,A
     1 PVNN_MAIN_CPU1_FB @S9S_MB_2U_LIB.S9S_MB_2U(SCH_1):PVNN_MAIN_CPU1_FB    I26 @S9S_MB_2U_LIB.S9S_MB_2U(SCH_1):PAGE286
     2    GND @S9S_MB_2U_LIB.S9S_MB_2U(SCH_1):GND    I26 @S9S_MB_2U_LIB.S9S_MB_2U(SCH_1):PAGE286

PR73 Q_RES_0402LF-10K,1%,1/16W,CHIPA
     1 P3V3_AUX @S9S_MB_2U_LIB.S9S_MB_2U(SCH_1):P3V3_AUX   I139 @S9S_MB_2U_LIB.S9S_MB_2U(SCH_1):PAGE245
     2 PWRGD_P3V3_AUX @S9S_MB_2U_LIB.S9S_MB_2U(SCH_1):PWRGD_P3V3_AUX   I139 @S9S_MB_2U_LIB.S9S_MB_2U(SCH_1):PAGE245

PR89 Q_RES_0402LF-16.9K,1%,1/16W,CHA
     1 P5V_AUX_CS @S9S_MB_2U_LIB.S9S_MB_2U(SCH_1):P5V_AUX_CS    I16 @S9S_MB_2U_LIB.S9S_MB_2U(SCH_1):PAGE244
     2    GND @S9S_MB_2U_LIB.S9S_MB_2U(SCH_1):GND    I16 @S9S_MB_2U_LIB.S9S_MB_2U(SCH_1):PAGE244

PR91 Q_RES_0402LF-11.8K,0.1%,1/16W,A
     1 P5V_AUX_FB @S9S_MB_2U_LIB.S9S_MB_2U(SCH_1):P5V_AUX_FB    I25 @S9S_MB_2U_LIB.S9S_MB_2U(SCH_1):PAGE244
     2    GND @S9S_MB_2U_LIB.S9S_MB_2U(SCH_1):GND    I25 @S9S_MB_2U_LIB.S9S_MB_2U(SCH_1):PAGE244

PR92 Q_RES_0402LF-88.7K,1%,1/16W,CHA
     1 P5V_AUX_FB @S9S_MB_2U_LIB.S9S_MB_2U(SCH_1):P5V_AUX_FB    I39 @S9S_MB_2U_LIB.S9S_MB_2U(SCH_1):PAGE244
     2 P5V_AUX @S9S_MB_2U_LIB.S9S_MB_2U(SCH_1):P5V_AUX    I39 @S9S_MB_2U_LIB.S9S_MB_2U(SCH_1):PAGE244

PR97 Q_RES_0402LF-2.2,1%,1/16W,CHIPA
     1 PVCCFA_EHV_CPU0_PVCC @S9S_MB_2U_LIB.S9S_MB_2U(SCH_1):PVCCFA_EHV_CPU0_PVCC    I21 @S9S_MB_2U_LIB.S9S_MB_2U(SCH_1):PAGE262
     2 PVCCFA_EHV_CPU0_VDD1 @S9S_MB_2U_LIB.S9S_MB_2U(SCH_1):PVCCFA_EHV_CPU0_VDD1    I21 @S9S_MB_2U_LIB.S9S_MB_2U(SCH_1):PAGE262

PR101 Q_RES_0402LF-2.2,1%,1/16W,CHIPA
     1 PVCCFA_EHV_CPU0_PVCC @S9S_MB_2U_LIB.S9S_MB_2U(SCH_1):PVCCFA_EHV_CPU0_PVCC    I26 @S9S_MB_2U_LIB.S9S_MB_2U(SCH_1):PAGE261
     2 PVCCINFAON_CPU0_VDD1 @S9S_MB_2U_LIB.S9S_MB_2U(SCH_1):PVCCINFAON_CPU0_VDD1    I26 @S9S_MB_2U_LIB.S9S_MB_2U(SCH_1):PAGE261

PR102 Q_RES_0402LF-2.2,1%,1/16W,CHIPA
     1 PVCCFA_EHV_CPU0_PVCC @S9S_MB_2U_LIB.S9S_MB_2U(SCH_1):PVCCFA_EHV_CPU0_PVCC    I14 @S9S_MB_2U_LIB.S9S_MB_2U(SCH_1):PAGE261
     2 PVCCINFAON_CPU0_VDD2 @S9S_MB_2U_LIB.S9S_MB_2U(SCH_1):PVCCINFAON_CPU0_VDD2    I14 @S9S_MB_2U_LIB.S9S_MB_2U(SCH_1):PAGE261

PR105 Q_RES_0402LF-28K,1%,1/16W,EMPTA
     1 PVCCINFAON_CPU0_VREF @S9S_MB_2U_LIB.S9S_MB_2U(SCH_1):PVCCINFAON_CPU0_VREF     I7 @S9S_MB_2U_LIB.S9S_MB_2U(SCH_1):PAGE260
     2 PVCCINFAON_CPU0_ADDR @S9S_MB_2U_LIB.S9S_MB_2U(SCH_1):PVCCINFAON_CPU0_ADDR     I7 @S9S_MB_2U_LIB.S9S_MB_2U(SCH_1):PAGE260

PR106 Q_RES_0402LF-681,1%,1/16W,CHIPA
     1 PVCCINFAON_CPU0_ADDR @S9S_MB_2U_LIB.S9S_MB_2U(SCH_1):PVCCINFAON_CPU0_ADDR   I109 @S9S_MB_2U_LIB.S9S_MB_2U(SCH_1):PAGE260
     2    GND @S9S_MB_2U_LIB.S9S_MB_2U(SCH_1):GND   I109 @S9S_MB_2U_LIB.S9S_MB_2U(SCH_1):PAGE260

PR107 Q_RES_0402LF-0,5%,1/16W,EMPTY,A
     1 P12V_AUX @S9S_MB_2U_LIB.S9S_MB_2U(SCH_1):P12V_AUX    I10 @S9S_MB_2U_LIB.S9S_MB_2U(SCH_1):PAGE260
     2 PVCCINFAON_CPU0_CSPIN @S9S_MB_2U_LIB.S9S_MB_2U(SCH_1):PVCCINFAON_CPU0_CSPIN    I10 @S9S_MB_2U_LIB.S9S_MB_2U(SCH_1):PAGE260

PR108 Q_RES_0402LF-0,5%,1/16W,CHIP,CA
     1 P12V_AUX @S9S_MB_2U_LIB.S9S_MB_2U(SCH_1):P12V_AUX     I9 @S9S_MB_2U_LIB.S9S_MB_2U(SCH_1):PAGE260
     2 PVCCINFAON_CPU0_VIN_CSNIN @S9S_MB_2U_LIB.S9S_MB_2U(SCH_1):PVCCINFAON_CPU0_VIN_CSNIN     I9 @S9S_MB_2U_LIB.S9S_MB_2U(SCH_1):PAGE260

PR120 Q_RES_0402LF-0,5%,1/16W,CHIP,CA
     1 SH_PVCCINFAON_CPU0 @S9S_MB_2U_LIB.S9S_MB_2U(SCH_1):SH_PVCCINFAON_CPU0    I49 @S9S_MB_2U_LIB.S9S_MB_2U(SCH_1):PAGE260
     2 SH_PVCCINFAON_CPU0_R @S9S_MB_2U_LIB.S9S_MB_2U(SCH_1):SH_PVCCINFAON_CPU0_R    I49 @S9S_MB_2U_LIB.S9S_MB_2U(SCH_1):PAGE260

PR121 Q_RES_0402LF-0,5%,1/16W,CHIP,CA
     1 SH_PVCCFA_EHV_CPU0 @S9S_MB_2U_LIB.S9S_MB_2U(SCH_1):SH_PVCCFA_EHV_CPU0    I47 @S9S_MB_2U_LIB.S9S_MB_2U(SCH_1):PAGE260
     2 SH_PVCCFA_EHV_CPU0_R @S9S_MB_2U_LIB.S9S_MB_2U(SCH_1):SH_PVCCFA_EHV_CPU0_R    I47 @S9S_MB_2U_LIB.S9S_MB_2U(SCH_1):PAGE260

PR123 Q_RES_0402LF-1K,1%,1/16W,EMPTYA
     1 PVCCINFAON_CPU0_VIN_CSNIN @S9S_MB_2U_LIB.S9S_MB_2U(SCH_1):PVCCINFAON_CPU0_VIN_CSNIN    I21 @S9S_MB_2U_LIB.S9S_MB_2U(SCH_1):PAGE260
     2    GND @S9S_MB_2U_LIB.S9S_MB_2U(SCH_1):GND    I21 @S9S_MB_2U_LIB.S9S_MB_2U(SCH_1):PAGE260

PR130 Q_RES_0402LF-1,1%,1/16W,CHIP,CA
     1 PVCCINFAON_CPU0_VCC @S9S_MB_2U_LIB.S9S_MB_2U(SCH_1):PVCCINFAON_CPU0_VCC   I100 @S9S_MB_2U_LIB.S9S_MB_2U(SCH_1):PAGE260
     2 P3V3_AUX @S9S_MB_2U_LIB.S9S_MB_2U(SCH_1):P3V3_AUX   I100 @S9S_MB_2U_LIB.S9S_MB_2U(SCH_1):PAGE260

PR132 Q_RES_0402LF-8.87K,1%,1/16W,EMA
     1 PVCCIN_CPU0_LSET8 @S9S_MB_2U_LIB.S9S_MB_2U(SCH_1):PVCCIN_CPU0_LSET8     I4 @S9S_MB_2U_LIB.S9S_MB_2U(SCH_1):PAGE256
     2    GND @S9S_MB_2U_LIB.S9S_MB_2U(SCH_1):GND     I4 @S9S_MB_2U_LIB.S9S_MB_2U(SCH_1):PAGE256

PR133 Q_RES_0402LF-8.87K,1%,1/16W,EMA
     1 PVCCIN_CPU0_LSET7 @S9S_MB_2U_LIB.S9S_MB_2U(SCH_1):PVCCIN_CPU0_LSET7    I23 @S9S_MB_2U_LIB.S9S_MB_2U(SCH_1):PAGE256
     2    GND @S9S_MB_2U_LIB.S9S_MB_2U(SCH_1):GND    I23 @S9S_MB_2U_LIB.S9S_MB_2U(SCH_1):PAGE256

PR134 Q_RES_0402LF-2.2,1%,1/16W,CHIPA
     1 PVCCIN_CPU0_PVCC @S9S_MB_2U_LIB.S9S_MB_2U(SCH_1):PVCCIN_CPU0_PVCC    I12 @S9S_MB_2U_LIB.S9S_MB_2U(SCH_1):PAGE256
     2 PVCCIN_CPU0_VDD8 @S9S_MB_2U_LIB.S9S_MB_2U(SCH_1):PVCCIN_CPU0_VDD8    I12 @S9S_MB_2U_LIB.S9S_MB_2U(SCH_1):PAGE256

PR135 Q_RES_0402LF-2.2,1%,1/16W,CHIPA
     1 PVCCIN_CPU0_PVCC @S9S_MB_2U_LIB.S9S_MB_2U(SCH_1):PVCCIN_CPU0_PVCC    I33 @S9S_MB_2U_LIB.S9S_MB_2U(SCH_1):PAGE256
     2 PVCCIN_CPU0_VDD7 @S9S_MB_2U_LIB.S9S_MB_2U(SCH_1):PVCCIN_CPU0_VDD7    I33 @S9S_MB_2U_LIB.S9S_MB_2U(SCH_1):PAGE256

PR136 Q_RES_0402LF-0,5%,1/16W,CHIP,CA
     1 PVCCIN_CPU0_VOS8 @S9S_MB_2U_LIB.S9S_MB_2U(SCH_1):PVCCIN_CPU0_VOS8    I46 @S9S_MB_2U_LIB.S9S_MB_2U(SCH_1):PAGE256
     2 PVCCIN_CPU0 @S9S_MB_2U_LIB.S9S_MB_2U(SCH_1):PVCCIN_CPU0    I46 @S9S_MB_2U_LIB.S9S_MB_2U(SCH_1):PAGE256

PR137 Q_RES_0402LF-0,5%,1/16W,CHIP,CA
     1 PVCCIN_CPU0_VOS7 @S9S_MB_2U_LIB.S9S_MB_2U(SCH_1):PVCCIN_CPU0_VOS7    I57 @S9S_MB_2U_LIB.S9S_MB_2U(SCH_1):PAGE256
     2 PVCCIN_CPU0 @S9S_MB_2U_LIB.S9S_MB_2U(SCH_1):PVCCIN_CPU0    I57 @S9S_MB_2U_LIB.S9S_MB_2U(SCH_1):PAGE256

PR138 Q_RES_0402LF-8.87K,1%,1/16W,EMA
     1 PVCCIN_CPU0_LSET6 @S9S_MB_2U_LIB.S9S_MB_2U(SCH_1):PVCCIN_CPU0_LSET6     I2 @S9S_MB_2U_LIB.S9S_MB_2U(SCH_1):PAGE255
     2    GND @S9S_MB_2U_LIB.S9S_MB_2U(SCH_1):GND     I2 @S9S_MB_2U_LIB.S9S_MB_2U(SCH_1):PAGE255

PR139 Q_RES_0402LF-8.87K,1%,1/16W,EMA
     1 PVCCIN_CPU0_LSET5 @S9S_MB_2U_LIB.S9S_MB_2U(SCH_1):PVCCIN_CPU0_LSET5     I4 @S9S_MB_2U_LIB.S9S_MB_2U(SCH_1):PAGE255
     2    GND @S9S_MB_2U_LIB.S9S_MB_2U(SCH_1):GND     I4 @S9S_MB_2U_LIB.S9S_MB_2U(SCH_1):PAGE255

PR140 Q_RES_0402LF-2.2,1%,1/16W,CHIPA
     1 PVCCIN_CPU0_PVCC @S9S_MB_2U_LIB.S9S_MB_2U(SCH_1):PVCCIN_CPU0_PVCC    I14 @S9S_MB_2U_LIB.S9S_MB_2U(SCH_1):PAGE255
     2 PVCCIN_CPU0_VDD6 @S9S_MB_2U_LIB.S9S_MB_2U(SCH_1):PVCCIN_CPU0_VDD6    I14 @S9S_MB_2U_LIB.S9S_MB_2U(SCH_1):PAGE255

PR141 Q_RES_0402LF-2.2,1%,1/16W,CHIPA
     1 PVCCIN_CPU0_PVCC @S9S_MB_2U_LIB.S9S_MB_2U(SCH_1):PVCCIN_CPU0_PVCC    I26 @S9S_MB_2U_LIB.S9S_MB_2U(SCH_1):PAGE255
     2 PVCCIN_CPU0_VDD5 @S9S_MB_2U_LIB.S9S_MB_2U(SCH_1):PVCCIN_CPU0_VDD5    I26 @S9S_MB_2U_LIB.S9S_MB_2U(SCH_1):PAGE255

PR142 Q_RES_0402LF-0,5%,1/16W,CHIP,CA
     1 PVCCIN_CPU0_VOS6 @S9S_MB_2U_LIB.S9S_MB_2U(SCH_1):PVCCIN_CPU0_VOS6    I40 @S9S_MB_2U_LIB.S9S_MB_2U(SCH_1):PAGE255
     2 PVCCIN_CPU0 @S9S_MB_2U_LIB.S9S_MB_2U(SCH_1):PVCCIN_CPU0    I40 @S9S_MB_2U_LIB.S9S_MB_2U(SCH_1):PAGE255

PR143 Q_RES_0402LF-0,5%,1/16W,CHIP,CA
     1 PVCCIN_CPU0_VOS5 @S9S_MB_2U_LIB.S9S_MB_2U(SCH_1):PVCCIN_CPU0_VOS5    I46 @S9S_MB_2U_LIB.S9S_MB_2U(SCH_1):PAGE255
     2 PVCCIN_CPU0 @S9S_MB_2U_LIB.S9S_MB_2U(SCH_1):PVCCIN_CPU0    I46 @S9S_MB_2U_LIB.S9S_MB_2U(SCH_1):PAGE255

PR144 Q_RES_0402LF-8.87K,1%,1/16W,EMA
     1 PVCCIN_CPU0_LSET4 @S9S_MB_2U_LIB.S9S_MB_2U(SCH_1):PVCCIN_CPU0_LSET4     I2 @S9S_MB_2U_LIB.S9S_MB_2U(SCH_1):PAGE254
     2    GND @S9S_MB_2U_LIB.S9S_MB_2U(SCH_1):GND     I2 @S9S_MB_2U_LIB.S9S_MB_2U(SCH_1):PAGE254

PR145 Q_RES_0402LF-8.87K,1%,1/16W,EMA
     1 PVCCIN_CPU0_LSET3 @S9S_MB_2U_LIB.S9S_MB_2U(SCH_1):PVCCIN_CPU0_LSET3     I4 @S9S_MB_2U_LIB.S9S_MB_2U(SCH_1):PAGE254
     2    GND @S9S_MB_2U_LIB.S9S_MB_2U(SCH_1):GND     I4 @S9S_MB_2U_LIB.S9S_MB_2U(SCH_1):PAGE254

PR146 Q_RES_0402LF-2.2,1%,1/16W,CHIPA
     1 PVCCIN_CPU0_PVCC @S9S_MB_2U_LIB.S9S_MB_2U(SCH_1):PVCCIN_CPU0_PVCC    I14 @S9S_MB_2U_LIB.S9S_MB_2U(SCH_1):PAGE254
     2 PVCCIN_CPU0_VDD4 @S9S_MB_2U_LIB.S9S_MB_2U(SCH_1):PVCCIN_CPU0_VDD4    I14 @S9S_MB_2U_LIB.S9S_MB_2U(SCH_1):PAGE254

PR147 Q_RES_0402LF-2.2,1%,1/16W,CHIPA
     1 PVCCIN_CPU0_PVCC @S9S_MB_2U_LIB.S9S_MB_2U(SCH_1):PVCCIN_CPU0_PVCC    I27 @S9S_MB_2U_LIB.S9S_MB_2U(SCH_1):PAGE254
     2 PVCCIN_CPU0_VDD3 @S9S_MB_2U_LIB.S9S_MB_2U(SCH_1):PVCCIN_CPU0_VDD3    I27 @S9S_MB_2U_LIB.S9S_MB_2U(SCH_1):PAGE254

PR148 Q_RES_0402LF-0,5%,1/16W,CHIP,CA
     1 PVCCIN_CPU0_VOS4 @S9S_MB_2U_LIB.S9S_MB_2U(SCH_1):PVCCIN_CPU0_VOS4    I41 @S9S_MB_2U_LIB.S9S_MB_2U(SCH_1):PAGE254
     2 PVCCIN_CPU0 @S9S_MB_2U_LIB.S9S_MB_2U(SCH_1):PVCCIN_CPU0    I41 @S9S_MB_2U_LIB.S9S_MB_2U(SCH_1):PAGE254

PR149 Q_RES_0402LF-0,5%,1/16W,CHIP,CA
     1 PVCCIN_CPU0_VOS3 @S9S_MB_2U_LIB.S9S_MB_2U(SCH_1):PVCCIN_CPU0_VOS3    I46 @S9S_MB_2U_LIB.S9S_MB_2U(SCH_1):PAGE254
     2 PVCCIN_CPU0 @S9S_MB_2U_LIB.S9S_MB_2U(SCH_1):PVCCIN_CPU0    I46 @S9S_MB_2U_LIB.S9S_MB_2U(SCH_1):PAGE254

PR150 Q_RES_0402LF-8.87K,1%,1/16W,EMA
     1 PVCCIN_CPU0_LSET2 @S9S_MB_2U_LIB.S9S_MB_2U(SCH_1):PVCCIN_CPU0_LSET2     I2 @S9S_MB_2U_LIB.S9S_MB_2U(SCH_1):PAGE253
     2    GND @S9S_MB_2U_LIB.S9S_MB_2U(SCH_1):GND     I2 @S9S_MB_2U_LIB.S9S_MB_2U(SCH_1):PAGE253

PR151 Q_RES_0402LF-8.87K,1%,1/16W,EMA
     1 PVCCIN_CPU0_LSET1 @S9S_MB_2U_LIB.S9S_MB_2U(SCH_1):PVCCIN_CPU0_LSET1    I29 @S9S_MB_2U_LIB.S9S_MB_2U(SCH_1):PAGE253
     2    GND @S9S_MB_2U_LIB.S9S_MB_2U(SCH_1):GND    I29 @S9S_MB_2U_LIB.S9S_MB_2U(SCH_1):PAGE253

PR152 Q_RES_0402LF-2.2,1%,1/16W,CHIPA
     1 PVCCIN_CPU0_PVCC @S9S_MB_2U_LIB.S9S_MB_2U(SCH_1):PVCCIN_CPU0_PVCC    I12 @S9S_MB_2U_LIB.S9S_MB_2U(SCH_1):PAGE253
     2 PVCCIN_CPU0_VDD2 @S9S_MB_2U_LIB.S9S_MB_2U(SCH_1):PVCCIN_CPU0_VDD2    I12 @S9S_MB_2U_LIB.S9S_MB_2U(SCH_1):PAGE253

PR153 Q_RES_0402LF-2.2,1%,1/16W,CHIPA
     1 PVCCIN_CPU0_PVCC @S9S_MB_2U_LIB.S9S_MB_2U(SCH_1):PVCCIN_CPU0_PVCC    I37 @S9S_MB_2U_LIB.S9S_MB_2U(SCH_1):PAGE253
     2 PVCCIN_CPU0_VDD1 @S9S_MB_2U_LIB.S9S_MB_2U(SCH_1):PVCCIN_CPU0_VDD1    I37 @S9S_MB_2U_LIB.S9S_MB_2U(SCH_1):PAGE253

PR154 Q_RES_0402LF-0,5%,1/16W,CHIP,CA
     1 PVCCIN_CPU0_VOS2 @S9S_MB_2U_LIB.S9S_MB_2U(SCH_1):PVCCIN_CPU0_VOS2    I51 @S9S_MB_2U_LIB.S9S_MB_2U(SCH_1):PAGE253
     2 PVCCIN_CPU0 @S9S_MB_2U_LIB.S9S_MB_2U(SCH_1):PVCCIN_CPU0    I51 @S9S_MB_2U_LIB.S9S_MB_2U(SCH_1):PAGE253

PR155 Q_RES_0402LF-0,5%,1/16W,CHIP,CA
     1 PVCCIN_CPU0_VOS1 @S9S_MB_2U_LIB.S9S_MB_2U(SCH_1):PVCCIN_CPU0_VOS1    I73 @S9S_MB_2U_LIB.S9S_MB_2U(SCH_1):PAGE253
     2 PVCCIN_CPU0 @S9S_MB_2U_LIB.S9S_MB_2U(SCH_1):PVCCIN_CPU0    I73 @S9S_MB_2U_LIB.S9S_MB_2U(SCH_1):PAGE253

PR156 Q_RES_0402LF-0,5%,1/16W,CHIP,CA
     1 P12V_AUX @S9S_MB_2U_LIB.S9S_MB_2U(SCH_1):P12V_AUX    I10 @S9S_MB_2U_LIB.S9S_MB_2U(SCH_1):PAGE252
     2 PVCCIN_CPU0_VIN_CSNIN @S9S_MB_2U_LIB.S9S_MB_2U(SCH_1):PVCCIN_CPU0_VIN_CSNIN    I10 @S9S_MB_2U_LIB.S9S_MB_2U(SCH_1):PAGE252

PR157 Q_RES_0402LF-0,5%,1/16W,EMPTY,A
     1 P12V_AUX @S9S_MB_2U_LIB.S9S_MB_2U(SCH_1):P12V_AUX    I11 @S9S_MB_2U_LIB.S9S_MB_2U(SCH_1):PAGE252
     2 PVCCIN_CPU0_CSPIN @S9S_MB_2U_LIB.S9S_MB_2U(SCH_1):PVCCIN_CPU0_CSPIN    I11 @S9S_MB_2U_LIB.S9S_MB_2U(SCH_1):PAGE252

PR158 Q_RES_0402LF-0,5%,1/16W,CHIP,CA
     1 PVCCIN_CPU0_CSPIN @S9S_MB_2U_LIB.S9S_MB_2U(SCH_1):PVCCIN_CPU0_CSPIN    I51 @S9S_MB_2U_LIB.S9S_MB_2U(SCH_1):PAGE252
     2    GND @S9S_MB_2U_LIB.S9S_MB_2U(SCH_1):GND    I51 @S9S_MB_2U_LIB.S9S_MB_2U(SCH_1):PAGE252

PR159 Q_RES_0402LF-28K,1%,1/16W,EMPTA
     1 PVCCIN_CPU0_VREF @S9S_MB_2U_LIB.S9S_MB_2U(SCH_1):PVCCIN_CPU0_VREF     I5 @S9S_MB_2U_LIB.S9S_MB_2U(SCH_1):PAGE252
     2 PVCCIN_CPU0_ADDR @S9S_MB_2U_LIB.S9S_MB_2U(SCH_1):PVCCIN_CPU0_ADDR     I5 @S9S_MB_2U_LIB.S9S_MB_2U(SCH_1):PAGE252

PR166 Q_RES_0402LF-1K,1%,1/16W,EMPTYA
     1 PVCCIN_CPU0_VIN_CSNIN @S9S_MB_2U_LIB.S9S_MB_2U(SCH_1):PVCCIN_CPU0_VIN_CSNIN    I60 @S9S_MB_2U_LIB.S9S_MB_2U(SCH_1):PAGE252
     2    GND @S9S_MB_2U_LIB.S9S_MB_2U(SCH_1):GND    I60 @S9S_MB_2U_LIB.S9S_MB_2U(SCH_1):PAGE252

PR170 Q_RES_0402LF-0,5%,1/16W,CHIP,CA
     1 SH_PVCCIN_CPU0 @S9S_MB_2U_LIB.S9S_MB_2U(SCH_1):SH_PVCCIN_CPU0    I77 @S9S_MB_2U_LIB.S9S_MB_2U(SCH_1):PAGE252
     2 SH_PVCCIN_CPU0_R @S9S_MB_2U_LIB.S9S_MB_2U(SCH_1):SH_PVCCIN_CPU0_R    I77 @S9S_MB_2U_LIB.S9S_MB_2U(SCH_1):PAGE252

PR171 Q_RES_0402LF-0,5%,1/16W,CHIP,CA
     1 PVCCIN_CPU0_ADDR @S9S_MB_2U_LIB.S9S_MB_2U(SCH_1):PVCCIN_CPU0_ADDR     I8 @S9S_MB_2U_LIB.S9S_MB_2U(SCH_1):PAGE252
     2    GND @S9S_MB_2U_LIB.S9S_MB_2U(SCH_1):GND     I8 @S9S_MB_2U_LIB.S9S_MB_2U(SCH_1):PAGE252

PR176 Q_RES_0402LF-1,1%,1/16W,CHIP,CA
     1 PVCCIN_CPU0_VCC @S9S_MB_2U_LIB.S9S_MB_2U(SCH_1):PVCCIN_CPU0_VCC   I133 @S9S_MB_2U_LIB.S9S_MB_2U(SCH_1):PAGE252
     2 P3V3_AUX @S9S_MB_2U_LIB.S9S_MB_2U(SCH_1):P3V3_AUX   I133 @S9S_MB_2U_LIB.S9S_MB_2U(SCH_1):PAGE252

PR187 Q_RES_0402LF-10K,0.1%,1/16W,CHA
     1 P1V05_PCH_AUX_FB @S9S_MB_2U_LIB.S9S_MB_2U(SCH_1):P1V05_PCH_AUX_FB    I34 @S9S_MB_2U_LIB.S9S_MB_2U(SCH_1):PAGE248
     2 SH_P1V05_PCH_AUX_N @S9S_MB_2U_LIB.S9S_MB_2U(SCH_1):SH_P1V05_PCH_AUX_N    I34 @S9S_MB_2U_LIB.S9S_MB_2U(SCH_1):PAGE248

PR200 Q_RES_0402LF-2.2,1%,1/16W,CHIPA
     1 PVCCFA_EHV_CPU1_PVCC @S9S_MB_2U_LIB.S9S_MB_2U(SCH_1):PVCCFA_EHV_CPU1_PVCC    I16 @S9S_MB_2U_LIB.S9S_MB_2U(SCH_1):PAGE283
     2 PVCCD_HV_CPU1_VDD1 @S9S_MB_2U_LIB.S9S_MB_2U(SCH_1):PVCCD_HV_CPU1_VDD1    I16 @S9S_MB_2U_LIB.S9S_MB_2U(SCH_1):PAGE283

PR202 Q_RES_0402LF-28K,1%,1/16W,EMPTA
     1 PVCCD_HV_CPU1_VREF @S9S_MB_2U_LIB.S9S_MB_2U(SCH_1):PVCCD_HV_CPU1_VREF     I8 @S9S_MB_2U_LIB.S9S_MB_2U(SCH_1):PAGE282
     2 PVCCD_HV_CPU1_ADDR @S9S_MB_2U_LIB.S9S_MB_2U(SCH_1):PVCCD_HV_CPU1_ADDR     I8 @S9S_MB_2U_LIB.S9S_MB_2U(SCH_1):PAGE282

PR203 Q_RES_0402LF-24.3K,1%,1/16W,CHA
     1    GND @S9S_MB_2U_LIB.S9S_MB_2U(SCH_1):GND    I95 @S9S_MB_2U_LIB.S9S_MB_2U(SCH_1):PAGE282
     2 PVCCD_HV_CPU1_ADDR @S9S_MB_2U_LIB.S9S_MB_2U(SCH_1):PVCCD_HV_CPU1_ADDR    I95 @S9S_MB_2U_LIB.S9S_MB_2U(SCH_1):PAGE282

PR214 Q_RES_0402LF-1K,1%,1/16W,EMPTYA
     1 PVCCD_HV_CPU1_ISENSE_P @S9S_MB_2U_LIB.S9S_MB_2U(SCH_1):PVCCD_HV_CPU1_ISENSE_P    I11 @S9S_MB_2U_LIB.S9S_MB_2U(SCH_1):PAGE282
     2    GND @S9S_MB_2U_LIB.S9S_MB_2U(SCH_1):GND    I11 @S9S_MB_2U_LIB.S9S_MB_2U(SCH_1):PAGE282

PR215 Q_RES_0402LF-1K,1%,1/16W,CHIP,A
     1 P3V3_AUX @S9S_MB_2U_LIB.S9S_MB_2U(SCH_1):P3V3_AUX    I18 @S9S_MB_2U_LIB.S9S_MB_2U(SCH_1):PAGE282
     2 PVCCD_HV_CPU1_PIN_ALT @S9S_MB_2U_LIB.S9S_MB_2U(SCH_1):PVCCD_HV_CPU1_PIN_ALT    I18 @S9S_MB_2U_LIB.S9S_MB_2U(SCH_1):PAGE282

PR216 Q_RES_0402LF-0,5%,1/16W,CHIP,CA
     1 SH_PVCCD_HV_CPU1 @S9S_MB_2U_LIB.S9S_MB_2U(SCH_1):SH_PVCCD_HV_CPU1    I21 @S9S_MB_2U_LIB.S9S_MB_2U(SCH_1):PAGE282
     2 SH_PVCCD_HV_CPU1_R @S9S_MB_2U_LIB.S9S_MB_2U(SCH_1):SH_PVCCD_HV_CPU1_R    I21 @S9S_MB_2U_LIB.S9S_MB_2U(SCH_1):PAGE282

PR217 Q_RES_0402LF-1K,1%,1/16W,CHIP,A
     1 P3V3_AUX @S9S_MB_2U_LIB.S9S_MB_2U(SCH_1):P3V3_AUX    I20 @S9S_MB_2U_LIB.S9S_MB_2U(SCH_1):PAGE282
     2 PVCCD_HV_CPU1_FAULT @S9S_MB_2U_LIB.S9S_MB_2U(SCH_1):PVCCD_HV_CPU1_FAULT    I20 @S9S_MB_2U_LIB.S9S_MB_2U(SCH_1):PAGE282

PR218 Q_RES_0402LF-1K,1%,1/16W,EMPTYA
     1 PVCCD_HV_CPU1_ISENSE_N @S9S_MB_2U_LIB.S9S_MB_2U(SCH_1):PVCCD_HV_CPU1_ISENSE_N    I48 @S9S_MB_2U_LIB.S9S_MB_2U(SCH_1):PAGE282
     2    GND @S9S_MB_2U_LIB.S9S_MB_2U(SCH_1):GND    I48 @S9S_MB_2U_LIB.S9S_MB_2U(SCH_1):PAGE282

PR220 Q_RES_0402LF-1,1%,1/16W,CHIP,CA
     1 PVCCD_HV_CPU1_VCC @S9S_MB_2U_LIB.S9S_MB_2U(SCH_1):PVCCD_HV_CPU1_VCC    I78 @S9S_MB_2U_LIB.S9S_MB_2U(SCH_1):PAGE282
     2 P3V3_AUX @S9S_MB_2U_LIB.S9S_MB_2U(SCH_1):P3V3_AUX    I78 @S9S_MB_2U_LIB.S9S_MB_2U(SCH_1):PAGE282

PR224 Q_RES_0402LF-8.87K,1%,1/16W,EMA
     1 PVCCFA_EHV_FIVRA_CPU1_LSET2 @S9S_MB_2U_LIB.S9S_MB_2U(SCH_1):PVCCFA_EHV_FIVRA_CPU1_LSET2     I2 @S9S_MB_2U_LIB.S9S_MB_2U(SCH_1):PAGE275
     2    GND @S9S_MB_2U_LIB.S9S_MB_2U(SCH_1):GND     I2 @S9S_MB_2U_LIB.S9S_MB_2U(SCH_1):PAGE275

PR225 Q_RES_0402LF-8.87K,1%,1/16W,EMA
     1 PVCCFA_EHV_FIVRA_CPU1_LSET1 @S9S_MB_2U_LIB.S9S_MB_2U(SCH_1):PVCCFA_EHV_FIVRA_CPU1_LSET1    I20 @S9S_MB_2U_LIB.S9S_MB_2U(SCH_1):PAGE275
     2    GND @S9S_MB_2U_LIB.S9S_MB_2U(SCH_1):GND    I20 @S9S_MB_2U_LIB.S9S_MB_2U(SCH_1):PAGE275

PR226 Q_RES_0402LF-2.2,1%,1/16W,CHIPA
     1 PVCCFA_EHV_FIVRA_CPU1_PVCC1 @S9S_MB_2U_LIB.S9S_MB_2U(SCH_1):PVCCFA_EHV_FIVRA_CPU1_PVCC1    I28 @S9S_MB_2U_LIB.S9S_MB_2U(SCH_1):PAGE275
     2 PVCCFA_EHV_FIVRA_CPU1_VDD1 @S9S_MB_2U_LIB.S9S_MB_2U(SCH_1):PVCCFA_EHV_FIVRA_CPU1_VDD1    I28 @S9S_MB_2U_LIB.S9S_MB_2U(SCH_1):PAGE275

PR227 Q_RES_0402LF-2.2,1%,1/16W,CHIPA
     1 PVCCFA_EHV_FIVRA_CPU1_PVCC2 @S9S_MB_2U_LIB.S9S_MB_2U(SCH_1):PVCCFA_EHV_FIVRA_CPU1_PVCC2    I12 @S9S_MB_2U_LIB.S9S_MB_2U(SCH_1):PAGE275
     2 PVCCFA_EHV_FIVRA_CPU1_VDD2 @S9S_MB_2U_LIB.S9S_MB_2U(SCH_1):PVCCFA_EHV_FIVRA_CPU1_VDD2    I12 @S9S_MB_2U_LIB.S9S_MB_2U(SCH_1):PAGE275

PR242 Q_RES_0402LF-0,5%,1/16W,CHIP,CA
     1 SH_PVCCFA_EHV_FIVRA_CPU1 @S9S_MB_2U_LIB.S9S_MB_2U(SCH_1):SH_PVCCFA_EHV_FIVRA_CPU1    I37 @S9S_MB_2U_LIB.S9S_MB_2U(SCH_1):PAGE270
     2 SH_PVCCFA_EHV_FIVRA_CPU1_R @S9S_MB_2U_LIB.S9S_MB_2U(SCH_1):SH_PVCCFA_EHV_FIVRA_CPU1_R    I37 @S9S_MB_2U_LIB.S9S_MB_2U(SCH_1):PAGE270

PR250 Q_RES_0402LF-2.2,1%,1/16W,CHIPA
     1 PVCCFA_EHV_CPU1_PVCC @S9S_MB_2U_LIB.S9S_MB_2U(SCH_1):PVCCFA_EHV_CPU1_PVCC    I15 @S9S_MB_2U_LIB.S9S_MB_2U(SCH_1):PAGE280
     2 PVCCFA_EHV_CPU1_VDD1 @S9S_MB_2U_LIB.S9S_MB_2U(SCH_1):PVCCFA_EHV_CPU1_VDD1    I15 @S9S_MB_2U_LIB.S9S_MB_2U(SCH_1):PAGE280

PR254 Q_RES_0402LF-2.2,1%,1/16W,CHIPA
     1 PVCCFA_EHV_CPU1_PVCC @S9S_MB_2U_LIB.S9S_MB_2U(SCH_1):PVCCFA_EHV_CPU1_PVCC    I25 @S9S_MB_2U_LIB.S9S_MB_2U(SCH_1):PAGE279
     2 PVCCINFAON_CPU1_VDD1 @S9S_MB_2U_LIB.S9S_MB_2U(SCH_1):PVCCINFAON_CPU1_VDD1    I25 @S9S_MB_2U_LIB.S9S_MB_2U(SCH_1):PAGE279

PR255 Q_RES_0402LF-2.2,1%,1/16W,CHIPA
     1 PVCCFA_EHV_CPU1_PVCC @S9S_MB_2U_LIB.S9S_MB_2U(SCH_1):PVCCFA_EHV_CPU1_PVCC    I11 @S9S_MB_2U_LIB.S9S_MB_2U(SCH_1):PAGE279
     2 PVCCINFAON_CPU1_VDD2 @S9S_MB_2U_LIB.S9S_MB_2U(SCH_1):PVCCINFAON_CPU1_VDD2    I11 @S9S_MB_2U_LIB.S9S_MB_2U(SCH_1):PAGE279

PR258 Q_RES_0402LF-28K,1%,1/16W,EMPTA
     1 PVCCINFAON_CPU1_VREF @S9S_MB_2U_LIB.S9S_MB_2U(SCH_1):PVCCINFAON_CPU1_VREF    I23 @S9S_MB_2U_LIB.S9S_MB_2U(SCH_1):PAGE278
     2 PVCCINFAON_CPU1_ADDR @S9S_MB_2U_LIB.S9S_MB_2U(SCH_1):PVCCINFAON_CPU1_ADDR    I23 @S9S_MB_2U_LIB.S9S_MB_2U(SCH_1):PAGE278

PR259 Q_RES_0402LF-8.45K,1%,1/16W,CHA
     1 PVCCINFAON_CPU1_ADDR @S9S_MB_2U_LIB.S9S_MB_2U(SCH_1):PVCCINFAON_CPU1_ADDR   I110 @S9S_MB_2U_LIB.S9S_MB_2U(SCH_1):PAGE278
     2    GND @S9S_MB_2U_LIB.S9S_MB_2U(SCH_1):GND   I110 @S9S_MB_2U_LIB.S9S_MB_2U(SCH_1):PAGE278

PR260 Q_RES_0402LF-0,5%,1/16W,EMPTY,A
     1 P12V_AUX @S9S_MB_2U_LIB.S9S_MB_2U(SCH_1):P12V_AUX    I22 @S9S_MB_2U_LIB.S9S_MB_2U(SCH_1):PAGE278
     2 PVCCINFAON_CPU1_CSPIN @S9S_MB_2U_LIB.S9S_MB_2U(SCH_1):PVCCINFAON_CPU1_CSPIN    I22 @S9S_MB_2U_LIB.S9S_MB_2U(SCH_1):PAGE278

PR261 Q_RES_0402LF-0,5%,1/16W,CHIP,CA
     1 P12V_AUX @S9S_MB_2U_LIB.S9S_MB_2U(SCH_1):P12V_AUX    I21 @S9S_MB_2U_LIB.S9S_MB_2U(SCH_1):PAGE278
     2 PVCCINFAON_CPU1_VIN_CSNIN @S9S_MB_2U_LIB.S9S_MB_2U(SCH_1):PVCCINFAON_CPU1_VIN_CSNIN    I21 @S9S_MB_2U_LIB.S9S_MB_2U(SCH_1):PAGE278

PR273 Q_RES_0402LF-0,5%,1/16W,CHIP,CA
     1 SH_PVCCINFAON_CPU1 @S9S_MB_2U_LIB.S9S_MB_2U(SCH_1):SH_PVCCINFAON_CPU1    I62 @S9S_MB_2U_LIB.S9S_MB_2U(SCH_1):PAGE278
     2 SH_PVCCINFAON_CPU1_R @S9S_MB_2U_LIB.S9S_MB_2U(SCH_1):SH_PVCCINFAON_CPU1_R    I62 @S9S_MB_2U_LIB.S9S_MB_2U(SCH_1):PAGE278

PR274 Q_RES_0402LF-0,5%,1/16W,CHIP,CA
     1 SH_PVCCFA_EHV_CPU1 @S9S_MB_2U_LIB.S9S_MB_2U(SCH_1):SH_PVCCFA_EHV_CPU1    I52 @S9S_MB_2U_LIB.S9S_MB_2U(SCH_1):PAGE278
     2 SH_PVCCFA_EHV_CPU1_R @S9S_MB_2U_LIB.S9S_MB_2U(SCH_1):SH_PVCCFA_EHV_CPU1_R    I52 @S9S_MB_2U_LIB.S9S_MB_2U(SCH_1):PAGE278

PR275 Q_RES_0402LF-0,5%,1/16W,CHIP,CA
     1 PVCCINFAON_CPU1_CSPIN @S9S_MB_2U_LIB.S9S_MB_2U(SCH_1):PVCCINFAON_CPU1_CSPIN    I26 @S9S_MB_2U_LIB.S9S_MB_2U(SCH_1):PAGE278
     2    GND @S9S_MB_2U_LIB.S9S_MB_2U(SCH_1):GND    I26 @S9S_MB_2U_LIB.S9S_MB_2U(SCH_1):PAGE278

PR276 Q_RES_0402LF-1K,1%,1/16W,EMPTYA
     1 PVCCINFAON_CPU1_VIN_CSNIN @S9S_MB_2U_LIB.S9S_MB_2U(SCH_1):PVCCINFAON_CPU1_VIN_CSNIN    I35 @S9S_MB_2U_LIB.S9S_MB_2U(SCH_1):PAGE278
     2    GND @S9S_MB_2U_LIB.S9S_MB_2U(SCH_1):GND    I35 @S9S_MB_2U_LIB.S9S_MB_2U(SCH_1):PAGE278

PR283 Q_RES_0402LF-1,1%,1/16W,CHIP,CA
     1 PVCCINFAON_CPU1_VCC @S9S_MB_2U_LIB.S9S_MB_2U(SCH_1):PVCCINFAON_CPU1_VCC   I108 @S9S_MB_2U_LIB.S9S_MB_2U(SCH_1):PAGE278
     2 P3V3_AUX @S9S_MB_2U_LIB.S9S_MB_2U(SCH_1):P3V3_AUX   I108 @S9S_MB_2U_LIB.S9S_MB_2U(SCH_1):PAGE278

PR285 Q_RES_0402LF-8.87K,1%,1/16W,EMA
     1 PVCCIN_CPU1_LSET8 @S9S_MB_2U_LIB.S9S_MB_2U(SCH_1):PVCCIN_CPU1_LSET8     I3 @S9S_MB_2U_LIB.S9S_MB_2U(SCH_1):PAGE274
     2    GND @S9S_MB_2U_LIB.S9S_MB_2U(SCH_1):GND     I3 @S9S_MB_2U_LIB.S9S_MB_2U(SCH_1):PAGE274

PR286 Q_RES_0402LF-8.87K,1%,1/16W,EMA
     1 PVCCIN_CPU1_LSET7 @S9S_MB_2U_LIB.S9S_MB_2U(SCH_1):PVCCIN_CPU1_LSET7    I15 @S9S_MB_2U_LIB.S9S_MB_2U(SCH_1):PAGE274
     2    GND @S9S_MB_2U_LIB.S9S_MB_2U(SCH_1):GND    I15 @S9S_MB_2U_LIB.S9S_MB_2U(SCH_1):PAGE274

PR287 Q_RES_0402LF-2.2,1%,1/16W,CHIPA
     1 PVCCIN_CPU1_PVCC @S9S_MB_2U_LIB.S9S_MB_2U(SCH_1):PVCCIN_CPU1_PVCC    I12 @S9S_MB_2U_LIB.S9S_MB_2U(SCH_1):PAGE274
     2 PVCCIN_CPU1_VDD8 @S9S_MB_2U_LIB.S9S_MB_2U(SCH_1):PVCCIN_CPU1_VDD8    I12 @S9S_MB_2U_LIB.S9S_MB_2U(SCH_1):PAGE274

PR288 Q_RES_0402LF-2.2,1%,1/16W,CHIPA
     1 PVCCIN_CPU1_PVCC @S9S_MB_2U_LIB.S9S_MB_2U(SCH_1):PVCCIN_CPU1_PVCC    I68 @S9S_MB_2U_LIB.S9S_MB_2U(SCH_1):PAGE274
     2 PVCCIN_CPU1_VDD7 @S9S_MB_2U_LIB.S9S_MB_2U(SCH_1):PVCCIN_CPU1_VDD7    I68 @S9S_MB_2U_LIB.S9S_MB_2U(SCH_1):PAGE274

PR289 Q_RES_0402LF-0,5%,1/16W,CHIP,CA
     1 PVCCIN_CPU1_VOS8 @S9S_MB_2U_LIB.S9S_MB_2U(SCH_1):PVCCIN_CPU1_VOS8    I44 @S9S_MB_2U_LIB.S9S_MB_2U(SCH_1):PAGE274
     2 PVCCIN_CPU1 @S9S_MB_2U_LIB.S9S_MB_2U(SCH_1):PVCCIN_CPU1    I44 @S9S_MB_2U_LIB.S9S_MB_2U(SCH_1):PAGE274

PR290 Q_RES_0402LF-0,5%,1/16W,CHIP,CA
     1 PVCCIN_CPU1_VOS7 @S9S_MB_2U_LIB.S9S_MB_2U(SCH_1):PVCCIN_CPU1_VOS7    I50 @S9S_MB_2U_LIB.S9S_MB_2U(SCH_1):PAGE274
     2 PVCCIN_CPU1 @S9S_MB_2U_LIB.S9S_MB_2U(SCH_1):PVCCIN_CPU1    I50 @S9S_MB_2U_LIB.S9S_MB_2U(SCH_1):PAGE274

PR291 Q_RES_0402LF-8.87K,1%,1/16W,EMA
     1 PVCCIN_CPU1_LSET6 @S9S_MB_2U_LIB.S9S_MB_2U(SCH_1):PVCCIN_CPU1_LSET6     I2 @S9S_MB_2U_LIB.S9S_MB_2U(SCH_1):PAGE273
     2    GND @S9S_MB_2U_LIB.S9S_MB_2U(SCH_1):GND     I2 @S9S_MB_2U_LIB.S9S_MB_2U(SCH_1):PAGE273

PR292 Q_RES_0402LF-8.87K,1%,1/16W,EMA
     1 PVCCIN_CPU1_LSET5 @S9S_MB_2U_LIB.S9S_MB_2U(SCH_1):PVCCIN_CPU1_LSET5     I7 @S9S_MB_2U_LIB.S9S_MB_2U(SCH_1):PAGE273
     2    GND @S9S_MB_2U_LIB.S9S_MB_2U(SCH_1):GND     I7 @S9S_MB_2U_LIB.S9S_MB_2U(SCH_1):PAGE273

PR293 Q_RES_0402LF-2.2,1%,1/16W,CHIPA
     1 PVCCIN_CPU1_PVCC @S9S_MB_2U_LIB.S9S_MB_2U(SCH_1):PVCCIN_CPU1_PVCC    I19 @S9S_MB_2U_LIB.S9S_MB_2U(SCH_1):PAGE273
     2 PVCCIN_CPU1_VDD6 @S9S_MB_2U_LIB.S9S_MB_2U(SCH_1):PVCCIN_CPU1_VDD6    I19 @S9S_MB_2U_LIB.S9S_MB_2U(SCH_1):PAGE273

PR294 Q_RES_0402LF-2.2,1%,1/16W,CHIPA
     1 PVCCIN_CPU1_PVCC @S9S_MB_2U_LIB.S9S_MB_2U(SCH_1):PVCCIN_CPU1_PVCC    I39 @S9S_MB_2U_LIB.S9S_MB_2U(SCH_1):PAGE273
     2 PVCCIN_CPU1_VDD5 @S9S_MB_2U_LIB.S9S_MB_2U(SCH_1):PVCCIN_CPU1_VDD5    I39 @S9S_MB_2U_LIB.S9S_MB_2U(SCH_1):PAGE273

PR295 Q_RES_0402LF-0,5%,1/16W,CHIP,CA
     1 PVCCIN_CPU1_VOS6 @S9S_MB_2U_LIB.S9S_MB_2U(SCH_1):PVCCIN_CPU1_VOS6    I27 @S9S_MB_2U_LIB.S9S_MB_2U(SCH_1):PAGE273
     2 PVCCIN_CPU1 @S9S_MB_2U_LIB.S9S_MB_2U(SCH_1):PVCCIN_CPU1    I27 @S9S_MB_2U_LIB.S9S_MB_2U(SCH_1):PAGE273

PR296 Q_RES_0402LF-0,5%,1/16W,CHIP,CA
     1 PVCCIN_CPU1_VOS5 @S9S_MB_2U_LIB.S9S_MB_2U(SCH_1):PVCCIN_CPU1_VOS5    I49 @S9S_MB_2U_LIB.S9S_MB_2U(SCH_1):PAGE273
     2 PVCCIN_CPU1 @S9S_MB_2U_LIB.S9S_MB_2U(SCH_1):PVCCIN_CPU1    I49 @S9S_MB_2U_LIB.S9S_MB_2U(SCH_1):PAGE273

PR297 Q_RES_0402LF-8.87K,1%,1/16W,EMA
     1 PVCCIN_CPU1_LSET4 @S9S_MB_2U_LIB.S9S_MB_2U(SCH_1):PVCCIN_CPU1_LSET4     I3 @S9S_MB_2U_LIB.S9S_MB_2U(SCH_1):PAGE272
     2    GND @S9S_MB_2U_LIB.S9S_MB_2U(SCH_1):GND     I3 @S9S_MB_2U_LIB.S9S_MB_2U(SCH_1):PAGE272

PR298 Q_RES_0402LF-8.87K,1%,1/16W,EMA
     1 PVCCIN_CPU1_LSET3 @S9S_MB_2U_LIB.S9S_MB_2U(SCH_1):PVCCIN_CPU1_LSET3    I15 @S9S_MB_2U_LIB.S9S_MB_2U(SCH_1):PAGE272
     2    GND @S9S_MB_2U_LIB.S9S_MB_2U(SCH_1):GND    I15 @S9S_MB_2U_LIB.S9S_MB_2U(SCH_1):PAGE272

PR299 Q_RES_0402LF-2.2,1%,1/16W,CHIPA
     1 PVCCIN_CPU1_PVCC @S9S_MB_2U_LIB.S9S_MB_2U(SCH_1):PVCCIN_CPU1_PVCC    I12 @S9S_MB_2U_LIB.S9S_MB_2U(SCH_1):PAGE272
     2 PVCCIN_CPU1_VDD4 @S9S_MB_2U_LIB.S9S_MB_2U(SCH_1):PVCCIN_CPU1_VDD4    I12 @S9S_MB_2U_LIB.S9S_MB_2U(SCH_1):PAGE272

PR300 Q_RES_0402LF-2.2,1%,1/16W,CHIPA
     1 PVCCIN_CPU1_PVCC @S9S_MB_2U_LIB.S9S_MB_2U(SCH_1):PVCCIN_CPU1_PVCC    I25 @S9S_MB_2U_LIB.S9S_MB_2U(SCH_1):PAGE272
     2 PVCCIN_CPU1_VDD3 @S9S_MB_2U_LIB.S9S_MB_2U(SCH_1):PVCCIN_CPU1_VDD3    I25 @S9S_MB_2U_LIB.S9S_MB_2U(SCH_1):PAGE272

PR301 Q_RES_0402LF-0,5%,1/16W,CHIP,CA
     1 PVCCIN_CPU1_VOS4 @S9S_MB_2U_LIB.S9S_MB_2U(SCH_1):PVCCIN_CPU1_VOS4    I38 @S9S_MB_2U_LIB.S9S_MB_2U(SCH_1):PAGE272
     2 PVCCIN_CPU1 @S9S_MB_2U_LIB.S9S_MB_2U(SCH_1):PVCCIN_CPU1    I38 @S9S_MB_2U_LIB.S9S_MB_2U(SCH_1):PAGE272

PR302 Q_RES_0402LF-0,5%,1/16W,CHIP,CA
     1 PVCCIN_CPU1_VOS3 @S9S_MB_2U_LIB.S9S_MB_2U(SCH_1):PVCCIN_CPU1_VOS3    I45 @S9S_MB_2U_LIB.S9S_MB_2U(SCH_1):PAGE272
     2 PVCCIN_CPU1 @S9S_MB_2U_LIB.S9S_MB_2U(SCH_1):PVCCIN_CPU1    I45 @S9S_MB_2U_LIB.S9S_MB_2U(SCH_1):PAGE272

PR303 Q_RES_0402LF-0,5%,1/16W,CHIP,CA
     1 P12V_AUX @S9S_MB_2U_LIB.S9S_MB_2U(SCH_1):P12V_AUX     I7 @S9S_MB_2U_LIB.S9S_MB_2U(SCH_1):PAGE270
     2 PVCCIN_CPU1_VIN_CSNIN @S9S_MB_2U_LIB.S9S_MB_2U(SCH_1):PVCCIN_CPU1_VIN_CSNIN     I7 @S9S_MB_2U_LIB.S9S_MB_2U(SCH_1):PAGE270

PR304 Q_RES_0402LF-0,5%,1/16W,EMPTY,A
     1 P12V_AUX @S9S_MB_2U_LIB.S9S_MB_2U(SCH_1):P12V_AUX     I9 @S9S_MB_2U_LIB.S9S_MB_2U(SCH_1):PAGE270
     2 PVCCIN_CPU1_CSPIN @S9S_MB_2U_LIB.S9S_MB_2U(SCH_1):PVCCIN_CPU1_CSPIN     I9 @S9S_MB_2U_LIB.S9S_MB_2U(SCH_1):PAGE270

PR305 Q_RES_0402LF-0,5%,1/16W,CHIP,CA
     1 PVCCIN_CPU1_CSPIN @S9S_MB_2U_LIB.S9S_MB_2U(SCH_1):PVCCIN_CPU1_CSPIN    I27 @S9S_MB_2U_LIB.S9S_MB_2U(SCH_1):PAGE270
     2    GND @S9S_MB_2U_LIB.S9S_MB_2U(SCH_1):GND    I27 @S9S_MB_2U_LIB.S9S_MB_2U(SCH_1):PAGE270

PR306 Q_RES_0402LF-28K,1%,1/16W,EMPTA
     1 PVCCIN_CPU1_VREF @S9S_MB_2U_LIB.S9S_MB_2U(SCH_1):PVCCIN_CPU1_VREF     I4 @S9S_MB_2U_LIB.S9S_MB_2U(SCH_1):PAGE270
     2 PVCCIN_CPU1_ADDR @S9S_MB_2U_LIB.S9S_MB_2U(SCH_1):PVCCIN_CPU1_ADDR     I4 @S9S_MB_2U_LIB.S9S_MB_2U(SCH_1):PAGE270

PR313 Q_RES_0402LF-1K,1%,1/16W,EMPTYA
     1 PVCCIN_CPU1_VIN_CSNIN @S9S_MB_2U_LIB.S9S_MB_2U(SCH_1):PVCCIN_CPU1_VIN_CSNIN    I29 @S9S_MB_2U_LIB.S9S_MB_2U(SCH_1):PAGE270
     2    GND @S9S_MB_2U_LIB.S9S_MB_2U(SCH_1):GND    I29 @S9S_MB_2U_LIB.S9S_MB_2U(SCH_1):PAGE270

PR317 Q_RES_0402LF-0,5%,1/16W,CHIP,CA
     1 SH_PVCCIN_CPU1 @S9S_MB_2U_LIB.S9S_MB_2U(SCH_1):SH_PVCCIN_CPU1    I63 @S9S_MB_2U_LIB.S9S_MB_2U(SCH_1):PAGE270
     2 SH_PVCCIN_CPU1_R @S9S_MB_2U_LIB.S9S_MB_2U(SCH_1):SH_PVCCIN_CPU1_R    I63 @S9S_MB_2U_LIB.S9S_MB_2U(SCH_1):PAGE270

PR318 Q_RES_0402LF-5.23K,1%,1/16W,CHA
     1 PVCCIN_CPU1_ADDR @S9S_MB_2U_LIB.S9S_MB_2U(SCH_1):PVCCIN_CPU1_ADDR     I6 @S9S_MB_2U_LIB.S9S_MB_2U(SCH_1):PAGE270
     2    GND @S9S_MB_2U_LIB.S9S_MB_2U(SCH_1):GND     I6 @S9S_MB_2U_LIB.S9S_MB_2U(SCH_1):PAGE270

PR323 Q_RES_0402LF-1,1%,1/16W,CHIP,CA
     1 PVCCIN_CPU1_VCC @S9S_MB_2U_LIB.S9S_MB_2U(SCH_1):PVCCIN_CPU1_VCC   I126 @S9S_MB_2U_LIB.S9S_MB_2U(SCH_1):PAGE270
     2 P3V3_AUX @S9S_MB_2U_LIB.S9S_MB_2U(SCH_1):P3V3_AUX   I126 @S9S_MB_2U_LIB.S9S_MB_2U(SCH_1):PAGE270

PR325 Q_RES_0402LF-8.87K,1%,1/16W,EMA
     1 PVCCIN_CPU1_LSET2 @S9S_MB_2U_LIB.S9S_MB_2U(SCH_1):PVCCIN_CPU1_LSET2     I3 @S9S_MB_2U_LIB.S9S_MB_2U(SCH_1):PAGE271
     2    GND @S9S_MB_2U_LIB.S9S_MB_2U(SCH_1):GND     I3 @S9S_MB_2U_LIB.S9S_MB_2U(SCH_1):PAGE271

PR326 Q_RES_0402LF-8.87K,1%,1/16W,EMA
     1 PVCCIN_CPU1_LSET1 @S9S_MB_2U_LIB.S9S_MB_2U(SCH_1):PVCCIN_CPU1_LSET1    I29 @S9S_MB_2U_LIB.S9S_MB_2U(SCH_1):PAGE271
     2    GND @S9S_MB_2U_LIB.S9S_MB_2U(SCH_1):GND    I29 @S9S_MB_2U_LIB.S9S_MB_2U(SCH_1):PAGE271

PR327 Q_RES_0402LF-2.2,1%,1/16W,CHIPA
     1 PVCCIN_CPU1_PVCC @S9S_MB_2U_LIB.S9S_MB_2U(SCH_1):PVCCIN_CPU1_PVCC    I13 @S9S_MB_2U_LIB.S9S_MB_2U(SCH_1):PAGE271
     2 PVCCIN_CPU1_VDD2 @S9S_MB_2U_LIB.S9S_MB_2U(SCH_1):PVCCIN_CPU1_VDD2    I13 @S9S_MB_2U_LIB.S9S_MB_2U(SCH_1):PAGE271

PR328 Q_RES_0402LF-2.2,1%,1/16W,CHIPA
     1 PVCCIN_CPU1_PVCC @S9S_MB_2U_LIB.S9S_MB_2U(SCH_1):PVCCIN_CPU1_PVCC    I37 @S9S_MB_2U_LIB.S9S_MB_2U(SCH_1):PAGE271
     2 PVCCIN_CPU1_VDD1 @S9S_MB_2U_LIB.S9S_MB_2U(SCH_1):PVCCIN_CPU1_VDD1    I37 @S9S_MB_2U_LIB.S9S_MB_2U(SCH_1):PAGE271

PR329 Q_RES_0402LF-0,5%,1/16W,CHIP,CA
     1 PVCCIN_CPU1_VOS2 @S9S_MB_2U_LIB.S9S_MB_2U(SCH_1):PVCCIN_CPU1_VOS2    I51 @S9S_MB_2U_LIB.S9S_MB_2U(SCH_1):PAGE271
     2 PVCCIN_CPU1 @S9S_MB_2U_LIB.S9S_MB_2U(SCH_1):PVCCIN_CPU1    I51 @S9S_MB_2U_LIB.S9S_MB_2U(SCH_1):PAGE271

PR330 Q_RES_0402LF-0,5%,1/16W,CHIP,CA
     1 PVCCIN_CPU1_VOS1 @S9S_MB_2U_LIB.S9S_MB_2U(SCH_1):PVCCIN_CPU1_VOS1    I73 @S9S_MB_2U_LIB.S9S_MB_2U(SCH_1):PAGE271
     2 PVCCIN_CPU1 @S9S_MB_2U_LIB.S9S_MB_2U(SCH_1):PVCCIN_CPU1    I73 @S9S_MB_2U_LIB.S9S_MB_2U(SCH_1):PAGE271

PR338 Q_RES_0402LF-0,5%,1/16W,CHIP,CA
     1 P1V05_PCH_AUX_MODE @S9S_MB_2U_LIB.S9S_MB_2U(SCH_1):P1V05_PCH_AUX_MODE    I10 @S9S_MB_2U_LIB.S9S_MB_2U(SCH_1):PAGE248
     2    GND @S9S_MB_2U_LIB.S9S_MB_2U(SCH_1):GND    I10 @S9S_MB_2U_LIB.S9S_MB_2U(SCH_1):PAGE248

PR345 Q_RES_0402LF-0,5%,1/16W,CHIP,CA
     1 SH_PVCCFA_EHV_FIVRA_CPU0 @S9S_MB_2U_LIB.S9S_MB_2U(SCH_1):SH_PVCCFA_EHV_FIVRA_CPU0    I68 @S9S_MB_2U_LIB.S9S_MB_2U(SCH_1):PAGE252
     2 SH_PVCCFA_EHV_FIVRA_CPU0_R @S9S_MB_2U_LIB.S9S_MB_2U(SCH_1):SH_PVCCFA_EHV_FIVRA_CPU0_R    I68 @S9S_MB_2U_LIB.S9S_MB_2U(SCH_1):PAGE252

PR353 Q_RES_0402LF-8.87K,1%,1/16W,EMA
     1 PVCCFA_EHV_FIVRA_CPU0_LSET2 @S9S_MB_2U_LIB.S9S_MB_2U(SCH_1):PVCCFA_EHV_FIVRA_CPU0_LSET2     I2 @S9S_MB_2U_LIB.S9S_MB_2U(SCH_1):PAGE257
     2    GND @S9S_MB_2U_LIB.S9S_MB_2U(SCH_1):GND     I2 @S9S_MB_2U_LIB.S9S_MB_2U(SCH_1):PAGE257

PR354 Q_RES_0402LF-8.87K,1%,1/16W,EMA
     1 PVCCFA_EHV_FIVRA_CPU0_LSET1 @S9S_MB_2U_LIB.S9S_MB_2U(SCH_1):PVCCFA_EHV_FIVRA_CPU0_LSET1     I8 @S9S_MB_2U_LIB.S9S_MB_2U(SCH_1):PAGE257
     2    GND @S9S_MB_2U_LIB.S9S_MB_2U(SCH_1):GND     I8 @S9S_MB_2U_LIB.S9S_MB_2U(SCH_1):PAGE257

PR355 Q_RES_0402LF-2.2,1%,1/16W,CHIPA
     1 PVCCFA_EHV_FIVRA_CPU0_PVCC1 @S9S_MB_2U_LIB.S9S_MB_2U(SCH_1):PVCCFA_EHV_FIVRA_CPU0_PVCC1    I39 @S9S_MB_2U_LIB.S9S_MB_2U(SCH_1):PAGE257
     2 PVCCFA_EHV_FIVRA_CPU0_VDD1 @S9S_MB_2U_LIB.S9S_MB_2U(SCH_1):PVCCFA_EHV_FIVRA_CPU0_VDD1    I39 @S9S_MB_2U_LIB.S9S_MB_2U(SCH_1):PAGE257

PR356 Q_RES_0402LF-2.2,1%,1/16W,CHIPA
     1 PVCCFA_EHV_FIVRA_CPU0_PVCC2 @S9S_MB_2U_LIB.S9S_MB_2U(SCH_1):PVCCFA_EHV_FIVRA_CPU0_PVCC2    I19 @S9S_MB_2U_LIB.S9S_MB_2U(SCH_1):PAGE257
     2 PVCCFA_EHV_FIVRA_CPU0_VDD2 @S9S_MB_2U_LIB.S9S_MB_2U(SCH_1):PVCCFA_EHV_FIVRA_CPU0_VDD2    I19 @S9S_MB_2U_LIB.S9S_MB_2U(SCH_1):PAGE257

PR357 Q_RES_0402LF-28K,1%,1/16W,EMPTA
     1 PVCCD_HV_CPU0_VREF @S9S_MB_2U_LIB.S9S_MB_2U(SCH_1):PVCCD_HV_CPU0_VREF     I5 @S9S_MB_2U_LIB.S9S_MB_2U(SCH_1):PAGE264
     2 PVCCD_HV_CPU0_ADDR @S9S_MB_2U_LIB.S9S_MB_2U(SCH_1):PVCCD_HV_CPU0_ADDR     I5 @S9S_MB_2U_LIB.S9S_MB_2U(SCH_1):PAGE264

PR358 Q_RES_0402LF-3.57K,1%,1/16W,CHA
     1    GND @S9S_MB_2U_LIB.S9S_MB_2U(SCH_1):GND    I95 @S9S_MB_2U_LIB.S9S_MB_2U(SCH_1):PAGE264
     2 PVCCD_HV_CPU0_ADDR @S9S_MB_2U_LIB.S9S_MB_2U(SCH_1):PVCCD_HV_CPU0_ADDR    I95 @S9S_MB_2U_LIB.S9S_MB_2U(SCH_1):PAGE264

PR369 Q_RES_0402LF-1K,1%,1/16W,EMPTYA
     1 PVCCD_HV_CPU0_ISENSE_P @S9S_MB_2U_LIB.S9S_MB_2U(SCH_1):PVCCD_HV_CPU0_ISENSE_P     I7 @S9S_MB_2U_LIB.S9S_MB_2U(SCH_1):PAGE264
     2    GND @S9S_MB_2U_LIB.S9S_MB_2U(SCH_1):GND     I7 @S9S_MB_2U_LIB.S9S_MB_2U(SCH_1):PAGE264

PR370 Q_RES_0402LF-1K,1%,1/16W,CHIP,A
     1 P3V3_AUX @S9S_MB_2U_LIB.S9S_MB_2U(SCH_1):P3V3_AUX    I13 @S9S_MB_2U_LIB.S9S_MB_2U(SCH_1):PAGE264
     2 PVCCD_HV_CPU0_PIN_ALT @S9S_MB_2U_LIB.S9S_MB_2U(SCH_1):PVCCD_HV_CPU0_PIN_ALT    I13 @S9S_MB_2U_LIB.S9S_MB_2U(SCH_1):PAGE264

PR371 Q_RES_0402LF-0,5%,1/16W,CHIP,CA
     1 SH_PVCCD_HV_CPU0 @S9S_MB_2U_LIB.S9S_MB_2U(SCH_1):SH_PVCCD_HV_CPU0    I36 @S9S_MB_2U_LIB.S9S_MB_2U(SCH_1):PAGE264
     2 SH_PVCCD_HV_CPU0_R @S9S_MB_2U_LIB.S9S_MB_2U(SCH_1):SH_PVCCD_HV_CPU0_R    I36 @S9S_MB_2U_LIB.S9S_MB_2U(SCH_1):PAGE264

PR372 Q_RES_0402LF-1K,1%,1/16W,CHIP,A
     1 P3V3_AUX @S9S_MB_2U_LIB.S9S_MB_2U(SCH_1):P3V3_AUX    I14 @S9S_MB_2U_LIB.S9S_MB_2U(SCH_1):PAGE264
     2 PVCCD_HV_CPU0_FAULT @S9S_MB_2U_LIB.S9S_MB_2U(SCH_1):PVCCD_HV_CPU0_FAULT    I14 @S9S_MB_2U_LIB.S9S_MB_2U(SCH_1):PAGE264

PR373 Q_RES_0402LF-1K,1%,1/16W,EMPTYA
     1 PVCCD_HV_CPU0_ISENSE_N @S9S_MB_2U_LIB.S9S_MB_2U(SCH_1):PVCCD_HV_CPU0_ISENSE_N    I48 @S9S_MB_2U_LIB.S9S_MB_2U(SCH_1):PAGE264
     2    GND @S9S_MB_2U_LIB.S9S_MB_2U(SCH_1):GND    I48 @S9S_MB_2U_LIB.S9S_MB_2U(SCH_1):PAGE264

PR375 Q_RES_0402LF-1,1%,1/16W,CHIP,CA
     1 PVCCD_HV_CPU0_VCC @S9S_MB_2U_LIB.S9S_MB_2U(SCH_1):PVCCD_HV_CPU0_VCC    I80 @S9S_MB_2U_LIB.S9S_MB_2U(SCH_1):PAGE264
     2 P3V3_AUX @S9S_MB_2U_LIB.S9S_MB_2U(SCH_1):P3V3_AUX    I80 @S9S_MB_2U_LIB.S9S_MB_2U(SCH_1):PAGE264

PR380 Q_RES_0402LF-2.2,1%,1/16W,CHIPA
     1 PVCCFA_EHV_CPU0_PVCC @S9S_MB_2U_LIB.S9S_MB_2U(SCH_1):PVCCFA_EHV_CPU0_PVCC    I12 @S9S_MB_2U_LIB.S9S_MB_2U(SCH_1):PAGE265
     2 PVCCD_HV_CPU0_VDD1 @S9S_MB_2U_LIB.S9S_MB_2U(SCH_1):PVCCD_HV_CPU0_VDD1    I12 @S9S_MB_2U_LIB.S9S_MB_2U(SCH_1):PAGE265

PR389 Q_RES_0402LF-1,1%,1/16W,CHIP,CA
     1 P3V3_AUX_VDRV @S9S_MB_2U_LIB.S9S_MB_2U(SCH_1):P3V3_AUX_VDRV    I94 @S9S_MB_2U_LIB.S9S_MB_2U(SCH_1):PAGE245
     2 P3V3_AUX_VCC @S9S_MB_2U_LIB.S9S_MB_2U(SCH_1):P3V3_AUX_VCC    I94 @S9S_MB_2U_LIB.S9S_MB_2U(SCH_1):PAGE245

PR395 Q_RES_0402LF-0,5%,1/16W,CHIP,CA
     1 P3V3_AUX @S9S_MB_2U_LIB.S9S_MB_2U(SCH_1):P3V3_AUX     I8 @S9S_MB_2U_LIB.S9S_MB_2U(SCH_1):PAGE249
     2 PVCC1_AUX @S9S_MB_2U_LIB.S9S_MB_2U(SCH_1):PVCC1_AUX     I8 @S9S_MB_2U_LIB.S9S_MB_2U(SCH_1):PAGE249

PR396 Q_RES_0402LF-0,5%,1/16W,EMPTY,A
     1 P5V_AUX @S9S_MB_2U_LIB.S9S_MB_2U(SCH_1):P5V_AUX     I2 @S9S_MB_2U_LIB.S9S_MB_2U(SCH_1):PAGE249
     2 PVCC1_AUX @S9S_MB_2U_LIB.S9S_MB_2U(SCH_1):PVCC1_AUX     I2 @S9S_MB_2U_LIB.S9S_MB_2U(SCH_1):PAGE249

PR400 Q_RES_0402LF-10K,1%,1/16W,EMPTA
     1 PVCCIN_CPU0_ATSEN @S9S_MB_2U_LIB.S9S_MB_2U(SCH_1):PVCCIN_CPU0_ATSEN    I72 @S9S_MB_2U_LIB.S9S_MB_2U(SCH_1):PAGE252
     2    GND @S9S_MB_2U_LIB.S9S_MB_2U(SCH_1):GND    I72 @S9S_MB_2U_LIB.S9S_MB_2U(SCH_1):PAGE252

PR402 Q_RES_0402LF-0,5%,1/16W,CHIP,CA
     1    P5V @S9S_MB_2U_LIB.S9S_MB_2U(SCH_1):P5V    I26 @S9S_MB_2U_LIB.S9S_MB_2U(SCH_1):PAGE253
     2 PVCCIN_CPU0_PVCC @S9S_MB_2U_LIB.S9S_MB_2U(SCH_1):PVCCIN_CPU0_PVCC    I26 @S9S_MB_2U_LIB.S9S_MB_2U(SCH_1):PAGE253

PR403 Q_RES_0402LF-0,5%,1/16W,EMPTY,A
     1   P3V3 @S9S_MB_2U_LIB.S9S_MB_2U(SCH_1):P3V3    I42 @S9S_MB_2U_LIB.S9S_MB_2U(SCH_1):PAGE253
     2 PVCCIN_CPU0_PVCC @S9S_MB_2U_LIB.S9S_MB_2U(SCH_1):PVCCIN_CPU0_PVCC    I42 @S9S_MB_2U_LIB.S9S_MB_2U(SCH_1):PAGE253

PR409 Q_RES_0402LF-0,5%,1/16W,EMPTY,A
     1 PVCCD_HV_CPU0_ISYS_R @S9S_MB_2U_LIB.S9S_MB_2U(SCH_1):PVCCD_HV_CPU0_ISYS_R    I63 @S9S_MB_2U_LIB.S9S_MB_2U(SCH_1):PAGE264
     2 PVCCD_HV_CPU0_NVDIMM_ISENSE @S9S_MB_2U_LIB.S9S_MB_2U(SCH_1):PVCCD_HV_CPU0_NVDIMM_ISENSE    I63 @S9S_MB_2U_LIB.S9S_MB_2U(SCH_1):PAGE264

PR410 Q_RES_0402LF-0,5%,1/16W,EMPTY,A
     1 PVCCD_HV_CPU1_ISYS_R @S9S_MB_2U_LIB.S9S_MB_2U(SCH_1):PVCCD_HV_CPU1_ISYS_R    I61 @S9S_MB_2U_LIB.S9S_MB_2U(SCH_1):PAGE282
     2 PVCCD_HV_CPU1_NVDIMM_ISENSE @S9S_MB_2U_LIB.S9S_MB_2U(SCH_1):PVCCD_HV_CPU1_NVDIMM_ISENSE    I61 @S9S_MB_2U_LIB.S9S_MB_2U(SCH_1):PAGE282

PR435 Q_RES_0402LF-10K,1%,1/16W,EMPTA
     1 PVCCINFAON_CPU0_ATSEN @S9S_MB_2U_LIB.S9S_MB_2U(SCH_1):PVCCINFAON_CPU0_ATSEN    I71 @S9S_MB_2U_LIB.S9S_MB_2U(SCH_1):PAGE260
     2    GND @S9S_MB_2U_LIB.S9S_MB_2U(SCH_1):GND    I71 @S9S_MB_2U_LIB.S9S_MB_2U(SCH_1):PAGE260

PR436 Q_RES_0402LF-10K,1%,1/16W,EMPTA
     1 PVCCFA_EHV_CPU0_BTSEN @S9S_MB_2U_LIB.S9S_MB_2U(SCH_1):PVCCFA_EHV_CPU0_BTSEN   I106 @S9S_MB_2U_LIB.S9S_MB_2U(SCH_1):PAGE260
     2    GND @S9S_MB_2U_LIB.S9S_MB_2U(SCH_1):GND   I106 @S9S_MB_2U_LIB.S9S_MB_2U(SCH_1):PAGE260

PR442 Q_RES_0402LF-0,5%,1/16W,CHIP,CA
     1    P5V @S9S_MB_2U_LIB.S9S_MB_2U(SCH_1):P5V     I8 @S9S_MB_2U_LIB.S9S_MB_2U(SCH_1):PAGE262
     2 PVCCFA_EHV_CPU0_PVCC @S9S_MB_2U_LIB.S9S_MB_2U(SCH_1):PVCCFA_EHV_CPU0_PVCC     I8 @S9S_MB_2U_LIB.S9S_MB_2U(SCH_1):PAGE262

PR443 Q_RES_0402LF-0,5%,1/16W,EMPTY,A
     1   P3V3 @S9S_MB_2U_LIB.S9S_MB_2U(SCH_1):P3V3    I22 @S9S_MB_2U_LIB.S9S_MB_2U(SCH_1):PAGE262
     2 PVCCFA_EHV_CPU0_PVCC @S9S_MB_2U_LIB.S9S_MB_2U(SCH_1):PVCCFA_EHV_CPU0_PVCC    I22 @S9S_MB_2U_LIB.S9S_MB_2U(SCH_1):PAGE262

PR444 Q_RES_0402LF-0,5%,1/16W,CHIP,CA
     1    P5V @S9S_MB_2U_LIB.S9S_MB_2U(SCH_1):P5V     I9 @S9S_MB_2U_LIB.S9S_MB_2U(SCH_1):PAGE257
     2 PVCCFA_EHV_FIVRA_CPU0_PVCC1 @S9S_MB_2U_LIB.S9S_MB_2U(SCH_1):PVCCFA_EHV_FIVRA_CPU0_PVCC1     I9 @S9S_MB_2U_LIB.S9S_MB_2U(SCH_1):PAGE257

PR447 Q_RES_0402LF-0,5%,1/16W,CHIP,CA
     1    P5V @S9S_MB_2U_LIB.S9S_MB_2U(SCH_1):P5V     I4 @S9S_MB_2U_LIB.S9S_MB_2U(SCH_1):PAGE257
     2 PVCCFA_EHV_FIVRA_CPU0_PVCC2 @S9S_MB_2U_LIB.S9S_MB_2U(SCH_1):PVCCFA_EHV_FIVRA_CPU0_PVCC2     I4 @S9S_MB_2U_LIB.S9S_MB_2U(SCH_1):PAGE257

PR451 Q_RES_0402LF-10K,1%,1/16W,EMPTA
     1 PVCCFA_EHV_FIVRA_CPU0_BTSEN @S9S_MB_2U_LIB.S9S_MB_2U(SCH_1):PVCCFA_EHV_FIVRA_CPU0_BTSEN   I121 @S9S_MB_2U_LIB.S9S_MB_2U(SCH_1):PAGE252
     2    GND @S9S_MB_2U_LIB.S9S_MB_2U(SCH_1):GND   I121 @S9S_MB_2U_LIB.S9S_MB_2U(SCH_1):PAGE252

PR453 Q_RES_0402LF-10K,1%,1/16W,EMPTA
     1 PVCCFA_EHV_FIVRA_CPU1_BTSEN @S9S_MB_2U_LIB.S9S_MB_2U(SCH_1):PVCCFA_EHV_FIVRA_CPU1_BTSEN    I94 @S9S_MB_2U_LIB.S9S_MB_2U(SCH_1):PAGE270
     2    GND @S9S_MB_2U_LIB.S9S_MB_2U(SCH_1):GND    I94 @S9S_MB_2U_LIB.S9S_MB_2U(SCH_1):PAGE270

PR501 Q_RES_0402LF-8.25K,0.1%,1/16W,A
     1 PVNN_MAIN_CPU0_FB @S9S_MB_2U_LIB.S9S_MB_2U(SCH_1):PVNN_MAIN_CPU0_FB    I36 @S9S_MB_2U_LIB.S9S_MB_2U(SCH_1):PAGE268
     2 PVNN_MAIN_CPU0_FB_RC @S9S_MB_2U_LIB.S9S_MB_2U(SCH_1):PVNN_MAIN_CPU0_FB_RC    I36 @S9S_MB_2U_LIB.S9S_MB_2U(SCH_1):PAGE268

PR502 Q_RES_0402LF-8.25K,0.1%,1/16W,A
     1 PVNN_MAIN_CPU1_FB @S9S_MB_2U_LIB.S9S_MB_2U(SCH_1):PVNN_MAIN_CPU1_FB    I34 @S9S_MB_2U_LIB.S9S_MB_2U(SCH_1):PAGE286
     2 PVNN_MAIN_CPU1_FB_RC @S9S_MB_2U_LIB.S9S_MB_2U(SCH_1):PVNN_MAIN_CPU1_FB_RC    I34 @S9S_MB_2U_LIB.S9S_MB_2U(SCH_1):PAGE286

PR519 Q_RES_0402LF-100,1%,1/16W,CHIPA
     1 VSENSE_PVCCINFAON_CPU0_DN @S9S_MB_2U_LIB.S9S_MB_2U(SCH_1):VSENSE_PVCCINFAON_CPU0_DN    I42 @S9S_MB_2U_LIB.S9S_MB_2U(SCH_1):PAGE260
     2    GND @S9S_MB_2U_LIB.S9S_MB_2U(SCH_1):GND    I42 @S9S_MB_2U_LIB.S9S_MB_2U(SCH_1):PAGE260

PR520 Q_RES_0402LF-100,1%,1/16W,CHIPA
     1 VSENSE_PVCCFA_EHV_CPU0_DN @S9S_MB_2U_LIB.S9S_MB_2U(SCH_1):VSENSE_PVCCFA_EHV_CPU0_DN    I38 @S9S_MB_2U_LIB.S9S_MB_2U(SCH_1):PAGE260
     2    GND @S9S_MB_2U_LIB.S9S_MB_2U(SCH_1):GND    I38 @S9S_MB_2U_LIB.S9S_MB_2U(SCH_1):PAGE260

PR521 Q_RES_0402LF-100,1%,1/16W,CHIPA
     1 VSENSE_PVCCINFAON_CPU0_DP @S9S_MB_2U_LIB.S9S_MB_2U(SCH_1):VSENSE_PVCCINFAON_CPU0_DP    I44 @S9S_MB_2U_LIB.S9S_MB_2U(SCH_1):PAGE260
     2 PVCCINFAON_CPU0 @S9S_MB_2U_LIB.S9S_MB_2U(SCH_1):PVCCINFAON_CPU0    I44 @S9S_MB_2U_LIB.S9S_MB_2U(SCH_1):PAGE260

PR522 Q_RES_0402LF-100,1%,1/16W,CHIPA
     1 VSENSE_PVCCFA_EHV_CPU0_DP @S9S_MB_2U_LIB.S9S_MB_2U(SCH_1):VSENSE_PVCCFA_EHV_CPU0_DP    I40 @S9S_MB_2U_LIB.S9S_MB_2U(SCH_1):PAGE260
     2 PVCCFA_EHV_CPU0 @S9S_MB_2U_LIB.S9S_MB_2U(SCH_1):PVCCFA_EHV_CPU0    I40 @S9S_MB_2U_LIB.S9S_MB_2U(SCH_1):PAGE260

PR527 Q_RES_0402LF-100,1%,1/16W,CHIPA
     1 VSENSE_PVCCIN_CPU0_DN @S9S_MB_2U_LIB.S9S_MB_2U(SCH_1):VSENSE_PVCCIN_CPU0_DN    I26 @S9S_MB_2U_LIB.S9S_MB_2U(SCH_1):PAGE252
     2    GND @S9S_MB_2U_LIB.S9S_MB_2U(SCH_1):GND    I26 @S9S_MB_2U_LIB.S9S_MB_2U(SCH_1):PAGE252

PR531 Q_RES_0402LF-100,1%,1/16W,CHIPA
     1 VSENSE_PVCCIN_CPU0_DP @S9S_MB_2U_LIB.S9S_MB_2U(SCH_1):VSENSE_PVCCIN_CPU0_DP    I38 @S9S_MB_2U_LIB.S9S_MB_2U(SCH_1):PAGE252
     2 PVCCIN_CPU0 @S9S_MB_2U_LIB.S9S_MB_2U(SCH_1):PVCCIN_CPU0    I38 @S9S_MB_2U_LIB.S9S_MB_2U(SCH_1):PAGE252

PR558 Q_RES_0402LF-100,1%,1/16W,CHIPA
     1 VSENSE_PVCCD_HV_CPU1_DN @S9S_MB_2U_LIB.S9S_MB_2U(SCH_1):VSENSE_PVCCD_HV_CPU1_DN    I15 @S9S_MB_2U_LIB.S9S_MB_2U(SCH_1):PAGE282
     2    GND @S9S_MB_2U_LIB.S9S_MB_2U(SCH_1):GND    I15 @S9S_MB_2U_LIB.S9S_MB_2U(SCH_1):PAGE282

PR559 Q_RES_0402LF-100,1%,1/16W,CHIPA
     1 VSENSE_PVCCD_HV_CPU1_DP @S9S_MB_2U_LIB.S9S_MB_2U(SCH_1):VSENSE_PVCCD_HV_CPU1_DP    I36 @S9S_MB_2U_LIB.S9S_MB_2U(SCH_1):PAGE282
     2 PVCCD_HV_CPU1 @S9S_MB_2U_LIB.S9S_MB_2U(SCH_1):PVCCD_HV_CPU1    I36 @S9S_MB_2U_LIB.S9S_MB_2U(SCH_1):PAGE282

PR560 Q_RES_0402LF-100,1%,1/16W,CHIPA
     1 VSENSE_PVCCFA_EHV_FIVRA_CPU1_DN @S9S_MB_2U_LIB.S9S_MB_2U(SCH_1):VSENSE_PVCCFA_EHV_FIVRA_CPU1_DN    I12 @S9S_MB_2U_LIB.S9S_MB_2U(SCH_1):PAGE270
     2    GND @S9S_MB_2U_LIB.S9S_MB_2U(SCH_1):GND    I12 @S9S_MB_2U_LIB.S9S_MB_2U(SCH_1):PAGE270

PR561 Q_RES_0402LF-100,1%,1/16W,CHIPA
     1 VSENSE_PVCCFA_EHV_FIVRA_CPU1_DP @S9S_MB_2U_LIB.S9S_MB_2U(SCH_1):VSENSE_PVCCFA_EHV_FIVRA_CPU1_DP    I23 @S9S_MB_2U_LIB.S9S_MB_2U(SCH_1):PAGE270
     2 PVCCFA_EHV_FIVRA_CPU1 @S9S_MB_2U_LIB.S9S_MB_2U(SCH_1):PVCCFA_EHV_FIVRA_CPU1    I23 @S9S_MB_2U_LIB.S9S_MB_2U(SCH_1):PAGE270

PR566 Q_RES_0402LF-100,1%,1/16W,CHIPA
     1 VSENSE_PVCCINFAON_CPU1_DN @S9S_MB_2U_LIB.S9S_MB_2U(SCH_1):VSENSE_PVCCINFAON_CPU1_DN    I46 @S9S_MB_2U_LIB.S9S_MB_2U(SCH_1):PAGE278
     2    GND @S9S_MB_2U_LIB.S9S_MB_2U(SCH_1):GND    I46 @S9S_MB_2U_LIB.S9S_MB_2U(SCH_1):PAGE278

PR567 Q_RES_0402LF-100,1%,1/16W,CHIPA
     1 VSENSE_PVCCFA_EHV_CPU1_DN @S9S_MB_2U_LIB.S9S_MB_2U(SCH_1):VSENSE_PVCCFA_EHV_CPU1_DN    I41 @S9S_MB_2U_LIB.S9S_MB_2U(SCH_1):PAGE278
     2    GND @S9S_MB_2U_LIB.S9S_MB_2U(SCH_1):GND    I41 @S9S_MB_2U_LIB.S9S_MB_2U(SCH_1):PAGE278

PR568 Q_RES_0402LF-100,1%,1/16W,CHIPA
     1 VSENSE_PVCCINFAON_CPU1_DP @S9S_MB_2U_LIB.S9S_MB_2U(SCH_1):VSENSE_PVCCINFAON_CPU1_DP    I55 @S9S_MB_2U_LIB.S9S_MB_2U(SCH_1):PAGE278
     2 PVCCINFAON_CPU1 @S9S_MB_2U_LIB.S9S_MB_2U(SCH_1):PVCCINFAON_CPU1    I55 @S9S_MB_2U_LIB.S9S_MB_2U(SCH_1):PAGE278

PR569 Q_RES_0402LF-100,1%,1/16W,CHIPA
     1 VSENSE_PVCCFA_EHV_CPU1_DP @S9S_MB_2U_LIB.S9S_MB_2U(SCH_1):VSENSE_PVCCFA_EHV_CPU1_DP    I45 @S9S_MB_2U_LIB.S9S_MB_2U(SCH_1):PAGE278
     2 PVCCFA_EHV_CPU1 @S9S_MB_2U_LIB.S9S_MB_2U(SCH_1):PVCCFA_EHV_CPU1    I45 @S9S_MB_2U_LIB.S9S_MB_2U(SCH_1):PAGE278

PR574 Q_RES_0402LF-100,1%,1/16W,CHIPA
     1 VSENSE_PVCCIN_CPU1_DN @S9S_MB_2U_LIB.S9S_MB_2U(SCH_1):VSENSE_PVCCIN_CPU1_DN    I45 @S9S_MB_2U_LIB.S9S_MB_2U(SCH_1):PAGE270
     2    GND @S9S_MB_2U_LIB.S9S_MB_2U(SCH_1):GND    I45 @S9S_MB_2U_LIB.S9S_MB_2U(SCH_1):PAGE270

PR578 Q_RES_0402LF-100,1%,1/16W,CHIPA
     1 VSENSE_PVCCIN_CPU1_DP @S9S_MB_2U_LIB.S9S_MB_2U(SCH_1):VSENSE_PVCCIN_CPU1_DP    I49 @S9S_MB_2U_LIB.S9S_MB_2U(SCH_1):PAGE270
     2 PVCCIN_CPU1 @S9S_MB_2U_LIB.S9S_MB_2U(SCH_1):PVCCIN_CPU1    I49 @S9S_MB_2U_LIB.S9S_MB_2U(SCH_1):PAGE270

PR586 Q_RES_0402LF-100,1%,1/16W,CHIPA
     1 VSENSE_PVCCFA_EHV_FIVRA_CPU0_DN @S9S_MB_2U_LIB.S9S_MB_2U(SCH_1):VSENSE_PVCCFA_EHV_FIVRA_CPU0_DN    I15 @S9S_MB_2U_LIB.S9S_MB_2U(SCH_1):PAGE252
     2    GND @S9S_MB_2U_LIB.S9S_MB_2U(SCH_1):GND    I15 @S9S_MB_2U_LIB.S9S_MB_2U(SCH_1):PAGE252

PR587 Q_RES_0402LF-100,1%,1/16W,CHIPA
     1 VSENSE_PVCCFA_EHV_FIVRA_CPU0_DP @S9S_MB_2U_LIB.S9S_MB_2U(SCH_1):VSENSE_PVCCFA_EHV_FIVRA_CPU0_DP    I25 @S9S_MB_2U_LIB.S9S_MB_2U(SCH_1):PAGE252
     2 PVCCFA_EHV_FIVRA_CPU0 @S9S_MB_2U_LIB.S9S_MB_2U(SCH_1):PVCCFA_EHV_FIVRA_CPU0    I25 @S9S_MB_2U_LIB.S9S_MB_2U(SCH_1):PAGE252

PR591 Q_RES_0402LF-100,1%,1/16W,CHIPA
     1 VSENSE_PVCCD_HV_CPU0_DN @S9S_MB_2U_LIB.S9S_MB_2U(SCH_1):VSENSE_PVCCD_HV_CPU0_DN    I30 @S9S_MB_2U_LIB.S9S_MB_2U(SCH_1):PAGE264
     2    GND @S9S_MB_2U_LIB.S9S_MB_2U(SCH_1):GND    I30 @S9S_MB_2U_LIB.S9S_MB_2U(SCH_1):PAGE264

PR592 Q_RES_0402LF-100,1%,1/16W,CHIPA
     1 VSENSE_PVCCD_HV_CPU0_DP @S9S_MB_2U_LIB.S9S_MB_2U(SCH_1):VSENSE_PVCCD_HV_CPU0_DP    I31 @S9S_MB_2U_LIB.S9S_MB_2U(SCH_1):PAGE264
     2 PVCCD_HV_CPU0 @S9S_MB_2U_LIB.S9S_MB_2U(SCH_1):PVCCD_HV_CPU0    I31 @S9S_MB_2U_LIB.S9S_MB_2U(SCH_1):PAGE264

PR632 Q_RES_0402LF-0,5%,1/16W,EMPTY,A
     1   P3V3 @S9S_MB_2U_LIB.S9S_MB_2U(SCH_1):P3V3    I40 @S9S_MB_2U_LIB.S9S_MB_2U(SCH_1):PAGE257
     2 PVCCFA_EHV_FIVRA_CPU0_PVCC1 @S9S_MB_2U_LIB.S9S_MB_2U(SCH_1):PVCCFA_EHV_FIVRA_CPU0_PVCC1    I40 @S9S_MB_2U_LIB.S9S_MB_2U(SCH_1):PAGE257

PR633 Q_RES_0402LF-0,5%,1/16W,EMPTY,A
     1   P3V3 @S9S_MB_2U_LIB.S9S_MB_2U(SCH_1):P3V3    I22 @S9S_MB_2U_LIB.S9S_MB_2U(SCH_1):PAGE257
     2 PVCCFA_EHV_FIVRA_CPU0_PVCC2 @S9S_MB_2U_LIB.S9S_MB_2U(SCH_1):PVCCFA_EHV_FIVRA_CPU0_PVCC2    I22 @S9S_MB_2U_LIB.S9S_MB_2U(SCH_1):PAGE257

PR634 Q_RES_0402LF-10K,1%,1/16W,EMPTA
     1 PVCCD_HV_CPU0_ATSEN @S9S_MB_2U_LIB.S9S_MB_2U(SCH_1):PVCCD_HV_CPU0_ATSEN    I57 @S9S_MB_2U_LIB.S9S_MB_2U(SCH_1):PAGE264
     2    GND @S9S_MB_2U_LIB.S9S_MB_2U(SCH_1):GND    I57 @S9S_MB_2U_LIB.S9S_MB_2U(SCH_1):PAGE264

PR637 Q_RES_0402LF-10K,1%,1/16W,EMPTA
     1 PVCCIN_CPU1_ATSEN @S9S_MB_2U_LIB.S9S_MB_2U(SCH_1):PVCCIN_CPU1_ATSEN    I74 @S9S_MB_2U_LIB.S9S_MB_2U(SCH_1):PAGE270
     2    GND @S9S_MB_2U_LIB.S9S_MB_2U(SCH_1):GND    I74 @S9S_MB_2U_LIB.S9S_MB_2U(SCH_1):PAGE270

PR639 Q_RES_0402LF-0,5%,1/16W,CHIP,CA
     1    P5V @S9S_MB_2U_LIB.S9S_MB_2U(SCH_1):P5V    I26 @S9S_MB_2U_LIB.S9S_MB_2U(SCH_1):PAGE271
     2 PVCCIN_CPU1_PVCC @S9S_MB_2U_LIB.S9S_MB_2U(SCH_1):PVCCIN_CPU1_PVCC    I26 @S9S_MB_2U_LIB.S9S_MB_2U(SCH_1):PAGE271

PR640 Q_RES_0402LF-0,5%,1/16W,EMPTY,A
     1   P3V3 @S9S_MB_2U_LIB.S9S_MB_2U(SCH_1):P3V3    I41 @S9S_MB_2U_LIB.S9S_MB_2U(SCH_1):PAGE271
     2 PVCCIN_CPU1_PVCC @S9S_MB_2U_LIB.S9S_MB_2U(SCH_1):PVCCIN_CPU1_PVCC    I41 @S9S_MB_2U_LIB.S9S_MB_2U(SCH_1):PAGE271

PR665 Q_RES_0402LF-10K,1%,1/16W,EMPTA
     1 PVCCINFAON_CPU1_ATSEN @S9S_MB_2U_LIB.S9S_MB_2U(SCH_1):PVCCINFAON_CPU1_ATSEN    I67 @S9S_MB_2U_LIB.S9S_MB_2U(SCH_1):PAGE278
     2    GND @S9S_MB_2U_LIB.S9S_MB_2U(SCH_1):GND    I67 @S9S_MB_2U_LIB.S9S_MB_2U(SCH_1):PAGE278

PR667 Q_RES_0402LF-10K,1%,1/16W,EMPTA
     1 PVCCFA_EHV_CPU1_BTSEN @S9S_MB_2U_LIB.S9S_MB_2U(SCH_1):PVCCFA_EHV_CPU1_BTSEN    I75 @S9S_MB_2U_LIB.S9S_MB_2U(SCH_1):PAGE278
     2    GND @S9S_MB_2U_LIB.S9S_MB_2U(SCH_1):GND    I75 @S9S_MB_2U_LIB.S9S_MB_2U(SCH_1):PAGE278

PR678 Q_RES_0402LF-0,5%,1/16W,CHIP,CA
     1    P5V @S9S_MB_2U_LIB.S9S_MB_2U(SCH_1):P5V     I4 @S9S_MB_2U_LIB.S9S_MB_2U(SCH_1):PAGE280
     2 PVCCFA_EHV_CPU1_PVCC @S9S_MB_2U_LIB.S9S_MB_2U(SCH_1):PVCCFA_EHV_CPU1_PVCC     I4 @S9S_MB_2U_LIB.S9S_MB_2U(SCH_1):PAGE280

PR699 Q_RES_0402LF-0,5%,1/16W,EMPTY,A
     1   P3V3 @S9S_MB_2U_LIB.S9S_MB_2U(SCH_1):P3V3    I16 @S9S_MB_2U_LIB.S9S_MB_2U(SCH_1):PAGE280
     2 PVCCFA_EHV_CPU1_PVCC @S9S_MB_2U_LIB.S9S_MB_2U(SCH_1):PVCCFA_EHV_CPU1_PVCC    I16 @S9S_MB_2U_LIB.S9S_MB_2U(SCH_1):PAGE280

PR701 Q_RES_0402LF-0,5%,1/16W,CHIP,CA
     1    P5V @S9S_MB_2U_LIB.S9S_MB_2U(SCH_1):P5V    I32 @S9S_MB_2U_LIB.S9S_MB_2U(SCH_1):PAGE275
     2 PVCCFA_EHV_FIVRA_CPU1_PVCC1 @S9S_MB_2U_LIB.S9S_MB_2U(SCH_1):PVCCFA_EHV_FIVRA_CPU1_PVCC1    I32 @S9S_MB_2U_LIB.S9S_MB_2U(SCH_1):PAGE275

PR702 Q_RES_0402LF-0,5%,1/16W,CHIP,CA
     1    P5V @S9S_MB_2U_LIB.S9S_MB_2U(SCH_1):P5V    I13 @S9S_MB_2U_LIB.S9S_MB_2U(SCH_1):PAGE275
     2 PVCCFA_EHV_FIVRA_CPU1_PVCC2 @S9S_MB_2U_LIB.S9S_MB_2U(SCH_1):PVCCFA_EHV_FIVRA_CPU1_PVCC2    I13 @S9S_MB_2U_LIB.S9S_MB_2U(SCH_1):PAGE275

PR703 Q_RES_0402LF-0,5%,1/16W,EMPTY,A
     1   P3V3 @S9S_MB_2U_LIB.S9S_MB_2U(SCH_1):P3V3    I34 @S9S_MB_2U_LIB.S9S_MB_2U(SCH_1):PAGE275
     2 PVCCFA_EHV_FIVRA_CPU1_PVCC1 @S9S_MB_2U_LIB.S9S_MB_2U(SCH_1):PVCCFA_EHV_FIVRA_CPU1_PVCC1    I34 @S9S_MB_2U_LIB.S9S_MB_2U(SCH_1):PAGE275

PR704 Q_RES_0402LF-0,5%,1/16W,EMPTY,A
     1   P3V3 @S9S_MB_2U_LIB.S9S_MB_2U(SCH_1):P3V3    I17 @S9S_MB_2U_LIB.S9S_MB_2U(SCH_1):PAGE275
     2 PVCCFA_EHV_FIVRA_CPU1_PVCC2 @S9S_MB_2U_LIB.S9S_MB_2U(SCH_1):PVCCFA_EHV_FIVRA_CPU1_PVCC2    I17 @S9S_MB_2U_LIB.S9S_MB_2U(SCH_1):PAGE275

PR705 Q_RES_0402LF-10K,1%,1/16W,EMPTA
     1 PVCCD_HV_CPU1_ATSEN @S9S_MB_2U_LIB.S9S_MB_2U(SCH_1):PVCCD_HV_CPU1_ATSEN    I81 @S9S_MB_2U_LIB.S9S_MB_2U(SCH_1):PAGE282
     2    GND @S9S_MB_2U_LIB.S9S_MB_2U(SCH_1):GND    I81 @S9S_MB_2U_LIB.S9S_MB_2U(SCH_1):PAGE282

PR830 Q_RES_0402LF-15K,0.1%,1/16W,CHA
     1 P3V3_AUX_FB @S9S_MB_2U_LIB.S9S_MB_2U(SCH_1):P3V3_AUX_FB   I125 @S9S_MB_2U_LIB.S9S_MB_2U(SCH_1):PAGE245
     2    GND @S9S_MB_2U_LIB.S9S_MB_2U(SCH_1):GND   I125 @S9S_MB_2U_LIB.S9S_MB_2U(SCH_1):PAGE245

PR831 Q_RES_0402LF-47K,0.1%,1/16W,CHA
     1 P3V3_AUX_FB @S9S_MB_2U_LIB.S9S_MB_2U(SCH_1):P3V3_AUX_FB   I128 @S9S_MB_2U_LIB.S9S_MB_2U(SCH_1):PAGE245
     2 P3V3_AUX @S9S_MB_2U_LIB.S9S_MB_2U(SCH_1):P3V3_AUX   I128 @S9S_MB_2U_LIB.S9S_MB_2U(SCH_1):PAGE245

PR832 Q_RES_0402LF-0,5%,1/16W,CHIP,CA
     1 P3V3_AUX_MODE @S9S_MB_2U_LIB.S9S_MB_2U(SCH_1):P3V3_AUX_MODE    I84 @S9S_MB_2U_LIB.S9S_MB_2U(SCH_1):PAGE245
     2    GND @S9S_MB_2U_LIB.S9S_MB_2U(SCH_1):GND    I84 @S9S_MB_2U_LIB.S9S_MB_2U(SCH_1):PAGE245

PR833 Q_RES_0402LF-1.5K,1%,1/16W,EMPA
     1 P3V3_AUX_SS @S9S_MB_2U_LIB.S9S_MB_2U(SCH_1):P3V3_AUX_SS    I89 @S9S_MB_2U_LIB.S9S_MB_2U(SCH_1):PAGE245
     2    GND @S9S_MB_2U_LIB.S9S_MB_2U(SCH_1):GND    I89 @S9S_MB_2U_LIB.S9S_MB_2U(SCH_1):PAGE245

PR834 Q_RES_0402LF-21.5K,1%,1/16W,CHA
     1 P3V3_AUX_ILIM @S9S_MB_2U_LIB.S9S_MB_2U(SCH_1):P3V3_AUX_ILIM    I91 @S9S_MB_2U_LIB.S9S_MB_2U(SCH_1):PAGE245
     2    GND @S9S_MB_2U_LIB.S9S_MB_2U(SCH_1):GND    I91 @S9S_MB_2U_LIB.S9S_MB_2U(SCH_1):PAGE245

PR835 Q_RES_0402LF-0,5%,1/16W,CHIP,CA
     1 SW_P3V3_AUX_BOOT @S9S_MB_2U_LIB.S9S_MB_2U(SCH_1):SW_P3V3_AUX_BOOT   I123 @S9S_MB_2U_LIB.S9S_MB_2U(SCH_1):PAGE245
     2 SW_P3V3_AUX_BOOT_R @S9S_MB_2U_LIB.S9S_MB_2U(SCH_1):SW_P3V3_AUX_BOOT_R   I123 @S9S_MB_2U_LIB.S9S_MB_2U(SCH_1):PAGE245

PR836 Q_RES_0402LF-1K,1%,1/16W,EMPTYA
     1 P3V3_AUX_VOS @S9S_MB_2U_LIB.S9S_MB_2U(SCH_1):P3V3_AUX_VOS   I121 @S9S_MB_2U_LIB.S9S_MB_2U(SCH_1):PAGE245
     2 P3V3_AUX @S9S_MB_2U_LIB.S9S_MB_2U(SCH_1):P3V3_AUX   I121 @S9S_MB_2U_LIB.S9S_MB_2U(SCH_1):PAGE245

PR1101 Q_RES_0402LF-2K,0.1%,1/16W,CHIA
     1 HSC_IMON @S9S_MB_2U_LIB.S9S_MB_2U(SCH_1):HSC_IMON    I13 @S9S_MB_2U_LIB.S9S_MB_2U(SCH_1):PAGE301
     2 AGND_HSC @S9S_MB_2U_LIB.S9S_MB_2U(SCH_1):AGND_HSC    I13 @S9S_MB_2U_LIB.S9S_MB_2U(SCH_1):PAGE301

PR1131 Q_RES_0402LF-2K,0.1%,1/16W,CHIA
     1 HSC_CS @S9S_MB_2U_LIB.S9S_MB_2U(SCH_1):HSC_CS    I58 @S9S_MB_2U_LIB.S9S_MB_2U(SCH_1):PAGE303
     2 AGND_HSC @S9S_MB_2U_LIB.S9S_MB_2U(SCH_1):AGND_HSC    I58 @S9S_MB_2U_LIB.S9S_MB_2U(SCH_1):PAGE303

PR1133 Q_RES_0402LF-2K,0.1%,1/16W,CHIA
     1 HSC_IMON @S9S_MB_2U_LIB.S9S_MB_2U(SCH_1):HSC_IMON    I91 @S9S_MB_2U_LIB.S9S_MB_2U(SCH_1):PAGE303
     2 AGND_HSC @S9S_MB_2U_LIB.S9S_MB_2U(SCH_1):AGND_HSC    I91 @S9S_MB_2U_LIB.S9S_MB_2U(SCH_1):PAGE303

PR1134 Q_RES_0402LF-120K,1%,1/16W,CHIA
     1 AGND_HSC @S9S_MB_2U_LIB.S9S_MB_2U(SCH_1):AGND_HSC    I32 @S9S_MB_2U_LIB.S9S_MB_2U(SCH_1):PAGE301
     2 HSC_MODE_1 @S9S_MB_2U_LIB.S9S_MB_2U(SCH_1):HSC_MODE_1    I32 @S9S_MB_2U_LIB.S9S_MB_2U(SCH_1):PAGE301

PR1297 Q_RES_0402LF-8.87K,1%,1/16W,EMA
     1 PVCCFA_EHV_FIVRA_CPU0_LSET4 @S9S_MB_2U_LIB.S9S_MB_2U(SCH_1):PVCCFA_EHV_FIVRA_CPU0_LSET4     I3 @S9S_MB_2U_LIB.S9S_MB_2U(SCH_1):PAGE258
     2    GND @S9S_MB_2U_LIB.S9S_MB_2U(SCH_1):GND     I3 @S9S_MB_2U_LIB.S9S_MB_2U(SCH_1):PAGE258

PR1298 Q_RES_0402LF-8.87K,1%,1/16W,EMA
     1 PVCCFA_EHV_FIVRA_CPU0_LSET3 @S9S_MB_2U_LIB.S9S_MB_2U(SCH_1):PVCCFA_EHV_FIVRA_CPU0_LSET3    I15 @S9S_MB_2U_LIB.S9S_MB_2U(SCH_1):PAGE258
     2    GND @S9S_MB_2U_LIB.S9S_MB_2U(SCH_1):GND    I15 @S9S_MB_2U_LIB.S9S_MB_2U(SCH_1):PAGE258

PR1299 Q_RES_0402LF-2.2,1%,1/16W,CHIPA
     1 PVCCFA_EHV_FIVRA_CPU0_PVCC1 @S9S_MB_2U_LIB.S9S_MB_2U(SCH_1):PVCCFA_EHV_FIVRA_CPU0_PVCC1    I26 @S9S_MB_2U_LIB.S9S_MB_2U(SCH_1):PAGE258
     2 PVCCFA_EHV_FIVRA_CPU0_VDD3 @S9S_MB_2U_LIB.S9S_MB_2U(SCH_1):PVCCFA_EHV_FIVRA_CPU0_VDD3    I26 @S9S_MB_2U_LIB.S9S_MB_2U(SCH_1):PAGE258

PR1300 Q_RES_0402LF-2.2,1%,1/16W,CHIPA
     1 PVCCFA_EHV_FIVRA_CPU0_PVCC2 @S9S_MB_2U_LIB.S9S_MB_2U(SCH_1):PVCCFA_EHV_FIVRA_CPU0_PVCC2    I11 @S9S_MB_2U_LIB.S9S_MB_2U(SCH_1):PAGE258
     2 PVCCFA_EHV_FIVRA_CPU0_VDD4 @S9S_MB_2U_LIB.S9S_MB_2U(SCH_1):PVCCFA_EHV_FIVRA_CPU0_VDD4    I11 @S9S_MB_2U_LIB.S9S_MB_2U(SCH_1):PAGE258

PR1301 Q_RES_0402LF-60.4K,1%,1/16W,CHA
     1 PVNN_MAIN_CPU0_MODE @S9S_MB_2U_LIB.S9S_MB_2U(SCH_1):PVNN_MAIN_CPU0_MODE     I9 @S9S_MB_2U_LIB.S9S_MB_2U(SCH_1):PAGE268
     2    GND @S9S_MB_2U_LIB.S9S_MB_2U(SCH_1):GND     I9 @S9S_MB_2U_LIB.S9S_MB_2U(SCH_1):PAGE268

PR1303 Q_RES_0402LF-22.6K,1%,1/16W,CHA
     1 PVNN_MAIN_CPU0_CS @S9S_MB_2U_LIB.S9S_MB_2U(SCH_1):PVNN_MAIN_CPU0_CS    I21 @S9S_MB_2U_LIB.S9S_MB_2U(SCH_1):PAGE268
     2    GND @S9S_MB_2U_LIB.S9S_MB_2U(SCH_1):GND    I21 @S9S_MB_2U_LIB.S9S_MB_2U(SCH_1):PAGE268

PR1304 Q_RES_0402LF-8.87K,1%,1/16W,EMA
     1 PVCCFA_EHV_FIVRA_CPU1_LSET4 @S9S_MB_2U_LIB.S9S_MB_2U(SCH_1):PVCCFA_EHV_FIVRA_CPU1_LSET4     I2 @S9S_MB_2U_LIB.S9S_MB_2U(SCH_1):PAGE276
     2    GND @S9S_MB_2U_LIB.S9S_MB_2U(SCH_1):GND     I2 @S9S_MB_2U_LIB.S9S_MB_2U(SCH_1):PAGE276

PR1305 Q_RES_0402LF-8.87K,1%,1/16W,EMA
     1 PVCCFA_EHV_FIVRA_CPU1_LSET3 @S9S_MB_2U_LIB.S9S_MB_2U(SCH_1):PVCCFA_EHV_FIVRA_CPU1_LSET3     I5 @S9S_MB_2U_LIB.S9S_MB_2U(SCH_1):PAGE276
     2    GND @S9S_MB_2U_LIB.S9S_MB_2U(SCH_1):GND     I5 @S9S_MB_2U_LIB.S9S_MB_2U(SCH_1):PAGE276

PR1306 Q_RES_0402LF-2.2,1%,1/16W,CHIPA
     1 PVCCFA_EHV_FIVRA_CPU1_PVCC1 @S9S_MB_2U_LIB.S9S_MB_2U(SCH_1):PVCCFA_EHV_FIVRA_CPU1_PVCC1    I29 @S9S_MB_2U_LIB.S9S_MB_2U(SCH_1):PAGE276
     2 PVCCFA_EHV_FIVRA_CPU1_VDD3 @S9S_MB_2U_LIB.S9S_MB_2U(SCH_1):PVCCFA_EHV_FIVRA_CPU1_VDD3    I29 @S9S_MB_2U_LIB.S9S_MB_2U(SCH_1):PAGE276

PR1307 Q_RES_0402LF-2.2,1%,1/16W,CHIPA
     1 PVCCFA_EHV_FIVRA_CPU1_PVCC2 @S9S_MB_2U_LIB.S9S_MB_2U(SCH_1):PVCCFA_EHV_FIVRA_CPU1_PVCC2    I18 @S9S_MB_2U_LIB.S9S_MB_2U(SCH_1):PAGE276
     2 PVCCFA_EHV_FIVRA_CPU1_VDD4 @S9S_MB_2U_LIB.S9S_MB_2U(SCH_1):PVCCFA_EHV_FIVRA_CPU1_VDD4    I18 @S9S_MB_2U_LIB.S9S_MB_2U(SCH_1):PAGE276

PR1310 Q_RES_0402LF-11.3K,0.1%,1/16W,A
     1 PVPP_HBM_CPU0_FB @S9S_MB_2U_LIB.S9S_MB_2U(SCH_1):PVPP_HBM_CPU0_FB    I26 @S9S_MB_2U_LIB.S9S_MB_2U(SCH_1):PAGE267
     2 SH_PVPP_HBM_CPU0_N @S9S_MB_2U_LIB.S9S_MB_2U(SCH_1):SH_PVPP_HBM_CPU0_N    I26 @S9S_MB_2U_LIB.S9S_MB_2U(SCH_1):PAGE267

PR1311 Q_RES_0402LF-0,5%,1/16W,CHIP,CA
     1 PVCCD_HV_CPU0_ISYS_R @S9S_MB_2U_LIB.S9S_MB_2U(SCH_1):PVCCD_HV_CPU0_ISYS_R    I59 @S9S_MB_2U_LIB.S9S_MB_2U(SCH_1):PAGE264
     2    GND @S9S_MB_2U_LIB.S9S_MB_2U(SCH_1):GND    I59 @S9S_MB_2U_LIB.S9S_MB_2U(SCH_1):PAGE264

PR1314 Q_RES_0402LF-11.3K,0.1%,1/16W,A
     1 PVPP_HBM_CPU1_FB @S9S_MB_2U_LIB.S9S_MB_2U(SCH_1):PVPP_HBM_CPU1_FB    I28 @S9S_MB_2U_LIB.S9S_MB_2U(SCH_1):PAGE285
     2 SH_PVPP_HBM_CPU1_N @S9S_MB_2U_LIB.S9S_MB_2U(SCH_1):SH_PVPP_HBM_CPU1_N    I28 @S9S_MB_2U_LIB.S9S_MB_2U(SCH_1):PAGE285

PR1315 Q_RES_0402LF-0,5%,1/16W,CHIP,CA
     1 PVCCD_HV_CPU1_ISYS_R @S9S_MB_2U_LIB.S9S_MB_2U(SCH_1):PVCCD_HV_CPU1_ISYS_R    I60 @S9S_MB_2U_LIB.S9S_MB_2U(SCH_1):PAGE282
     2    GND @S9S_MB_2U_LIB.S9S_MB_2U(SCH_1):GND    I60 @S9S_MB_2U_LIB.S9S_MB_2U(SCH_1):PAGE282

PR1322 Q_RES_0402LF-0,5%,1/16W,CHIP,CA
     1 PVCCFA_EHV_FIVRA_CPU0_VOS1 @S9S_MB_2U_LIB.S9S_MB_2U(SCH_1):PVCCFA_EHV_FIVRA_CPU0_VOS1    I69 @S9S_MB_2U_LIB.S9S_MB_2U(SCH_1):PAGE257
     2 PVCCFA_EHV_FIVRA_CPU0 @S9S_MB_2U_LIB.S9S_MB_2U(SCH_1):PVCCFA_EHV_FIVRA_CPU0    I69 @S9S_MB_2U_LIB.S9S_MB_2U(SCH_1):PAGE257

PR1323 Q_RES_0402LF-0,5%,1/16W,CHIP,CA
     1 PVCCFA_EHV_FIVRA_CPU0_VOS2 @S9S_MB_2U_LIB.S9S_MB_2U(SCH_1):PVCCFA_EHV_FIVRA_CPU0_VOS2    I50 @S9S_MB_2U_LIB.S9S_MB_2U(SCH_1):PAGE257
     2 PVCCFA_EHV_FIVRA_CPU0 @S9S_MB_2U_LIB.S9S_MB_2U(SCH_1):PVCCFA_EHV_FIVRA_CPU0    I50 @S9S_MB_2U_LIB.S9S_MB_2U(SCH_1):PAGE257

PR1324 Q_RES_0402LF-0,5%,1/16W,CHIP,CA
     1 PVCCFA_EHV_FIVRA_CPU0_VOS3 @S9S_MB_2U_LIB.S9S_MB_2U(SCH_1):PVCCFA_EHV_FIVRA_CPU0_VOS3    I50 @S9S_MB_2U_LIB.S9S_MB_2U(SCH_1):PAGE258
     2 PVCCFA_EHV_FIVRA_CPU0 @S9S_MB_2U_LIB.S9S_MB_2U(SCH_1):PVCCFA_EHV_FIVRA_CPU0    I50 @S9S_MB_2U_LIB.S9S_MB_2U(SCH_1):PAGE258

PR1325 Q_RES_0402LF-0,5%,1/16W,CHIP,CA
     1 PVCCFA_EHV_FIVRA_CPU0_VOS4 @S9S_MB_2U_LIB.S9S_MB_2U(SCH_1):PVCCFA_EHV_FIVRA_CPU0_VOS4    I38 @S9S_MB_2U_LIB.S9S_MB_2U(SCH_1):PAGE258
     2 PVCCFA_EHV_FIVRA_CPU0 @S9S_MB_2U_LIB.S9S_MB_2U(SCH_1):PVCCFA_EHV_FIVRA_CPU0    I38 @S9S_MB_2U_LIB.S9S_MB_2U(SCH_1):PAGE258

PR1326 Q_RES_0402LF-0,5%,1/16W,CHIP,CA
     1 P3V3_AUX @S9S_MB_2U_LIB.S9S_MB_2U(SCH_1):P3V3_AUX     I3 @S9S_MB_2U_LIB.S9S_MB_2U(SCH_1):PAGE248
     2 P1V05_PCH_AUX_VCC @S9S_MB_2U_LIB.S9S_MB_2U(SCH_1):P1V05_PCH_AUX_VCC     I3 @S9S_MB_2U_LIB.S9S_MB_2U(SCH_1):PAGE248

PR1327 Q_RES_0402LF-8.45K,1%,1/16W,CHA
     1 P1V05_PCH_AUX_CS @S9S_MB_2U_LIB.S9S_MB_2U(SCH_1):P1V05_PCH_AUX_CS     I6 @S9S_MB_2U_LIB.S9S_MB_2U(SCH_1):PAGE248
     2    GND @S9S_MB_2U_LIB.S9S_MB_2U(SCH_1):GND     I6 @S9S_MB_2U_LIB.S9S_MB_2U(SCH_1):PAGE248

PR1328 Q_RES_0402LF-7.32K,0.1%,1/16W,A
     1 P1V05_PCH_AUX_FB @S9S_MB_2U_LIB.S9S_MB_2U(SCH_1):P1V05_PCH_AUX_FB    I36 @S9S_MB_2U_LIB.S9S_MB_2U(SCH_1):PAGE248
     2 SH_P1V05_PCH_AUX_P @S9S_MB_2U_LIB.S9S_MB_2U(SCH_1):SH_P1V05_PCH_AUX_P    I36 @S9S_MB_2U_LIB.S9S_MB_2U(SCH_1):PAGE248

PR1329 Q_RES_0402LF-5.1,5%,1/16W,CHIPA
     1 PVCC1_AUX @S9S_MB_2U_LIB.S9S_MB_2U(SCH_1):PVCC1_AUX     I5 @S9S_MB_2U_LIB.S9S_MB_2U(SCH_1):PAGE249
     2 P1V8_PCH_AUX_VCC @S9S_MB_2U_LIB.S9S_MB_2U(SCH_1):P1V8_PCH_AUX_VCC     I5 @S9S_MB_2U_LIB.S9S_MB_2U(SCH_1):PAGE249

PR1330 Q_RES_0402LF-150K,1%,1/16W,CHIA
     1 P1V8_PCH_AUX_MODE @S9S_MB_2U_LIB.S9S_MB_2U(SCH_1):P1V8_PCH_AUX_MODE    I24 @S9S_MB_2U_LIB.S9S_MB_2U(SCH_1):PAGE249
     2    GND @S9S_MB_2U_LIB.S9S_MB_2U(SCH_1):GND    I24 @S9S_MB_2U_LIB.S9S_MB_2U(SCH_1):PAGE249

PR1331 Q_RES_0402LF-0,5%,1/16W,CHIP,CA
     1 PVCCFA_EHV_FIVRA_CPU1_VOS1 @S9S_MB_2U_LIB.S9S_MB_2U(SCH_1):PVCCFA_EHV_FIVRA_CPU1_VOS1    I53 @S9S_MB_2U_LIB.S9S_MB_2U(SCH_1):PAGE275
     2 PVCCFA_EHV_FIVRA_CPU1 @S9S_MB_2U_LIB.S9S_MB_2U(SCH_1):PVCCFA_EHV_FIVRA_CPU1    I53 @S9S_MB_2U_LIB.S9S_MB_2U(SCH_1):PAGE275

PR1332 Q_RES_0402LF-0,5%,1/16W,CHIP,CA
     1 PVCCFA_EHV_FIVRA_CPU1_VOS2 @S9S_MB_2U_LIB.S9S_MB_2U(SCH_1):PVCCFA_EHV_FIVRA_CPU1_VOS2    I41 @S9S_MB_2U_LIB.S9S_MB_2U(SCH_1):PAGE275
     2 PVCCFA_EHV_FIVRA_CPU1 @S9S_MB_2U_LIB.S9S_MB_2U(SCH_1):PVCCFA_EHV_FIVRA_CPU1    I41 @S9S_MB_2U_LIB.S9S_MB_2U(SCH_1):PAGE275

PR1333 Q_RES_0402LF-0,5%,1/16W,CHIP,CA
     1 PVCCFA_EHV_FIVRA_CPU1_VOS3 @S9S_MB_2U_LIB.S9S_MB_2U(SCH_1):PVCCFA_EHV_FIVRA_CPU1_VOS3    I54 @S9S_MB_2U_LIB.S9S_MB_2U(SCH_1):PAGE276
     2 PVCCFA_EHV_FIVRA_CPU1 @S9S_MB_2U_LIB.S9S_MB_2U(SCH_1):PVCCFA_EHV_FIVRA_CPU1    I54 @S9S_MB_2U_LIB.S9S_MB_2U(SCH_1):PAGE276

PR1334 Q_RES_0402LF-0,5%,1/16W,CHIP,CA
     1 PVCCFA_EHV_FIVRA_CPU1_VOS4 @S9S_MB_2U_LIB.S9S_MB_2U(SCH_1):PVCCFA_EHV_FIVRA_CPU1_VOS4    I43 @S9S_MB_2U_LIB.S9S_MB_2U(SCH_1):PAGE276
     2 PVCCFA_EHV_FIVRA_CPU1 @S9S_MB_2U_LIB.S9S_MB_2U(SCH_1):PVCCFA_EHV_FIVRA_CPU1    I43 @S9S_MB_2U_LIB.S9S_MB_2U(SCH_1):PAGE276

PR1335 Q_RES_0402LF-0,5%,1/16W,CHIP,CA
     1 P3V3_AUX @S9S_MB_2U_LIB.S9S_MB_2U(SCH_1):P3V3_AUX     I5 @S9S_MB_2U_LIB.S9S_MB_2U(SCH_1):PAGE267
     2 PVPP_HBM_CPU0_VCC @S9S_MB_2U_LIB.S9S_MB_2U(SCH_1):PVPP_HBM_CPU0_VCC     I5 @S9S_MB_2U_LIB.S9S_MB_2U(SCH_1):PAGE267

PR1336 Q_RES_0402LF-9.76K,1%,1/16W,CHA
     1 PVPP_HBM_CPU0_CS @S9S_MB_2U_LIB.S9S_MB_2U(SCH_1):PVPP_HBM_CPU0_CS    I15 @S9S_MB_2U_LIB.S9S_MB_2U(SCH_1):PAGE267
     2    GND @S9S_MB_2U_LIB.S9S_MB_2U(SCH_1):GND    I15 @S9S_MB_2U_LIB.S9S_MB_2U(SCH_1):PAGE267

PR1337 Q_RES_0402LF-38.3K,0.1%,1/16W,A
     1 PVPP_HBM_CPU0_FB @S9S_MB_2U_LIB.S9S_MB_2U(SCH_1):PVPP_HBM_CPU0_FB    I36 @S9S_MB_2U_LIB.S9S_MB_2U(SCH_1):PAGE267
     2 SH_PVPP_HBM_CPU0_P @S9S_MB_2U_LIB.S9S_MB_2U(SCH_1):SH_PVPP_HBM_CPU0_P    I36 @S9S_MB_2U_LIB.S9S_MB_2U(SCH_1):PAGE267

PR1338 Q_RES_0402LF-0,5%,1/16W,CHIP,CA
     1 P3V3_AUX @S9S_MB_2U_LIB.S9S_MB_2U(SCH_1):P3V3_AUX     I3 @S9S_MB_2U_LIB.S9S_MB_2U(SCH_1):PAGE285
     2 PVPP_HBM_CPU1_VCC @S9S_MB_2U_LIB.S9S_MB_2U(SCH_1):PVPP_HBM_CPU1_VCC     I3 @S9S_MB_2U_LIB.S9S_MB_2U(SCH_1):PAGE285

PR1339 Q_RES_0402LF-9.76K,1%,1/16W,CHA
     1 PVPP_HBM_CPU1_CS @S9S_MB_2U_LIB.S9S_MB_2U(SCH_1):PVPP_HBM_CPU1_CS    I10 @S9S_MB_2U_LIB.S9S_MB_2U(SCH_1):PAGE285
     2    GND @S9S_MB_2U_LIB.S9S_MB_2U(SCH_1):GND    I10 @S9S_MB_2U_LIB.S9S_MB_2U(SCH_1):PAGE285

PR1340 Q_RES_0402LF-38.3K,0.1%,1/16W,A
     1 PVPP_HBM_CPU1_FB @S9S_MB_2U_LIB.S9S_MB_2U(SCH_1):PVPP_HBM_CPU1_FB    I34 @S9S_MB_2U_LIB.S9S_MB_2U(SCH_1):PAGE285
     2 SH_PVPP_HBM_CPU1_P @S9S_MB_2U_LIB.S9S_MB_2U(SCH_1):SH_PVPP_HBM_CPU1_P    I34 @S9S_MB_2U_LIB.S9S_MB_2U(SCH_1):PAGE285

PR1380 Q_RES_0402LF-49.9,1%,1/16W,CHIA
     1 P12V_AUX_CPU0_DIMM_ISEN_P @S9S_MB_2U_LIB.S9S_MB_2U(SCH_1):P12V_AUX_CPU0_DIMM_ISEN_P    I11 @S9S_MB_2U_LIB.S9S_MB_2U(SCH_1):PAGE264
     2 PVCCD_HV_CPU0_ISENSE_P @S9S_MB_2U_LIB.S9S_MB_2U(SCH_1):PVCCD_HV_CPU0_ISENSE_P    I11 @S9S_MB_2U_LIB.S9S_MB_2U(SCH_1):PAGE264

PR1390 Q_RES_0402LF-49.9,1%,1/16W,CHIA
     1 P12V_AUX_CPU0_DIMM_ISEN_N @S9S_MB_2U_LIB.S9S_MB_2U(SCH_1):P12V_AUX_CPU0_DIMM_ISEN_N    I10 @S9S_MB_2U_LIB.S9S_MB_2U(SCH_1):PAGE264
     2 PVCCD_HV_CPU0_ISENSE_N @S9S_MB_2U_LIB.S9S_MB_2U(SCH_1):PVCCD_HV_CPU0_ISENSE_N    I10 @S9S_MB_2U_LIB.S9S_MB_2U(SCH_1):PAGE264

PR1400 Q_RES_0402LF-49.9,1%,1/16W,CHIA
     1 P12V_AUX_CPU1_DIMM_ISEN_P @S9S_MB_2U_LIB.S9S_MB_2U(SCH_1):P12V_AUX_CPU1_DIMM_ISEN_P     I9 @S9S_MB_2U_LIB.S9S_MB_2U(SCH_1):PAGE282
     2 PVCCD_HV_CPU1_ISENSE_P @S9S_MB_2U_LIB.S9S_MB_2U(SCH_1):PVCCD_HV_CPU1_ISENSE_P     I9 @S9S_MB_2U_LIB.S9S_MB_2U(SCH_1):PAGE282

PR1410 Q_RES_0402LF-49.9,1%,1/16W,CHIA
     1 P12V_AUX_CPU1_DIMM_ISEN_N @S9S_MB_2U_LIB.S9S_MB_2U(SCH_1):P12V_AUX_CPU1_DIMM_ISEN_N    I10 @S9S_MB_2U_LIB.S9S_MB_2U(SCH_1):PAGE282
     2 PVCCD_HV_CPU1_ISENSE_N @S9S_MB_2U_LIB.S9S_MB_2U(SCH_1):PVCCD_HV_CPU1_ISENSE_N    I10 @S9S_MB_2U_LIB.S9S_MB_2U(SCH_1):PAGE282

PR1647 Q_RES_0402LF-10K,1%,1/16W,EMPTA
     1 P3V3_AUX @S9S_MB_2U_LIB.S9S_MB_2U(SCH_1):P3V3_AUX    I26 @S9S_MB_2U_LIB.S9S_MB_2U(SCH_1):PAGE248
     2 FM_P1V05_PCH_AUX_R_EN @S9S_MB_2U_LIB.S9S_MB_2U(SCH_1):FM_P1V05_PCH_AUX_R_EN    I26 @S9S_MB_2U_LIB.S9S_MB_2U(SCH_1):PAGE248

PR1649 Q_RES_0402LF-2K,1%,1/16W,CHIP,A
     1 FM_P1V05_PCH_AUX_R_EN @S9S_MB_2U_LIB.S9S_MB_2U(SCH_1):FM_P1V05_PCH_AUX_R_EN     I9 @S9S_MB_2U_LIB.S9S_MB_2U(SCH_1):PAGE248
     2    GND @S9S_MB_2U_LIB.S9S_MB_2U(SCH_1):GND     I9 @S9S_MB_2U_LIB.S9S_MB_2U(SCH_1):PAGE248

PR1653 Q_RES_0402LF-470,1%,1/16W,CHIPA
     1 P1V8_PCH_AUX @S9S_MB_2U_LIB.S9S_MB_2U(SCH_1):P1V8_PCH_AUX    I42 @S9S_MB_2U_LIB.S9S_MB_2U(SCH_1):PAGE249
     2    GND @S9S_MB_2U_LIB.S9S_MB_2U(SCH_1):GND    I42 @S9S_MB_2U_LIB.S9S_MB_2U(SCH_1):PAGE249

PR1707 Q_RES_0402LF-8.87K,1%,1/16W,EMA
     1 PVCCINFAON_CPU0_LSET2 @S9S_MB_2U_LIB.S9S_MB_2U(SCH_1):PVCCINFAON_CPU0_LSET2     I2 @S9S_MB_2U_LIB.S9S_MB_2U(SCH_1):PAGE261
     2    GND @S9S_MB_2U_LIB.S9S_MB_2U(SCH_1):GND     I2 @S9S_MB_2U_LIB.S9S_MB_2U(SCH_1):PAGE261

PR1708 Q_RES_0402LF-8.87K,1%,1/16W,EMA
     1 PVCCINFAON_CPU0_LSET1 @S9S_MB_2U_LIB.S9S_MB_2U(SCH_1):PVCCINFAON_CPU0_LSET1     I5 @S9S_MB_2U_LIB.S9S_MB_2U(SCH_1):PAGE261
     2    GND @S9S_MB_2U_LIB.S9S_MB_2U(SCH_1):GND     I5 @S9S_MB_2U_LIB.S9S_MB_2U(SCH_1):PAGE261

PR1709 Q_RES_0402LF-8.87K,1%,1/16W,EMA
     1 PVCCFA_EHV_CPU0_LSET1 @S9S_MB_2U_LIB.S9S_MB_2U(SCH_1):PVCCFA_EHV_CPU0_LSET1     I2 @S9S_MB_2U_LIB.S9S_MB_2U(SCH_1):PAGE262
     2    GND @S9S_MB_2U_LIB.S9S_MB_2U(SCH_1):GND     I2 @S9S_MB_2U_LIB.S9S_MB_2U(SCH_1):PAGE262

PR1726 Q_RES_0402LF-8.87K,1%,1/16W,EMA
     1 PVCCINFAON_CPU1_LSET1 @S9S_MB_2U_LIB.S9S_MB_2U(SCH_1):PVCCINFAON_CPU1_LSET1    I16 @S9S_MB_2U_LIB.S9S_MB_2U(SCH_1):PAGE279
     2    GND @S9S_MB_2U_LIB.S9S_MB_2U(SCH_1):GND    I16 @S9S_MB_2U_LIB.S9S_MB_2U(SCH_1):PAGE279

PR1727 Q_RES_0402LF-8.87K,1%,1/16W,EMA
     1 PVCCINFAON_CPU1_LSET2 @S9S_MB_2U_LIB.S9S_MB_2U(SCH_1):PVCCINFAON_CPU1_LSET2     I3 @S9S_MB_2U_LIB.S9S_MB_2U(SCH_1):PAGE279
     2    GND @S9S_MB_2U_LIB.S9S_MB_2U(SCH_1):GND     I3 @S9S_MB_2U_LIB.S9S_MB_2U(SCH_1):PAGE279

PR1728 Q_RES_0402LF-8.87K,1%,1/16W,EMA
     1 PVCCFA_EHV_CPU1_LSET1 @S9S_MB_2U_LIB.S9S_MB_2U(SCH_1):PVCCFA_EHV_CPU1_LSET1     I1 @S9S_MB_2U_LIB.S9S_MB_2U(SCH_1):PAGE280
     2    GND @S9S_MB_2U_LIB.S9S_MB_2U(SCH_1):GND     I1 @S9S_MB_2U_LIB.S9S_MB_2U(SCH_1):PAGE280

PR1746 Q_RES_0402LF-8.87K,1%,1/16W,EMA
     1 PVCCD_HV_CPU1_LSET1 @S9S_MB_2U_LIB.S9S_MB_2U(SCH_1):PVCCD_HV_CPU1_LSET1     I3 @S9S_MB_2U_LIB.S9S_MB_2U(SCH_1):PAGE283
     2    GND @S9S_MB_2U_LIB.S9S_MB_2U(SCH_1):GND     I3 @S9S_MB_2U_LIB.S9S_MB_2U(SCH_1):PAGE283

PR1766 Q_RES_0402LF-3.3,1%,1/16W,CHIPA
     1 SW_PVCCIN_CPU1_BOOT2 @S9S_MB_2U_LIB.S9S_MB_2U(SCH_1):SW_PVCCIN_CPU1_BOOT2    I20 @S9S_MB_2U_LIB.S9S_MB_2U(SCH_1):PAGE271
     2 SW_PVCCIN_CPU1_BOOT2_R @S9S_MB_2U_LIB.S9S_MB_2U(SCH_1):SW_PVCCIN_CPU1_BOOT2_R    I20 @S9S_MB_2U_LIB.S9S_MB_2U(SCH_1):PAGE271

PR1767 Q_RES_0402LF-3.3,1%,1/16W,CHIPA
     1 SW_PVCCIN_CPU1_BOOT1 @S9S_MB_2U_LIB.S9S_MB_2U(SCH_1):SW_PVCCIN_CPU1_BOOT1    I46 @S9S_MB_2U_LIB.S9S_MB_2U(SCH_1):PAGE271
     2 SW_PVCCIN_CPU1_BOOT1_R @S9S_MB_2U_LIB.S9S_MB_2U(SCH_1):SW_PVCCIN_CPU1_BOOT1_R    I46 @S9S_MB_2U_LIB.S9S_MB_2U(SCH_1):PAGE271

PR1768 Q_RES_0402LF-3.3,1%,1/16W,CHIPA
     1 SW_PVCCIN_CPU0_BOOT4 @S9S_MB_2U_LIB.S9S_MB_2U(SCH_1):SW_PVCCIN_CPU0_BOOT4    I36 @S9S_MB_2U_LIB.S9S_MB_2U(SCH_1):PAGE254
     2 SW_PVCCIN_CPU0_BOOT4_R @S9S_MB_2U_LIB.S9S_MB_2U(SCH_1):SW_PVCCIN_CPU0_BOOT4_R    I36 @S9S_MB_2U_LIB.S9S_MB_2U(SCH_1):PAGE254

PR1769 Q_RES_0402LF-3.3,1%,1/16W,CHIPA
     1 SW_PVCCIN_CPU0_BOOT3 @S9S_MB_2U_LIB.S9S_MB_2U(SCH_1):SW_PVCCIN_CPU0_BOOT3    I49 @S9S_MB_2U_LIB.S9S_MB_2U(SCH_1):PAGE254
     2 SW_PVCCIN_CPU0_BOOT3_R @S9S_MB_2U_LIB.S9S_MB_2U(SCH_1):SW_PVCCIN_CPU0_BOOT3_R    I49 @S9S_MB_2U_LIB.S9S_MB_2U(SCH_1):PAGE254

PR1770 Q_RES_0402LF-3.3,1%,1/16W,CHIPA
     1 SW_PVCCIN_CPU0_BOOT6 @S9S_MB_2U_LIB.S9S_MB_2U(SCH_1):SW_PVCCIN_CPU0_BOOT6    I35 @S9S_MB_2U_LIB.S9S_MB_2U(SCH_1):PAGE255
     2 SW_PVCCIN_CPU0_BOOT6_R @S9S_MB_2U_LIB.S9S_MB_2U(SCH_1):SW_PVCCIN_CPU0_BOOT6_R    I35 @S9S_MB_2U_LIB.S9S_MB_2U(SCH_1):PAGE255

PR1771 Q_RES_0402LF-3.3,1%,1/16W,CHIPA
     1 SW_PVCCIN_CPU0_BOOT5 @S9S_MB_2U_LIB.S9S_MB_2U(SCH_1):SW_PVCCIN_CPU0_BOOT5    I49 @S9S_MB_2U_LIB.S9S_MB_2U(SCH_1):PAGE255
     2 SW_PVCCIN_CPU0_BOOT5_R @S9S_MB_2U_LIB.S9S_MB_2U(SCH_1):SW_PVCCIN_CPU0_BOOT5_R    I49 @S9S_MB_2U_LIB.S9S_MB_2U(SCH_1):PAGE255

PR1772 Q_RES_0402LF-3.3,1%,1/16W,CHIPA
     1 SW_PVCCIN_CPU0_BOOT8 @S9S_MB_2U_LIB.S9S_MB_2U(SCH_1):SW_PVCCIN_CPU0_BOOT8    I19 @S9S_MB_2U_LIB.S9S_MB_2U(SCH_1):PAGE256
     2 SW_PVCCIN_CPU0_BOOT8_R @S9S_MB_2U_LIB.S9S_MB_2U(SCH_1):SW_PVCCIN_CPU0_BOOT8_R    I19 @S9S_MB_2U_LIB.S9S_MB_2U(SCH_1):PAGE256

PR1773 Q_RES_0402LF-3.3,1%,1/16W,CHIPA
     1 SW_PVCCIN_CPU0_BOOT7 @S9S_MB_2U_LIB.S9S_MB_2U(SCH_1):SW_PVCCIN_CPU0_BOOT7    I40 @S9S_MB_2U_LIB.S9S_MB_2U(SCH_1):PAGE256
     2 SW_PVCCIN_CPU0_BOOT7_R @S9S_MB_2U_LIB.S9S_MB_2U(SCH_1):SW_PVCCIN_CPU0_BOOT7_R    I40 @S9S_MB_2U_LIB.S9S_MB_2U(SCH_1):PAGE256

PR1774 Q_RES_0402LF-3.3,1%,1/16W,CHIPA
     1 SW_PVCCINFAON_CPU0_BOOT1 @S9S_MB_2U_LIB.S9S_MB_2U(SCH_1):SW_PVCCINFAON_CPU0_BOOT1    I47 @S9S_MB_2U_LIB.S9S_MB_2U(SCH_1):PAGE261
     2 SW_PVCCINFAON_CPU0_BOOT1_R @S9S_MB_2U_LIB.S9S_MB_2U(SCH_1):SW_PVCCINFAON_CPU0_BOOT1_R    I47 @S9S_MB_2U_LIB.S9S_MB_2U(SCH_1):PAGE261

PR1775 Q_RES_0402LF-3.3,1%,1/16W,CHIPA
     1 SW_PVCCINFAON_CPU0_BOOT2 @S9S_MB_2U_LIB.S9S_MB_2U(SCH_1):SW_PVCCINFAON_CPU0_BOOT2    I34 @S9S_MB_2U_LIB.S9S_MB_2U(SCH_1):PAGE261
     2 SW_PVCCINFAON_CPU0_BOOT2_R @S9S_MB_2U_LIB.S9S_MB_2U(SCH_1):SW_PVCCINFAON_CPU0_BOOT2_R    I34 @S9S_MB_2U_LIB.S9S_MB_2U(SCH_1):PAGE261

PR1776 Q_RES_0402LF-0,5%,1/16W,CHIP,CA
     1 PVCCINFAON_CPU0_VOS1 @S9S_MB_2U_LIB.S9S_MB_2U(SCH_1):PVCCINFAON_CPU0_VOS1    I46 @S9S_MB_2U_LIB.S9S_MB_2U(SCH_1):PAGE261
     2 PVCCINFAON_CPU0 @S9S_MB_2U_LIB.S9S_MB_2U(SCH_1):PVCCINFAON_CPU0    I46 @S9S_MB_2U_LIB.S9S_MB_2U(SCH_1):PAGE261

PR1777 Q_RES_0402LF-0,5%,1/16W,CHIP,CA
     1 PVCCINFAON_CPU0_VOS2 @S9S_MB_2U_LIB.S9S_MB_2U(SCH_1):PVCCINFAON_CPU0_VOS2    I31 @S9S_MB_2U_LIB.S9S_MB_2U(SCH_1):PAGE261
     2 PVCCINFAON_CPU0 @S9S_MB_2U_LIB.S9S_MB_2U(SCH_1):PVCCINFAON_CPU0    I31 @S9S_MB_2U_LIB.S9S_MB_2U(SCH_1):PAGE261

PR1778 Q_RES_0402LF-3.3,1%,1/16W,CHIPA
     1 SW_PVCCFA_EHV_CPU0_BOOT1 @S9S_MB_2U_LIB.S9S_MB_2U(SCH_1):SW_PVCCFA_EHV_CPU0_BOOT1    I17 @S9S_MB_2U_LIB.S9S_MB_2U(SCH_1):PAGE262
     2 SW_PVCCFA_EHV_CPU0_BOOT1_R @S9S_MB_2U_LIB.S9S_MB_2U(SCH_1):SW_PVCCFA_EHV_CPU0_BOOT1_R    I17 @S9S_MB_2U_LIB.S9S_MB_2U(SCH_1):PAGE262

PR1779 Q_RES_0402LF-0,5%,1/16W,CHIP,CA
     1 PVCCFA_EHV_CPU0_NC1 @S9S_MB_2U_LIB.S9S_MB_2U(SCH_1):PVCCFA_EHV_CPU0_NC1    I16 @S9S_MB_2U_LIB.S9S_MB_2U(SCH_1):PAGE262
     2 PVCCFA_EHV_CPU0_VDD1 @S9S_MB_2U_LIB.S9S_MB_2U(SCH_1):PVCCFA_EHV_CPU0_VDD1    I16 @S9S_MB_2U_LIB.S9S_MB_2U(SCH_1):PAGE262

PR1780 Q_RES_0402LF-3.3,1%,1/16W,CHIPA
     1 SW_PVCCFA_EHV_FIVRA_CPU0_BOOT1 @S9S_MB_2U_LIB.S9S_MB_2U(SCH_1):SW_PVCCFA_EHV_FIVRA_CPU0_BOOT1    I46 @S9S_MB_2U_LIB.S9S_MB_2U(SCH_1):PAGE257
     2 SW_PVCCFA_EHV_FIVRA_CPU0_BOOT1_ @S9S_MB_2U_LIB.S9S_MB_2U(SCH_1):SW_PVCCFA_EHV_FIVRA_CPU0_BOOT1_R    I46 @S9S_MB_2U_LIB.S9S_MB_2U(SCH_1):PAGE257

PR1781 Q_RES_0402LF-3.3,1%,1/16W,CHIPA
     1 SW_PVCCFA_EHV_FIVRA_CPU0_BOOT2 @S9S_MB_2U_LIB.S9S_MB_2U(SCH_1):SW_PVCCFA_EHV_FIVRA_CPU0_BOOT2    I30 @S9S_MB_2U_LIB.S9S_MB_2U(SCH_1):PAGE257
     2 SW_PVCCFA_EHV_FIVRA_CPU0_BOOT2_ @S9S_MB_2U_LIB.S9S_MB_2U(SCH_1):SW_PVCCFA_EHV_FIVRA_CPU0_BOOT2_R    I30 @S9S_MB_2U_LIB.S9S_MB_2U(SCH_1):PAGE257

PR1782 Q_RES_0402LF-3.3,1%,1/16W,CHIPA
     1 SW_PVCCFA_EHV_FIVRA_CPU0_BOOT3 @S9S_MB_2U_LIB.S9S_MB_2U(SCH_1):SW_PVCCFA_EHV_FIVRA_CPU0_BOOT3    I45 @S9S_MB_2U_LIB.S9S_MB_2U(SCH_1):PAGE258
     2 SW_PVCCFA_EHV_FIVRA_CPU0_BOOT3_ @S9S_MB_2U_LIB.S9S_MB_2U(SCH_1):SW_PVCCFA_EHV_FIVRA_CPU0_BOOT3_R    I45 @S9S_MB_2U_LIB.S9S_MB_2U(SCH_1):PAGE258

PR1783 Q_RES_0402LF-3.3,1%,1/16W,CHIPA
     1 SW_PVCCFA_EHV_FIVRA_CPU0_BOOT4 @S9S_MB_2U_LIB.S9S_MB_2U(SCH_1):SW_PVCCFA_EHV_FIVRA_CPU0_BOOT4    I33 @S9S_MB_2U_LIB.S9S_MB_2U(SCH_1):PAGE258
     2 SW_PVCCFA_EHV_FIVRA_CPU0_BOOT4_ @S9S_MB_2U_LIB.S9S_MB_2U(SCH_1):SW_PVCCFA_EHV_FIVRA_CPU0_BOOT4_R    I33 @S9S_MB_2U_LIB.S9S_MB_2U(SCH_1):PAGE258

PR1784 Q_RES_0402LF-3.3,1%,1/16W,CHIPA
     1 SW_PVCCD_HV_CPU0_BOOT1 @S9S_MB_2U_LIB.S9S_MB_2U(SCH_1):SW_PVCCD_HV_CPU0_BOOT1    I19 @S9S_MB_2U_LIB.S9S_MB_2U(SCH_1):PAGE265
     2 SW_PVCCD_HV_CPU0_BOOT1_R @S9S_MB_2U_LIB.S9S_MB_2U(SCH_1):SW_PVCCD_HV_CPU0_BOOT1_R    I19 @S9S_MB_2U_LIB.S9S_MB_2U(SCH_1):PAGE265

PR1785 Q_RES_0402LF-0,5%,1/16W,CHIP,CA
     1 PVCCD_HV_CPU0_VOS @S9S_MB_2U_LIB.S9S_MB_2U(SCH_1):PVCCD_HV_CPU0_VOS    I17 @S9S_MB_2U_LIB.S9S_MB_2U(SCH_1):PAGE265
     2 PVCCD_HV_CPU0 @S9S_MB_2U_LIB.S9S_MB_2U(SCH_1):PVCCD_HV_CPU0    I17 @S9S_MB_2U_LIB.S9S_MB_2U(SCH_1):PAGE265

PR1786 Q_RES_0402LF-3.3,1%,1/16W,CHIPA
     1 SW_PVCCIN_CPU0_BOOT2 @S9S_MB_2U_LIB.S9S_MB_2U(SCH_1):SW_PVCCIN_CPU0_BOOT2    I18 @S9S_MB_2U_LIB.S9S_MB_2U(SCH_1):PAGE253
     2 SW_PVCCIN_CPU0_BOOT2_R @S9S_MB_2U_LIB.S9S_MB_2U(SCH_1):SW_PVCCIN_CPU0_BOOT2_R    I18 @S9S_MB_2U_LIB.S9S_MB_2U(SCH_1):PAGE253

PR1787 Q_RES_0402LF-3.3,1%,1/16W,CHIPA
     1 SW_PVCCIN_CPU0_BOOT1 @S9S_MB_2U_LIB.S9S_MB_2U(SCH_1):SW_PVCCIN_CPU0_BOOT1    I97 @S9S_MB_2U_LIB.S9S_MB_2U(SCH_1):PAGE253
     2 SW_PVCCIN_CPU0_BOOT1_R @S9S_MB_2U_LIB.S9S_MB_2U(SCH_1):SW_PVCCIN_CPU0_BOOT1_R    I97 @S9S_MB_2U_LIB.S9S_MB_2U(SCH_1):PAGE253

PR1788 Q_RES_0402LF-3.3,1%,1/16W,CHIPA
     1 SW_PVCCIN_CPU1_BOOT4 @S9S_MB_2U_LIB.S9S_MB_2U(SCH_1):SW_PVCCIN_CPU1_BOOT4    I34 @S9S_MB_2U_LIB.S9S_MB_2U(SCH_1):PAGE272
     2 SW_PVCCIN_CPU1_BOOT4_R @S9S_MB_2U_LIB.S9S_MB_2U(SCH_1):SW_PVCCIN_CPU1_BOOT4_R    I34 @S9S_MB_2U_LIB.S9S_MB_2U(SCH_1):PAGE272

PR1789 Q_RES_0402LF-3.3,1%,1/16W,CHIPA
     1 SW_PVCCIN_CPU1_BOOT3 @S9S_MB_2U_LIB.S9S_MB_2U(SCH_1):SW_PVCCIN_CPU1_BOOT3    I46 @S9S_MB_2U_LIB.S9S_MB_2U(SCH_1):PAGE272
     2 SW_PVCCIN_CPU1_BOOT3_R @S9S_MB_2U_LIB.S9S_MB_2U(SCH_1):SW_PVCCIN_CPU1_BOOT3_R    I46 @S9S_MB_2U_LIB.S9S_MB_2U(SCH_1):PAGE272

PR1790 Q_RES_0402LF-3.3,1%,1/16W,CHIPA
     1 SW_PVCCIN_CPU1_BOOT6 @S9S_MB_2U_LIB.S9S_MB_2U(SCH_1):SW_PVCCIN_CPU1_BOOT6    I30 @S9S_MB_2U_LIB.S9S_MB_2U(SCH_1):PAGE273
     2 SW_PVCCIN_CPU1_BOOT6_R @S9S_MB_2U_LIB.S9S_MB_2U(SCH_1):SW_PVCCIN_CPU1_BOOT6_R    I30 @S9S_MB_2U_LIB.S9S_MB_2U(SCH_1):PAGE273

PR1791 Q_RES_0402LF-3.3,1%,1/16W,CHIPA
     1 SW_PVCCIN_CPU1_BOOT5 @S9S_MB_2U_LIB.S9S_MB_2U(SCH_1):SW_PVCCIN_CPU1_BOOT5    I44 @S9S_MB_2U_LIB.S9S_MB_2U(SCH_1):PAGE273
     2 SW_PVCCIN_CPU1_BOOT5_R @S9S_MB_2U_LIB.S9S_MB_2U(SCH_1):SW_PVCCIN_CPU1_BOOT5_R    I44 @S9S_MB_2U_LIB.S9S_MB_2U(SCH_1):PAGE273

PR1792 Q_RES_0402LF-3.3,1%,1/16W,CHIPA
     1 SW_PVCCIN_CPU1_BOOT8 @S9S_MB_2U_LIB.S9S_MB_2U(SCH_1):SW_PVCCIN_CPU1_BOOT8    I26 @S9S_MB_2U_LIB.S9S_MB_2U(SCH_1):PAGE274
     2 SW_PVCCIN_CPU1_BOOT8_R @S9S_MB_2U_LIB.S9S_MB_2U(SCH_1):SW_PVCCIN_CPU1_BOOT8_R    I26 @S9S_MB_2U_LIB.S9S_MB_2U(SCH_1):PAGE274

PR1793 Q_RES_0402LF-3.3,1%,1/16W,CHIPA
     1 SW_PVCCIN_CPU1_BOOT7 @S9S_MB_2U_LIB.S9S_MB_2U(SCH_1):SW_PVCCIN_CPU1_BOOT7    I39 @S9S_MB_2U_LIB.S9S_MB_2U(SCH_1):PAGE274
     2 SW_PVCCIN_CPU1_BOOT7_R @S9S_MB_2U_LIB.S9S_MB_2U(SCH_1):SW_PVCCIN_CPU1_BOOT7_R    I39 @S9S_MB_2U_LIB.S9S_MB_2U(SCH_1):PAGE274

PR1794 Q_RES_0402LF-3.3,1%,1/16W,CHIPA
     1 SW_PVCCINFAON_CPU1_BOOT1 @S9S_MB_2U_LIB.S9S_MB_2U(SCH_1):SW_PVCCINFAON_CPU1_BOOT1    I50 @S9S_MB_2U_LIB.S9S_MB_2U(SCH_1):PAGE279
     2 SW_PVCCINFAON_CPU1_BOOT1_R @S9S_MB_2U_LIB.S9S_MB_2U(SCH_1):SW_PVCCINFAON_CPU1_BOOT1_R    I50 @S9S_MB_2U_LIB.S9S_MB_2U(SCH_1):PAGE279

PR1795 Q_RES_0402LF-3.3,1%,1/16W,CHIPA
     1 SW_PVCCINFAON_CPU1_BOOT2 @S9S_MB_2U_LIB.S9S_MB_2U(SCH_1):SW_PVCCINFAON_CPU1_BOOT2    I42 @S9S_MB_2U_LIB.S9S_MB_2U(SCH_1):PAGE279
     2 SW_PVCCINFAON_CPU1_BOOT2_R @S9S_MB_2U_LIB.S9S_MB_2U(SCH_1):SW_PVCCINFAON_CPU1_BOOT2_R    I42 @S9S_MB_2U_LIB.S9S_MB_2U(SCH_1):PAGE279

PR1796 Q_RES_0402LF-0,5%,1/16W,CHIP,CA
     1 PVCCINFAON_CPU1_VOS1 @S9S_MB_2U_LIB.S9S_MB_2U(SCH_1):PVCCINFAON_CPU1_VOS1    I49 @S9S_MB_2U_LIB.S9S_MB_2U(SCH_1):PAGE279
     2 PVCCINFAON_CPU1 @S9S_MB_2U_LIB.S9S_MB_2U(SCH_1):PVCCINFAON_CPU1    I49 @S9S_MB_2U_LIB.S9S_MB_2U(SCH_1):PAGE279

PR1797 Q_RES_0402LF-0,5%,1/16W,CHIP,CA
     1 PVCCINFAON_CPU1_VOS2 @S9S_MB_2U_LIB.S9S_MB_2U(SCH_1):PVCCINFAON_CPU1_VOS2    I31 @S9S_MB_2U_LIB.S9S_MB_2U(SCH_1):PAGE279
     2 PVCCINFAON_CPU1 @S9S_MB_2U_LIB.S9S_MB_2U(SCH_1):PVCCINFAON_CPU1    I31 @S9S_MB_2U_LIB.S9S_MB_2U(SCH_1):PAGE279

PR1798 Q_RES_0402LF-3.3,1%,1/16W,CHIPA
     1 SW_PVCCFA_EHV_CPU1_BOOT1 @S9S_MB_2U_LIB.S9S_MB_2U(SCH_1):SW_PVCCFA_EHV_CPU1_BOOT1    I25 @S9S_MB_2U_LIB.S9S_MB_2U(SCH_1):PAGE280
     2 SW_PVCCFA_EHV_CPU1_BOOT1_R @S9S_MB_2U_LIB.S9S_MB_2U(SCH_1):SW_PVCCFA_EHV_CPU1_BOOT1_R    I25 @S9S_MB_2U_LIB.S9S_MB_2U(SCH_1):PAGE280

PR1799 Q_RES_0402LF-0,5%,1/16W,CHIP,CA
     1 PVCCFA_EHV_CPU1_NC1 @S9S_MB_2U_LIB.S9S_MB_2U(SCH_1):PVCCFA_EHV_CPU1_NC1    I20 @S9S_MB_2U_LIB.S9S_MB_2U(SCH_1):PAGE280
     2 PVCCFA_EHV_CPU1_VDD1 @S9S_MB_2U_LIB.S9S_MB_2U(SCH_1):PVCCFA_EHV_CPU1_VDD1    I20 @S9S_MB_2U_LIB.S9S_MB_2U(SCH_1):PAGE280

PR1800 Q_RES_0402LF-3.3,1%,1/16W,CHIPA
     1 SW_PVCCFA_EHV_FIVRA_CPU1_BOOT1 @S9S_MB_2U_LIB.S9S_MB_2U(SCH_1):SW_PVCCFA_EHV_FIVRA_CPU1_BOOT1    I50 @S9S_MB_2U_LIB.S9S_MB_2U(SCH_1):PAGE275
     2 SW_PVCCFA_EHV_FIVRA_CPU1_BOOT1_ @S9S_MB_2U_LIB.S9S_MB_2U(SCH_1):SW_PVCCFA_EHV_FIVRA_CPU1_BOOT1_R    I50 @S9S_MB_2U_LIB.S9S_MB_2U(SCH_1):PAGE275

PR1801 Q_RES_0402LF-3.3,1%,1/16W,CHIPA
     1 SW_PVCCFA_EHV_FIVRA_CPU1_BOOT2 @S9S_MB_2U_LIB.S9S_MB_2U(SCH_1):SW_PVCCFA_EHV_FIVRA_CPU1_BOOT2    I38 @S9S_MB_2U_LIB.S9S_MB_2U(SCH_1):PAGE275
     2 SW_PVCCFA_EHV_FIVRA_CPU1_BOOT2_ @S9S_MB_2U_LIB.S9S_MB_2U(SCH_1):SW_PVCCFA_EHV_FIVRA_CPU1_BOOT2_R    I38 @S9S_MB_2U_LIB.S9S_MB_2U(SCH_1):PAGE275

PR1802 Q_RES_0402LF-3.3,1%,1/16W,CHIPA
     1 SW_PVCCFA_EHV_FIVRA_CPU1_BOOT3 @S9S_MB_2U_LIB.S9S_MB_2U(SCH_1):SW_PVCCFA_EHV_FIVRA_CPU1_BOOT3    I40 @S9S_MB_2U_LIB.S9S_MB_2U(SCH_1):PAGE276
     2 SW_PVCCFA_EHV_FIVRA_CPU1_BOOT3_ @S9S_MB_2U_LIB.S9S_MB_2U(SCH_1):SW_PVCCFA_EHV_FIVRA_CPU1_BOOT3_R    I40 @S9S_MB_2U_LIB.S9S_MB_2U(SCH_1):PAGE276

PR1803 Q_RES_0402LF-3.3,1%,1/16W,CHIPA
     1 SW_PVCCFA_EHV_FIVRA_CPU1_BOOT4 @S9S_MB_2U_LIB.S9S_MB_2U(SCH_1):SW_PVCCFA_EHV_FIVRA_CPU1_BOOT4    I17 @S9S_MB_2U_LIB.S9S_MB_2U(SCH_1):PAGE276
     2 SW_PVCCFA_EHV_FIVRA_CPU1_BOOT4_ @S9S_MB_2U_LIB.S9S_MB_2U(SCH_1):SW_PVCCFA_EHV_FIVRA_CPU1_BOOT4_R    I17 @S9S_MB_2U_LIB.S9S_MB_2U(SCH_1):PAGE276

PR1804 Q_RES_0402LF-3.3,1%,1/16W,CHIPA
     1 SW_PVCCD_HV_CPU1_BOOT1 @S9S_MB_2U_LIB.S9S_MB_2U(SCH_1):SW_PVCCD_HV_CPU1_BOOT1    I21 @S9S_MB_2U_LIB.S9S_MB_2U(SCH_1):PAGE283
     2 SW_PVCCD_HV_CPU1_BOOT1_R @S9S_MB_2U_LIB.S9S_MB_2U(SCH_1):SW_PVCCD_HV_CPU1_BOOT1_R    I21 @S9S_MB_2U_LIB.S9S_MB_2U(SCH_1):PAGE283

PR1805 Q_RES_0402LF-0,5%,1/16W,CHIP,CA
     1 PVCCD_HV_CPU1_VOS @S9S_MB_2U_LIB.S9S_MB_2U(SCH_1):PVCCD_HV_CPU1_VOS    I12 @S9S_MB_2U_LIB.S9S_MB_2U(SCH_1):PAGE283
     2 PVCCD_HV_CPU1 @S9S_MB_2U_LIB.S9S_MB_2U(SCH_1):PVCCD_HV_CPU1    I12 @S9S_MB_2U_LIB.S9S_MB_2U(SCH_1):PAGE283

PR1850 Q_RES_0402LF-1K,1%,1/16W,EMPTYA
     1    GND @S9S_MB_2U_LIB.S9S_MB_2U(SCH_1):GND    I11 @S9S_MB_2U_LIB.S9S_MB_2U(SCH_1):PAGE249
     2 FM_PCH_P1V8_AUX_EN_R @S9S_MB_2U_LIB.S9S_MB_2U(SCH_1):FM_PCH_P1V8_AUX_EN_R    I11 @S9S_MB_2U_LIB.S9S_MB_2U(SCH_1):PAGE249

PR2106 Q_RES_0402LF-10K,1%,1/16W,CHIPA
     1 HSC_VDD @S9S_MB_2U_LIB.S9S_MB_2U(SCH_1):HSC_VDD    I43 @S9S_MB_2U_LIB.S9S_MB_2U(SCH_1):PAGE303
     2 HSC_VIN_UVW_N @S9S_MB_2U_LIB.S9S_MB_2U(SCH_1):HSC_VIN_UVW_N    I43 @S9S_MB_2U_LIB.S9S_MB_2U(SCH_1):PAGE303

PR2149 Q_RES_0402LF-0,5%,1/16W,CHIP,CA
     1 HSC_VDD_R @S9S_MB_2U_LIB.S9S_MB_2U(SCH_1):HSC_VDD_R    I24 @S9S_MB_2U_LIB.S9S_MB_2U(SCH_1):PAGE303
     2 HSC_VDD @S9S_MB_2U_LIB.S9S_MB_2U(SCH_1):HSC_VDD    I24 @S9S_MB_2U_LIB.S9S_MB_2U(SCH_1):PAGE303

PR2220 Q_RES_0402LF-60.4K,1%,1/16W,CHA
     1 PVNN_MAIN_CPU1_MODE @S9S_MB_2U_LIB.S9S_MB_2U(SCH_1):PVNN_MAIN_CPU1_MODE    I12 @S9S_MB_2U_LIB.S9S_MB_2U(SCH_1):PAGE286
     2    GND @S9S_MB_2U_LIB.S9S_MB_2U(SCH_1):GND    I12 @S9S_MB_2U_LIB.S9S_MB_2U(SCH_1):PAGE286

PR2222 Q_RES_0402LF-34.8K,1%,1/16W,CHA
     1 PVNN_MAIN_CPU1_CS @S9S_MB_2U_LIB.S9S_MB_2U(SCH_1):PVNN_MAIN_CPU1_CS    I19 @S9S_MB_2U_LIB.S9S_MB_2U(SCH_1):PAGE286
     2    GND @S9S_MB_2U_LIB.S9S_MB_2U(SCH_1):GND    I19 @S9S_MB_2U_LIB.S9S_MB_2U(SCH_1):PAGE286

PR2336 Q_RES_0402LF-26.1K,0.1%,1/16W,A
     1 PVPP_HBM_CPU0_FB @S9S_MB_2U_LIB.S9S_MB_2U(SCH_1):PVPP_HBM_CPU0_FB    I34 @S9S_MB_2U_LIB.S9S_MB_2U(SCH_1):PAGE267
     2 FM_HBM_VPP_SEL_CPU0_D @S9S_MB_2U_LIB.S9S_MB_2U(SCH_1):FM_HBM_VPP_SEL_CPU0_D    I34 @S9S_MB_2U_LIB.S9S_MB_2U(SCH_1):PAGE267

PR2381 Q_RES_0402LF-26.1K,0.1%,1/16W,A
     1 PVPP_HBM_CPU1_FB @S9S_MB_2U_LIB.S9S_MB_2U(SCH_1):PVPP_HBM_CPU1_FB    I30 @S9S_MB_2U_LIB.S9S_MB_2U(SCH_1):PAGE285
     2 FM_HBM_VPP_SEL_CPU1_D @S9S_MB_2U_LIB.S9S_MB_2U(SCH_1):FM_HBM_VPP_SEL_CPU1_D    I30 @S9S_MB_2U_LIB.S9S_MB_2U(SCH_1):PAGE285

PR2510 Q_RES_0402LF-1,1%,1/16W,EMPTY,A
     1 P12V_HSC_ADC_P @S9S_MB_2U_LIB.S9S_MB_2U(SCH_1):P12V_HSC_ADC_P    I98 @S9S_MB_2U_LIB.S9S_MB_2U(SCH_1):PAGE328
     2 P12V_HSC_SENSE2_R1_P @S9S_MB_2U_LIB.S9S_MB_2U(SCH_1):P12V_HSC_SENSE2_R1_P    I98 @S9S_MB_2U_LIB.S9S_MB_2U(SCH_1):PAGE328

PR2511 Q_RES_0402LF-1,1%,1/16W,EMPTY,A
     1 P12V_HSC_ADC_P @S9S_MB_2U_LIB.S9S_MB_2U(SCH_1):P12V_HSC_ADC_P    I99 @S9S_MB_2U_LIB.S9S_MB_2U(SCH_1):PAGE328
     2 P12V_HSC_SENSE2_R2_P @S9S_MB_2U_LIB.S9S_MB_2U(SCH_1):P12V_HSC_SENSE2_R2_P    I99 @S9S_MB_2U_LIB.S9S_MB_2U(SCH_1):PAGE328

PR2512 Q_RES_0402LF-1,1%,1/16W,EMPTY,A
     1 P12V_HSC_ADC_P @S9S_MB_2U_LIB.S9S_MB_2U(SCH_1):P12V_HSC_ADC_P    I96 @S9S_MB_2U_LIB.S9S_MB_2U(SCH_1):PAGE328
     2 P12V_HSC_SENSE2_R3_P @S9S_MB_2U_LIB.S9S_MB_2U(SCH_1):P12V_HSC_SENSE2_R3_P    I96 @S9S_MB_2U_LIB.S9S_MB_2U(SCH_1):PAGE328

PR2513 Q_RES_0402LF-1,1%,1/16W,EMPTY,A
     1 P12V_HSC_ADC_P @S9S_MB_2U_LIB.S9S_MB_2U(SCH_1):P12V_HSC_ADC_P    I95 @S9S_MB_2U_LIB.S9S_MB_2U(SCH_1):PAGE328
     2 P12V_HSC_SENSE2_R4_P @S9S_MB_2U_LIB.S9S_MB_2U(SCH_1):P12V_HSC_SENSE2_R4_P    I95 @S9S_MB_2U_LIB.S9S_MB_2U(SCH_1):PAGE328

PR2514 Q_RES_0402LF-10,1%,1/16W,EMPTYA
     1 P12V_HSC_ADC_P @S9S_MB_2U_LIB.S9S_MB_2U(SCH_1):P12V_HSC_ADC_P    I97 @S9S_MB_2U_LIB.S9S_MB_2U(SCH_1):PAGE328
     2 P12V_HSC_SENSE1_P @S9S_MB_2U_LIB.S9S_MB_2U(SCH_1):P12V_HSC_SENSE1_P    I97 @S9S_MB_2U_LIB.S9S_MB_2U(SCH_1):PAGE328

PR2515 Q_RES_0402LF-10,1%,1/16W,EMPTYA
     1 P12V_HSC_ADC_N @S9S_MB_2U_LIB.S9S_MB_2U(SCH_1):P12V_HSC_ADC_N    I93 @S9S_MB_2U_LIB.S9S_MB_2U(SCH_1):PAGE328
     2 P12V_HSC_SENSE2_R1_N @S9S_MB_2U_LIB.S9S_MB_2U(SCH_1):P12V_HSC_SENSE2_R1_N    I93 @S9S_MB_2U_LIB.S9S_MB_2U(SCH_1):PAGE328

PR2516 Q_RES_0402LF-10,1%,1/16W,EMPTYA
     1 P12V_HSC_ADC_N @S9S_MB_2U_LIB.S9S_MB_2U(SCH_1):P12V_HSC_ADC_N    I94 @S9S_MB_2U_LIB.S9S_MB_2U(SCH_1):PAGE328
     2 P12V_HSC_SENSE2_R2_N @S9S_MB_2U_LIB.S9S_MB_2U(SCH_1):P12V_HSC_SENSE2_R2_N    I94 @S9S_MB_2U_LIB.S9S_MB_2U(SCH_1):PAGE328

PR2517 Q_RES_0402LF-10,1%,1/16W,EMPTYA
     1 P12V_HSC_ADC_N @S9S_MB_2U_LIB.S9S_MB_2U(SCH_1):P12V_HSC_ADC_N    I90 @S9S_MB_2U_LIB.S9S_MB_2U(SCH_1):PAGE328
     2 P12V_HSC_SENSE2_R3_N @S9S_MB_2U_LIB.S9S_MB_2U(SCH_1):P12V_HSC_SENSE2_R3_N    I90 @S9S_MB_2U_LIB.S9S_MB_2U(SCH_1):PAGE328

PR2518 Q_RES_0402LF-10,1%,1/16W,EMPTYA
     1 P12V_HSC_ADC_N @S9S_MB_2U_LIB.S9S_MB_2U(SCH_1):P12V_HSC_ADC_N    I91 @S9S_MB_2U_LIB.S9S_MB_2U(SCH_1):PAGE328
     2 P12V_HSC_SENSE2_R4_N @S9S_MB_2U_LIB.S9S_MB_2U(SCH_1):P12V_HSC_SENSE2_R4_N    I91 @S9S_MB_2U_LIB.S9S_MB_2U(SCH_1):PAGE328

PR2519 Q_RES_0402LF-100,1%,1/16W,EMPTA
     1 P12V_HSC_ADC_N @S9S_MB_2U_LIB.S9S_MB_2U(SCH_1):P12V_HSC_ADC_N    I92 @S9S_MB_2U_LIB.S9S_MB_2U(SCH_1):PAGE328
     2 P12V_HSC_SENSE1_N @S9S_MB_2U_LIB.S9S_MB_2U(SCH_1):P12V_HSC_SENSE1_N    I92 @S9S_MB_2U_LIB.S9S_MB_2U(SCH_1):PAGE328

PR2520 Q_RES_0402LF-1,1%,1/16W,EMPTY,A
     1 P12V_HSC_SENSE2_P @S9S_MB_2U_LIB.S9S_MB_2U(SCH_1):P12V_HSC_SENSE2_P    I89 @S9S_MB_2U_LIB.S9S_MB_2U(SCH_1):PAGE328
     2 P12V_HSC_SENSE2_R1_P @S9S_MB_2U_LIB.S9S_MB_2U(SCH_1):P12V_HSC_SENSE2_R1_P    I89 @S9S_MB_2U_LIB.S9S_MB_2U(SCH_1):PAGE328

PR2521 Q_RES_0402LF-1,1%,1/16W,EMPTY,A
     1 P12V_HSC_SENSE2_P @S9S_MB_2U_LIB.S9S_MB_2U(SCH_1):P12V_HSC_SENSE2_P    I88 @S9S_MB_2U_LIB.S9S_MB_2U(SCH_1):PAGE328
     2 P12V_HSC_SENSE2_R2_P @S9S_MB_2U_LIB.S9S_MB_2U(SCH_1):P12V_HSC_SENSE2_R2_P    I88 @S9S_MB_2U_LIB.S9S_MB_2U(SCH_1):PAGE328

PR2522 Q_RES_0402LF-1,1%,1/16W,EMPTY,A
     1 P12V_HSC_SENSE2_P @S9S_MB_2U_LIB.S9S_MB_2U(SCH_1):P12V_HSC_SENSE2_P    I86 @S9S_MB_2U_LIB.S9S_MB_2U(SCH_1):PAGE328
     2 P12V_HSC_SENSE2_R3_P @S9S_MB_2U_LIB.S9S_MB_2U(SCH_1):P12V_HSC_SENSE2_R3_P    I86 @S9S_MB_2U_LIB.S9S_MB_2U(SCH_1):PAGE328

PR2523 Q_RES_0402LF-1,1%,1/16W,EMPTY,A
     1 P12V_HSC_SENSE2_P @S9S_MB_2U_LIB.S9S_MB_2U(SCH_1):P12V_HSC_SENSE2_P    I87 @S9S_MB_2U_LIB.S9S_MB_2U(SCH_1):PAGE328
     2 P12V_HSC_SENSE2_R4_P @S9S_MB_2U_LIB.S9S_MB_2U(SCH_1):P12V_HSC_SENSE2_R4_P    I87 @S9S_MB_2U_LIB.S9S_MB_2U(SCH_1):PAGE328

PR2524 Q_RES_0402LF-10,1%,1/16W,EMPTYA
     1 P12V_HSC_SENSE2_N @S9S_MB_2U_LIB.S9S_MB_2U(SCH_1):P12V_HSC_SENSE2_N   I119 @S9S_MB_2U_LIB.S9S_MB_2U(SCH_1):PAGE328
     2 P12V_HSC_SENSE2_R1_N @S9S_MB_2U_LIB.S9S_MB_2U(SCH_1):P12V_HSC_SENSE2_R1_N   I119 @S9S_MB_2U_LIB.S9S_MB_2U(SCH_1):PAGE328

PR2525 Q_RES_0402LF-10,1%,1/16W,EMPTYA
     1 P12V_HSC_SENSE2_N @S9S_MB_2U_LIB.S9S_MB_2U(SCH_1):P12V_HSC_SENSE2_N   I120 @S9S_MB_2U_LIB.S9S_MB_2U(SCH_1):PAGE328
     2 P12V_HSC_SENSE2_R2_N @S9S_MB_2U_LIB.S9S_MB_2U(SCH_1):P12V_HSC_SENSE2_R2_N   I120 @S9S_MB_2U_LIB.S9S_MB_2U(SCH_1):PAGE328

PR2526 Q_RES_0402LF-10,1%,1/16W,EMPTYA
     1 P12V_HSC_SENSE2_N @S9S_MB_2U_LIB.S9S_MB_2U(SCH_1):P12V_HSC_SENSE2_N   I118 @S9S_MB_2U_LIB.S9S_MB_2U(SCH_1):PAGE328
     2 P12V_HSC_SENSE2_R3_N @S9S_MB_2U_LIB.S9S_MB_2U(SCH_1):P12V_HSC_SENSE2_R3_N   I118 @S9S_MB_2U_LIB.S9S_MB_2U(SCH_1):PAGE328

PR2527 Q_RES_0402LF-10,1%,1/16W,EMPTYA
     1 P12V_HSC_SENSE2_N @S9S_MB_2U_LIB.S9S_MB_2U(SCH_1):P12V_HSC_SENSE2_N   I117 @S9S_MB_2U_LIB.S9S_MB_2U(SCH_1):PAGE328
     2 P12V_HSC_SENSE2_R4_N @S9S_MB_2U_LIB.S9S_MB_2U(SCH_1):P12V_HSC_SENSE2_R4_N   I117 @S9S_MB_2U_LIB.S9S_MB_2U(SCH_1):PAGE328

PR2528 Q_RES_0402LF-10,1%,1/16W,EMPTYA
     1 P12V_HSC_GATE_G1 @S9S_MB_2U_LIB.S9S_MB_2U(SCH_1):P12V_HSC_GATE_G1    I16 @S9S_MB_2U_LIB.S9S_MB_2U(SCH_1):PAGE328
     2 P12V_HSC_GATE2 @S9S_MB_2U_LIB.S9S_MB_2U(SCH_1):P12V_HSC_GATE2    I16 @S9S_MB_2U_LIB.S9S_MB_2U(SCH_1):PAGE328

PR2529 Q_RES_0402LF-10,1%,1/16W,EMPTYA
     1 P12V_HSC_GATE_G2 @S9S_MB_2U_LIB.S9S_MB_2U(SCH_1):P12V_HSC_GATE_G2    I38 @S9S_MB_2U_LIB.S9S_MB_2U(SCH_1):PAGE328
     2 P12V_HSC_GATE2 @S9S_MB_2U_LIB.S9S_MB_2U(SCH_1):P12V_HSC_GATE2    I38 @S9S_MB_2U_LIB.S9S_MB_2U(SCH_1):PAGE328

PR2530 Q_RES_0402LF-10,1%,1/16W,EMPTYA
     1 P12V_HSC_GATE_G3 @S9S_MB_2U_LIB.S9S_MB_2U(SCH_1):P12V_HSC_GATE_G3    I39 @S9S_MB_2U_LIB.S9S_MB_2U(SCH_1):PAGE328
     2 P12V_HSC_GATE2 @S9S_MB_2U_LIB.S9S_MB_2U(SCH_1):P12V_HSC_GATE2    I39 @S9S_MB_2U_LIB.S9S_MB_2U(SCH_1):PAGE328

PR2531 Q_RES_0402LF-10,1%,1/16W,EMPTYA
     1 P12V_HSC_GATE_G4 @S9S_MB_2U_LIB.S9S_MB_2U(SCH_1):P12V_HSC_GATE_G4    I59 @S9S_MB_2U_LIB.S9S_MB_2U(SCH_1):PAGE328
     2 P12V_HSC_GATE2 @S9S_MB_2U_LIB.S9S_MB_2U(SCH_1):P12V_HSC_GATE2    I59 @S9S_MB_2U_LIB.S9S_MB_2U(SCH_1):PAGE328

PR2532 Q_SP_RES4P-0.0003,1%,4W,SMLF,EA
    2B P12V_HSC_SENSE2_R2_N @S9S_MB_2U_LIB.S9S_MB_2U(SCH_1):P12V_HSC_SENSE2_R2_N    I78 @S9S_MB_2U_LIB.S9S_MB_2U(SCH_1):PAGE328
    1B P12V_HSC_SENSE2_R2_P @S9S_MB_2U_LIB.S9S_MB_2U(SCH_1):P12V_HSC_SENSE2_R2_P    I78 @S9S_MB_2U_LIB.S9S_MB_2U(SCH_1):PAGE328
    2A P12V_MAIN_R @S9S_MB_2U_LIB.S9S_MB_2U(SCH_1):P12V_MAIN_R    I78 @S9S_MB_2U_LIB.S9S_MB_2U(SCH_1):PAGE328
    1A P12V_PSU @S9S_MB_2U_LIB.S9S_MB_2U(SCH_1):P12V_PSU    I78 @S9S_MB_2U_LIB.S9S_MB_2U(SCH_1):PAGE328

PR2533 Q_SP_RES4P-0.0003,1%,4W,SMLF,EA
    2B P12V_HSC_SENSE2_R3_N @S9S_MB_2U_LIB.S9S_MB_2U(SCH_1):P12V_HSC_SENSE2_R3_N    I64 @S9S_MB_2U_LIB.S9S_MB_2U(SCH_1):PAGE328
    1B P12V_HSC_SENSE2_R3_P @S9S_MB_2U_LIB.S9S_MB_2U(SCH_1):P12V_HSC_SENSE2_R3_P    I64 @S9S_MB_2U_LIB.S9S_MB_2U(SCH_1):PAGE328
    2A P12V_MAIN_R @S9S_MB_2U_LIB.S9S_MB_2U(SCH_1):P12V_MAIN_R    I64 @S9S_MB_2U_LIB.S9S_MB_2U(SCH_1):PAGE328
    1A P12V_PSU @S9S_MB_2U_LIB.S9S_MB_2U(SCH_1):P12V_PSU    I64 @S9S_MB_2U_LIB.S9S_MB_2U(SCH_1):PAGE328

PR2534 Q_SP_RES4P-0.0003,1%,4W,SMLF,EA
    2B P12V_HSC_SENSE2_R4_N @S9S_MB_2U_LIB.S9S_MB_2U(SCH_1):P12V_HSC_SENSE2_R4_N    I63 @S9S_MB_2U_LIB.S9S_MB_2U(SCH_1):PAGE328
    1B P12V_HSC_SENSE2_R4_P @S9S_MB_2U_LIB.S9S_MB_2U(SCH_1):P12V_HSC_SENSE2_R4_P    I63 @S9S_MB_2U_LIB.S9S_MB_2U(SCH_1):PAGE328
    2A P12V_MAIN_R @S9S_MB_2U_LIB.S9S_MB_2U(SCH_1):P12V_MAIN_R    I63 @S9S_MB_2U_LIB.S9S_MB_2U(SCH_1):PAGE328
    1A P12V_PSU @S9S_MB_2U_LIB.S9S_MB_2U(SCH_1):P12V_PSU    I63 @S9S_MB_2U_LIB.S9S_MB_2U(SCH_1):PAGE328

PR2535 Q_RES_0402LF-10,1%,1/16W,EMPTYA
     1 P12V_HSC_GATE_G5 @S9S_MB_2U_LIB.S9S_MB_2U(SCH_1):P12V_HSC_GATE_G5    I60 @S9S_MB_2U_LIB.S9S_MB_2U(SCH_1):PAGE328
     2 P12V_HSC_GATE2 @S9S_MB_2U_LIB.S9S_MB_2U(SCH_1):P12V_HSC_GATE2    I60 @S9S_MB_2U_LIB.S9S_MB_2U(SCH_1):PAGE328

PR2536 Q_RES_0402LF-10,1%,1/16W,EMPTYA
     1 P12V_HSC_GATE_G6 @S9S_MB_2U_LIB.S9S_MB_2U(SCH_1):P12V_HSC_GATE_G6    I61 @S9S_MB_2U_LIB.S9S_MB_2U(SCH_1):PAGE328
     2 P12V_HSC_GATE2 @S9S_MB_2U_LIB.S9S_MB_2U(SCH_1):P12V_HSC_GATE2    I61 @S9S_MB_2U_LIB.S9S_MB_2U(SCH_1):PAGE328

PR2537 Q_RES_0402LF-10,1%,1/16W,EMPTYA
     1 P12V_AUX @S9S_MB_2U_LIB.S9S_MB_2U(SCH_1):P12V_AUX    I70 @S9S_MB_2U_LIB.S9S_MB_2U(SCH_1):PAGE328
     2 P12V_HSC_GATE_RC @S9S_MB_2U_LIB.S9S_MB_2U(SCH_1):P12V_HSC_GATE_RC    I70 @S9S_MB_2U_LIB.S9S_MB_2U(SCH_1):PAGE328

PR2538 Q_RES_0402LF-10,1%,1/16W,EMPTYA
     1 MB0_CM_GATE_G0 @S9S_MB_2U_LIB.S9S_MB_2U(SCH_1):MB0_CM_GATE_G0    I76 @S9S_MB_2U_LIB.S9S_MB_2U(SCH_1):PAGE328
     2 P12V_HSC_GATE1 @S9S_MB_2U_LIB.S9S_MB_2U(SCH_1):P12V_HSC_GATE1    I76 @S9S_MB_2U_LIB.S9S_MB_2U(SCH_1):PAGE328

PR2554 Q_RES_2512LF-0.03,0.1%,1W,EMPTA
     1 P12V_AUX @S9S_MB_2U_LIB.S9S_MB_2U(SCH_1):P12V_AUX    I81 @S9S_MB_2U_LIB.S9S_MB_2U(SCH_1):PAGE253
     2 SW_P12V_PVCCIN_CPU0_FLT @S9S_MB_2U_LIB.S9S_MB_2U(SCH_1):SW_P12V_PVCCIN_CPU0_FLT    I81 @S9S_MB_2U_LIB.S9S_MB_2U(SCH_1):PAGE253

PR2556 Q_RES_2512LF-0.03,0.1%,1W,EMPTA
     1 P12V_AUX @S9S_MB_2U_LIB.S9S_MB_2U(SCH_1):P12V_AUX    I82 @S9S_MB_2U_LIB.S9S_MB_2U(SCH_1):PAGE271
     2 SW_P12V_PVCCIN_CPU1_FLT @S9S_MB_2U_LIB.S9S_MB_2U(SCH_1):SW_P12V_PVCCIN_CPU1_FLT    I82 @S9S_MB_2U_LIB.S9S_MB_2U(SCH_1):PAGE271

PR2718 Q_RES_0402LF-8.87K,1%,1/16W,EMA
     1 PVCCD_HV_CPU0_LSET1 @S9S_MB_2U_LIB.S9S_MB_2U(SCH_1):PVCCD_HV_CPU0_LSET1     I3 @S9S_MB_2U_LIB.S9S_MB_2U(SCH_1):PAGE265
     2    GND @S9S_MB_2U_LIB.S9S_MB_2U(SCH_1):GND     I3 @S9S_MB_2U_LIB.S9S_MB_2U(SCH_1):PAGE265

PR3002 Q_RES_0402LF-0,5%,1/16W,CHIP,CA
     1    GND @S9S_MB_2U_LIB.S9S_MB_2U(SCH_1):GND    I54 @S9S_MB_2U_LIB.S9S_MB_2U(SCH_1):PAGE303
     2 AGND_HSC @S9S_MB_2U_LIB.S9S_MB_2U(SCH_1):AGND_HSC    I54 @S9S_MB_2U_LIB.S9S_MB_2U(SCH_1):PAGE303

PR3335 Q_RES_0402LF-30.1K,1%,1/16W,CHA
     1 PVPP_HBM_CPU0_MODE @S9S_MB_2U_LIB.S9S_MB_2U(SCH_1):PVPP_HBM_CPU0_MODE    I18 @S9S_MB_2U_LIB.S9S_MB_2U(SCH_1):PAGE267
     2    GND @S9S_MB_2U_LIB.S9S_MB_2U(SCH_1):GND    I18 @S9S_MB_2U_LIB.S9S_MB_2U(SCH_1):PAGE267

PR3336 Q_RES_0402LF-30.1K,1%,1/16W,CHA
     1 PVPP_HBM_CPU1_MODE @S9S_MB_2U_LIB.S9S_MB_2U(SCH_1):PVPP_HBM_CPU1_MODE    I18 @S9S_MB_2U_LIB.S9S_MB_2U(SCH_1):PAGE285
     2    GND @S9S_MB_2U_LIB.S9S_MB_2U(SCH_1):GND    I18 @S9S_MB_2U_LIB.S9S_MB_2U(SCH_1):PAGE285

PR3337 Q_RES_0402LF-0,5%,1/16W,CHIP,CA
     1 P5V_AUX_MODE @S9S_MB_2U_LIB.S9S_MB_2U(SCH_1):P5V_AUX_MODE    I10 @S9S_MB_2U_LIB.S9S_MB_2U(SCH_1):PAGE244
     2    GND @S9S_MB_2U_LIB.S9S_MB_2U(SCH_1):GND    I10 @S9S_MB_2U_LIB.S9S_MB_2U(SCH_1):PAGE244

PR3338 Q_RES_0402LF-0,5%,1/16W,CHIP,CA
     1 P3V3_AUX @S9S_MB_2U_LIB.S9S_MB_2U(SCH_1):P3V3_AUX    I13 @S9S_MB_2U_LIB.S9S_MB_2U(SCH_1):PAGE286
     2 PVNN_MAIN_CPU1_VCC @S9S_MB_2U_LIB.S9S_MB_2U(SCH_1):PVNN_MAIN_CPU1_VCC    I13 @S9S_MB_2U_LIB.S9S_MB_2U(SCH_1):PAGE286

PR3339 Q_RES_0402LF-0,5%,1/16W,CHIP,CA
     1 P3V3_AUX @S9S_MB_2U_LIB.S9S_MB_2U(SCH_1):P3V3_AUX    I10 @S9S_MB_2U_LIB.S9S_MB_2U(SCH_1):PAGE268
     2 PVNN_MAIN_CPU0_VCC @S9S_MB_2U_LIB.S9S_MB_2U(SCH_1):PVNN_MAIN_CPU0_VCC    I10 @S9S_MB_2U_LIB.S9S_MB_2U(SCH_1):PAGE268

PR3780 Q_RES_0402LF-5.36K,1%,1/16W,CHA
     1 P3V3_OCP_CB_1 @S9S_MB_2U_LIB.S9S_MB_2U(SCH_1):P3V3_OCP_CB_1    I60 @S9S_MB_2U_LIB.S9S_MB_2U(SCH_1):PAGE153
     2    GND @S9S_MB_2U_LIB.S9S_MB_2U(SCH_1):GND    I60 @S9S_MB_2U_LIB.S9S_MB_2U(SCH_1):PAGE153

PR3781 Q_RES_0402LF-845,1%,1/16W,EMPTA
     1 P12V_OCP_SENSE_1 @S9S_MB_2U_LIB.S9S_MB_2U(SCH_1):P12V_OCP_SENSE_1    I80 @S9S_MB_2U_LIB.S9S_MB_2U(SCH_1):PAGE153
     2    GND @S9S_MB_2U_LIB.S9S_MB_2U(SCH_1):GND    I80 @S9S_MB_2U_LIB.S9S_MB_2U(SCH_1):PAGE153

PR3782 Q_RES_0402LF-10,1%,1/16W,CHIP,A
     1 P3V3_AUX @S9S_MB_2U_LIB.S9S_MB_2U(SCH_1):P3V3_AUX    I92 @S9S_MB_2U_LIB.S9S_MB_2U(SCH_1):PAGE131
     2 P3V3_OCP_VCC_2 @S9S_MB_2U_LIB.S9S_MB_2U(SCH_1):P3V3_OCP_VCC_2    I92 @S9S_MB_2U_LIB.S9S_MB_2U(SCH_1):PAGE131

PR3786 Q_RES_0402LF-160K,1%,1/16W,EMPA
     1 P12V_AUX @S9S_MB_2U_LIB.S9S_MB_2U(SCH_1):P12V_AUX    I42 @S9S_MB_2U_LIB.S9S_MB_2U(SCH_1):PAGE153
     2 P12V_OCP_UV_1 @S9S_MB_2U_LIB.S9S_MB_2U(SCH_1):P12V_OCP_UV_1    I42 @S9S_MB_2U_LIB.S9S_MB_2U(SCH_1):PAGE153

PR3787 Q_RES_0402LF-6.8K,1%,1/16W,EMPA
     1 P12V_OCP_UV_1 @S9S_MB_2U_LIB.S9S_MB_2U(SCH_1):P12V_OCP_UV_1    I41 @S9S_MB_2U_LIB.S9S_MB_2U(SCH_1):PAGE153
     2 P12V_OCP_OV_1 @S9S_MB_2U_LIB.S9S_MB_2U(SCH_1):P12V_OCP_OV_1    I41 @S9S_MB_2U_LIB.S9S_MB_2U(SCH_1):PAGE153

PR3788 Q_RES_0402LF-15K,1%,1/16W,EMPTA
     1 P12V_OCP_OV_1 @S9S_MB_2U_LIB.S9S_MB_2U(SCH_1):P12V_OCP_OV_1    I33 @S9S_MB_2U_LIB.S9S_MB_2U(SCH_1):PAGE153
     2    GND @S9S_MB_2U_LIB.S9S_MB_2U(SCH_1):GND    I33 @S9S_MB_2U_LIB.S9S_MB_2U(SCH_1):PAGE153

PR3789 Q_RES_0402LF-25.5K,1%,1/16W,CHA
     1 P3V3_AUX @S9S_MB_2U_LIB.S9S_MB_2U(SCH_1):P3V3_AUX    I70 @S9S_MB_2U_LIB.S9S_MB_2U(SCH_1):PAGE153
     2 P3V3_OCP_UV_1 @S9S_MB_2U_LIB.S9S_MB_2U(SCH_1):P3V3_OCP_UV_1    I70 @S9S_MB_2U_LIB.S9S_MB_2U(SCH_1):PAGE153

PR3790 Q_RES_0402LF-7.15K,1%,1/16W,CHA
     1 P3V3_OCP_UV_1 @S9S_MB_2U_LIB.S9S_MB_2U(SCH_1):P3V3_OCP_UV_1    I68 @S9S_MB_2U_LIB.S9S_MB_2U(SCH_1):PAGE153
     2 P3V3_OCP_OV_1 @S9S_MB_2U_LIB.S9S_MB_2U(SCH_1):P3V3_OCP_OV_1    I68 @S9S_MB_2U_LIB.S9S_MB_2U(SCH_1):PAGE153

PR3791 Q_RES_0402LF-15K,1%,1/16W,CHIPA
     1 P3V3_OCP_OV_1 @S9S_MB_2U_LIB.S9S_MB_2U(SCH_1):P3V3_OCP_OV_1    I58 @S9S_MB_2U_LIB.S9S_MB_2U(SCH_1):PAGE153
     2    GND @S9S_MB_2U_LIB.S9S_MB_2U(SCH_1):GND    I58 @S9S_MB_2U_LIB.S9S_MB_2U(SCH_1):PAGE153

PR3792 Q_RES_0402LF-10,1%,1/16W,EMPTYA
     1 P12V_AUX @S9S_MB_2U_LIB.S9S_MB_2U(SCH_1):P12V_AUX    I56 @S9S_MB_2U_LIB.S9S_MB_2U(SCH_1):PAGE153
     2 P12V_OCP_VCC_1 @S9S_MB_2U_LIB.S9S_MB_2U(SCH_1):P12V_OCP_VCC_1    I56 @S9S_MB_2U_LIB.S9S_MB_2U(SCH_1):PAGE153

PR3795 Q_RES_0402LF-25.5K,1%,1/16W,CHA
     1 P3V3_AUX @S9S_MB_2U_LIB.S9S_MB_2U(SCH_1):P3V3_AUX    I53 @S9S_MB_2U_LIB.S9S_MB_2U(SCH_1):PAGE131
     2 P3V3_OCP_UV_2 @S9S_MB_2U_LIB.S9S_MB_2U(SCH_1):P3V3_OCP_UV_2    I53 @S9S_MB_2U_LIB.S9S_MB_2U(SCH_1):PAGE131

PR3798 Q_RES_0402LF-10,1%,1/16W,CHIP,A
     1 P3V3_AUX @S9S_MB_2U_LIB.S9S_MB_2U(SCH_1):P3V3_AUX    I73 @S9S_MB_2U_LIB.S9S_MB_2U(SCH_1):PAGE153
     2 P3V3_OCP_VCC_1 @S9S_MB_2U_LIB.S9S_MB_2U(SCH_1):P3V3_OCP_VCC_1    I73 @S9S_MB_2U_LIB.S9S_MB_2U(SCH_1):PAGE153

PR3805 Q_RES_0402LF-160K,1%,1/16W,EMPA
     1 P12V_AUX @S9S_MB_2U_LIB.S9S_MB_2U(SCH_1):P12V_AUX    I33 @S9S_MB_2U_LIB.S9S_MB_2U(SCH_1):PAGE131
     2 P12V_OCP_UV_2 @S9S_MB_2U_LIB.S9S_MB_2U(SCH_1):P12V_OCP_UV_2    I33 @S9S_MB_2U_LIB.S9S_MB_2U(SCH_1):PAGE131

PR3806 Q_RES_0402LF-6.8K,1%,1/16W,EMPA
     1 P12V_OCP_UV_2 @S9S_MB_2U_LIB.S9S_MB_2U(SCH_1):P12V_OCP_UV_2    I32 @S9S_MB_2U_LIB.S9S_MB_2U(SCH_1):PAGE131
     2 P12V_OCP_OV_2 @S9S_MB_2U_LIB.S9S_MB_2U(SCH_1):P12V_OCP_OV_2    I32 @S9S_MB_2U_LIB.S9S_MB_2U(SCH_1):PAGE131

PR3812 Q_RES_0402LF-15K,1%,1/16W,CHIPA
     1 P3V3_OCP_OV_2 @S9S_MB_2U_LIB.S9S_MB_2U(SCH_1):P3V3_OCP_OV_2    I48 @S9S_MB_2U_LIB.S9S_MB_2U(SCH_1):PAGE131
     2    GND @S9S_MB_2U_LIB.S9S_MB_2U(SCH_1):GND    I48 @S9S_MB_2U_LIB.S9S_MB_2U(SCH_1):PAGE131

PR3821 Q_RES_0402LF-30.1K,1%,1/16W,EMA
     1 P12V_OCP_CB_2 @S9S_MB_2U_LIB.S9S_MB_2U(SCH_1):P12V_OCP_CB_2    I59 @S9S_MB_2U_LIB.S9S_MB_2U(SCH_1):PAGE131
     2    GND @S9S_MB_2U_LIB.S9S_MB_2U(SCH_1):GND    I59 @S9S_MB_2U_LIB.S9S_MB_2U(SCH_1):PAGE131

PR3822 Q_RES_0402LF-5.36K,1%,1/16W,CHA
     1 P3V3_OCP_CB_2 @S9S_MB_2U_LIB.S9S_MB_2U(SCH_1):P3V3_OCP_CB_2    I89 @S9S_MB_2U_LIB.S9S_MB_2U(SCH_1):PAGE131
     2    GND @S9S_MB_2U_LIB.S9S_MB_2U(SCH_1):GND    I89 @S9S_MB_2U_LIB.S9S_MB_2U(SCH_1):PAGE131

PR3823 Q_RES_0402LF-845,1%,1/16W,EMPTA
     1 P12V_OCP_SENSE_2 @S9S_MB_2U_LIB.S9S_MB_2U(SCH_1):P12V_OCP_SENSE_2    I72 @S9S_MB_2U_LIB.S9S_MB_2U(SCH_1):PAGE131
     2    GND @S9S_MB_2U_LIB.S9S_MB_2U(SCH_1):GND    I72 @S9S_MB_2U_LIB.S9S_MB_2U(SCH_1):PAGE131

PR3824 Q_RES_0402LF-4.53K,1%,1/16W,CHA
     1 P3V3_OCP_SENSE_2 @S9S_MB_2U_LIB.S9S_MB_2U(SCH_1):P3V3_OCP_SENSE_2    I95 @S9S_MB_2U_LIB.S9S_MB_2U(SCH_1):PAGE131
     2    GND @S9S_MB_2U_LIB.S9S_MB_2U(SCH_1):GND    I95 @S9S_MB_2U_LIB.S9S_MB_2U(SCH_1):PAGE131

PR3828 Q_RES_0402LF-15K,1%,1/16W,EMPTA
     1 P12V_OCP_OV_2 @S9S_MB_2U_LIB.S9S_MB_2U(SCH_1):P12V_OCP_OV_2    I29 @S9S_MB_2U_LIB.S9S_MB_2U(SCH_1):PAGE131
     2    GND @S9S_MB_2U_LIB.S9S_MB_2U(SCH_1):GND    I29 @S9S_MB_2U_LIB.S9S_MB_2U(SCH_1):PAGE131

PR3829 Q_RES_0402LF-7.15K,1%,1/16W,CHA
     1 P3V3_OCP_UV_2 @S9S_MB_2U_LIB.S9S_MB_2U(SCH_1):P3V3_OCP_UV_2    I50 @S9S_MB_2U_LIB.S9S_MB_2U(SCH_1):PAGE131
     2 P3V3_OCP_OV_2 @S9S_MB_2U_LIB.S9S_MB_2U(SCH_1):P3V3_OCP_OV_2    I50 @S9S_MB_2U_LIB.S9S_MB_2U(SCH_1):PAGE131

PR3830 Q_RES_0402LF-10,1%,1/16W,EMPTYA
     1 P12V_AUX @S9S_MB_2U_LIB.S9S_MB_2U(SCH_1):P12V_AUX    I85 @S9S_MB_2U_LIB.S9S_MB_2U(SCH_1):PAGE131
     2 P12V_OCP_VCC_2 @S9S_MB_2U_LIB.S9S_MB_2U(SCH_1):P12V_OCP_VCC_2    I85 @S9S_MB_2U_LIB.S9S_MB_2U(SCH_1):PAGE131

PR3835 Q_RES_0402LF-14.3K,1%,1/16W,CHA
     1 P12V_OCP_ISET_1 @S9S_MB_2U_LIB.S9S_MB_2U(SCH_1):P12V_OCP_ISET_1    I62 @S9S_MB_2U_LIB.S9S_MB_2U(SCH_1):PAGE236
     2    GND @S9S_MB_2U_LIB.S9S_MB_2U(SCH_1):GND    I62 @S9S_MB_2U_LIB.S9S_MB_2U(SCH_1):PAGE236

PR3837 Q_RES_0402LF-17.4K,1%,1/16W,CHA
     1 P12V_OCP_IMON_1 @S9S_MB_2U_LIB.S9S_MB_2U(SCH_1):P12V_OCP_IMON_1    I72 @S9S_MB_2U_LIB.S9S_MB_2U(SCH_1):PAGE236
     2    GND @S9S_MB_2U_LIB.S9S_MB_2U(SCH_1):GND    I72 @S9S_MB_2U_LIB.S9S_MB_2U(SCH_1):PAGE236

PR3838 Q_RES_0402LF-100,1%,1/16W,EMPTA
     1 P12V_OCP_SFF @S9S_MB_2U_LIB.S9S_MB_2U(SCH_1):P12V_OCP_SFF    I77 @S9S_MB_2U_LIB.S9S_MB_2U(SCH_1):PAGE236
     2 P12V_OCP_AVIN_PD_1 @S9S_MB_2U_LIB.S9S_MB_2U(SCH_1):P12V_OCP_AVIN_PD_1    I77 @S9S_MB_2U_LIB.S9S_MB_2U(SCH_1):PAGE236

PR3839 Q_RES_0402LF-10K,1%,1/16W,CHIPA
     1 P12V_OCP_FLTB_1 @S9S_MB_2U_LIB.S9S_MB_2U(SCH_1):P12V_OCP_FLTB_1    I75 @S9S_MB_2U_LIB.S9S_MB_2U(SCH_1):PAGE236
     2 P3V3_AUX @S9S_MB_2U_LIB.S9S_MB_2U(SCH_1):P3V3_AUX    I75 @S9S_MB_2U_LIB.S9S_MB_2U(SCH_1):PAGE236

PR3840 Q_RES_0402LF-71.5K,1%,1/16W,EMA
     1 P12V_OCP_SFF @S9S_MB_2U_LIB.S9S_MB_2U(SCH_1):P12V_OCP_SFF    I85 @S9S_MB_2U_LIB.S9S_MB_2U(SCH_1):PAGE236
     2 P12V_OCP_OV_FB_1 @S9S_MB_2U_LIB.S9S_MB_2U(SCH_1):P12V_OCP_OV_FB_1    I85 @S9S_MB_2U_LIB.S9S_MB_2U(SCH_1):PAGE236

PR3841 Q_RES_0402LF-120K,1%,1/16W,CHIA
     1 P12V_AUX @S9S_MB_2U_LIB.S9S_MB_2U(SCH_1):P12V_AUX    I86 @S9S_MB_2U_LIB.S9S_MB_2U(SCH_1):PAGE236
     2 P12V_OCP_OV_FB_1 @S9S_MB_2U_LIB.S9S_MB_2U(SCH_1):P12V_OCP_OV_FB_1    I86 @S9S_MB_2U_LIB.S9S_MB_2U(SCH_1):PAGE236

PR3842 Q_RES_0402LF-10K,1%,1/16W,CHIPA
     1 P12V_OCP_OV_FB_1 @S9S_MB_2U_LIB.S9S_MB_2U(SCH_1):P12V_OCP_OV_FB_1    I83 @S9S_MB_2U_LIB.S9S_MB_2U(SCH_1):PAGE236
     2    GND @S9S_MB_2U_LIB.S9S_MB_2U(SCH_1):GND    I83 @S9S_MB_2U_LIB.S9S_MB_2U(SCH_1):PAGE236

PR3843 Q_RES_0603LF-49.9,1%,1/10W,CHIA
     1 P12V_AUX @S9S_MB_2U_LIB.S9S_MB_2U(SCH_1):P12V_AUX    I89 @S9S_MB_2U_LIB.S9S_MB_2U(SCH_1):PAGE236
     2 P12V_OCP_AVIN_PD_1 @S9S_MB_2U_LIB.S9S_MB_2U(SCH_1):P12V_OCP_AVIN_PD_1    I89 @S9S_MB_2U_LIB.S9S_MB_2U(SCH_1):PAGE236

PR3844 Q_RES_0402LF-71.5K,1%,1/16W,EMA
     1 P3V3_OCP_MODE_1 @S9S_MB_2U_LIB.S9S_MB_2U(SCH_1):P3V3_OCP_MODE_1    I43 @S9S_MB_2U_LIB.S9S_MB_2U(SCH_1):PAGE236
     2    GND @S9S_MB_2U_LIB.S9S_MB_2U(SCH_1):GND    I43 @S9S_MB_2U_LIB.S9S_MB_2U(SCH_1):PAGE236

PR3846 Q_RES_0402LF-1.33K,1%,1/16W,EMA
     1    GND @S9S_MB_2U_LIB.S9S_MB_2U(SCH_1):GND    I45 @S9S_MB_2U_LIB.S9S_MB_2U(SCH_1):PAGE236
     2 P3V3_OCP_ILIMIT_1 @S9S_MB_2U_LIB.S9S_MB_2U(SCH_1):P3V3_OCP_ILIMIT_1    I45 @S9S_MB_2U_LIB.S9S_MB_2U(SCH_1):PAGE236

PR3847 Q_RES_0402LF-14.3K,1%,1/16W,CHA
     1 P12V_OCP_ISET_2 @S9S_MB_2U_LIB.S9S_MB_2U(SCH_1):P12V_OCP_ISET_2    I61 @S9S_MB_2U_LIB.S9S_MB_2U(SCH_1):PAGE237
     2    GND @S9S_MB_2U_LIB.S9S_MB_2U(SCH_1):GND    I61 @S9S_MB_2U_LIB.S9S_MB_2U(SCH_1):PAGE237

PR3849 Q_RES_0402LF-17.4K,1%,1/16W,CHA
     1 P12V_OCP_IMON_2 @S9S_MB_2U_LIB.S9S_MB_2U(SCH_1):P12V_OCP_IMON_2    I72 @S9S_MB_2U_LIB.S9S_MB_2U(SCH_1):PAGE237
     2    GND @S9S_MB_2U_LIB.S9S_MB_2U(SCH_1):GND    I72 @S9S_MB_2U_LIB.S9S_MB_2U(SCH_1):PAGE237

PR3850 Q_RES_0402LF-100,1%,1/16W,EMPTA
     1 P12V_OCP_V3_2 @S9S_MB_2U_LIB.S9S_MB_2U(SCH_1):P12V_OCP_V3_2    I77 @S9S_MB_2U_LIB.S9S_MB_2U(SCH_1):PAGE237
     2 P12V_OCP_AVIN_PD_2 @S9S_MB_2U_LIB.S9S_MB_2U(SCH_1):P12V_OCP_AVIN_PD_2    I77 @S9S_MB_2U_LIB.S9S_MB_2U(SCH_1):PAGE237

PR3851 Q_RES_0402LF-10K,1%,1/16W,CHIPA
     1 P12V_OCP_FLTB_2 @S9S_MB_2U_LIB.S9S_MB_2U(SCH_1):P12V_OCP_FLTB_2    I74 @S9S_MB_2U_LIB.S9S_MB_2U(SCH_1):PAGE237
     2 P3V3_AUX @S9S_MB_2U_LIB.S9S_MB_2U(SCH_1):P3V3_AUX    I74 @S9S_MB_2U_LIB.S9S_MB_2U(SCH_1):PAGE237

PR3852 Q_RES_0402LF-71.5K,1%,1/16W,EMA
     1 P12V_OCP_V3_2 @S9S_MB_2U_LIB.S9S_MB_2U(SCH_1):P12V_OCP_V3_2    I85 @S9S_MB_2U_LIB.S9S_MB_2U(SCH_1):PAGE237
     2 P12V_OCP_OV_FB_2 @S9S_MB_2U_LIB.S9S_MB_2U(SCH_1):P12V_OCP_OV_FB_2    I85 @S9S_MB_2U_LIB.S9S_MB_2U(SCH_1):PAGE237

PR3853 Q_RES_0402LF-120K,1%,1/16W,CHIA
     1 P12V_AUX @S9S_MB_2U_LIB.S9S_MB_2U(SCH_1):P12V_AUX    I84 @S9S_MB_2U_LIB.S9S_MB_2U(SCH_1):PAGE237
     2 P12V_OCP_OV_FB_2 @S9S_MB_2U_LIB.S9S_MB_2U(SCH_1):P12V_OCP_OV_FB_2    I84 @S9S_MB_2U_LIB.S9S_MB_2U(SCH_1):PAGE237

PR3854 Q_RES_0402LF-10K,1%,1/16W,CHIPA
     1 P12V_OCP_OV_FB_2 @S9S_MB_2U_LIB.S9S_MB_2U(SCH_1):P12V_OCP_OV_FB_2    I83 @S9S_MB_2U_LIB.S9S_MB_2U(SCH_1):PAGE237
     2    GND @S9S_MB_2U_LIB.S9S_MB_2U(SCH_1):GND    I83 @S9S_MB_2U_LIB.S9S_MB_2U(SCH_1):PAGE237

PR3855 Q_RES_0402LF-71.5K,1%,1/16W,EMA
     1 P3V3_OCP_MODE_2 @S9S_MB_2U_LIB.S9S_MB_2U(SCH_1):P3V3_OCP_MODE_2    I43 @S9S_MB_2U_LIB.S9S_MB_2U(SCH_1):PAGE237
     2    GND @S9S_MB_2U_LIB.S9S_MB_2U(SCH_1):GND    I43 @S9S_MB_2U_LIB.S9S_MB_2U(SCH_1):PAGE237

PR3856 Q_RES_0402LF-1.33K,1%,1/16W,EMA
     1    GND @S9S_MB_2U_LIB.S9S_MB_2U(SCH_1):GND    I46 @S9S_MB_2U_LIB.S9S_MB_2U(SCH_1):PAGE237
     2 P3V3_OCP_ILIMIT_2 @S9S_MB_2U_LIB.S9S_MB_2U(SCH_1):P3V3_OCP_ILIMIT_2    I46 @S9S_MB_2U_LIB.S9S_MB_2U(SCH_1):PAGE237

PR3857 Q_RES_0603LF-49.9,1%,1/10W,CHIA
     1 P12V_AUX @S9S_MB_2U_LIB.S9S_MB_2U(SCH_1):P12V_AUX    I87 @S9S_MB_2U_LIB.S9S_MB_2U(SCH_1):PAGE237
     2 P12V_OCP_AVIN_PD_2 @S9S_MB_2U_LIB.S9S_MB_2U(SCH_1):P12V_OCP_AVIN_PD_2    I87 @S9S_MB_2U_LIB.S9S_MB_2U(SCH_1):PAGE237

PR3910 Q_RES_0402LF-0,5%,1/16W,CHIP,CA
     1 HSC_VDD_R_1 @S9S_MB_2U_LIB.S9S_MB_2U(SCH_1):HSC_VDD_R_1    I21 @S9S_MB_2U_LIB.S9S_MB_2U(SCH_1):PAGE301
     2 HSC_VDD @S9S_MB_2U_LIB.S9S_MB_2U(SCH_1):HSC_VDD    I21 @S9S_MB_2U_LIB.S9S_MB_2U(SCH_1):PAGE301

PR3911 Q_RES_0402LF-0,5%,1/16W,CHIP,CA
     1 HSC_VDD_R_2 @S9S_MB_2U_LIB.S9S_MB_2U(SCH_1):HSC_VDD_R_2     I5 @S9S_MB_2U_LIB.S9S_MB_2U(SCH_1):PAGE301
     2 HSC_VDD @S9S_MB_2U_LIB.S9S_MB_2U(SCH_1):HSC_VDD     I5 @S9S_MB_2U_LIB.S9S_MB_2U(SCH_1):PAGE301

PR3912 Q_RES_0402LF-120K,1%,1/16W,CHIA
     1 AGND_HSC @S9S_MB_2U_LIB.S9S_MB_2U(SCH_1):AGND_HSC    I15 @S9S_MB_2U_LIB.S9S_MB_2U(SCH_1):PAGE301
     2 HSC_MODE_2 @S9S_MB_2U_LIB.S9S_MB_2U(SCH_1):HSC_MODE_2    I15 @S9S_MB_2U_LIB.S9S_MB_2U(SCH_1):PAGE301

PR3914 Q_RES_0402LF-2K,0.1%,1/16W,CHIA
     1 HSC_CS_1 @S9S_MB_2U_LIB.S9S_MB_2U(SCH_1):HSC_CS_1    I30 @S9S_MB_2U_LIB.S9S_MB_2U(SCH_1):PAGE301
     2 AGND_HSC @S9S_MB_2U_LIB.S9S_MB_2U(SCH_1):AGND_HSC    I30 @S9S_MB_2U_LIB.S9S_MB_2U(SCH_1):PAGE301

PR3915 Q_RES_0402LF-2K,0.1%,1/16W,CHIA
     1 HSC_CS_2 @S9S_MB_2U_LIB.S9S_MB_2U(SCH_1):HSC_CS_2    I12 @S9S_MB_2U_LIB.S9S_MB_2U(SCH_1):PAGE301
     2 AGND_HSC @S9S_MB_2U_LIB.S9S_MB_2U(SCH_1):AGND_HSC    I12 @S9S_MB_2U_LIB.S9S_MB_2U(SCH_1):PAGE301

PR3916 Q_RES_0402LF-0,5%,1/16W,CHIP,CA
     1 HSC_SCREF @S9S_MB_2U_LIB.S9S_MB_2U(SCH_1):HSC_SCREF    I33 @S9S_MB_2U_LIB.S9S_MB_2U(SCH_1):PAGE301
     2 HSC_SCREF_1 @S9S_MB_2U_LIB.S9S_MB_2U(SCH_1):HSC_SCREF_1    I33 @S9S_MB_2U_LIB.S9S_MB_2U(SCH_1):PAGE301

PR3917 Q_RES_0402LF-0,5%,1/16W,CHIP,CA
     1 HSC_SCREF @S9S_MB_2U_LIB.S9S_MB_2U(SCH_1):HSC_SCREF    I17 @S9S_MB_2U_LIB.S9S_MB_2U(SCH_1):PAGE301
     2 HSC_SCREF_2 @S9S_MB_2U_LIB.S9S_MB_2U(SCH_1):HSC_SCREF_2    I17 @S9S_MB_2U_LIB.S9S_MB_2U(SCH_1):PAGE301

PR3918 Q_RES_0402LF-2K,0.1%,1/16W,CHIA
     1 HSC_IMON @S9S_MB_2U_LIB.S9S_MB_2U(SCH_1):HSC_IMON    I34 @S9S_MB_2U_LIB.S9S_MB_2U(SCH_1):PAGE301
     2 AGND_HSC @S9S_MB_2U_LIB.S9S_MB_2U(SCH_1):AGND_HSC    I34 @S9S_MB_2U_LIB.S9S_MB_2U(SCH_1):PAGE301

PR3919 Q_RES_0402LF-0,5%,1/16W,CHIP,CA
     1 HSC_D_OC_1 @S9S_MB_2U_LIB.S9S_MB_2U(SCH_1):HSC_D_OC_1    I49 @S9S_MB_2U_LIB.S9S_MB_2U(SCH_1):PAGE301
     2 HSC_D_OC_R @S9S_MB_2U_LIB.S9S_MB_2U(SCH_1):HSC_D_OC_R    I49 @S9S_MB_2U_LIB.S9S_MB_2U(SCH_1):PAGE301

PR3920 Q_RES_0402LF-0,5%,1/16W,CHIP,CA
     1 HSC_FLT_TYPE_1 @S9S_MB_2U_LIB.S9S_MB_2U(SCH_1):HSC_FLT_TYPE_1    I50 @S9S_MB_2U_LIB.S9S_MB_2U(SCH_1):PAGE301
     2 HSC_FLT_TYPE @S9S_MB_2U_LIB.S9S_MB_2U(SCH_1):HSC_FLT_TYPE    I50 @S9S_MB_2U_LIB.S9S_MB_2U(SCH_1):PAGE301

PR3921 Q_RES_0402LF-0,5%,1/16W,CHIP,CA
     1 HSC_D_OC_2 @S9S_MB_2U_LIB.S9S_MB_2U(SCH_1):HSC_D_OC_2    I39 @S9S_MB_2U_LIB.S9S_MB_2U(SCH_1):PAGE301
     2 HSC_D_OC_R @S9S_MB_2U_LIB.S9S_MB_2U(SCH_1):HSC_D_OC_R    I39 @S9S_MB_2U_LIB.S9S_MB_2U(SCH_1):PAGE301

PR3922 Q_RES_0402LF-0,5%,1/16W,CHIP,CA
     1 HSC_FLT_TYPE_2 @S9S_MB_2U_LIB.S9S_MB_2U(SCH_1):HSC_FLT_TYPE_2    I40 @S9S_MB_2U_LIB.S9S_MB_2U(SCH_1):PAGE301
     2 HSC_FLT_TYPE @S9S_MB_2U_LIB.S9S_MB_2U(SCH_1):HSC_FLT_TYPE    I40 @S9S_MB_2U_LIB.S9S_MB_2U(SCH_1):PAGE301

PR3926 Q_RES_0402LF-75K,0.1%,1/16W,CHA
     1 P12V_PSU @S9S_MB_2U_LIB.S9S_MB_2U(SCH_1):P12V_PSU    I52 @S9S_MB_2U_LIB.S9S_MB_2U(SCH_1):PAGE303
     2 HSC_VSENSE @S9S_MB_2U_LIB.S9S_MB_2U(SCH_1):HSC_VSENSE    I52 @S9S_MB_2U_LIB.S9S_MB_2U(SCH_1):PAGE303

PR3927 Q_RES_0402LF-4.99K,0.1%,1/16W,A
     1 HSC_VSENSE @S9S_MB_2U_LIB.S9S_MB_2U(SCH_1):HSC_VSENSE    I40 @S9S_MB_2U_LIB.S9S_MB_2U(SCH_1):PAGE303
     2 AGND_HSC @S9S_MB_2U_LIB.S9S_MB_2U(SCH_1):AGND_HSC    I40 @S9S_MB_2U_LIB.S9S_MB_2U(SCH_1):PAGE303

PR3928 Q_RES_0402LF-0,5%,1/16W,CHIP,CA
     1 HSC_ON @S9S_MB_2U_LIB.S9S_MB_2U(SCH_1):HSC_ON    I41 @S9S_MB_2U_LIB.S9S_MB_2U(SCH_1):PAGE303
     2 HSC_ON_R @S9S_MB_2U_LIB.S9S_MB_2U(SCH_1):HSC_ON_R    I41 @S9S_MB_2U_LIB.S9S_MB_2U(SCH_1):PAGE303

PR3929 Q_RES_0402LF-1K,1%,1/16W,EMPTYA
     1 HSC_ADDR @S9S_MB_2U_LIB.S9S_MB_2U(SCH_1):HSC_ADDR    I42 @S9S_MB_2U_LIB.S9S_MB_2U(SCH_1):PAGE303
     2 HSC_VDD18 @S9S_MB_2U_LIB.S9S_MB_2U(SCH_1):HSC_VDD18    I42 @S9S_MB_2U_LIB.S9S_MB_2U(SCH_1):PAGE303

PR3930 Q_RES_0402LF-0,5%,1/16W,CHIP,CA
     1 AGND_HSC @S9S_MB_2U_LIB.S9S_MB_2U(SCH_1):AGND_HSC    I32 @S9S_MB_2U_LIB.S9S_MB_2U(SCH_1):PAGE303
     2 HSC_ADDR @S9S_MB_2U_LIB.S9S_MB_2U(SCH_1):HSC_ADDR    I32 @S9S_MB_2U_LIB.S9S_MB_2U(SCH_1):PAGE303

PR3931 Q_RES_0402LF-75K,0.1%,1/16W,CHA
     1 P12V_AUX @S9S_MB_2U_LIB.S9S_MB_2U(SCH_1):P12V_AUX    I86 @S9S_MB_2U_LIB.S9S_MB_2U(SCH_1):PAGE303
     2 HSC_VOSEN @S9S_MB_2U_LIB.S9S_MB_2U(SCH_1):HSC_VOSEN    I86 @S9S_MB_2U_LIB.S9S_MB_2U(SCH_1):PAGE303

PR3932 Q_RES_0402LF-4.99K,0.1%,1/16W,A
     1 HSC_VOSEN @S9S_MB_2U_LIB.S9S_MB_2U(SCH_1):HSC_VOSEN    I59 @S9S_MB_2U_LIB.S9S_MB_2U(SCH_1):PAGE303
     2 AGND_HSC @S9S_MB_2U_LIB.S9S_MB_2U(SCH_1):AGND_HSC    I59 @S9S_MB_2U_LIB.S9S_MB_2U(SCH_1):PAGE303

PR3935 Q_RES_0402LF-10K,1%,1/16W,CHIPA
     1 HSC_VTEMP @S9S_MB_2U_LIB.S9S_MB_2U(SCH_1):HSC_VTEMP    I79 @S9S_MB_2U_LIB.S9S_MB_2U(SCH_1):PAGE303
     2 AGND_HSC @S9S_MB_2U_LIB.S9S_MB_2U(SCH_1):AGND_HSC    I79 @S9S_MB_2U_LIB.S9S_MB_2U(SCH_1):PAGE303

PR3937 Q_RES_0402LF-120K,1%,1/16W,CHIA
     1 HSC_MODE @S9S_MB_2U_LIB.S9S_MB_2U(SCH_1):HSC_MODE    I84 @S9S_MB_2U_LIB.S9S_MB_2U(SCH_1):PAGE303
     2 AGND_HSC @S9S_MB_2U_LIB.S9S_MB_2U(SCH_1):AGND_HSC    I84 @S9S_MB_2U_LIB.S9S_MB_2U(SCH_1):PAGE303

PR3944 Q_RES_0402LF-46.4K,1%,1/16W,CHA
     1 P12V_E1S_ISET_0 @S9S_MB_2U_LIB.S9S_MB_2U(SCH_1):P12V_E1S_ISET_0    I40 @S9S_MB_2U_LIB.S9S_MB_2U(SCH_1):PAGE323
     2    GND @S9S_MB_2U_LIB.S9S_MB_2U(SCH_1):GND    I40 @S9S_MB_2U_LIB.S9S_MB_2U(SCH_1):PAGE323

PR3945 Q_RES_0402LF-71.5K,1%,1/16W,EMA
     1 P3V3_E1S_MODE_0 @S9S_MB_2U_LIB.S9S_MB_2U(SCH_1):P3V3_E1S_MODE_0     I4 @S9S_MB_2U_LIB.S9S_MB_2U(SCH_1):PAGE323
     2    GND @S9S_MB_2U_LIB.S9S_MB_2U(SCH_1):GND     I4 @S9S_MB_2U_LIB.S9S_MB_2U(SCH_1):PAGE323

PR3947 Q_RES_0402LF-2.8K,1%,1/16W,EMPA
     1    GND @S9S_MB_2U_LIB.S9S_MB_2U(SCH_1):GND     I6 @S9S_MB_2U_LIB.S9S_MB_2U(SCH_1):PAGE323
     2 P3V3_E1S_ILIMIT_0 @S9S_MB_2U_LIB.S9S_MB_2U(SCH_1):P3V3_E1S_ILIMIT_0     I6 @S9S_MB_2U_LIB.S9S_MB_2U(SCH_1):PAGE323

PR3949 Q_RES_0402LF-56K,1%,1/16W,CHIPA
     1 P12V_E1S_IMON_0 @S9S_MB_2U_LIB.S9S_MB_2U(SCH_1):P12V_E1S_IMON_0    I53 @S9S_MB_2U_LIB.S9S_MB_2U(SCH_1):PAGE323
     2    GND @S9S_MB_2U_LIB.S9S_MB_2U(SCH_1):GND    I53 @S9S_MB_2U_LIB.S9S_MB_2U(SCH_1):PAGE323

PR3950 Q_RES_0402LF-100,1%,1/16W,EMPTA
     1 P12V_E1S_0 @S9S_MB_2U_LIB.S9S_MB_2U(SCH_1):P12V_E1S_0    I55 @S9S_MB_2U_LIB.S9S_MB_2U(SCH_1):PAGE323
     2 P12V_E1S_AVIN_PD_0 @S9S_MB_2U_LIB.S9S_MB_2U(SCH_1):P12V_E1S_AVIN_PD_0    I55 @S9S_MB_2U_LIB.S9S_MB_2U(SCH_1):PAGE323

PR3951 Q_RES_0402LF-10K,1%,1/16W,CHIPA
     1 P12V_E1S_FLTB_0 @S9S_MB_2U_LIB.S9S_MB_2U(SCH_1):P12V_E1S_FLTB_0    I54 @S9S_MB_2U_LIB.S9S_MB_2U(SCH_1):PAGE323
     2 P3V3_AUX @S9S_MB_2U_LIB.S9S_MB_2U(SCH_1):P3V3_AUX    I54 @S9S_MB_2U_LIB.S9S_MB_2U(SCH_1):PAGE323

PR3952 Q_RES_0402LF-71.5K,1%,1/16W,EMA
     1 P12V_E1S_0 @S9S_MB_2U_LIB.S9S_MB_2U(SCH_1):P12V_E1S_0    I62 @S9S_MB_2U_LIB.S9S_MB_2U(SCH_1):PAGE323
     2 P12V_E1S_OV_FB_0 @S9S_MB_2U_LIB.S9S_MB_2U(SCH_1):P12V_E1S_OV_FB_0    I62 @S9S_MB_2U_LIB.S9S_MB_2U(SCH_1):PAGE323

PR3953 Q_RES_0402LF-120K,1%,1/16W,CHIA
     1 P12V_AUX @S9S_MB_2U_LIB.S9S_MB_2U(SCH_1):P12V_AUX    I63 @S9S_MB_2U_LIB.S9S_MB_2U(SCH_1):PAGE323
     2 P12V_E1S_OV_FB_0 @S9S_MB_2U_LIB.S9S_MB_2U(SCH_1):P12V_E1S_OV_FB_0    I63 @S9S_MB_2U_LIB.S9S_MB_2U(SCH_1):PAGE323

PR3954 Q_RES_0402LF-10K,1%,1/16W,CHIPA
     1 P12V_E1S_OV_FB_0 @S9S_MB_2U_LIB.S9S_MB_2U(SCH_1):P12V_E1S_OV_FB_0    I58 @S9S_MB_2U_LIB.S9S_MB_2U(SCH_1):PAGE323
     2    GND @S9S_MB_2U_LIB.S9S_MB_2U(SCH_1):GND    I58 @S9S_MB_2U_LIB.S9S_MB_2U(SCH_1):PAGE323

PR3957 Q_RES_0603LF-49.9,1%,1/10W,CHIA
     1 P12V_AUX @S9S_MB_2U_LIB.S9S_MB_2U(SCH_1):P12V_AUX    I70 @S9S_MB_2U_LIB.S9S_MB_2U(SCH_1):PAGE323
     2 P12V_E1S_AVIN_PD_0 @S9S_MB_2U_LIB.S9S_MB_2U(SCH_1):P12V_E1S_AVIN_PD_0    I70 @S9S_MB_2U_LIB.S9S_MB_2U(SCH_1):PAGE323

PR3960 Q_RES_0402LF-160K,1%,1/16W,EMPA
     1 P12V_AUX @S9S_MB_2U_LIB.S9S_MB_2U(SCH_1):P12V_AUX    I32 @S9S_MB_2U_LIB.S9S_MB_2U(SCH_1):PAGE324
     2 P12V_E1S_UV_0 @S9S_MB_2U_LIB.S9S_MB_2U(SCH_1):P12V_E1S_UV_0    I32 @S9S_MB_2U_LIB.S9S_MB_2U(SCH_1):PAGE324

PR3961 Q_RES_0402LF-6.8K,1%,1/16W,EMPA
     1 P12V_E1S_UV_0 @S9S_MB_2U_LIB.S9S_MB_2U(SCH_1):P12V_E1S_UV_0    I85 @S9S_MB_2U_LIB.S9S_MB_2U(SCH_1):PAGE324
     2 P12V_E1S_OV_0 @S9S_MB_2U_LIB.S9S_MB_2U(SCH_1):P12V_E1S_OV_0    I85 @S9S_MB_2U_LIB.S9S_MB_2U(SCH_1):PAGE324

PR3962 Q_RES_0402LF-15K,1%,1/16W,EMPTA
     1 P12V_E1S_OV_0 @S9S_MB_2U_LIB.S9S_MB_2U(SCH_1):P12V_E1S_OV_0    I28 @S9S_MB_2U_LIB.S9S_MB_2U(SCH_1):PAGE324
     2    GND @S9S_MB_2U_LIB.S9S_MB_2U(SCH_1):GND    I28 @S9S_MB_2U_LIB.S9S_MB_2U(SCH_1):PAGE324

PR3963 Q_RES_0402LF-25.5K,1%,1/16W,CHA
     1 P3V3_AUX @S9S_MB_2U_LIB.S9S_MB_2U(SCH_1):P3V3_AUX    I18 @S9S_MB_2U_LIB.S9S_MB_2U(SCH_1):PAGE324
     2 P3V3_E1S_UV_0 @S9S_MB_2U_LIB.S9S_MB_2U(SCH_1):P3V3_E1S_UV_0    I18 @S9S_MB_2U_LIB.S9S_MB_2U(SCH_1):PAGE324

PR3964 Q_RES_0402LF-7.15K,1%,1/16W,CHA
     1 P3V3_E1S_UV_0 @S9S_MB_2U_LIB.S9S_MB_2U(SCH_1):P3V3_E1S_UV_0    I14 @S9S_MB_2U_LIB.S9S_MB_2U(SCH_1):PAGE324
     2 P3V3_E1S_OV_0 @S9S_MB_2U_LIB.S9S_MB_2U(SCH_1):P3V3_E1S_OV_0    I14 @S9S_MB_2U_LIB.S9S_MB_2U(SCH_1):PAGE324

PR3965 Q_RES_0402LF-15K,1%,1/16W,CHIPA
     1 P3V3_E1S_OV_0 @S9S_MB_2U_LIB.S9S_MB_2U(SCH_1):P3V3_E1S_OV_0    I13 @S9S_MB_2U_LIB.S9S_MB_2U(SCH_1):PAGE324
     2    GND @S9S_MB_2U_LIB.S9S_MB_2U(SCH_1):GND    I13 @S9S_MB_2U_LIB.S9S_MB_2U(SCH_1):PAGE324

PR3966 Q_RES_0402LF-10,1%,1/16W,EMPTYA
     1 P12V_AUX @S9S_MB_2U_LIB.S9S_MB_2U(SCH_1):P12V_AUX    I61 @S9S_MB_2U_LIB.S9S_MB_2U(SCH_1):PAGE324
     2 P12V_E1S_VCC_0 @S9S_MB_2U_LIB.S9S_MB_2U(SCH_1):P12V_E1S_VCC_0    I61 @S9S_MB_2U_LIB.S9S_MB_2U(SCH_1):PAGE324

PR3967 Q_RES_0402LF-10,1%,1/16W,CHIP,A
     1 P3V3_AUX @S9S_MB_2U_LIB.S9S_MB_2U(SCH_1):P3V3_AUX    I39 @S9S_MB_2U_LIB.S9S_MB_2U(SCH_1):PAGE324
     2 P3V3_E1S_VCC_0 @S9S_MB_2U_LIB.S9S_MB_2U(SCH_1):P3V3_E1S_VCC_0    I39 @S9S_MB_2U_LIB.S9S_MB_2U(SCH_1):PAGE324

PR3968 Q_RES_0402LF-9.31K,1%,1/16W,EMA
     1 P12V_E1S_CB_0 @S9S_MB_2U_LIB.S9S_MB_2U(SCH_1):P12V_E1S_CB_0    I59 @S9S_MB_2U_LIB.S9S_MB_2U(SCH_1):PAGE324
     2    GND @S9S_MB_2U_LIB.S9S_MB_2U(SCH_1):GND    I59 @S9S_MB_2U_LIB.S9S_MB_2U(SCH_1):PAGE324

PR3969 Q_RES_0402LF-2.49K,1%,1/16W,CHA
     1 P3V3_E1S_CB_0 @S9S_MB_2U_LIB.S9S_MB_2U(SCH_1):P3V3_E1S_CB_0    I34 @S9S_MB_2U_LIB.S9S_MB_2U(SCH_1):PAGE324
     2    GND @S9S_MB_2U_LIB.S9S_MB_2U(SCH_1):GND    I34 @S9S_MB_2U_LIB.S9S_MB_2U(SCH_1):PAGE324

PR3970 Q_RES_0402LF-2.67K,1%,1/16W,EMA
     1 P12V_E1S_SENSE_0 @S9S_MB_2U_LIB.S9S_MB_2U(SCH_1):P12V_E1S_SENSE_0    I64 @S9S_MB_2U_LIB.S9S_MB_2U(SCH_1):PAGE324
     2    GND @S9S_MB_2U_LIB.S9S_MB_2U(SCH_1):GND    I64 @S9S_MB_2U_LIB.S9S_MB_2U(SCH_1):PAGE324

PR3971 Q_RES_0402LF-9.76K,1%,1/16W,CHA
     1 P3V3_E1S_SENSE_0 @S9S_MB_2U_LIB.S9S_MB_2U(SCH_1):P3V3_E1S_SENSE_0    I41 @S9S_MB_2U_LIB.S9S_MB_2U(SCH_1):PAGE324
     2    GND @S9S_MB_2U_LIB.S9S_MB_2U(SCH_1):GND    I41 @S9S_MB_2U_LIB.S9S_MB_2U(SCH_1):PAGE324

PR3980 Q_RES_0402LF-0,5%,1/16W,CHIP,CA
     1 HSC_VDD_R_3 @S9S_MB_2U_LIB.S9S_MB_2U(SCH_1):HSC_VDD_R_3    I21 @S9S_MB_2U_LIB.S9S_MB_2U(SCH_1):PAGE325
     2 HSC_VDD @S9S_MB_2U_LIB.S9S_MB_2U(SCH_1):HSC_VDD    I21 @S9S_MB_2U_LIB.S9S_MB_2U(SCH_1):PAGE325

PR3981 Q_RES_0402LF-0,5%,1/16W,CHIP,CA
     1 HSC_VDD_R_4 @S9S_MB_2U_LIB.S9S_MB_2U(SCH_1):HSC_VDD_R_4     I5 @S9S_MB_2U_LIB.S9S_MB_2U(SCH_1):PAGE325
     2 HSC_VDD @S9S_MB_2U_LIB.S9S_MB_2U(SCH_1):HSC_VDD     I5 @S9S_MB_2U_LIB.S9S_MB_2U(SCH_1):PAGE325

PR3982 Q_RES_0402LF-120K,1%,1/16W,CHIA
     1 AGND_HSC @S9S_MB_2U_LIB.S9S_MB_2U(SCH_1):AGND_HSC    I32 @S9S_MB_2U_LIB.S9S_MB_2U(SCH_1):PAGE325
     2 HSC_MODE_3 @S9S_MB_2U_LIB.S9S_MB_2U(SCH_1):HSC_MODE_3    I32 @S9S_MB_2U_LIB.S9S_MB_2U(SCH_1):PAGE325

PR3984 Q_RES_0402LF-120K,1%,1/16W,CHIA
     1 AGND_HSC @S9S_MB_2U_LIB.S9S_MB_2U(SCH_1):AGND_HSC    I14 @S9S_MB_2U_LIB.S9S_MB_2U(SCH_1):PAGE325
     2 HSC_MODE_4 @S9S_MB_2U_LIB.S9S_MB_2U(SCH_1):HSC_MODE_4    I14 @S9S_MB_2U_LIB.S9S_MB_2U(SCH_1):PAGE325

PR3986 Q_RES_0402LF-2K,0.1%,1/16W,CHIA
     1 HSC_CS_3 @S9S_MB_2U_LIB.S9S_MB_2U(SCH_1):HSC_CS_3    I30 @S9S_MB_2U_LIB.S9S_MB_2U(SCH_1):PAGE325
     2 AGND_HSC @S9S_MB_2U_LIB.S9S_MB_2U(SCH_1):AGND_HSC    I30 @S9S_MB_2U_LIB.S9S_MB_2U(SCH_1):PAGE325

PR3987 Q_RES_0402LF-2K,0.1%,1/16W,CHIA
     1 HSC_CS_4 @S9S_MB_2U_LIB.S9S_MB_2U(SCH_1):HSC_CS_4    I12 @S9S_MB_2U_LIB.S9S_MB_2U(SCH_1):PAGE325
     2 AGND_HSC @S9S_MB_2U_LIB.S9S_MB_2U(SCH_1):AGND_HSC    I12 @S9S_MB_2U_LIB.S9S_MB_2U(SCH_1):PAGE325

PR3988 Q_RES_0402LF-0,5%,1/16W,CHIP,CA
     1 HSC_SCREF @S9S_MB_2U_LIB.S9S_MB_2U(SCH_1):HSC_SCREF    I33 @S9S_MB_2U_LIB.S9S_MB_2U(SCH_1):PAGE325
     2 HSC_SCREF_3 @S9S_MB_2U_LIB.S9S_MB_2U(SCH_1):HSC_SCREF_3    I33 @S9S_MB_2U_LIB.S9S_MB_2U(SCH_1):PAGE325

PR3989 Q_RES_0402LF-0,5%,1/16W,CHIP,CA
     1 HSC_SCREF @S9S_MB_2U_LIB.S9S_MB_2U(SCH_1):HSC_SCREF    I16 @S9S_MB_2U_LIB.S9S_MB_2U(SCH_1):PAGE325
     2 HSC_SCREF_4 @S9S_MB_2U_LIB.S9S_MB_2U(SCH_1):HSC_SCREF_4    I16 @S9S_MB_2U_LIB.S9S_MB_2U(SCH_1):PAGE325

PR3990 Q_RES_0402LF-2K,0.1%,1/16W,CHIA
     1 HSC_IMON @S9S_MB_2U_LIB.S9S_MB_2U(SCH_1):HSC_IMON    I34 @S9S_MB_2U_LIB.S9S_MB_2U(SCH_1):PAGE325
     2 AGND_HSC @S9S_MB_2U_LIB.S9S_MB_2U(SCH_1):AGND_HSC    I34 @S9S_MB_2U_LIB.S9S_MB_2U(SCH_1):PAGE325

PR3991 Q_RES_0402LF-2K,0.1%,1/16W,CHIA
     1 HSC_IMON @S9S_MB_2U_LIB.S9S_MB_2U(SCH_1):HSC_IMON    I13 @S9S_MB_2U_LIB.S9S_MB_2U(SCH_1):PAGE325
     2 AGND_HSC @S9S_MB_2U_LIB.S9S_MB_2U(SCH_1):AGND_HSC    I13 @S9S_MB_2U_LIB.S9S_MB_2U(SCH_1):PAGE325

PR3992 Q_RES_0402LF-0,5%,1/16W,CHIP,CA
     1 HSC_D_OC_3 @S9S_MB_2U_LIB.S9S_MB_2U(SCH_1):HSC_D_OC_3    I50 @S9S_MB_2U_LIB.S9S_MB_2U(SCH_1):PAGE325
     2 HSC_D_OC_R @S9S_MB_2U_LIB.S9S_MB_2U(SCH_1):HSC_D_OC_R    I50 @S9S_MB_2U_LIB.S9S_MB_2U(SCH_1):PAGE325

PR3993 Q_RES_0402LF-0,5%,1/16W,CHIP,CA
     1 HSC_FLT_TYPE_3 @S9S_MB_2U_LIB.S9S_MB_2U(SCH_1):HSC_FLT_TYPE_3    I49 @S9S_MB_2U_LIB.S9S_MB_2U(SCH_1):PAGE325
     2 HSC_FLT_TYPE @S9S_MB_2U_LIB.S9S_MB_2U(SCH_1):HSC_FLT_TYPE    I49 @S9S_MB_2U_LIB.S9S_MB_2U(SCH_1):PAGE325

PR3994 Q_RES_0402LF-0,5%,1/16W,CHIP,CA
     1 HSC_D_OC_4 @S9S_MB_2U_LIB.S9S_MB_2U(SCH_1):HSC_D_OC_4    I40 @S9S_MB_2U_LIB.S9S_MB_2U(SCH_1):PAGE325
     2 HSC_D_OC_R @S9S_MB_2U_LIB.S9S_MB_2U(SCH_1):HSC_D_OC_R    I40 @S9S_MB_2U_LIB.S9S_MB_2U(SCH_1):PAGE325

PR3995 Q_RES_0402LF-0,5%,1/16W,CHIP,CA
     1 HSC_FLT_TYPE_4 @S9S_MB_2U_LIB.S9S_MB_2U(SCH_1):HSC_FLT_TYPE_4    I39 @S9S_MB_2U_LIB.S9S_MB_2U(SCH_1):PAGE325
     2 HSC_FLT_TYPE @S9S_MB_2U_LIB.S9S_MB_2U(SCH_1):HSC_FLT_TYPE    I39 @S9S_MB_2U_LIB.S9S_MB_2U(SCH_1):PAGE325

PR3999 Q_RES_0402LF-24.3K,1%,1/16W,CHA
     1 P12V_SCM_ISET @S9S_MB_2U_LIB.S9S_MB_2U(SCH_1):P12V_SCM_ISET    I11 @S9S_MB_2U_LIB.S9S_MB_2U(SCH_1):PAGE229
     2    GND @S9S_MB_2U_LIB.S9S_MB_2U(SCH_1):GND    I11 @S9S_MB_2U_LIB.S9S_MB_2U(SCH_1):PAGE229

PR4000 Q_RES_0402LF-160K,1%,1/16W,EMPA
     1 P12V_AUX @S9S_MB_2U_LIB.S9S_MB_2U(SCH_1):P12V_AUX    I67 @S9S_MB_2U_LIB.S9S_MB_2U(SCH_1):PAGE229
     2 P12V_SCM_UV @S9S_MB_2U_LIB.S9S_MB_2U(SCH_1):P12V_SCM_UV    I67 @S9S_MB_2U_LIB.S9S_MB_2U(SCH_1):PAGE229

PR4001 Q_RES_0402LF-6.8K,1%,1/16W,EMPA
     1 P12V_SCM_UV @S9S_MB_2U_LIB.S9S_MB_2U(SCH_1):P12V_SCM_UV    I64 @S9S_MB_2U_LIB.S9S_MB_2U(SCH_1):PAGE229
     2 P12V_SCM_OV @S9S_MB_2U_LIB.S9S_MB_2U(SCH_1):P12V_SCM_OV    I64 @S9S_MB_2U_LIB.S9S_MB_2U(SCH_1):PAGE229

PR4002 Q_RES_0402LF-15K,1%,1/16W,EMPTA
     1 P12V_SCM_OV @S9S_MB_2U_LIB.S9S_MB_2U(SCH_1):P12V_SCM_OV    I61 @S9S_MB_2U_LIB.S9S_MB_2U(SCH_1):PAGE229
     2    GND @S9S_MB_2U_LIB.S9S_MB_2U(SCH_1):GND    I61 @S9S_MB_2U_LIB.S9S_MB_2U(SCH_1):PAGE229

PR4003 Q_RES_0402LF-10,1%,1/16W,EMPTYA
     1 P12V_AUX @S9S_MB_2U_LIB.S9S_MB_2U(SCH_1):P12V_AUX    I70 @S9S_MB_2U_LIB.S9S_MB_2U(SCH_1):PAGE229
     2 P12V_SCM_VCC @S9S_MB_2U_LIB.S9S_MB_2U(SCH_1):P12V_SCM_VCC    I70 @S9S_MB_2U_LIB.S9S_MB_2U(SCH_1):PAGE229

PR4004 Q_RES_0402LF-17.8K,1%,1/16W,EMA
     1 P12V_SCM_CB @S9S_MB_2U_LIB.S9S_MB_2U(SCH_1):P12V_SCM_CB    I63 @S9S_MB_2U_LIB.S9S_MB_2U(SCH_1):PAGE229
     2    GND @S9S_MB_2U_LIB.S9S_MB_2U(SCH_1):GND    I63 @S9S_MB_2U_LIB.S9S_MB_2U(SCH_1):PAGE229

PR4005 Q_RES_0402LF-30.1K,1%,1/16W,CHA
     1 P12V_SCM_IMON @S9S_MB_2U_LIB.S9S_MB_2U(SCH_1):P12V_SCM_IMON    I34 @S9S_MB_2U_LIB.S9S_MB_2U(SCH_1):PAGE229
     2    GND @S9S_MB_2U_LIB.S9S_MB_2U(SCH_1):GND    I34 @S9S_MB_2U_LIB.S9S_MB_2U(SCH_1):PAGE229

PR4006 Q_RES_0402LF-100,1%,1/16W,EMPTA
     1 P12V_SCM_R @S9S_MB_2U_LIB.S9S_MB_2U(SCH_1):P12V_SCM_R    I39 @S9S_MB_2U_LIB.S9S_MB_2U(SCH_1):PAGE229
     2 P12V_SCM_AVIN_PD @S9S_MB_2U_LIB.S9S_MB_2U(SCH_1):P12V_SCM_AVIN_PD    I39 @S9S_MB_2U_LIB.S9S_MB_2U(SCH_1):PAGE229

PR4007 Q_RES_0402LF-10K,1%,1/16W,CHIPA
     1 P12V_SCM_FLTB_N @S9S_MB_2U_LIB.S9S_MB_2U(SCH_1):P12V_SCM_FLTB_N    I48 @S9S_MB_2U_LIB.S9S_MB_2U(SCH_1):PAGE229
     2 P3V3_AUX @S9S_MB_2U_LIB.S9S_MB_2U(SCH_1):P3V3_AUX    I48 @S9S_MB_2U_LIB.S9S_MB_2U(SCH_1):PAGE229

PR4008 Q_RES_0402LF-1.33K,1%,1/16W,EMA
     1 P12V_SCM_SENSE @S9S_MB_2U_LIB.S9S_MB_2U(SCH_1):P12V_SCM_SENSE    I72 @S9S_MB_2U_LIB.S9S_MB_2U(SCH_1):PAGE229
     2    GND @S9S_MB_2U_LIB.S9S_MB_2U(SCH_1):GND    I72 @S9S_MB_2U_LIB.S9S_MB_2U(SCH_1):PAGE229

PR4009 Q_RES_0402LF-71.5K,1%,1/16W,EMA
     1 P12V_SCM_R @S9S_MB_2U_LIB.S9S_MB_2U(SCH_1):P12V_SCM_R    I51 @S9S_MB_2U_LIB.S9S_MB_2U(SCH_1):PAGE229
     2 P12V_SCM_OV_FB @S9S_MB_2U_LIB.S9S_MB_2U(SCH_1):P12V_SCM_OV_FB    I51 @S9S_MB_2U_LIB.S9S_MB_2U(SCH_1):PAGE229

PR4010 Q_RES_0402LF-120K,1%,1/16W,CHIA
     1 P12V_AUX @S9S_MB_2U_LIB.S9S_MB_2U(SCH_1):P12V_AUX    I52 @S9S_MB_2U_LIB.S9S_MB_2U(SCH_1):PAGE229
     2 P12V_SCM_OV_FB @S9S_MB_2U_LIB.S9S_MB_2U(SCH_1):P12V_SCM_OV_FB    I52 @S9S_MB_2U_LIB.S9S_MB_2U(SCH_1):PAGE229

PR4011 Q_RES_0402LF-10K,1%,1/16W,CHIPA
     1 P12V_SCM_OV_FB @S9S_MB_2U_LIB.S9S_MB_2U(SCH_1):P12V_SCM_OV_FB    I50 @S9S_MB_2U_LIB.S9S_MB_2U(SCH_1):PAGE229
     2    GND @S9S_MB_2U_LIB.S9S_MB_2U(SCH_1):GND    I50 @S9S_MB_2U_LIB.S9S_MB_2U(SCH_1):PAGE229

PR4012 Q_RES_0402LF-0,5%,1/16W,EMPTY,A
     1 P12V_SCM_PWRGD @S9S_MB_2U_LIB.S9S_MB_2U(SCH_1):P12V_SCM_PWRGD    I74 @S9S_MB_2U_LIB.S9S_MB_2U(SCH_1):PAGE229
     2 HP_LVC3_SCM_HSC_PWRGD @S9S_MB_2U_LIB.S9S_MB_2U(SCH_1):HP_LVC3_SCM_HSC_PWRGD    I74 @S9S_MB_2U_LIB.S9S_MB_2U(SCH_1):PAGE229

PR4014 Q_RES_0603LF-49.9,1%,1/10W,CHIA
     1 P12V_AUX @S9S_MB_2U_LIB.S9S_MB_2U(SCH_1):P12V_AUX    I54 @S9S_MB_2U_LIB.S9S_MB_2U(SCH_1):PAGE229
     2 P12V_SCM_AVIN_PD @S9S_MB_2U_LIB.S9S_MB_2U(SCH_1):P12V_SCM_AVIN_PD    I54 @S9S_MB_2U_LIB.S9S_MB_2U(SCH_1):PAGE229

PR4217 Q_RES_0402LF-0,5%,1/16W,EMPTY,A
     1 PVCCFA_EHV_FIVRA_CPU0_IMON4 @S9S_MB_2U_LIB.S9S_MB_2U(SCH_1):PVCCFA_EHV_FIVRA_CPU0_IMON4    I74 @S9S_MB_2U_LIB.S9S_MB_2U(SCH_1):PAGE252
     2    GND @S9S_MB_2U_LIB.S9S_MB_2U(SCH_1):GND    I74 @S9S_MB_2U_LIB.S9S_MB_2U(SCH_1):PAGE252

PR4218 Q_RES_0402LF-0,5%,1/16W,EMPTY,A
     1 PVCCFA_EHV_FIVRA_CPU0_IMON3 @S9S_MB_2U_LIB.S9S_MB_2U(SCH_1):PVCCFA_EHV_FIVRA_CPU0_IMON3    I73 @S9S_MB_2U_LIB.S9S_MB_2U(SCH_1):PAGE252
     2    GND @S9S_MB_2U_LIB.S9S_MB_2U(SCH_1):GND    I73 @S9S_MB_2U_LIB.S9S_MB_2U(SCH_1):PAGE252

PR4219 Q_RES_0402LF-499,1%,1/16W,CHIPA
     1 PVCCIN_CPU0 @S9S_MB_2U_LIB.S9S_MB_2U(SCH_1):PVCCIN_CPU0    I59 @S9S_MB_2U_LIB.S9S_MB_2U(SCH_1):PAGE253
     2    GND @S9S_MB_2U_LIB.S9S_MB_2U(SCH_1):GND    I59 @S9S_MB_2U_LIB.S9S_MB_2U(SCH_1):PAGE253

PR4220 Q_RES_0402LF-0,5%,1/16W,CHIP,CA
     1 PVCCINFAON_CPU0_CSPIN @S9S_MB_2U_LIB.S9S_MB_2U(SCH_1):PVCCINFAON_CPU0_CSPIN    I19 @S9S_MB_2U_LIB.S9S_MB_2U(SCH_1):PAGE260
     2    GND @S9S_MB_2U_LIB.S9S_MB_2U(SCH_1):GND    I19 @S9S_MB_2U_LIB.S9S_MB_2U(SCH_1):PAGE260

PR4221 Q_RES_0402LF-0,5%,1/16W,CHIP,CA
     1 NC_PVCCINFAON_CPU0_ACSP3 @S9S_MB_2U_LIB.S9S_MB_2U(SCH_1):NC_PVCCINFAON_CPU0_ACSP3    I87 @S9S_MB_2U_LIB.S9S_MB_2U(SCH_1):PAGE260
     2    GND @S9S_MB_2U_LIB.S9S_MB_2U(SCH_1):GND    I87 @S9S_MB_2U_LIB.S9S_MB_2U(SCH_1):PAGE260

PR4222 Q_RES_0402LF-0,5%,1/16W,CHIP,CA
     1 NC_PVCCINFAON_CPU0_ACSP4 @S9S_MB_2U_LIB.S9S_MB_2U(SCH_1):NC_PVCCINFAON_CPU0_ACSP4    I86 @S9S_MB_2U_LIB.S9S_MB_2U(SCH_1):PAGE260
     2    GND @S9S_MB_2U_LIB.S9S_MB_2U(SCH_1):GND    I86 @S9S_MB_2U_LIB.S9S_MB_2U(SCH_1):PAGE260

PR4223 Q_RES_0402LF-0,5%,1/16W,CHIP,CA
     1 NC_PVCCINFAON_CPU0_ACSP5 @S9S_MB_2U_LIB.S9S_MB_2U(SCH_1):NC_PVCCINFAON_CPU0_ACSP5    I85 @S9S_MB_2U_LIB.S9S_MB_2U(SCH_1):PAGE260
     2    GND @S9S_MB_2U_LIB.S9S_MB_2U(SCH_1):GND    I85 @S9S_MB_2U_LIB.S9S_MB_2U(SCH_1):PAGE260

PR4224 Q_RES_0402LF-0,5%,1/16W,CHIP,CA
     1 NC_PVCCINFAON_CPU0_ACSP6 @S9S_MB_2U_LIB.S9S_MB_2U(SCH_1):NC_PVCCINFAON_CPU0_ACSP6    I84 @S9S_MB_2U_LIB.S9S_MB_2U(SCH_1):PAGE260
     2    GND @S9S_MB_2U_LIB.S9S_MB_2U(SCH_1):GND    I84 @S9S_MB_2U_LIB.S9S_MB_2U(SCH_1):PAGE260

PR4225 Q_RES_0402LF-0,5%,1/16W,CHIP,CA
     1 NC_PVCCINFAON_CPU0_ACSP7 @S9S_MB_2U_LIB.S9S_MB_2U(SCH_1):NC_PVCCINFAON_CPU0_ACSP7    I76 @S9S_MB_2U_LIB.S9S_MB_2U(SCH_1):PAGE260
     2    GND @S9S_MB_2U_LIB.S9S_MB_2U(SCH_1):GND    I76 @S9S_MB_2U_LIB.S9S_MB_2U(SCH_1):PAGE260

PR4226 Q_RES_0402LF-499,1%,1/16W,CHIPA
     1 PVCCINFAON_CPU0 @S9S_MB_2U_LIB.S9S_MB_2U(SCH_1):PVCCINFAON_CPU0    I63 @S9S_MB_2U_LIB.S9S_MB_2U(SCH_1):PAGE261
     2    GND @S9S_MB_2U_LIB.S9S_MB_2U(SCH_1):GND    I63 @S9S_MB_2U_LIB.S9S_MB_2U(SCH_1):PAGE261

PR4227 Q_RES_0402LF-0,5%,1/16W,EMPTY,A
     1 PVCCFA_EHV_CPU0_VDD1 @S9S_MB_2U_LIB.S9S_MB_2U(SCH_1):PVCCFA_EHV_CPU0_VDD1    I13 @S9S_MB_2U_LIB.S9S_MB_2U(SCH_1):PAGE262
     2 PVCCFA_EHV_CPU0_NC2 @S9S_MB_2U_LIB.S9S_MB_2U(SCH_1):PVCCFA_EHV_CPU0_NC2    I13 @S9S_MB_2U_LIB.S9S_MB_2U(SCH_1):PAGE262

PR4228 Q_RES_0402LF-0,5%,1/16W,EMPTY,A
     1 PVCCFA_EHV_CPU0_FAULT @S9S_MB_2U_LIB.S9S_MB_2U(SCH_1):PVCCFA_EHV_CPU0_FAULT    I15 @S9S_MB_2U_LIB.S9S_MB_2U(SCH_1):PAGE262
     2    GND @S9S_MB_2U_LIB.S9S_MB_2U(SCH_1):GND    I15 @S9S_MB_2U_LIB.S9S_MB_2U(SCH_1):PAGE262

PR4229 Q_RES_0402LF-499,1%,1/16W,CHIPA
     1 PVCCFA_EHV_CPU0 @S9S_MB_2U_LIB.S9S_MB_2U(SCH_1):PVCCFA_EHV_CPU0    I36 @S9S_MB_2U_LIB.S9S_MB_2U(SCH_1):PAGE262
     2    GND @S9S_MB_2U_LIB.S9S_MB_2U(SCH_1):GND    I36 @S9S_MB_2U_LIB.S9S_MB_2U(SCH_1):PAGE262

PR4230 Q_RES_0402LF-0,5%,1/16W,CHIP,CA
     1 NC_PVCCD_HV_CPU0_ACSP2 @S9S_MB_2U_LIB.S9S_MB_2U(SCH_1):NC_PVCCD_HV_CPU0_ACSP2    I74 @S9S_MB_2U_LIB.S9S_MB_2U(SCH_1):PAGE264
     2    GND @S9S_MB_2U_LIB.S9S_MB_2U(SCH_1):GND    I74 @S9S_MB_2U_LIB.S9S_MB_2U(SCH_1):PAGE264

PR4231 Q_RES_0402LF-0,5%,1/16W,CHIP,CA
     1 NC_PVCCD_HV_CPU0_ACSP3 @S9S_MB_2U_LIB.S9S_MB_2U(SCH_1):NC_PVCCD_HV_CPU0_ACSP3    I69 @S9S_MB_2U_LIB.S9S_MB_2U(SCH_1):PAGE264
     2    GND @S9S_MB_2U_LIB.S9S_MB_2U(SCH_1):GND    I69 @S9S_MB_2U_LIB.S9S_MB_2U(SCH_1):PAGE264

PR4232 Q_RES_0402LF-0,5%,1/16W,CHIP,CA
     1 NC_PVCCD_HV_CPU0_ACSP4 @S9S_MB_2U_LIB.S9S_MB_2U(SCH_1):NC_PVCCD_HV_CPU0_ACSP4    I68 @S9S_MB_2U_LIB.S9S_MB_2U(SCH_1):PAGE264
     2    GND @S9S_MB_2U_LIB.S9S_MB_2U(SCH_1):GND    I68 @S9S_MB_2U_LIB.S9S_MB_2U(SCH_1):PAGE264

PR4233 Q_RES_0402LF-0,5%,1/16W,CHIP,CA
     1 NC_PVCCD_HV_CPU0_ACSP5 @S9S_MB_2U_LIB.S9S_MB_2U(SCH_1):NC_PVCCD_HV_CPU0_ACSP5    I67 @S9S_MB_2U_LIB.S9S_MB_2U(SCH_1):PAGE264
     2    GND @S9S_MB_2U_LIB.S9S_MB_2U(SCH_1):GND    I67 @S9S_MB_2U_LIB.S9S_MB_2U(SCH_1):PAGE264

PR4234 Q_RES_0402LF-0,5%,1/16W,CHIP,CA
     1 NC_PVCCD_HV_CPU0_ACSP6 @S9S_MB_2U_LIB.S9S_MB_2U(SCH_1):NC_PVCCD_HV_CPU0_ACSP6    I66 @S9S_MB_2U_LIB.S9S_MB_2U(SCH_1):PAGE264
     2    GND @S9S_MB_2U_LIB.S9S_MB_2U(SCH_1):GND    I66 @S9S_MB_2U_LIB.S9S_MB_2U(SCH_1):PAGE264

PR4235 Q_RES_0402LF-0,5%,1/16W,CHIP,CA
     1 NC_PVCCD_HV_CPU0_ACSP7 @S9S_MB_2U_LIB.S9S_MB_2U(SCH_1):NC_PVCCD_HV_CPU0_ACSP7    I62 @S9S_MB_2U_LIB.S9S_MB_2U(SCH_1):PAGE264
     2    GND @S9S_MB_2U_LIB.S9S_MB_2U(SCH_1):GND    I62 @S9S_MB_2U_LIB.S9S_MB_2U(SCH_1):PAGE264

PR4236 Q_RES_0402LF-0,5%,1/16W,CHIP,CA
     1 NC_PVCCD_HV_CPU0_ACSP8 @S9S_MB_2U_LIB.S9S_MB_2U(SCH_1):NC_PVCCD_HV_CPU0_ACSP8    I61 @S9S_MB_2U_LIB.S9S_MB_2U(SCH_1):PAGE264
     2    GND @S9S_MB_2U_LIB.S9S_MB_2U(SCH_1):GND    I61 @S9S_MB_2U_LIB.S9S_MB_2U(SCH_1):PAGE264

PR4237 Q_RES_0402LF-499,1%,1/16W,CHIPA
     1 PVCCD_HV_CPU0 @S9S_MB_2U_LIB.S9S_MB_2U(SCH_1):PVCCD_HV_CPU0    I37 @S9S_MB_2U_LIB.S9S_MB_2U(SCH_1):PAGE265
     2    GND @S9S_MB_2U_LIB.S9S_MB_2U(SCH_1):GND    I37 @S9S_MB_2U_LIB.S9S_MB_2U(SCH_1):PAGE265

PR4238 Q_RES_0402LF-0,5%,1/16W,EMPTY,A
     1 PVCCFA_EHV_FIVRA_CPU1_IMON4 @S9S_MB_2U_LIB.S9S_MB_2U(SCH_1):PVCCFA_EHV_FIVRA_CPU1_IMON4    I81 @S9S_MB_2U_LIB.S9S_MB_2U(SCH_1):PAGE270
     2    GND @S9S_MB_2U_LIB.S9S_MB_2U(SCH_1):GND    I81 @S9S_MB_2U_LIB.S9S_MB_2U(SCH_1):PAGE270

PR4239 Q_RES_0402LF-0,5%,1/16W,EMPTY,A
     1 PVCCFA_EHV_FIVRA_CPU1_IMON3 @S9S_MB_2U_LIB.S9S_MB_2U(SCH_1):PVCCFA_EHV_FIVRA_CPU1_IMON3    I80 @S9S_MB_2U_LIB.S9S_MB_2U(SCH_1):PAGE270
     2    GND @S9S_MB_2U_LIB.S9S_MB_2U(SCH_1):GND    I80 @S9S_MB_2U_LIB.S9S_MB_2U(SCH_1):PAGE270

PR4240 Q_RES_0402LF-499,1%,1/16W,CHIPA
     1 PVCCIN_CPU1 @S9S_MB_2U_LIB.S9S_MB_2U(SCH_1):PVCCIN_CPU1    I59 @S9S_MB_2U_LIB.S9S_MB_2U(SCH_1):PAGE271
     2    GND @S9S_MB_2U_LIB.S9S_MB_2U(SCH_1):GND    I59 @S9S_MB_2U_LIB.S9S_MB_2U(SCH_1):PAGE271

PR4241 Q_RES_0402LF-499,1%,1/16W,CHIPA
     1 PVCCFA_EHV_FIVRA_CPU1 @S9S_MB_2U_LIB.S9S_MB_2U(SCH_1):PVCCFA_EHV_FIVRA_CPU1    I64 @S9S_MB_2U_LIB.S9S_MB_2U(SCH_1):PAGE275
     2    GND @S9S_MB_2U_LIB.S9S_MB_2U(SCH_1):GND    I64 @S9S_MB_2U_LIB.S9S_MB_2U(SCH_1):PAGE275

PR4242 Q_RES_0402LF-0,5%,1/16W,CHIP,CA
     1 NC_PVCCINFAON_CPU1_ACSP3 @S9S_MB_2U_LIB.S9S_MB_2U(SCH_1):NC_PVCCINFAON_CPU1_ACSP3    I89 @S9S_MB_2U_LIB.S9S_MB_2U(SCH_1):PAGE278
     2    GND @S9S_MB_2U_LIB.S9S_MB_2U(SCH_1):GND    I89 @S9S_MB_2U_LIB.S9S_MB_2U(SCH_1):PAGE278

PR4243 Q_RES_0402LF-0,5%,1/16W,CHIP,CA
     1 NC_PVCCINFAON_CPU1_ACSP4 @S9S_MB_2U_LIB.S9S_MB_2U(SCH_1):NC_PVCCINFAON_CPU1_ACSP4    I81 @S9S_MB_2U_LIB.S9S_MB_2U(SCH_1):PAGE278
     2    GND @S9S_MB_2U_LIB.S9S_MB_2U(SCH_1):GND    I81 @S9S_MB_2U_LIB.S9S_MB_2U(SCH_1):PAGE278

PR4244 Q_RES_0402LF-0,5%,1/16W,CHIP,CA
     1 NC_PVCCINFAON_CPU1_ACSP5 @S9S_MB_2U_LIB.S9S_MB_2U(SCH_1):NC_PVCCINFAON_CPU1_ACSP5    I80 @S9S_MB_2U_LIB.S9S_MB_2U(SCH_1):PAGE278
     2    GND @S9S_MB_2U_LIB.S9S_MB_2U(SCH_1):GND    I80 @S9S_MB_2U_LIB.S9S_MB_2U(SCH_1):PAGE278

PR4245 Q_RES_0402LF-0,5%,1/16W,CHIP,CA
     1 NC_PVCCINFAON_CPU1_ACSP6 @S9S_MB_2U_LIB.S9S_MB_2U(SCH_1):NC_PVCCINFAON_CPU1_ACSP6    I79 @S9S_MB_2U_LIB.S9S_MB_2U(SCH_1):PAGE278
     2    GND @S9S_MB_2U_LIB.S9S_MB_2U(SCH_1):GND    I79 @S9S_MB_2U_LIB.S9S_MB_2U(SCH_1):PAGE278

PR4246 Q_RES_0402LF-0,5%,1/16W,CHIP,CA
     1 NC_PVCCINFAON_CPU1_ACSP7 @S9S_MB_2U_LIB.S9S_MB_2U(SCH_1):NC_PVCCINFAON_CPU1_ACSP7    I78 @S9S_MB_2U_LIB.S9S_MB_2U(SCH_1):PAGE278
     2    GND @S9S_MB_2U_LIB.S9S_MB_2U(SCH_1):GND    I78 @S9S_MB_2U_LIB.S9S_MB_2U(SCH_1):PAGE278

PR4247 Q_RES_0402LF-499,1%,1/16W,CHIPA
     1 PVCCINFAON_CPU1 @S9S_MB_2U_LIB.S9S_MB_2U(SCH_1):PVCCINFAON_CPU1    I34 @S9S_MB_2U_LIB.S9S_MB_2U(SCH_1):PAGE279
     2    GND @S9S_MB_2U_LIB.S9S_MB_2U(SCH_1):GND    I34 @S9S_MB_2U_LIB.S9S_MB_2U(SCH_1):PAGE279

PR4248 Q_RES_0402LF-0,5%,1/16W,EMPTY,A
     1 PVCCFA_EHV_CPU1_NC2 @S9S_MB_2U_LIB.S9S_MB_2U(SCH_1):PVCCFA_EHV_CPU1_NC2    I13 @S9S_MB_2U_LIB.S9S_MB_2U(SCH_1):PAGE280
     2 PVCCFA_EHV_CPU1_VDD1 @S9S_MB_2U_LIB.S9S_MB_2U(SCH_1):PVCCFA_EHV_CPU1_VDD1    I13 @S9S_MB_2U_LIB.S9S_MB_2U(SCH_1):PAGE280

PR4249 Q_RES_0402LF-0,5%,1/16W,EMPTY,A
     1 PVCCFA_EHV_CPU1_FAULT @S9S_MB_2U_LIB.S9S_MB_2U(SCH_1):PVCCFA_EHV_CPU1_FAULT    I18 @S9S_MB_2U_LIB.S9S_MB_2U(SCH_1):PAGE280
     2    GND @S9S_MB_2U_LIB.S9S_MB_2U(SCH_1):GND    I18 @S9S_MB_2U_LIB.S9S_MB_2U(SCH_1):PAGE280

PR4250 Q_RES_0402LF-499,1%,1/16W,CHIPA
     1 PVCCFA_EHV_CPU1 @S9S_MB_2U_LIB.S9S_MB_2U(SCH_1):PVCCFA_EHV_CPU1    I37 @S9S_MB_2U_LIB.S9S_MB_2U(SCH_1):PAGE280
     2    GND @S9S_MB_2U_LIB.S9S_MB_2U(SCH_1):GND    I37 @S9S_MB_2U_LIB.S9S_MB_2U(SCH_1):PAGE280

PR4251 Q_RES_0402LF-0,5%,1/16W,CHIP,CA
     1 NC_PVCCD_HV_CPU1_ACSP2 @S9S_MB_2U_LIB.S9S_MB_2U(SCH_1):NC_PVCCD_HV_CPU1_ACSP2    I70 @S9S_MB_2U_LIB.S9S_MB_2U(SCH_1):PAGE282
     2    GND @S9S_MB_2U_LIB.S9S_MB_2U(SCH_1):GND    I70 @S9S_MB_2U_LIB.S9S_MB_2U(SCH_1):PAGE282

PR4252 Q_RES_0402LF-0,5%,1/16W,CHIP,CA
     1 NC_PVCCD_HV_CPU1_ACSP3 @S9S_MB_2U_LIB.S9S_MB_2U(SCH_1):NC_PVCCD_HV_CPU1_ACSP3    I64 @S9S_MB_2U_LIB.S9S_MB_2U(SCH_1):PAGE282
     2    GND @S9S_MB_2U_LIB.S9S_MB_2U(SCH_1):GND    I64 @S9S_MB_2U_LIB.S9S_MB_2U(SCH_1):PAGE282

PR4253 Q_RES_0402LF-0,5%,1/16W,CHIP,CA
     1 NC_PVCCD_HV_CPU1_ACSP4 @S9S_MB_2U_LIB.S9S_MB_2U(SCH_1):NC_PVCCD_HV_CPU1_ACSP4    I65 @S9S_MB_2U_LIB.S9S_MB_2U(SCH_1):PAGE282
     2    GND @S9S_MB_2U_LIB.S9S_MB_2U(SCH_1):GND    I65 @S9S_MB_2U_LIB.S9S_MB_2U(SCH_1):PAGE282

PR4254 Q_RES_0402LF-0,5%,1/16W,CHIP,CA
     1 NC_PVCCD_HV_CPU1_ACSP5 @S9S_MB_2U_LIB.S9S_MB_2U(SCH_1):NC_PVCCD_HV_CPU1_ACSP5    I66 @S9S_MB_2U_LIB.S9S_MB_2U(SCH_1):PAGE282
     2    GND @S9S_MB_2U_LIB.S9S_MB_2U(SCH_1):GND    I66 @S9S_MB_2U_LIB.S9S_MB_2U(SCH_1):PAGE282

PR4255 Q_RES_0402LF-0,5%,1/16W,CHIP,CA
     1 NC_PVCCD_HV_CPU1_ACSP6 @S9S_MB_2U_LIB.S9S_MB_2U(SCH_1):NC_PVCCD_HV_CPU1_ACSP6    I62 @S9S_MB_2U_LIB.S9S_MB_2U(SCH_1):PAGE282
     2    GND @S9S_MB_2U_LIB.S9S_MB_2U(SCH_1):GND    I62 @S9S_MB_2U_LIB.S9S_MB_2U(SCH_1):PAGE282

PR4256 Q_RES_0402LF-0,5%,1/16W,CHIP,CA
     1 NC_PVCCD_HV_CPU1_ACSP7 @S9S_MB_2U_LIB.S9S_MB_2U(SCH_1):NC_PVCCD_HV_CPU1_ACSP7    I63 @S9S_MB_2U_LIB.S9S_MB_2U(SCH_1):PAGE282
     2    GND @S9S_MB_2U_LIB.S9S_MB_2U(SCH_1):GND    I63 @S9S_MB_2U_LIB.S9S_MB_2U(SCH_1):PAGE282

PR4257 Q_RES_0402LF-0,5%,1/16W,CHIP,CA
     1 NC_PVCCD_HV_CPU1_ACSP8 @S9S_MB_2U_LIB.S9S_MB_2U(SCH_1):NC_PVCCD_HV_CPU1_ACSP8    I59 @S9S_MB_2U_LIB.S9S_MB_2U(SCH_1):PAGE282
     2    GND @S9S_MB_2U_LIB.S9S_MB_2U(SCH_1):GND    I59 @S9S_MB_2U_LIB.S9S_MB_2U(SCH_1):PAGE282

PR4258 Q_RES_0402LF-499,1%,1/16W,CHIPA
     1 PVCCD_HV_CPU1 @S9S_MB_2U_LIB.S9S_MB_2U(SCH_1):PVCCD_HV_CPU1    I35 @S9S_MB_2U_LIB.S9S_MB_2U(SCH_1):PAGE283
     2    GND @S9S_MB_2U_LIB.S9S_MB_2U(SCH_1):GND    I35 @S9S_MB_2U_LIB.S9S_MB_2U(SCH_1):PAGE283

PR4265 Q_RES_0402LF-499,1%,1/16W,CHIPA
     1 PVCCFA_EHV_FIVRA_CPU0 @S9S_MB_2U_LIB.S9S_MB_2U(SCH_1):PVCCFA_EHV_FIVRA_CPU0    I60 @S9S_MB_2U_LIB.S9S_MB_2U(SCH_1):PAGE257
     2    GND @S9S_MB_2U_LIB.S9S_MB_2U(SCH_1):GND    I60 @S9S_MB_2U_LIB.S9S_MB_2U(SCH_1):PAGE257

PR4271 Q_RES_0402LF-0,5%,1/16W,CHIP,CA
     1 SW_PVNN_MAIN_CPU0_BST @S9S_MB_2U_LIB.S9S_MB_2U(SCH_1):SW_PVNN_MAIN_CPU0_BST    I27 @S9S_MB_2U_LIB.S9S_MB_2U(SCH_1):PAGE268
     2 SW_PVNN_MAIN_CPU0_BST_R @S9S_MB_2U_LIB.S9S_MB_2U(SCH_1):SW_PVNN_MAIN_CPU0_BST_R    I27 @S9S_MB_2U_LIB.S9S_MB_2U(SCH_1):PAGE268

PR4272 Q_RES_0402LF-0,5%,1/16W,CHIP,CA
     1 SW_PVNN_MAIN_CPU1_BST @S9S_MB_2U_LIB.S9S_MB_2U(SCH_1):SW_PVNN_MAIN_CPU1_BST    I25 @S9S_MB_2U_LIB.S9S_MB_2U(SCH_1):PAGE286
     2 SW_PVNN_MAIN_CPU1_BST_R @S9S_MB_2U_LIB.S9S_MB_2U(SCH_1):SW_PVNN_MAIN_CPU1_BST_R    I25 @S9S_MB_2U_LIB.S9S_MB_2U(SCH_1):PAGE286

PR4522 Q_RES_0402LF-10M,1%,1/16W,EMPTA
     1 P12V_OCP_V3_2 @S9S_MB_2U_LIB.S9S_MB_2U(SCH_1):P12V_OCP_V3_2    I77 @S9S_MB_2U_LIB.S9S_MB_2U(SCH_1):PAGE131
     2 P12V_OCP_GATE_2 @S9S_MB_2U_LIB.S9S_MB_2U(SCH_1):P12V_OCP_GATE_2    I77 @S9S_MB_2U_LIB.S9S_MB_2U(SCH_1):PAGE131

PR4523 Q_RES_0402LF-10M,1%,1/16W,CHIPA
     1 P3V3_OCP_V3_2_R @S9S_MB_2U_LIB.S9S_MB_2U(SCH_1):P3V3_OCP_V3_2_R   I106 @S9S_MB_2U_LIB.S9S_MB_2U(SCH_1):PAGE131
     2 P3V3_OCP_GATE_2 @S9S_MB_2U_LIB.S9S_MB_2U(SCH_1):P3V3_OCP_GATE_2   I106 @S9S_MB_2U_LIB.S9S_MB_2U(SCH_1):PAGE131

PR4524 Q_RES_0402LF-10M,1%,1/16W,EMPTA
     1 P12V_OCP_SFF @S9S_MB_2U_LIB.S9S_MB_2U(SCH_1):P12V_OCP_SFF    I84 @S9S_MB_2U_LIB.S9S_MB_2U(SCH_1):PAGE153
     2 P12V_OCP_GATE_1 @S9S_MB_2U_LIB.S9S_MB_2U(SCH_1):P12V_OCP_GATE_1    I84 @S9S_MB_2U_LIB.S9S_MB_2U(SCH_1):PAGE153

PR4525 Q_RES_0402LF-10M,1%,1/16W,CHIPA
     1 P3V3_OCP_SFF_R @S9S_MB_2U_LIB.S9S_MB_2U(SCH_1):P3V3_OCP_SFF_R   I103 @S9S_MB_2U_LIB.S9S_MB_2U(SCH_1):PAGE153
     2 P3V3_OCP_GATE_PU202_1 @S9S_MB_2U_LIB.S9S_MB_2U(SCH_1):P3V3_OCP_GATE_PU202_1   I103 @S9S_MB_2U_LIB.S9S_MB_2U(SCH_1):PAGE153

PR4526 Q_RES_0402LF-10M,1%,1/16W,EMPTA
     1 P12V_SCM_R @S9S_MB_2U_LIB.S9S_MB_2U(SCH_1):P12V_SCM_R    I76 @S9S_MB_2U_LIB.S9S_MB_2U(SCH_1):PAGE229
     2 P12V_SCM_GATE @S9S_MB_2U_LIB.S9S_MB_2U(SCH_1):P12V_SCM_GATE    I76 @S9S_MB_2U_LIB.S9S_MB_2U(SCH_1):PAGE229

PR4527 Q_RES_0402LF-10M,1%,1/16W,CHIPA
     1 P3V3_E1S_0_R @S9S_MB_2U_LIB.S9S_MB_2U(SCH_1):P3V3_E1S_0_R    I43 @S9S_MB_2U_LIB.S9S_MB_2U(SCH_1):PAGE324
     2 P3V3_E1S_GATE_0 @S9S_MB_2U_LIB.S9S_MB_2U(SCH_1):P3V3_E1S_GATE_0    I43 @S9S_MB_2U_LIB.S9S_MB_2U(SCH_1):PAGE324

PR4528 Q_RES_0402LF-10M,1%,1/16W,EMPTA
     1 P12V_E1S_0 @S9S_MB_2U_LIB.S9S_MB_2U(SCH_1):P12V_E1S_0    I70 @S9S_MB_2U_LIB.S9S_MB_2U(SCH_1):PAGE324
     2 P12V_E1S_GATE_0 @S9S_MB_2U_LIB.S9S_MB_2U(SCH_1):P12V_E1S_GATE_0    I70 @S9S_MB_2U_LIB.S9S_MB_2U(SCH_1):PAGE324

PR4540 Q_RES_0402LF-20K,1%,1/16W,CHIPA
     1 P12V_SCM_ISET @S9S_MB_2U_LIB.S9S_MB_2U(SCH_1):P12V_SCM_ISET    I12 @S9S_MB_2U_LIB.S9S_MB_2U(SCH_1):PAGE229
     2 P12V_SCM_ISET_R @S9S_MB_2U_LIB.S9S_MB_2U(SCH_1):P12V_SCM_ISET_R    I12 @S9S_MB_2U_LIB.S9S_MB_2U(SCH_1):PAGE229

PR4541 Q_RES_0402LF-20K,1%,1/16W,CHIPA
     1 P12V_E1S_ISET_0 @S9S_MB_2U_LIB.S9S_MB_2U(SCH_1):P12V_E1S_ISET_0    I43 @S9S_MB_2U_LIB.S9S_MB_2U(SCH_1):PAGE323
     2 P12V_E1S_ISET_0_R @S9S_MB_2U_LIB.S9S_MB_2U(SCH_1):P12V_E1S_ISET_0_R    I43 @S9S_MB_2U_LIB.S9S_MB_2U(SCH_1):PAGE323

PR4683 Q_RES_0402LF-0,5%,1/16W,CHIP,CA
     1 PVNN_MAIN_CPU0_FB_RC @S9S_MB_2U_LIB.S9S_MB_2U(SCH_1):PVNN_MAIN_CPU0_FB_RC    I41 @S9S_MB_2U_LIB.S9S_MB_2U(SCH_1):PAGE268
     2 PVNN_MAIN_CPU0 @S9S_MB_2U_LIB.S9S_MB_2U(SCH_1):PVNN_MAIN_CPU0    I41 @S9S_MB_2U_LIB.S9S_MB_2U(SCH_1):PAGE268

PR4698 Q_RES_0402LF-0,5%,1/16W,EMPTY,A
     1 PVNN_MAIN_CPU0_FB_RC @S9S_MB_2U_LIB.S9S_MB_2U(SCH_1):PVNN_MAIN_CPU0_FB_RC    I40 @S9S_MB_2U_LIB.S9S_MB_2U(SCH_1):PAGE268
     2 PVNN_MAIN_CPU0 @S9S_MB_2U_LIB.S9S_MB_2U(SCH_1):PVNN_MAIN_CPU0    I40 @S9S_MB_2U_LIB.S9S_MB_2U(SCH_1):PAGE268

PR4699 Q_RES_0402LF-0,5%,1/16W,CHIP,CA
     1 PVNN_MAIN_CPU1_FB_RC @S9S_MB_2U_LIB.S9S_MB_2U(SCH_1):PVNN_MAIN_CPU1_FB_RC    I43 @S9S_MB_2U_LIB.S9S_MB_2U(SCH_1):PAGE286
     2 PVNN_MAIN_CPU1 @S9S_MB_2U_LIB.S9S_MB_2U(SCH_1):PVNN_MAIN_CPU1    I43 @S9S_MB_2U_LIB.S9S_MB_2U(SCH_1):PAGE286

PR4700 Q_RES_0402LF-0,5%,1/16W,EMPTY,A
     1 PVNN_MAIN_CPU1_FB_RC @S9S_MB_2U_LIB.S9S_MB_2U(SCH_1):PVNN_MAIN_CPU1_FB_RC    I42 @S9S_MB_2U_LIB.S9S_MB_2U(SCH_1):PAGE286
     2 PVNN_MAIN_CPU1 @S9S_MB_2U_LIB.S9S_MB_2U(SCH_1):PVNN_MAIN_CPU1    I42 @S9S_MB_2U_LIB.S9S_MB_2U(SCH_1):PAGE286

PR5481 Q_RES_0402LF-4.53K,1%,1/16W,CHA
     1 P3V3_OCP_SENSE_1 @S9S_MB_2U_LIB.S9S_MB_2U(SCH_1):P3V3_OCP_SENSE_1   I102 @S9S_MB_2U_LIB.S9S_MB_2U(SCH_1):PAGE153
     2    GND @S9S_MB_2U_LIB.S9S_MB_2U(SCH_1):GND   I102 @S9S_MB_2U_LIB.S9S_MB_2U(SCH_1):PAGE153

PR5484 Q_RES_0402LF-30.1K,1%,1/16W,EMA
     1 P12V_OCP_CB_1 @S9S_MB_2U_LIB.S9S_MB_2U(SCH_1):P12V_OCP_CB_1    I49 @S9S_MB_2U_LIB.S9S_MB_2U(SCH_1):PAGE153
     2    GND @S9S_MB_2U_LIB.S9S_MB_2U(SCH_1):GND    I49 @S9S_MB_2U_LIB.S9S_MB_2U(SCH_1):PAGE153

 PU5 ISL69260IRAZT-ISL69260IRAZ-T,SA
    23 PVCCINFAON_CPU0_ACSP1 @S9S_MB_2U_LIB.S9S_MB_2U(SCH_1):PVCCINFAON_CPU0_ACSP1    I65 @S9S_MB_2U_LIB.S9S_MB_2U(SCH_1):PAGE260
    39 PVCCINFAON_CPU0_VCC @S9S_MB_2U_LIB.S9S_MB_2U(SCH_1):PVCCINFAON_CPU0_VCC    I65 @S9S_MB_2U_LIB.S9S_MB_2U(SCH_1):PAGE260
    20 PVCCFA_EHV_CPU0_EN_R @S9S_MB_2U_LIB.S9S_MB_2U(SCH_1):PVCCFA_EHV_CPU0_EN_R    I65 @S9S_MB_2U_LIB.S9S_MB_2U(SCH_1):PAGE260
    10 SMB_CLK_PVCCINFAON_CPU0 @S9S_MB_2U_LIB.S9S_MB_2U(SCH_1):SMB_CLK_PVCCINFAON_CPU0    I65 @S9S_MB_2U_LIB.S9S_MB_2U(SCH_1):PAGE260
    18 SVID_DIO_PVCCINFAON_CPU0_R @S9S_MB_2U_LIB.S9S_MB_2U(SCH_1):SVID_DIO_PVCCINFAON_CPU0_R    I65 @S9S_MB_2U_LIB.S9S_MB_2U(SCH_1):PAGE260
    24 PVCCINFAON_CPU0_ACSP2 @S9S_MB_2U_LIB.S9S_MB_2U(SCH_1):PVCCINFAON_CPU0_ACSP2    I65 @S9S_MB_2U_LIB.S9S_MB_2U(SCH_1):PAGE260
    19 SVID_ALERT_PVCCINFAON_CPU0_R @S9S_MB_2U_LIB.S9S_MB_2U(SCH_1):SVID_ALERT_PVCCINFAON_CPU0_R    I65 @S9S_MB_2U_LIB.S9S_MB_2U(SCH_1):PAGE260
    14 IRQ_PVCCFA_CPU0_VRHOT_N @S9S_MB_2U_LIB.S9S_MB_2U(SCH_1):IRQ_PVCCFA_CPU0_VRHOT_N    I65 @S9S_MB_2U_LIB.S9S_MB_2U(SCH_1):PAGE260
    25 NC_PVCCINFAON_CPU0_ACSP3 @S9S_MB_2U_LIB.S9S_MB_2U(SCH_1):NC_PVCCINFAON_CPU0_ACSP3    I65 @S9S_MB_2U_LIB.S9S_MB_2U(SCH_1):PAGE260
    26 NC_PVCCINFAON_CPU0_ACSP4 @S9S_MB_2U_LIB.S9S_MB_2U(SCH_1):NC_PVCCINFAON_CPU0_ACSP4    I65 @S9S_MB_2U_LIB.S9S_MB_2U(SCH_1):PAGE260
    16 PWRGD_PVCCFA_EHV_CPU0_R @S9S_MB_2U_LIB.S9S_MB_2U(SCH_1):PWRGD_PVCCFA_EHV_CPU0_R    I65 @S9S_MB_2U_LIB.S9S_MB_2U(SCH_1):PAGE260
    17 SVID_CLK_PVCCINFAON_CPU0_R @S9S_MB_2U_LIB.S9S_MB_2U(SCH_1):SVID_CLK_PVCCINFAON_CPU0_R    I65 @S9S_MB_2U_LIB.S9S_MB_2U(SCH_1):PAGE260
    11 NC_PVCCINFAON_CPU0_SMB_ALERT @S9S_MB_2U_LIB.S9S_MB_2U(SCH_1):NC_PVCCINFAON_CPU0_SMB_ALERT    I65 @S9S_MB_2U_LIB.S9S_MB_2U(SCH_1):PAGE260
    13 PVCCINFAON_CPU0_EN_R @S9S_MB_2U_LIB.S9S_MB_2U(SCH_1):PVCCINFAON_CPU0_EN_R    I65 @S9S_MB_2U_LIB.S9S_MB_2U(SCH_1):PAGE260
    22 VSENSE_PVCCINFAON_CPU0_DN @S9S_MB_2U_LIB.S9S_MB_2U(SCH_1):VSENSE_PVCCINFAON_CPU0_DN    I65 @S9S_MB_2U_LIB.S9S_MB_2U(SCH_1):PAGE260
     9 SMB_DIO_PVCCINFAON_CPU0 @S9S_MB_2U_LIB.S9S_MB_2U(SCH_1):SMB_DIO_PVCCINFAON_CPU0    I65 @S9S_MB_2U_LIB.S9S_MB_2U(SCH_1):PAGE260
     5 NC_PVCCINFAON_CPU0_APWM4 @S9S_MB_2U_LIB.S9S_MB_2U(SCH_1):NC_PVCCINFAON_CPU0_APWM4    I65 @S9S_MB_2U_LIB.S9S_MB_2U(SCH_1):PAGE260
     6 NC_PVCCINFAON_CPU0_APWM3 @S9S_MB_2U_LIB.S9S_MB_2U(SCH_1):NC_PVCCINFAON_CPU0_APWM3    I65 @S9S_MB_2U_LIB.S9S_MB_2U(SCH_1):PAGE260
    21 SH_PVCCINFAON_CPU0_R @S9S_MB_2U_LIB.S9S_MB_2U(SCH_1):SH_PVCCINFAON_CPU0_R    I65 @S9S_MB_2U_LIB.S9S_MB_2U(SCH_1):PAGE260
     2 NC_PVCCINFAON_CPU0_APWM7 @S9S_MB_2U_LIB.S9S_MB_2U(SCH_1):NC_PVCCINFAON_CPU0_APWM7    I65 @S9S_MB_2U_LIB.S9S_MB_2U(SCH_1):PAGE260
    12 PWRGD_PVCCINFAON_CPU0_R @S9S_MB_2U_LIB.S9S_MB_2U(SCH_1):PWRGD_PVCCINFAON_CPU0_R    I65 @S9S_MB_2U_LIB.S9S_MB_2U(SCH_1):PAGE260
     7 PVCCINFAON_CPU0_APWM2 @S9S_MB_2U_LIB.S9S_MB_2U(SCH_1):PVCCINFAON_CPU0_APWM2    I65 @S9S_MB_2U_LIB.S9S_MB_2U(SCH_1):PAGE260
    40 PVCCINFAON_CPU0_VREF @S9S_MB_2U_LIB.S9S_MB_2U(SCH_1):PVCCINFAON_CPU0_VREF    I65 @S9S_MB_2U_LIB.S9S_MB_2U(SCH_1):PAGE260
    37 PVCCINFAON_CPU0_CSPIN @S9S_MB_2U_LIB.S9S_MB_2U(SCH_1):PVCCINFAON_CPU0_CSPIN    I65 @S9S_MB_2U_LIB.S9S_MB_2U(SCH_1):PAGE260
    38 PVCCINFAON_CPU0_VIN_CSNIN @S9S_MB_2U_LIB.S9S_MB_2U(SCH_1):PVCCINFAON_CPU0_VIN_CSNIN    I65 @S9S_MB_2U_LIB.S9S_MB_2U(SCH_1):PAGE260
    36 PVCCFA_EHV_CPU0_BTSEN @S9S_MB_2U_LIB.S9S_MB_2U(SCH_1):PVCCFA_EHV_CPU0_BTSEN    I65 @S9S_MB_2U_LIB.S9S_MB_2U(SCH_1):PAGE260
    15 PVCCINFAON_CPU0_PIN_ALERT @S9S_MB_2U_LIB.S9S_MB_2U(SCH_1):PVCCINFAON_CPU0_PIN_ALERT    I65 @S9S_MB_2U_LIB.S9S_MB_2U(SCH_1):PAGE260
    32 SH_PVCCFA_EHV_CPU0_R @S9S_MB_2U_LIB.S9S_MB_2U(SCH_1):SH_PVCCFA_EHV_CPU0_R    I65 @S9S_MB_2U_LIB.S9S_MB_2U(SCH_1):PAGE260
    31 VSENSE_PVCCFA_EHV_CPU0_DN @S9S_MB_2U_LIB.S9S_MB_2U(SCH_1):VSENSE_PVCCFA_EHV_CPU0_DN    I65 @S9S_MB_2U_LIB.S9S_MB_2U(SCH_1):PAGE260
    29 NC_PVCCINFAON_CPU0_ACSP7 @S9S_MB_2U_LIB.S9S_MB_2U(SCH_1):NC_PVCCINFAON_CPU0_ACSP7    I65 @S9S_MB_2U_LIB.S9S_MB_2U(SCH_1):PAGE260
     8 PVCCINFAON_CPU0_APWM1 @S9S_MB_2U_LIB.S9S_MB_2U(SCH_1):PVCCINFAON_CPU0_APWM1    I65 @S9S_MB_2U_LIB.S9S_MB_2U(SCH_1):PAGE260
     4 NC_PVCCINFAON_CPU0_APWM5 @S9S_MB_2U_LIB.S9S_MB_2U(SCH_1):NC_PVCCINFAON_CPU0_APWM5    I65 @S9S_MB_2U_LIB.S9S_MB_2U(SCH_1):PAGE260
    27 NC_PVCCINFAON_CPU0_ACSP5 @S9S_MB_2U_LIB.S9S_MB_2U(SCH_1):NC_PVCCINFAON_CPU0_ACSP5    I65 @S9S_MB_2U_LIB.S9S_MB_2U(SCH_1):PAGE260
     3 NC_PVCCINFAON_CPU0_APWM6 @S9S_MB_2U_LIB.S9S_MB_2U(SCH_1):NC_PVCCINFAON_CPU0_APWM6    I65 @S9S_MB_2U_LIB.S9S_MB_2U(SCH_1):PAGE260
    28 NC_PVCCINFAON_CPU0_ACSP6 @S9S_MB_2U_LIB.S9S_MB_2U(SCH_1):NC_PVCCINFAON_CPU0_ACSP6    I65 @S9S_MB_2U_LIB.S9S_MB_2U(SCH_1):PAGE260
    33 PVCCINFAON_CPU0_VR_FAULT @S9S_MB_2U_LIB.S9S_MB_2U(SCH_1):PVCCINFAON_CPU0_VR_FAULT    I65 @S9S_MB_2U_LIB.S9S_MB_2U(SCH_1):PAGE260
    TH    GND @S9S_MB_2U_LIB.S9S_MB_2U(SCH_1):GND    I65 @S9S_MB_2U_LIB.S9S_MB_2U(SCH_1):PAGE260
    34 PVCCINFAON_CPU0_ADDR @S9S_MB_2U_LIB.S9S_MB_2U(SCH_1):PVCCINFAON_CPU0_ADDR    I65 @S9S_MB_2U_LIB.S9S_MB_2U(SCH_1):PAGE260
    35 PVCCINFAON_CPU0_ATSEN @S9S_MB_2U_LIB.S9S_MB_2U(SCH_1):PVCCINFAON_CPU0_ATSEN    I65 @S9S_MB_2U_LIB.S9S_MB_2U(SCH_1):PAGE260
     1 PVCCFA_EHV_CPU0_BPWM1 @S9S_MB_2U_LIB.S9S_MB_2U(SCH_1):PVCCFA_EHV_CPU0_BPWM1    I65 @S9S_MB_2U_LIB.S9S_MB_2U(SCH_1):PAGE260
    30 PVCCFA_EHV_CPU0_BCSP1 @S9S_MB_2U_LIB.S9S_MB_2U(SCH_1):PVCCFA_EHV_CPU0_BCSP1    I65 @S9S_MB_2U_LIB.S9S_MB_2U(SCH_1):PAGE260

PU6_P0_8 ISL99390FRZTR5935-ISL99390FRZ-A
    34 PVCCIN_CPU0_PWM8 @S9S_MB_2U_LIB.S9S_MB_2U(SCH_1):PVCCIN_CPU0_PWM8     I2 @S9S_MB_2U_LIB.S9S_MB_2U(SCH_1):PAGE256
    39 PVCCIN_CPU0_VREF @S9S_MB_2U_LIB.S9S_MB_2U(SCH_1):PVCCIN_CPU0_VREF     I2 @S9S_MB_2U_LIB.S9S_MB_2U(SCH_1):PAGE256
     3 PVCCIN_CPU0_VDD8 @S9S_MB_2U_LIB.S9S_MB_2U(SCH_1):PVCCIN_CPU0_VDD8     I2 @S9S_MB_2U_LIB.S9S_MB_2U(SCH_1):PAGE256
     2    GND @S9S_MB_2U_LIB.S9S_MB_2U(SCH_1):GND     I2 @S9S_MB_2U_LIB.S9S_MB_2U(SCH_1):PAGE256
    33 SW_PVCCIN_CPU0_BOOT8 @S9S_MB_2U_LIB.S9S_MB_2U(SCH_1):SW_PVCCIN_CPU0_BOOT8     I2 @S9S_MB_2U_LIB.S9S_MB_2U(SCH_1):PAGE256
 25_29 SW_P12V_PVCCIN_CPU0_FLT @S9S_MB_2U_LIB.S9S_MB_2U(SCH_1):SW_P12V_PVCCIN_CPU0_FLT     I2 @S9S_MB_2U_LIB.S9S_MB_2U(SCH_1):PAGE256
    32 SW_PVCCIN_CPU0_BOOTR8 @S9S_MB_2U_LIB.S9S_MB_2U(SCH_1):SW_PVCCIN_CPU0_BOOTR8     I2 @S9S_MB_2U_LIB.S9S_MB_2U(SCH_1):PAGE256
     4 PVCCIN_CPU0_PVCC @S9S_MB_2U_LIB.S9S_MB_2U(SCH_1):PVCCIN_CPU0_PVCC     I2 @S9S_MB_2U_LIB.S9S_MB_2U(SCH_1):PAGE256
    36 PVCCIN_CPU0_ATSEN @S9S_MB_2U_LIB.S9S_MB_2U(SCH_1):PVCCIN_CPU0_ATSEN     I2 @S9S_MB_2U_LIB.S9S_MB_2U(SCH_1):PAGE256
    38 PVCCIN_CPU0_IMON8 @S9S_MB_2U_LIB.S9S_MB_2U(SCH_1):PVCCIN_CPU0_IMON8     I2 @S9S_MB_2U_LIB.S9S_MB_2U(SCH_1):PAGE256
    37 PVCCIN_CPU0_LSET8 @S9S_MB_2U_LIB.S9S_MB_2U(SCH_1):PVCCIN_CPU0_LSET8     I2 @S9S_MB_2U_LIB.S9S_MB_2U(SCH_1):PAGE256
 10_19 SW_PVCCIN_CPU0_SW8 @S9S_MB_2U_LIB.S9S_MB_2U(SCH_1):SW_PVCCIN_CPU0_SW8     I2 @S9S_MB_2U_LIB.S9S_MB_2U(SCH_1):PAGE256
     5    GND @S9S_MB_2U_LIB.S9S_MB_2U(SCH_1):GND     I2 @S9S_MB_2U_LIB.S9S_MB_2U(SCH_1):PAGE256
    30 SW_P12V_PVCCIN_CPU0_FLT @S9S_MB_2U_LIB.S9S_MB_2U(SCH_1):SW_P12V_PVCCIN_CPU0_FLT     I2 @S9S_MB_2U_LIB.S9S_MB_2U(SCH_1):PAGE256
     1 PVCCIN_CPU0_VOS8 @S9S_MB_2U_LIB.S9S_MB_2U(SCH_1):PVCCIN_CPU0_VOS8     I2 @S9S_MB_2U_LIB.S9S_MB_2U(SCH_1):PAGE256
    40    GND @S9S_MB_2U_LIB.S9S_MB_2U(SCH_1):GND     I2 @S9S_MB_2U_LIB.S9S_MB_2U(SCH_1):PAGE256
    35 PVCCIN_CPU0_VDD8 @S9S_MB_2U_LIB.S9S_MB_2U(SCH_1):PVCCIN_CPU0_VDD8     I2 @S9S_MB_2U_LIB.S9S_MB_2U(SCH_1):PAGE256
    31     NC     NC     I2 @S9S_MB_2U_LIB.S9S_MB_2U(SCH_1):PAGE256
     6     NC     NC     I2 @S9S_MB_2U_LIB.S9S_MB_2U(SCH_1):PAGE256
    41     NC     NC     I2 @S9S_MB_2U_LIB.S9S_MB_2U(SCH_1):PAGE256
7_9-20_24    GND @S9S_MB_2U_LIB.S9S_MB_2U(SCH_1):GND     I2 @S9S_MB_2U_LIB.S9S_MB_2U(SCH_1):PAGE256

PU7_P0_7 ISL99390FRZTR5935-ISL99390FRZ-A
    34 PVCCIN_CPU0_PWM7 @S9S_MB_2U_LIB.S9S_MB_2U(SCH_1):PVCCIN_CPU0_PWM7    I32 @S9S_MB_2U_LIB.S9S_MB_2U(SCH_1):PAGE256
    39 PVCCIN_CPU0_VREF @S9S_MB_2U_LIB.S9S_MB_2U(SCH_1):PVCCIN_CPU0_VREF    I32 @S9S_MB_2U_LIB.S9S_MB_2U(SCH_1):PAGE256
     3 PVCCIN_CPU0_VDD7 @S9S_MB_2U_LIB.S9S_MB_2U(SCH_1):PVCCIN_CPU0_VDD7    I32 @S9S_MB_2U_LIB.S9S_MB_2U(SCH_1):PAGE256
     2    GND @S9S_MB_2U_LIB.S9S_MB_2U(SCH_1):GND    I32 @S9S_MB_2U_LIB.S9S_MB_2U(SCH_1):PAGE256
    33 SW_PVCCIN_CPU0_BOOT7 @S9S_MB_2U_LIB.S9S_MB_2U(SCH_1):SW_PVCCIN_CPU0_BOOT7    I32 @S9S_MB_2U_LIB.S9S_MB_2U(SCH_1):PAGE256
 25_29 SW_P12V_PVCCIN_CPU0_FLT @S9S_MB_2U_LIB.S9S_MB_2U(SCH_1):SW_P12V_PVCCIN_CPU0_FLT    I32 @S9S_MB_2U_LIB.S9S_MB_2U(SCH_1):PAGE256
    32 SW_PVCCIN_CPU0_BOOTR7 @S9S_MB_2U_LIB.S9S_MB_2U(SCH_1):SW_PVCCIN_CPU0_BOOTR7    I32 @S9S_MB_2U_LIB.S9S_MB_2U(SCH_1):PAGE256
     4 PVCCIN_CPU0_PVCC @S9S_MB_2U_LIB.S9S_MB_2U(SCH_1):PVCCIN_CPU0_PVCC    I32 @S9S_MB_2U_LIB.S9S_MB_2U(SCH_1):PAGE256
    36 PVCCIN_CPU0_ATSEN @S9S_MB_2U_LIB.S9S_MB_2U(SCH_1):PVCCIN_CPU0_ATSEN    I32 @S9S_MB_2U_LIB.S9S_MB_2U(SCH_1):PAGE256
    38 PVCCIN_CPU0_IMON7 @S9S_MB_2U_LIB.S9S_MB_2U(SCH_1):PVCCIN_CPU0_IMON7    I32 @S9S_MB_2U_LIB.S9S_MB_2U(SCH_1):PAGE256
    37 PVCCIN_CPU0_LSET7 @S9S_MB_2U_LIB.S9S_MB_2U(SCH_1):PVCCIN_CPU0_LSET7    I32 @S9S_MB_2U_LIB.S9S_MB_2U(SCH_1):PAGE256
 10_19 SW_PVCCIN_CPU0_SW7 @S9S_MB_2U_LIB.S9S_MB_2U(SCH_1):SW_PVCCIN_CPU0_SW7    I32 @S9S_MB_2U_LIB.S9S_MB_2U(SCH_1):PAGE256
     5    GND @S9S_MB_2U_LIB.S9S_MB_2U(SCH_1):GND    I32 @S9S_MB_2U_LIB.S9S_MB_2U(SCH_1):PAGE256
    30 SW_P12V_PVCCIN_CPU0_FLT @S9S_MB_2U_LIB.S9S_MB_2U(SCH_1):SW_P12V_PVCCIN_CPU0_FLT    I32 @S9S_MB_2U_LIB.S9S_MB_2U(SCH_1):PAGE256
     1 PVCCIN_CPU0_VOS7 @S9S_MB_2U_LIB.S9S_MB_2U(SCH_1):PVCCIN_CPU0_VOS7    I32 @S9S_MB_2U_LIB.S9S_MB_2U(SCH_1):PAGE256
    40    GND @S9S_MB_2U_LIB.S9S_MB_2U(SCH_1):GND    I32 @S9S_MB_2U_LIB.S9S_MB_2U(SCH_1):PAGE256
    35 PVCCIN_CPU0_VDD7 @S9S_MB_2U_LIB.S9S_MB_2U(SCH_1):PVCCIN_CPU0_VDD7    I32 @S9S_MB_2U_LIB.S9S_MB_2U(SCH_1):PAGE256
    31     NC     NC    I32 @S9S_MB_2U_LIB.S9S_MB_2U(SCH_1):PAGE256
     6     NC     NC    I32 @S9S_MB_2U_LIB.S9S_MB_2U(SCH_1):PAGE256
    41     NC     NC    I32 @S9S_MB_2U_LIB.S9S_MB_2U(SCH_1):PAGE256
7_9-20_24    GND @S9S_MB_2U_LIB.S9S_MB_2U(SCH_1):GND    I32 @S9S_MB_2U_LIB.S9S_MB_2U(SCH_1):PAGE256

PU8_P0_6 ISL99390FRZTR5935-ISL99390FRZ-A
    34 PVCCIN_CPU0_PWM6 @S9S_MB_2U_LIB.S9S_MB_2U(SCH_1):PVCCIN_CPU0_PWM6    I12 @S9S_MB_2U_LIB.S9S_MB_2U(SCH_1):PAGE255
    39 PVCCIN_CPU0_VREF @S9S_MB_2U_LIB.S9S_MB_2U(SCH_1):PVCCIN_CPU0_VREF    I12 @S9S_MB_2U_LIB.S9S_MB_2U(SCH_1):PAGE255
     3 PVCCIN_CPU0_VDD6 @S9S_MB_2U_LIB.S9S_MB_2U(SCH_1):PVCCIN_CPU0_VDD6    I12 @S9S_MB_2U_LIB.S9S_MB_2U(SCH_1):PAGE255
     2    GND @S9S_MB_2U_LIB.S9S_MB_2U(SCH_1):GND    I12 @S9S_MB_2U_LIB.S9S_MB_2U(SCH_1):PAGE255
    33 SW_PVCCIN_CPU0_BOOT6 @S9S_MB_2U_LIB.S9S_MB_2U(SCH_1):SW_PVCCIN_CPU0_BOOT6    I12 @S9S_MB_2U_LIB.S9S_MB_2U(SCH_1):PAGE255
 25_29 SW_P12V_PVCCIN_CPU0_FLT @S9S_MB_2U_LIB.S9S_MB_2U(SCH_1):SW_P12V_PVCCIN_CPU0_FLT    I12 @S9S_MB_2U_LIB.S9S_MB_2U(SCH_1):PAGE255
    32 SW_PVCCIN_CPU0_BOOTR6 @S9S_MB_2U_LIB.S9S_MB_2U(SCH_1):SW_PVCCIN_CPU0_BOOTR6    I12 @S9S_MB_2U_LIB.S9S_MB_2U(SCH_1):PAGE255
     4 PVCCIN_CPU0_PVCC @S9S_MB_2U_LIB.S9S_MB_2U(SCH_1):PVCCIN_CPU0_PVCC    I12 @S9S_MB_2U_LIB.S9S_MB_2U(SCH_1):PAGE255
    36 PVCCIN_CPU0_ATSEN @S9S_MB_2U_LIB.S9S_MB_2U(SCH_1):PVCCIN_CPU0_ATSEN    I12 @S9S_MB_2U_LIB.S9S_MB_2U(SCH_1):PAGE255
    38 PVCCIN_CPU0_IMON6 @S9S_MB_2U_LIB.S9S_MB_2U(SCH_1):PVCCIN_CPU0_IMON6    I12 @S9S_MB_2U_LIB.S9S_MB_2U(SCH_1):PAGE255
    37 PVCCIN_CPU0_LSET6 @S9S_MB_2U_LIB.S9S_MB_2U(SCH_1):PVCCIN_CPU0_LSET6    I12 @S9S_MB_2U_LIB.S9S_MB_2U(SCH_1):PAGE255
 10_19 SW_PVCCIN_CPU0_SW6 @S9S_MB_2U_LIB.S9S_MB_2U(SCH_1):SW_PVCCIN_CPU0_SW6    I12 @S9S_MB_2U_LIB.S9S_MB_2U(SCH_1):PAGE255
     5    GND @S9S_MB_2U_LIB.S9S_MB_2U(SCH_1):GND    I12 @S9S_MB_2U_LIB.S9S_MB_2U(SCH_1):PAGE255
    30 SW_P12V_PVCCIN_CPU0_FLT @S9S_MB_2U_LIB.S9S_MB_2U(SCH_1):SW_P12V_PVCCIN_CPU0_FLT    I12 @S9S_MB_2U_LIB.S9S_MB_2U(SCH_1):PAGE255
     1 PVCCIN_CPU0_VOS6 @S9S_MB_2U_LIB.S9S_MB_2U(SCH_1):PVCCIN_CPU0_VOS6    I12 @S9S_MB_2U_LIB.S9S_MB_2U(SCH_1):PAGE255
    40    GND @S9S_MB_2U_LIB.S9S_MB_2U(SCH_1):GND    I12 @S9S_MB_2U_LIB.S9S_MB_2U(SCH_1):PAGE255
    35 PVCCIN_CPU0_VDD6 @S9S_MB_2U_LIB.S9S_MB_2U(SCH_1):PVCCIN_CPU0_VDD6    I12 @S9S_MB_2U_LIB.S9S_MB_2U(SCH_1):PAGE255
    31     NC     NC    I12 @S9S_MB_2U_LIB.S9S_MB_2U(SCH_1):PAGE255
     6     NC     NC    I12 @S9S_MB_2U_LIB.S9S_MB_2U(SCH_1):PAGE255
    41     NC     NC    I12 @S9S_MB_2U_LIB.S9S_MB_2U(SCH_1):PAGE255
7_9-20_24    GND @S9S_MB_2U_LIB.S9S_MB_2U(SCH_1):GND    I12 @S9S_MB_2U_LIB.S9S_MB_2U(SCH_1):PAGE255

 PU9 IR3889MTRPBF-IR3889MTRPBF,SMLFA
    34 NC_PU9_2 @S9S_MB_2U_LIB.S9S_MB_2U(SCH_1):NC_PU9_2    I95 @S9S_MB_2U_LIB.S9S_MB_2U(SCH_1):PAGE245
    36 P3V3_AUX_MODE @S9S_MB_2U_LIB.S9S_MB_2U(SCH_1):P3V3_AUX_MODE    I95 @S9S_MB_2U_LIB.S9S_MB_2U(SCH_1):PAGE245
     3 P12V_AUX @S9S_MB_2U_LIB.S9S_MB_2U(SCH_1):P12V_AUX    I95 @S9S_MB_2U_LIB.S9S_MB_2U(SCH_1):PAGE245
    30 P3V3_AUX_FB @S9S_MB_2U_LIB.S9S_MB_2U(SCH_1):P3V3_AUX_FB    I95 @S9S_MB_2U_LIB.S9S_MB_2U(SCH_1):PAGE245
    26 SW_P3V3_AUX_BOOT @S9S_MB_2U_LIB.S9S_MB_2U(SCH_1):SW_P3V3_AUX_BOOT    I95 @S9S_MB_2U_LIB.S9S_MB_2U(SCH_1):PAGE245
     1 P3V3_AUX_ILIM @S9S_MB_2U_LIB.S9S_MB_2U(SCH_1):P3V3_AUX_ILIM    I95 @S9S_MB_2U_LIB.S9S_MB_2U(SCH_1):PAGE245
    25 SW_P3V3_AUX_BOOTR @S9S_MB_2U_LIB.S9S_MB_2U(SCH_1):SW_P3V3_AUX_BOOTR    I95 @S9S_MB_2U_LIB.S9S_MB_2U(SCH_1):PAGE245
     4 P3V3_AUX_VCC @S9S_MB_2U_LIB.S9S_MB_2U(SCH_1):P3V3_AUX_VCC    I95 @S9S_MB_2U_LIB.S9S_MB_2U(SCH_1):PAGE245
    31    GND @S9S_MB_2U_LIB.S9S_MB_2U(SCH_1):GND    I95 @S9S_MB_2U_LIB.S9S_MB_2U(SCH_1):PAGE245
    35 NC_HICCUP @S9S_MB_2U_LIB.S9S_MB_2U(SCH_1):NC_HICCUP    I95 @S9S_MB_2U_LIB.S9S_MB_2U(SCH_1):PAGE245
7_10-19    GND @S9S_MB_2U_LIB.S9S_MB_2U(SCH_1):GND    I95 @S9S_MB_2U_LIB.S9S_MB_2U(SCH_1):PAGE245
    33 NC_PU9_1 @S9S_MB_2U_LIB.S9S_MB_2U(SCH_1):NC_PU9_1    I95 @S9S_MB_2U_LIB.S9S_MB_2U(SCH_1):PAGE245
 11_18 SW_P3V3_AUX_SW @S9S_MB_2U_LIB.S9S_MB_2U(SCH_1):SW_P3V3_AUX_SW    I95 @S9S_MB_2U_LIB.S9S_MB_2U(SCH_1):PAGE245
 20_24 SW_P3V3_AUX_FLT @S9S_MB_2U_LIB.S9S_MB_2U(SCH_1):SW_P3V3_AUX_FLT    I95 @S9S_MB_2U_LIB.S9S_MB_2U(SCH_1):PAGE245
     2 PWRGD_P3V3_AUX @S9S_MB_2U_LIB.S9S_MB_2U(SCH_1):PWRGD_P3V3_AUX    I95 @S9S_MB_2U_LIB.S9S_MB_2U(SCH_1):PAGE245
    28 P3V3_AUX_VOS @S9S_MB_2U_LIB.S9S_MB_2U(SCH_1):P3V3_AUX_VOS    I95 @S9S_MB_2U_LIB.S9S_MB_2U(SCH_1):PAGE245
    32    GND @S9S_MB_2U_LIB.S9S_MB_2U(SCH_1):GND    I95 @S9S_MB_2U_LIB.S9S_MB_2U(SCH_1):PAGE245
    27 P3V3_AUX_EN @S9S_MB_2U_LIB.S9S_MB_2U(SCH_1):P3V3_AUX_EN    I95 @S9S_MB_2U_LIB.S9S_MB_2U(SCH_1):PAGE245
     5 P3V3_AUX_VDRV @S9S_MB_2U_LIB.S9S_MB_2U(SCH_1):P3V3_AUX_VDRV    I95 @S9S_MB_2U_LIB.S9S_MB_2U(SCH_1):PAGE245
     6 NC_PU9_3 @S9S_MB_2U_LIB.S9S_MB_2U(SCH_1):NC_PU9_3    I95 @S9S_MB_2U_LIB.S9S_MB_2U(SCH_1):PAGE245
    29 P3V3_AUX_SS @S9S_MB_2U_LIB.S9S_MB_2U(SCH_1):P3V3_AUX_SS    I95 @S9S_MB_2U_LIB.S9S_MB_2U(SCH_1):PAGE245
    37 NC_PU9_4 @S9S_MB_2U_LIB.S9S_MB_2U(SCH_1):NC_PU9_4    I95 @S9S_MB_2U_LIB.S9S_MB_2U(SCH_1):PAGE245

PU9_P0_5 ISL99390FRZTR5935-ISL99390FRZ-A
    34 PVCCIN_CPU0_PWM5 @S9S_MB_2U_LIB.S9S_MB_2U(SCH_1):PVCCIN_CPU0_PWM5    I66 @S9S_MB_2U_LIB.S9S_MB_2U(SCH_1):PAGE255
    39 PVCCIN_CPU0_VREF @S9S_MB_2U_LIB.S9S_MB_2U(SCH_1):PVCCIN_CPU0_VREF    I66 @S9S_MB_2U_LIB.S9S_MB_2U(SCH_1):PAGE255
     3 PVCCIN_CPU0_VDD5 @S9S_MB_2U_LIB.S9S_MB_2U(SCH_1):PVCCIN_CPU0_VDD5    I66 @S9S_MB_2U_LIB.S9S_MB_2U(SCH_1):PAGE255
     2    GND @S9S_MB_2U_LIB.S9S_MB_2U(SCH_1):GND    I66 @S9S_MB_2U_LIB.S9S_MB_2U(SCH_1):PAGE255
    33 SW_PVCCIN_CPU0_BOOT5 @S9S_MB_2U_LIB.S9S_MB_2U(SCH_1):SW_PVCCIN_CPU0_BOOT5    I66 @S9S_MB_2U_LIB.S9S_MB_2U(SCH_1):PAGE255
 25_29 SW_P12V_PVCCIN_CPU0_FLT @S9S_MB_2U_LIB.S9S_MB_2U(SCH_1):SW_P12V_PVCCIN_CPU0_FLT    I66 @S9S_MB_2U_LIB.S9S_MB_2U(SCH_1):PAGE255
    32 SW_PVCCIN_CPU0_BOOTR5 @S9S_MB_2U_LIB.S9S_MB_2U(SCH_1):SW_PVCCIN_CPU0_BOOTR5    I66 @S9S_MB_2U_LIB.S9S_MB_2U(SCH_1):PAGE255
     4 PVCCIN_CPU0_PVCC @S9S_MB_2U_LIB.S9S_MB_2U(SCH_1):PVCCIN_CPU0_PVCC    I66 @S9S_MB_2U_LIB.S9S_MB_2U(SCH_1):PAGE255
    36 PVCCIN_CPU0_ATSEN @S9S_MB_2U_LIB.S9S_MB_2U(SCH_1):PVCCIN_CPU0_ATSEN    I66 @S9S_MB_2U_LIB.S9S_MB_2U(SCH_1):PAGE255
    38 PVCCIN_CPU0_IMON5 @S9S_MB_2U_LIB.S9S_MB_2U(SCH_1):PVCCIN_CPU0_IMON5    I66 @S9S_MB_2U_LIB.S9S_MB_2U(SCH_1):PAGE255
    37 PVCCIN_CPU0_LSET5 @S9S_MB_2U_LIB.S9S_MB_2U(SCH_1):PVCCIN_CPU0_LSET5    I66 @S9S_MB_2U_LIB.S9S_MB_2U(SCH_1):PAGE255
 10_19 SW_PVCCIN_CPU0_SW5 @S9S_MB_2U_LIB.S9S_MB_2U(SCH_1):SW_PVCCIN_CPU0_SW5    I66 @S9S_MB_2U_LIB.S9S_MB_2U(SCH_1):PAGE255
     5    GND @S9S_MB_2U_LIB.S9S_MB_2U(SCH_1):GND    I66 @S9S_MB_2U_LIB.S9S_MB_2U(SCH_1):PAGE255
    30 SW_P12V_PVCCIN_CPU0_FLT @S9S_MB_2U_LIB.S9S_MB_2U(SCH_1):SW_P12V_PVCCIN_CPU0_FLT    I66 @S9S_MB_2U_LIB.S9S_MB_2U(SCH_1):PAGE255
     1 PVCCIN_CPU0_VOS5 @S9S_MB_2U_LIB.S9S_MB_2U(SCH_1):PVCCIN_CPU0_VOS5    I66 @S9S_MB_2U_LIB.S9S_MB_2U(SCH_1):PAGE255
    40    GND @S9S_MB_2U_LIB.S9S_MB_2U(SCH_1):GND    I66 @S9S_MB_2U_LIB.S9S_MB_2U(SCH_1):PAGE255
    35 PVCCIN_CPU0_VDD5 @S9S_MB_2U_LIB.S9S_MB_2U(SCH_1):PVCCIN_CPU0_VDD5    I66 @S9S_MB_2U_LIB.S9S_MB_2U(SCH_1):PAGE255
    31     NC     NC    I66 @S9S_MB_2U_LIB.S9S_MB_2U(SCH_1):PAGE255
     6     NC     NC    I66 @S9S_MB_2U_LIB.S9S_MB_2U(SCH_1):PAGE255
    41     NC     NC    I66 @S9S_MB_2U_LIB.S9S_MB_2U(SCH_1):PAGE255
7_9-20_24    GND @S9S_MB_2U_LIB.S9S_MB_2U(SCH_1):GND    I66 @S9S_MB_2U_LIB.S9S_MB_2U(SCH_1):PAGE255

PU10_P0_4 ISL99390FRZTR5935-ISL99390FRZ-A
    34 PVCCIN_CPU0_PWM4 @S9S_MB_2U_LIB.S9S_MB_2U(SCH_1):PVCCIN_CPU0_PWM4    I13 @S9S_MB_2U_LIB.S9S_MB_2U(SCH_1):PAGE254
    39 PVCCIN_CPU0_VREF @S9S_MB_2U_LIB.S9S_MB_2U(SCH_1):PVCCIN_CPU0_VREF    I13 @S9S_MB_2U_LIB.S9S_MB_2U(SCH_1):PAGE254
     3 PVCCIN_CPU0_VDD4 @S9S_MB_2U_LIB.S9S_MB_2U(SCH_1):PVCCIN_CPU0_VDD4    I13 @S9S_MB_2U_LIB.S9S_MB_2U(SCH_1):PAGE254
     2    GND @S9S_MB_2U_LIB.S9S_MB_2U(SCH_1):GND    I13 @S9S_MB_2U_LIB.S9S_MB_2U(SCH_1):PAGE254
    33 SW_PVCCIN_CPU0_BOOT4 @S9S_MB_2U_LIB.S9S_MB_2U(SCH_1):SW_PVCCIN_CPU0_BOOT4    I13 @S9S_MB_2U_LIB.S9S_MB_2U(SCH_1):PAGE254
 25_29 SW_P12V_PVCCIN_CPU0_FLT @S9S_MB_2U_LIB.S9S_MB_2U(SCH_1):SW_P12V_PVCCIN_CPU0_FLT    I13 @S9S_MB_2U_LIB.S9S_MB_2U(SCH_1):PAGE254
    32 SW_PVCCIN_CPU0_BOOTR4 @S9S_MB_2U_LIB.S9S_MB_2U(SCH_1):SW_PVCCIN_CPU0_BOOTR4    I13 @S9S_MB_2U_LIB.S9S_MB_2U(SCH_1):PAGE254
     4 PVCCIN_CPU0_PVCC @S9S_MB_2U_LIB.S9S_MB_2U(SCH_1):PVCCIN_CPU0_PVCC    I13 @S9S_MB_2U_LIB.S9S_MB_2U(SCH_1):PAGE254
    36 PVCCIN_CPU0_ATSEN @S9S_MB_2U_LIB.S9S_MB_2U(SCH_1):PVCCIN_CPU0_ATSEN    I13 @S9S_MB_2U_LIB.S9S_MB_2U(SCH_1):PAGE254
    38 PVCCIN_CPU0_IMON4 @S9S_MB_2U_LIB.S9S_MB_2U(SCH_1):PVCCIN_CPU0_IMON4    I13 @S9S_MB_2U_LIB.S9S_MB_2U(SCH_1):PAGE254
    37 PVCCIN_CPU0_LSET4 @S9S_MB_2U_LIB.S9S_MB_2U(SCH_1):PVCCIN_CPU0_LSET4    I13 @S9S_MB_2U_LIB.S9S_MB_2U(SCH_1):PAGE254
 10_19 SW_PVCCIN_CPU0_SW4 @S9S_MB_2U_LIB.S9S_MB_2U(SCH_1):SW_PVCCIN_CPU0_SW4    I13 @S9S_MB_2U_LIB.S9S_MB_2U(SCH_1):PAGE254
     5    GND @S9S_MB_2U_LIB.S9S_MB_2U(SCH_1):GND    I13 @S9S_MB_2U_LIB.S9S_MB_2U(SCH_1):PAGE254
    30 SW_P12V_PVCCIN_CPU0_FLT @S9S_MB_2U_LIB.S9S_MB_2U(SCH_1):SW_P12V_PVCCIN_CPU0_FLT    I13 @S9S_MB_2U_LIB.S9S_MB_2U(SCH_1):PAGE254
     1 PVCCIN_CPU0_VOS4 @S9S_MB_2U_LIB.S9S_MB_2U(SCH_1):PVCCIN_CPU0_VOS4    I13 @S9S_MB_2U_LIB.S9S_MB_2U(SCH_1):PAGE254
    40    GND @S9S_MB_2U_LIB.S9S_MB_2U(SCH_1):GND    I13 @S9S_MB_2U_LIB.S9S_MB_2U(SCH_1):PAGE254
    35 PVCCIN_CPU0_VDD4 @S9S_MB_2U_LIB.S9S_MB_2U(SCH_1):PVCCIN_CPU0_VDD4    I13 @S9S_MB_2U_LIB.S9S_MB_2U(SCH_1):PAGE254
    31     NC     NC    I13 @S9S_MB_2U_LIB.S9S_MB_2U(SCH_1):PAGE254
     6     NC     NC    I13 @S9S_MB_2U_LIB.S9S_MB_2U(SCH_1):PAGE254
    41     NC     NC    I13 @S9S_MB_2U_LIB.S9S_MB_2U(SCH_1):PAGE254
7_9-20_24    GND @S9S_MB_2U_LIB.S9S_MB_2U(SCH_1):GND    I13 @S9S_MB_2U_LIB.S9S_MB_2U(SCH_1):PAGE254

PU11_P0_3 ISL99390FRZTR5935-ISL99390FRZ-A
    34 PVCCIN_CPU0_PWM3 @S9S_MB_2U_LIB.S9S_MB_2U(SCH_1):PVCCIN_CPU0_PWM3    I20 @S9S_MB_2U_LIB.S9S_MB_2U(SCH_1):PAGE254
    39 PVCCIN_CPU0_VREF @S9S_MB_2U_LIB.S9S_MB_2U(SCH_1):PVCCIN_CPU0_VREF    I20 @S9S_MB_2U_LIB.S9S_MB_2U(SCH_1):PAGE254
     3 PVCCIN_CPU0_VDD3 @S9S_MB_2U_LIB.S9S_MB_2U(SCH_1):PVCCIN_CPU0_VDD3    I20 @S9S_MB_2U_LIB.S9S_MB_2U(SCH_1):PAGE254
     2    GND @S9S_MB_2U_LIB.S9S_MB_2U(SCH_1):GND    I20 @S9S_MB_2U_LIB.S9S_MB_2U(SCH_1):PAGE254
    33 SW_PVCCIN_CPU0_BOOT3 @S9S_MB_2U_LIB.S9S_MB_2U(SCH_1):SW_PVCCIN_CPU0_BOOT3    I20 @S9S_MB_2U_LIB.S9S_MB_2U(SCH_1):PAGE254
 25_29 SW_P12V_PVCCIN_CPU0_FLT @S9S_MB_2U_LIB.S9S_MB_2U(SCH_1):SW_P12V_PVCCIN_CPU0_FLT    I20 @S9S_MB_2U_LIB.S9S_MB_2U(SCH_1):PAGE254
    32 SW_PVCCIN_CPU0_BOOTR3 @S9S_MB_2U_LIB.S9S_MB_2U(SCH_1):SW_PVCCIN_CPU0_BOOTR3    I20 @S9S_MB_2U_LIB.S9S_MB_2U(SCH_1):PAGE254
     4 PVCCIN_CPU0_PVCC @S9S_MB_2U_LIB.S9S_MB_2U(SCH_1):PVCCIN_CPU0_PVCC    I20 @S9S_MB_2U_LIB.S9S_MB_2U(SCH_1):PAGE254
    36 PVCCIN_CPU0_ATSEN @S9S_MB_2U_LIB.S9S_MB_2U(SCH_1):PVCCIN_CPU0_ATSEN    I20 @S9S_MB_2U_LIB.S9S_MB_2U(SCH_1):PAGE254
    38 PVCCIN_CPU0_IMON3 @S9S_MB_2U_LIB.S9S_MB_2U(SCH_1):PVCCIN_CPU0_IMON3    I20 @S9S_MB_2U_LIB.S9S_MB_2U(SCH_1):PAGE254
    37 PVCCIN_CPU0_LSET3 @S9S_MB_2U_LIB.S9S_MB_2U(SCH_1):PVCCIN_CPU0_LSET3    I20 @S9S_MB_2U_LIB.S9S_MB_2U(SCH_1):PAGE254
 10_19 SW_PVCCIN_CPU0_SW3 @S9S_MB_2U_LIB.S9S_MB_2U(SCH_1):SW_PVCCIN_CPU0_SW3    I20 @S9S_MB_2U_LIB.S9S_MB_2U(SCH_1):PAGE254
     5    GND @S9S_MB_2U_LIB.S9S_MB_2U(SCH_1):GND    I20 @S9S_MB_2U_LIB.S9S_MB_2U(SCH_1):PAGE254
    30 SW_P12V_PVCCIN_CPU0_FLT @S9S_MB_2U_LIB.S9S_MB_2U(SCH_1):SW_P12V_PVCCIN_CPU0_FLT    I20 @S9S_MB_2U_LIB.S9S_MB_2U(SCH_1):PAGE254
     1 PVCCIN_CPU0_VOS3 @S9S_MB_2U_LIB.S9S_MB_2U(SCH_1):PVCCIN_CPU0_VOS3    I20 @S9S_MB_2U_LIB.S9S_MB_2U(SCH_1):PAGE254
    40    GND @S9S_MB_2U_LIB.S9S_MB_2U(SCH_1):GND    I20 @S9S_MB_2U_LIB.S9S_MB_2U(SCH_1):PAGE254
    35 PVCCIN_CPU0_VDD3 @S9S_MB_2U_LIB.S9S_MB_2U(SCH_1):PVCCIN_CPU0_VDD3    I20 @S9S_MB_2U_LIB.S9S_MB_2U(SCH_1):PAGE254
    31     NC     NC    I20 @S9S_MB_2U_LIB.S9S_MB_2U(SCH_1):PAGE254
     6     NC     NC    I20 @S9S_MB_2U_LIB.S9S_MB_2U(SCH_1):PAGE254
    41     NC     NC    I20 @S9S_MB_2U_LIB.S9S_MB_2U(SCH_1):PAGE254
7_9-20_24    GND @S9S_MB_2U_LIB.S9S_MB_2U(SCH_1):GND    I20 @S9S_MB_2U_LIB.S9S_MB_2U(SCH_1):PAGE254

PU12_P0_2 ISL99390FRZTR5935-ISL99390FRZ-A
    34 PVCCIN_CPU0_PWM2 @S9S_MB_2U_LIB.S9S_MB_2U(SCH_1):PVCCIN_CPU0_PWM2     I6 @S9S_MB_2U_LIB.S9S_MB_2U(SCH_1):PAGE253
    39 PVCCIN_CPU0_VREF @S9S_MB_2U_LIB.S9S_MB_2U(SCH_1):PVCCIN_CPU0_VREF     I6 @S9S_MB_2U_LIB.S9S_MB_2U(SCH_1):PAGE253
     3 PVCCIN_CPU0_VDD2 @S9S_MB_2U_LIB.S9S_MB_2U(SCH_1):PVCCIN_CPU0_VDD2     I6 @S9S_MB_2U_LIB.S9S_MB_2U(SCH_1):PAGE253
     2    GND @S9S_MB_2U_LIB.S9S_MB_2U(SCH_1):GND     I6 @S9S_MB_2U_LIB.S9S_MB_2U(SCH_1):PAGE253
    33 SW_PVCCIN_CPU0_BOOT2 @S9S_MB_2U_LIB.S9S_MB_2U(SCH_1):SW_PVCCIN_CPU0_BOOT2     I6 @S9S_MB_2U_LIB.S9S_MB_2U(SCH_1):PAGE253
 25_29 SW_P12V_PVCCIN_CPU0_FLT @S9S_MB_2U_LIB.S9S_MB_2U(SCH_1):SW_P12V_PVCCIN_CPU0_FLT     I6 @S9S_MB_2U_LIB.S9S_MB_2U(SCH_1):PAGE253
    32 SW_PVCCIN_CPU0_BOOTR2 @S9S_MB_2U_LIB.S9S_MB_2U(SCH_1):SW_PVCCIN_CPU0_BOOTR2     I6 @S9S_MB_2U_LIB.S9S_MB_2U(SCH_1):PAGE253
     4 PVCCIN_CPU0_PVCC @S9S_MB_2U_LIB.S9S_MB_2U(SCH_1):PVCCIN_CPU0_PVCC     I6 @S9S_MB_2U_LIB.S9S_MB_2U(SCH_1):PAGE253
    36 PVCCIN_CPU0_ATSEN @S9S_MB_2U_LIB.S9S_MB_2U(SCH_1):PVCCIN_CPU0_ATSEN     I6 @S9S_MB_2U_LIB.S9S_MB_2U(SCH_1):PAGE253
    38 PVCCIN_CPU0_IMON2 @S9S_MB_2U_LIB.S9S_MB_2U(SCH_1):PVCCIN_CPU0_IMON2     I6 @S9S_MB_2U_LIB.S9S_MB_2U(SCH_1):PAGE253
    37 PVCCIN_CPU0_LSET2 @S9S_MB_2U_LIB.S9S_MB_2U(SCH_1):PVCCIN_CPU0_LSET2     I6 @S9S_MB_2U_LIB.S9S_MB_2U(SCH_1):PAGE253
 10_19 SW_PVCCIN_CPU0_SW2 @S9S_MB_2U_LIB.S9S_MB_2U(SCH_1):SW_PVCCIN_CPU0_SW2     I6 @S9S_MB_2U_LIB.S9S_MB_2U(SCH_1):PAGE253
     5    GND @S9S_MB_2U_LIB.S9S_MB_2U(SCH_1):GND     I6 @S9S_MB_2U_LIB.S9S_MB_2U(SCH_1):PAGE253
    30 SW_P12V_PVCCIN_CPU0_FLT @S9S_MB_2U_LIB.S9S_MB_2U(SCH_1):SW_P12V_PVCCIN_CPU0_FLT     I6 @S9S_MB_2U_LIB.S9S_MB_2U(SCH_1):PAGE253
     1 PVCCIN_CPU0_VOS2 @S9S_MB_2U_LIB.S9S_MB_2U(SCH_1):PVCCIN_CPU0_VOS2     I6 @S9S_MB_2U_LIB.S9S_MB_2U(SCH_1):PAGE253
    40    GND @S9S_MB_2U_LIB.S9S_MB_2U(SCH_1):GND     I6 @S9S_MB_2U_LIB.S9S_MB_2U(SCH_1):PAGE253
    35 PVCCIN_CPU0_VDD2 @S9S_MB_2U_LIB.S9S_MB_2U(SCH_1):PVCCIN_CPU0_VDD2     I6 @S9S_MB_2U_LIB.S9S_MB_2U(SCH_1):PAGE253
    31     NC     NC     I6 @S9S_MB_2U_LIB.S9S_MB_2U(SCH_1):PAGE253
     6     NC     NC     I6 @S9S_MB_2U_LIB.S9S_MB_2U(SCH_1):PAGE253
    41     NC     NC     I6 @S9S_MB_2U_LIB.S9S_MB_2U(SCH_1):PAGE253
7_9-20_24    GND @S9S_MB_2U_LIB.S9S_MB_2U(SCH_1):GND     I6 @S9S_MB_2U_LIB.S9S_MB_2U(SCH_1):PAGE253

PU13_P0_1 ISL99390FRZTR5935-ISL99390FRZ-A
    34 PVCCIN_CPU0_PWM1 @S9S_MB_2U_LIB.S9S_MB_2U(SCH_1):PVCCIN_CPU0_PWM1    I40 @S9S_MB_2U_LIB.S9S_MB_2U(SCH_1):PAGE253
    39 PVCCIN_CPU0_VREF @S9S_MB_2U_LIB.S9S_MB_2U(SCH_1):PVCCIN_CPU0_VREF    I40 @S9S_MB_2U_LIB.S9S_MB_2U(SCH_1):PAGE253
     3 PVCCIN_CPU0_VDD1 @S9S_MB_2U_LIB.S9S_MB_2U(SCH_1):PVCCIN_CPU0_VDD1    I40 @S9S_MB_2U_LIB.S9S_MB_2U(SCH_1):PAGE253
     2    GND @S9S_MB_2U_LIB.S9S_MB_2U(SCH_1):GND    I40 @S9S_MB_2U_LIB.S9S_MB_2U(SCH_1):PAGE253
    33 SW_PVCCIN_CPU0_BOOT1 @S9S_MB_2U_LIB.S9S_MB_2U(SCH_1):SW_PVCCIN_CPU0_BOOT1    I40 @S9S_MB_2U_LIB.S9S_MB_2U(SCH_1):PAGE253
 25_29 SW_P12V_PVCCIN_CPU0_FLT @S9S_MB_2U_LIB.S9S_MB_2U(SCH_1):SW_P12V_PVCCIN_CPU0_FLT    I40 @S9S_MB_2U_LIB.S9S_MB_2U(SCH_1):PAGE253
    32 SW_PVCCIN_CPU0_BOOTR1 @S9S_MB_2U_LIB.S9S_MB_2U(SCH_1):SW_PVCCIN_CPU0_BOOTR1    I40 @S9S_MB_2U_LIB.S9S_MB_2U(SCH_1):PAGE253
     4 PVCCIN_CPU0_PVCC @S9S_MB_2U_LIB.S9S_MB_2U(SCH_1):PVCCIN_CPU0_PVCC    I40 @S9S_MB_2U_LIB.S9S_MB_2U(SCH_1):PAGE253
    36 PVCCIN_CPU0_ATSEN @S9S_MB_2U_LIB.S9S_MB_2U(SCH_1):PVCCIN_CPU0_ATSEN    I40 @S9S_MB_2U_LIB.S9S_MB_2U(SCH_1):PAGE253
    38 PVCCIN_CPU0_IMON1 @S9S_MB_2U_LIB.S9S_MB_2U(SCH_1):PVCCIN_CPU0_IMON1    I40 @S9S_MB_2U_LIB.S9S_MB_2U(SCH_1):PAGE253
    37 PVCCIN_CPU0_LSET1 @S9S_MB_2U_LIB.S9S_MB_2U(SCH_1):PVCCIN_CPU0_LSET1    I40 @S9S_MB_2U_LIB.S9S_MB_2U(SCH_1):PAGE253
 10_19 SW_PVCCIN_CPU0_SW1 @S9S_MB_2U_LIB.S9S_MB_2U(SCH_1):SW_PVCCIN_CPU0_SW1    I40 @S9S_MB_2U_LIB.S9S_MB_2U(SCH_1):PAGE253
     5    GND @S9S_MB_2U_LIB.S9S_MB_2U(SCH_1):GND    I40 @S9S_MB_2U_LIB.S9S_MB_2U(SCH_1):PAGE253
    30 SW_P12V_PVCCIN_CPU0_FLT @S9S_MB_2U_LIB.S9S_MB_2U(SCH_1):SW_P12V_PVCCIN_CPU0_FLT    I40 @S9S_MB_2U_LIB.S9S_MB_2U(SCH_1):PAGE253
     1 PVCCIN_CPU0_VOS1 @S9S_MB_2U_LIB.S9S_MB_2U(SCH_1):PVCCIN_CPU0_VOS1    I40 @S9S_MB_2U_LIB.S9S_MB_2U(SCH_1):PAGE253
    40    GND @S9S_MB_2U_LIB.S9S_MB_2U(SCH_1):GND    I40 @S9S_MB_2U_LIB.S9S_MB_2U(SCH_1):PAGE253
    35 PVCCIN_CPU0_VDD1 @S9S_MB_2U_LIB.S9S_MB_2U(SCH_1):PVCCIN_CPU0_VDD1    I40 @S9S_MB_2U_LIB.S9S_MB_2U(SCH_1):PAGE253
    31     NC     NC    I40 @S9S_MB_2U_LIB.S9S_MB_2U(SCH_1):PAGE253
     6     NC     NC    I40 @S9S_MB_2U_LIB.S9S_MB_2U(SCH_1):PAGE253
    41     NC     NC    I40 @S9S_MB_2U_LIB.S9S_MB_2U(SCH_1):PAGE253
7_9-20_24    GND @S9S_MB_2U_LIB.S9S_MB_2U(SCH_1):GND    I40 @S9S_MB_2U_LIB.S9S_MB_2U(SCH_1):PAGE253

PU14 RAA229126GNPHA0-RAA229126GNP#HA
    27 PVCCIN_CPU0_IMON1 @S9S_MB_2U_LIB.S9S_MB_2U(SCH_1):PVCCIN_CPU0_IMON1    I63 @S9S_MB_2U_LIB.S9S_MB_2U(SCH_1):PAGE252
    47 PVCCIN_CPU0_VCC @S9S_MB_2U_LIB.S9S_MB_2U(SCH_1):PVCCIN_CPU0_VCC    I63 @S9S_MB_2U_LIB.S9S_MB_2U(SCH_1):PAGE252
    24 PVCCFA_EHV_FIVRA_CPU0_EN_R @S9S_MB_2U_LIB.S9S_MB_2U(SCH_1):PVCCFA_EHV_FIVRA_CPU0_EN_R    I63 @S9S_MB_2U_LIB.S9S_MB_2U(SCH_1):PAGE252
    14 SMB_CLK_PVCCIN_CPU0 @S9S_MB_2U_LIB.S9S_MB_2U(SCH_1):SMB_CLK_PVCCIN_CPU0    I63 @S9S_MB_2U_LIB.S9S_MB_2U(SCH_1):PAGE252
    22 SVID_DIO_PVCCIN_CPU0_R @S9S_MB_2U_LIB.S9S_MB_2U(SCH_1):SVID_DIO_PVCCIN_CPU0_R    I63 @S9S_MB_2U_LIB.S9S_MB_2U(SCH_1):PAGE252
    32 PVCCIN_CPU0_IMON6 @S9S_MB_2U_LIB.S9S_MB_2U(SCH_1):PVCCIN_CPU0_IMON6    I63 @S9S_MB_2U_LIB.S9S_MB_2U(SCH_1):PAGE252
    23 SVID_ALERT_PVCCIN_CPU0_R @S9S_MB_2U_LIB.S9S_MB_2U(SCH_1):SVID_ALERT_PVCCIN_CPU0_R    I63 @S9S_MB_2U_LIB.S9S_MB_2U(SCH_1):PAGE252
    18 IRQ_PVCCIN_CPU0_VRHOT_N @S9S_MB_2U_LIB.S9S_MB_2U(SCH_1):IRQ_PVCCIN_CPU0_VRHOT_N    I63 @S9S_MB_2U_LIB.S9S_MB_2U(SCH_1):PAGE252
    33 PVCCIN_CPU0_IMON7 @S9S_MB_2U_LIB.S9S_MB_2U(SCH_1):PVCCIN_CPU0_IMON7    I63 @S9S_MB_2U_LIB.S9S_MB_2U(SCH_1):PAGE252
    34 PVCCIN_CPU0_IMON8 @S9S_MB_2U_LIB.S9S_MB_2U(SCH_1):PVCCIN_CPU0_IMON8    I63 @S9S_MB_2U_LIB.S9S_MB_2U(SCH_1):PAGE252
    20 PWRGD_PVCCFA_EHV_FIVRA_CPU0_R @S9S_MB_2U_LIB.S9S_MB_2U(SCH_1):PWRGD_PVCCFA_EHV_FIVRA_CPU0_R    I63 @S9S_MB_2U_LIB.S9S_MB_2U(SCH_1):PAGE252
    21 SVID_CLK_PVCCIN_CPU0_R @S9S_MB_2U_LIB.S9S_MB_2U(SCH_1):SVID_CLK_PVCCIN_CPU0_R    I63 @S9S_MB_2U_LIB.S9S_MB_2U(SCH_1):PAGE252
    15 NC_PVCCIN_CPU0_SMB_ALERT @S9S_MB_2U_LIB.S9S_MB_2U(SCH_1):NC_PVCCIN_CPU0_SMB_ALERT    I63 @S9S_MB_2U_LIB.S9S_MB_2U(SCH_1):PAGE252
    17 PVCCIN_CPU0_EN_R @S9S_MB_2U_LIB.S9S_MB_2U(SCH_1):PVCCIN_CPU0_EN_R    I63 @S9S_MB_2U_LIB.S9S_MB_2U(SCH_1):PAGE252
    26 VSENSE_PVCCIN_CPU0_DN @S9S_MB_2U_LIB.S9S_MB_2U(SCH_1):VSENSE_PVCCIN_CPU0_DN    I63 @S9S_MB_2U_LIB.S9S_MB_2U(SCH_1):PAGE252
    13 SMB_DIO_PVCCIN_CPU0 @S9S_MB_2U_LIB.S9S_MB_2U(SCH_1):SMB_DIO_PVCCIN_CPU0    I63 @S9S_MB_2U_LIB.S9S_MB_2U(SCH_1):PAGE252
     5 PVCCIN_CPU0_PWM8 @S9S_MB_2U_LIB.S9S_MB_2U(SCH_1):PVCCIN_CPU0_PWM8    I63 @S9S_MB_2U_LIB.S9S_MB_2U(SCH_1):PAGE252
     6 PVCCIN_CPU0_PWM7 @S9S_MB_2U_LIB.S9S_MB_2U(SCH_1):PVCCIN_CPU0_PWM7    I63 @S9S_MB_2U_LIB.S9S_MB_2U(SCH_1):PAGE252
    25 SH_PVCCIN_CPU0_R @S9S_MB_2U_LIB.S9S_MB_2U(SCH_1):SH_PVCCIN_CPU0_R    I63 @S9S_MB_2U_LIB.S9S_MB_2U(SCH_1):PAGE252
     2 PVCCFA_EHV_FIVRA_CPU0_PWM2 @S9S_MB_2U_LIB.S9S_MB_2U(SCH_1):PVCCFA_EHV_FIVRA_CPU0_PWM2    I63 @S9S_MB_2U_LIB.S9S_MB_2U(SCH_1):PAGE252
    16 PWRGD_PVCCIN_CPU0_R @S9S_MB_2U_LIB.S9S_MB_2U(SCH_1):PWRGD_PVCCIN_CPU0_R    I63 @S9S_MB_2U_LIB.S9S_MB_2U(SCH_1):PAGE252
     7 PVCCIN_CPU0_PWM6 @S9S_MB_2U_LIB.S9S_MB_2U(SCH_1):PVCCIN_CPU0_PWM6    I63 @S9S_MB_2U_LIB.S9S_MB_2U(SCH_1):PAGE252
    48 PVCCIN_CPU0_VREF @S9S_MB_2U_LIB.S9S_MB_2U(SCH_1):PVCCIN_CPU0_VREF    I63 @S9S_MB_2U_LIB.S9S_MB_2U(SCH_1):PAGE252
    45 PVCCIN_CPU0_CSPIN @S9S_MB_2U_LIB.S9S_MB_2U(SCH_1):PVCCIN_CPU0_CSPIN    I63 @S9S_MB_2U_LIB.S9S_MB_2U(SCH_1):PAGE252
    46 PVCCIN_CPU0_VIN_CSNIN @S9S_MB_2U_LIB.S9S_MB_2U(SCH_1):PVCCIN_CPU0_VIN_CSNIN    I63 @S9S_MB_2U_LIB.S9S_MB_2U(SCH_1):PAGE252
    44 PVCCFA_EHV_FIVRA_CPU0_BTSEN @S9S_MB_2U_LIB.S9S_MB_2U(SCH_1):PVCCFA_EHV_FIVRA_CPU0_BTSEN    I63 @S9S_MB_2U_LIB.S9S_MB_2U(SCH_1):PAGE252
    19 PVCCIN_CPU0_PIN_ALERT @S9S_MB_2U_LIB.S9S_MB_2U(SCH_1):PVCCIN_CPU0_PIN_ALERT    I63 @S9S_MB_2U_LIB.S9S_MB_2U(SCH_1):PAGE252
    40 SH_PVCCFA_EHV_FIVRA_CPU0_R @S9S_MB_2U_LIB.S9S_MB_2U(SCH_1):SH_PVCCFA_EHV_FIVRA_CPU0_R    I63 @S9S_MB_2U_LIB.S9S_MB_2U(SCH_1):PAGE252
    39 VSENSE_PVCCFA_EHV_FIVRA_CPU0_DN @S9S_MB_2U_LIB.S9S_MB_2U(SCH_1):VSENSE_PVCCFA_EHV_FIVRA_CPU0_DN    I63 @S9S_MB_2U_LIB.S9S_MB_2U(SCH_1):PAGE252
    37 PVCCFA_EHV_FIVRA_CPU0_IMON2 @S9S_MB_2U_LIB.S9S_MB_2U(SCH_1):PVCCFA_EHV_FIVRA_CPU0_IMON2    I63 @S9S_MB_2U_LIB.S9S_MB_2U(SCH_1):PAGE252
    12 PVCCIN_CPU0_PWM1 @S9S_MB_2U_LIB.S9S_MB_2U(SCH_1):PVCCIN_CPU0_PWM1    I63 @S9S_MB_2U_LIB.S9S_MB_2U(SCH_1):PAGE252
     4 PVCCFA_EHV_FIVRA_CPU0_PWM4 @S9S_MB_2U_LIB.S9S_MB_2U(SCH_1):PVCCFA_EHV_FIVRA_CPU0_PWM4    I63 @S9S_MB_2U_LIB.S9S_MB_2U(SCH_1):PAGE252
    35 PVCCFA_EHV_FIVRA_CPU0_IMON4 @S9S_MB_2U_LIB.S9S_MB_2U(SCH_1):PVCCFA_EHV_FIVRA_CPU0_IMON4    I63 @S9S_MB_2U_LIB.S9S_MB_2U(SCH_1):PAGE252
     3 PVCCFA_EHV_FIVRA_CPU0_PWM3 @S9S_MB_2U_LIB.S9S_MB_2U(SCH_1):PVCCFA_EHV_FIVRA_CPU0_PWM3    I63 @S9S_MB_2U_LIB.S9S_MB_2U(SCH_1):PAGE252
    36 PVCCFA_EHV_FIVRA_CPU0_IMON3 @S9S_MB_2U_LIB.S9S_MB_2U(SCH_1):PVCCFA_EHV_FIVRA_CPU0_IMON3    I63 @S9S_MB_2U_LIB.S9S_MB_2U(SCH_1):PAGE252
    41 PVCCIN_CPU0_VR_FAULT @S9S_MB_2U_LIB.S9S_MB_2U(SCH_1):PVCCIN_CPU0_VR_FAULT    I63 @S9S_MB_2U_LIB.S9S_MB_2U(SCH_1):PAGE252
    TH    GND @S9S_MB_2U_LIB.S9S_MB_2U(SCH_1):GND    I63 @S9S_MB_2U_LIB.S9S_MB_2U(SCH_1):PAGE252
    42 PVCCIN_CPU0_ADDR @S9S_MB_2U_LIB.S9S_MB_2U(SCH_1):PVCCIN_CPU0_ADDR    I63 @S9S_MB_2U_LIB.S9S_MB_2U(SCH_1):PAGE252
    43 PVCCIN_CPU0_ATSEN @S9S_MB_2U_LIB.S9S_MB_2U(SCH_1):PVCCIN_CPU0_ATSEN    I63 @S9S_MB_2U_LIB.S9S_MB_2U(SCH_1):PAGE252
     1 PVCCFA_EHV_FIVRA_CPU0_PWM1 @S9S_MB_2U_LIB.S9S_MB_2U(SCH_1):PVCCFA_EHV_FIVRA_CPU0_PWM1    I63 @S9S_MB_2U_LIB.S9S_MB_2U(SCH_1):PAGE252
    38 PVCCFA_EHV_FIVRA_CPU0_IMON1 @S9S_MB_2U_LIB.S9S_MB_2U(SCH_1):PVCCFA_EHV_FIVRA_CPU0_IMON1    I63 @S9S_MB_2U_LIB.S9S_MB_2U(SCH_1):PAGE252
     8 PVCCIN_CPU0_PWM5 @S9S_MB_2U_LIB.S9S_MB_2U(SCH_1):PVCCIN_CPU0_PWM5    I63 @S9S_MB_2U_LIB.S9S_MB_2U(SCH_1):PAGE252
    31 PVCCIN_CPU0_IMON5 @S9S_MB_2U_LIB.S9S_MB_2U(SCH_1):PVCCIN_CPU0_IMON5    I63 @S9S_MB_2U_LIB.S9S_MB_2U(SCH_1):PAGE252
     9 PVCCIN_CPU0_PWM4 @S9S_MB_2U_LIB.S9S_MB_2U(SCH_1):PVCCIN_CPU0_PWM4    I63 @S9S_MB_2U_LIB.S9S_MB_2U(SCH_1):PAGE252
    30 PVCCIN_CPU0_IMON4 @S9S_MB_2U_LIB.S9S_MB_2U(SCH_1):PVCCIN_CPU0_IMON4    I63 @S9S_MB_2U_LIB.S9S_MB_2U(SCH_1):PAGE252
    10 PVCCIN_CPU0_PWM3 @S9S_MB_2U_LIB.S9S_MB_2U(SCH_1):PVCCIN_CPU0_PWM3    I63 @S9S_MB_2U_LIB.S9S_MB_2U(SCH_1):PAGE252
    29 PVCCIN_CPU0_IMON3 @S9S_MB_2U_LIB.S9S_MB_2U(SCH_1):PVCCIN_CPU0_IMON3    I63 @S9S_MB_2U_LIB.S9S_MB_2U(SCH_1):PAGE252
    11 PVCCIN_CPU0_PWM2 @S9S_MB_2U_LIB.S9S_MB_2U(SCH_1):PVCCIN_CPU0_PWM2    I63 @S9S_MB_2U_LIB.S9S_MB_2U(SCH_1):PAGE252
    28 PVCCIN_CPU0_IMON2 @S9S_MB_2U_LIB.S9S_MB_2U(SCH_1):PVCCIN_CPU0_IMON2    I63 @S9S_MB_2U_LIB.S9S_MB_2U(SCH_1):PAGE252

PU17 ISL99390FRZTR5935-ISL99390FRZ-A
    34 PVCCD_HV_CPU1_APWM1 @S9S_MB_2U_LIB.S9S_MB_2U(SCH_1):PVCCD_HV_CPU1_APWM1    I10 @S9S_MB_2U_LIB.S9S_MB_2U(SCH_1):PAGE283
    39 PVCCD_HV_CPU1_VREF @S9S_MB_2U_LIB.S9S_MB_2U(SCH_1):PVCCD_HV_CPU1_VREF    I10 @S9S_MB_2U_LIB.S9S_MB_2U(SCH_1):PAGE283
     3 PVCCD_HV_CPU1_VDD1 @S9S_MB_2U_LIB.S9S_MB_2U(SCH_1):PVCCD_HV_CPU1_VDD1    I10 @S9S_MB_2U_LIB.S9S_MB_2U(SCH_1):PAGE283
     2    GND @S9S_MB_2U_LIB.S9S_MB_2U(SCH_1):GND    I10 @S9S_MB_2U_LIB.S9S_MB_2U(SCH_1):PAGE283
    33 SW_PVCCD_HV_CPU1_BOOT1 @S9S_MB_2U_LIB.S9S_MB_2U(SCH_1):SW_PVCCD_HV_CPU1_BOOT1    I10 @S9S_MB_2U_LIB.S9S_MB_2U(SCH_1):PAGE283
 25_29 SW_P12V_PVCCINFAON_CPU1_FLT @S9S_MB_2U_LIB.S9S_MB_2U(SCH_1):SW_P12V_PVCCINFAON_CPU1_FLT    I10 @S9S_MB_2U_LIB.S9S_MB_2U(SCH_1):PAGE283
    32 SW_PVCCD_HV_CPU1_BOOTR1 @S9S_MB_2U_LIB.S9S_MB_2U(SCH_1):SW_PVCCD_HV_CPU1_BOOTR1    I10 @S9S_MB_2U_LIB.S9S_MB_2U(SCH_1):PAGE283
     4 PVCCFA_EHV_CPU1_PVCC @S9S_MB_2U_LIB.S9S_MB_2U(SCH_1):PVCCFA_EHV_CPU1_PVCC    I10 @S9S_MB_2U_LIB.S9S_MB_2U(SCH_1):PAGE283
    36 PVCCD_HV_CPU1_ATSEN @S9S_MB_2U_LIB.S9S_MB_2U(SCH_1):PVCCD_HV_CPU1_ATSEN    I10 @S9S_MB_2U_LIB.S9S_MB_2U(SCH_1):PAGE283
    38 PVCCD_HV_CPU1_ACSP1 @S9S_MB_2U_LIB.S9S_MB_2U(SCH_1):PVCCD_HV_CPU1_ACSP1    I10 @S9S_MB_2U_LIB.S9S_MB_2U(SCH_1):PAGE283
    37 PVCCD_HV_CPU1_LSET1 @S9S_MB_2U_LIB.S9S_MB_2U(SCH_1):PVCCD_HV_CPU1_LSET1    I10 @S9S_MB_2U_LIB.S9S_MB_2U(SCH_1):PAGE283
 10_19 SW_PVCCD_HV_CPU1_SW1 @S9S_MB_2U_LIB.S9S_MB_2U(SCH_1):SW_PVCCD_HV_CPU1_SW1    I10 @S9S_MB_2U_LIB.S9S_MB_2U(SCH_1):PAGE283
     5    GND @S9S_MB_2U_LIB.S9S_MB_2U(SCH_1):GND    I10 @S9S_MB_2U_LIB.S9S_MB_2U(SCH_1):PAGE283
    30 SW_P12V_PVCCINFAON_CPU1_FLT @S9S_MB_2U_LIB.S9S_MB_2U(SCH_1):SW_P12V_PVCCINFAON_CPU1_FLT    I10 @S9S_MB_2U_LIB.S9S_MB_2U(SCH_1):PAGE283
     1 PVCCD_HV_CPU1_VOS @S9S_MB_2U_LIB.S9S_MB_2U(SCH_1):PVCCD_HV_CPU1_VOS    I10 @S9S_MB_2U_LIB.S9S_MB_2U(SCH_1):PAGE283
    40    GND @S9S_MB_2U_LIB.S9S_MB_2U(SCH_1):GND    I10 @S9S_MB_2U_LIB.S9S_MB_2U(SCH_1):PAGE283
    35 PVCCD_HV_CPU1_VDD1 @S9S_MB_2U_LIB.S9S_MB_2U(SCH_1):PVCCD_HV_CPU1_VDD1    I10 @S9S_MB_2U_LIB.S9S_MB_2U(SCH_1):PAGE283
    31     NC     NC    I10 @S9S_MB_2U_LIB.S9S_MB_2U(SCH_1):PAGE283
     6     NC     NC    I10 @S9S_MB_2U_LIB.S9S_MB_2U(SCH_1):PAGE283
    41     NC     NC    I10 @S9S_MB_2U_LIB.S9S_MB_2U(SCH_1):PAGE283
7_9-20_24    GND @S9S_MB_2U_LIB.S9S_MB_2U(SCH_1):GND    I10 @S9S_MB_2U_LIB.S9S_MB_2U(SCH_1):PAGE283

PU18 ISL69260IRAZT-ISL69260IRAZ-T,SA
    23 PVCCD_HV_CPU1_ACSP1 @S9S_MB_2U_LIB.S9S_MB_2U(SCH_1):PVCCD_HV_CPU1_ACSP1    I53 @S9S_MB_2U_LIB.S9S_MB_2U(SCH_1):PAGE282
    39 PVCCD_HV_CPU1_VCC @S9S_MB_2U_LIB.S9S_MB_2U(SCH_1):PVCCD_HV_CPU1_VCC    I53 @S9S_MB_2U_LIB.S9S_MB_2U(SCH_1):PAGE282
    20    GND @S9S_MB_2U_LIB.S9S_MB_2U(SCH_1):GND    I53 @S9S_MB_2U_LIB.S9S_MB_2U(SCH_1):PAGE282
    10 SMB_CLK_PVCCD_HV_CPU1 @S9S_MB_2U_LIB.S9S_MB_2U(SCH_1):SMB_CLK_PVCCD_HV_CPU1    I53 @S9S_MB_2U_LIB.S9S_MB_2U(SCH_1):PAGE282
    18 SVID_DIO_PVCCD_HV_CPU1_R @S9S_MB_2U_LIB.S9S_MB_2U(SCH_1):SVID_DIO_PVCCD_HV_CPU1_R    I53 @S9S_MB_2U_LIB.S9S_MB_2U(SCH_1):PAGE282
    24 NC_PVCCD_HV_CPU1_ACSP2 @S9S_MB_2U_LIB.S9S_MB_2U(SCH_1):NC_PVCCD_HV_CPU1_ACSP2    I53 @S9S_MB_2U_LIB.S9S_MB_2U(SCH_1):PAGE282
    19 SVID_ALERT_PVCCD_HV_CPU1_R @S9S_MB_2U_LIB.S9S_MB_2U(SCH_1):SVID_ALERT_PVCCD_HV_CPU1_R    I53 @S9S_MB_2U_LIB.S9S_MB_2U(SCH_1):PAGE282
    14 IRQ_PVCCD_CPU1_VRHOT_LVC3_R_N @S9S_MB_2U_LIB.S9S_MB_2U(SCH_1):IRQ_PVCCD_CPU1_VRHOT_LVC3_R_N    I53 @S9S_MB_2U_LIB.S9S_MB_2U(SCH_1):PAGE282
    25 NC_PVCCD_HV_CPU1_ACSP3 @S9S_MB_2U_LIB.S9S_MB_2U(SCH_1):NC_PVCCD_HV_CPU1_ACSP3    I53 @S9S_MB_2U_LIB.S9S_MB_2U(SCH_1):PAGE282
    26 NC_PVCCD_HV_CPU1_ACSP4 @S9S_MB_2U_LIB.S9S_MB_2U(SCH_1):NC_PVCCD_HV_CPU1_ACSP4    I53 @S9S_MB_2U_LIB.S9S_MB_2U(SCH_1):PAGE282
    16 NC_PVCCD_HV_CPU1_BVR_RDY @S9S_MB_2U_LIB.S9S_MB_2U(SCH_1):NC_PVCCD_HV_CPU1_BVR_RDY    I53 @S9S_MB_2U_LIB.S9S_MB_2U(SCH_1):PAGE282
    17 SVID_CLK_PVCCD_HV_CPU1_R @S9S_MB_2U_LIB.S9S_MB_2U(SCH_1):SVID_CLK_PVCCD_HV_CPU1_R    I53 @S9S_MB_2U_LIB.S9S_MB_2U(SCH_1):PAGE282
    11 NC_PVCCD_HV_CPU1_SMB_ALERT @S9S_MB_2U_LIB.S9S_MB_2U(SCH_1):NC_PVCCD_HV_CPU1_SMB_ALERT    I53 @S9S_MB_2U_LIB.S9S_MB_2U(SCH_1):PAGE282
    13 PVCCD_HV_CPU1_EN_R @S9S_MB_2U_LIB.S9S_MB_2U(SCH_1):PVCCD_HV_CPU1_EN_R    I53 @S9S_MB_2U_LIB.S9S_MB_2U(SCH_1):PAGE282
    22 VSENSE_PVCCD_HV_CPU1_DN @S9S_MB_2U_LIB.S9S_MB_2U(SCH_1):VSENSE_PVCCD_HV_CPU1_DN    I53 @S9S_MB_2U_LIB.S9S_MB_2U(SCH_1):PAGE282
     9 SMB_DIO_PVCCD_HV_CPU1 @S9S_MB_2U_LIB.S9S_MB_2U(SCH_1):SMB_DIO_PVCCD_HV_CPU1    I53 @S9S_MB_2U_LIB.S9S_MB_2U(SCH_1):PAGE282
     5 NC_PVCCD_HV_CPU1_APWM4 @S9S_MB_2U_LIB.S9S_MB_2U(SCH_1):NC_PVCCD_HV_CPU1_APWM4    I53 @S9S_MB_2U_LIB.S9S_MB_2U(SCH_1):PAGE282
     6 NC_PVCCD_HV_CPU1_APWM3 @S9S_MB_2U_LIB.S9S_MB_2U(SCH_1):NC_PVCCD_HV_CPU1_APWM3    I53 @S9S_MB_2U_LIB.S9S_MB_2U(SCH_1):PAGE282
    21 SH_PVCCD_HV_CPU1_R @S9S_MB_2U_LIB.S9S_MB_2U(SCH_1):SH_PVCCD_HV_CPU1_R    I53 @S9S_MB_2U_LIB.S9S_MB_2U(SCH_1):PAGE282
     2 NC_PVCCD_HV_CPU1_APWM7 @S9S_MB_2U_LIB.S9S_MB_2U(SCH_1):NC_PVCCD_HV_CPU1_APWM7    I53 @S9S_MB_2U_LIB.S9S_MB_2U(SCH_1):PAGE282
    12 PWRGD_PVCCD_HV_CPU1_R @S9S_MB_2U_LIB.S9S_MB_2U(SCH_1):PWRGD_PVCCD_HV_CPU1_R    I53 @S9S_MB_2U_LIB.S9S_MB_2U(SCH_1):PAGE282
     7 NC_PVCCD_HV_CPU1_APWM2 @S9S_MB_2U_LIB.S9S_MB_2U(SCH_1):NC_PVCCD_HV_CPU1_APWM2    I53 @S9S_MB_2U_LIB.S9S_MB_2U(SCH_1):PAGE282
    40 PVCCD_HV_CPU1_VREF @S9S_MB_2U_LIB.S9S_MB_2U(SCH_1):PVCCD_HV_CPU1_VREF    I53 @S9S_MB_2U_LIB.S9S_MB_2U(SCH_1):PAGE282
    37 PVCCD_HV_CPU1_ISENSE_P @S9S_MB_2U_LIB.S9S_MB_2U(SCH_1):PVCCD_HV_CPU1_ISENSE_P    I53 @S9S_MB_2U_LIB.S9S_MB_2U(SCH_1):PAGE282
    38 PVCCD_HV_CPU1_ISENSE_N @S9S_MB_2U_LIB.S9S_MB_2U(SCH_1):PVCCD_HV_CPU1_ISENSE_N    I53 @S9S_MB_2U_LIB.S9S_MB_2U(SCH_1):PAGE282
    36 PVCCD_HV_CPU1_ISYS_R @S9S_MB_2U_LIB.S9S_MB_2U(SCH_1):PVCCD_HV_CPU1_ISYS_R    I53 @S9S_MB_2U_LIB.S9S_MB_2U(SCH_1):PAGE282
    15 PVCCD_HV_CPU1_PIN_ALT @S9S_MB_2U_LIB.S9S_MB_2U(SCH_1):PVCCD_HV_CPU1_PIN_ALT    I53 @S9S_MB_2U_LIB.S9S_MB_2U(SCH_1):PAGE282
    32    GND @S9S_MB_2U_LIB.S9S_MB_2U(SCH_1):GND    I53 @S9S_MB_2U_LIB.S9S_MB_2U(SCH_1):PAGE282
    31    GND @S9S_MB_2U_LIB.S9S_MB_2U(SCH_1):GND    I53 @S9S_MB_2U_LIB.S9S_MB_2U(SCH_1):PAGE282
    29 NC_PVCCD_HV_CPU1_ACSP7 @S9S_MB_2U_LIB.S9S_MB_2U(SCH_1):NC_PVCCD_HV_CPU1_ACSP7    I53 @S9S_MB_2U_LIB.S9S_MB_2U(SCH_1):PAGE282
     8 PVCCD_HV_CPU1_APWM1 @S9S_MB_2U_LIB.S9S_MB_2U(SCH_1):PVCCD_HV_CPU1_APWM1    I53 @S9S_MB_2U_LIB.S9S_MB_2U(SCH_1):PAGE282
     4 NC_PVCCD_HV_CPU1_APWM5 @S9S_MB_2U_LIB.S9S_MB_2U(SCH_1):NC_PVCCD_HV_CPU1_APWM5    I53 @S9S_MB_2U_LIB.S9S_MB_2U(SCH_1):PAGE282
    27 NC_PVCCD_HV_CPU1_ACSP5 @S9S_MB_2U_LIB.S9S_MB_2U(SCH_1):NC_PVCCD_HV_CPU1_ACSP5    I53 @S9S_MB_2U_LIB.S9S_MB_2U(SCH_1):PAGE282
     3 NC_PVCCD_HV_CPU1_APWM6 @S9S_MB_2U_LIB.S9S_MB_2U(SCH_1):NC_PVCCD_HV_CPU1_APWM6    I53 @S9S_MB_2U_LIB.S9S_MB_2U(SCH_1):PAGE282
    28 NC_PVCCD_HV_CPU1_ACSP6 @S9S_MB_2U_LIB.S9S_MB_2U(SCH_1):NC_PVCCD_HV_CPU1_ACSP6    I53 @S9S_MB_2U_LIB.S9S_MB_2U(SCH_1):PAGE282
    33 PVCCD_HV_CPU1_FAULT @S9S_MB_2U_LIB.S9S_MB_2U(SCH_1):PVCCD_HV_CPU1_FAULT    I53 @S9S_MB_2U_LIB.S9S_MB_2U(SCH_1):PAGE282
    TH    GND @S9S_MB_2U_LIB.S9S_MB_2U(SCH_1):GND    I53 @S9S_MB_2U_LIB.S9S_MB_2U(SCH_1):PAGE282
    34 PVCCD_HV_CPU1_ADDR @S9S_MB_2U_LIB.S9S_MB_2U(SCH_1):PVCCD_HV_CPU1_ADDR    I53 @S9S_MB_2U_LIB.S9S_MB_2U(SCH_1):PAGE282
    35 PVCCD_HV_CPU1_ATSEN @S9S_MB_2U_LIB.S9S_MB_2U(SCH_1):PVCCD_HV_CPU1_ATSEN    I53 @S9S_MB_2U_LIB.S9S_MB_2U(SCH_1):PAGE282
     1 NC_PVCCD_HV_CPU1_APWM8 @S9S_MB_2U_LIB.S9S_MB_2U(SCH_1):NC_PVCCD_HV_CPU1_APWM8    I53 @S9S_MB_2U_LIB.S9S_MB_2U(SCH_1):PAGE282
    30 NC_PVCCD_HV_CPU1_ACSP8 @S9S_MB_2U_LIB.S9S_MB_2U(SCH_1):NC_PVCCD_HV_CPU1_ACSP8    I53 @S9S_MB_2U_LIB.S9S_MB_2U(SCH_1):PAGE282

PU22 ISL69260IRAZT-ISL69260IRAZ-T,SA
    23 PVCCINFAON_CPU1_ACSP1 @S9S_MB_2U_LIB.S9S_MB_2U(SCH_1):PVCCINFAON_CPU1_ACSP1    I38 @S9S_MB_2U_LIB.S9S_MB_2U(SCH_1):PAGE278
    39 PVCCINFAON_CPU1_VCC @S9S_MB_2U_LIB.S9S_MB_2U(SCH_1):PVCCINFAON_CPU1_VCC    I38 @S9S_MB_2U_LIB.S9S_MB_2U(SCH_1):PAGE278
    20 PVCCFA_EHV_CPU1_EN_R @S9S_MB_2U_LIB.S9S_MB_2U(SCH_1):PVCCFA_EHV_CPU1_EN_R    I38 @S9S_MB_2U_LIB.S9S_MB_2U(SCH_1):PAGE278
    10 SMB_CLK_PVCCINFAON_CPU1 @S9S_MB_2U_LIB.S9S_MB_2U(SCH_1):SMB_CLK_PVCCINFAON_CPU1    I38 @S9S_MB_2U_LIB.S9S_MB_2U(SCH_1):PAGE278
    18 SVID_DIO_PVCCINFAON_CPU1_R @S9S_MB_2U_LIB.S9S_MB_2U(SCH_1):SVID_DIO_PVCCINFAON_CPU1_R    I38 @S9S_MB_2U_LIB.S9S_MB_2U(SCH_1):PAGE278
    24 PVCCINFAON_CPU1_ACSP2 @S9S_MB_2U_LIB.S9S_MB_2U(SCH_1):PVCCINFAON_CPU1_ACSP2    I38 @S9S_MB_2U_LIB.S9S_MB_2U(SCH_1):PAGE278
    19 SVID_ALERT_PVCCINFAON_CPU1_R @S9S_MB_2U_LIB.S9S_MB_2U(SCH_1):SVID_ALERT_PVCCINFAON_CPU1_R    I38 @S9S_MB_2U_LIB.S9S_MB_2U(SCH_1):PAGE278
    14 IRQ_PVCCFA_CPU1_VRHOT_N @S9S_MB_2U_LIB.S9S_MB_2U(SCH_1):IRQ_PVCCFA_CPU1_VRHOT_N    I38 @S9S_MB_2U_LIB.S9S_MB_2U(SCH_1):PAGE278
    25 NC_PVCCINFAON_CPU1_ACSP3 @S9S_MB_2U_LIB.S9S_MB_2U(SCH_1):NC_PVCCINFAON_CPU1_ACSP3    I38 @S9S_MB_2U_LIB.S9S_MB_2U(SCH_1):PAGE278
    26 NC_PVCCINFAON_CPU1_ACSP4 @S9S_MB_2U_LIB.S9S_MB_2U(SCH_1):NC_PVCCINFAON_CPU1_ACSP4    I38 @S9S_MB_2U_LIB.S9S_MB_2U(SCH_1):PAGE278
    16 PWRGD_PVCCFA_EHV_CPU1_R @S9S_MB_2U_LIB.S9S_MB_2U(SCH_1):PWRGD_PVCCFA_EHV_CPU1_R    I38 @S9S_MB_2U_LIB.S9S_MB_2U(SCH_1):PAGE278
    17 SVID_CLK_PVCCINFAON_CPU1_R @S9S_MB_2U_LIB.S9S_MB_2U(SCH_1):SVID_CLK_PVCCINFAON_CPU1_R    I38 @S9S_MB_2U_LIB.S9S_MB_2U(SCH_1):PAGE278
    11 NC_PVCCINFAON_CPU1_SMB_ALERT @S9S_MB_2U_LIB.S9S_MB_2U(SCH_1):NC_PVCCINFAON_CPU1_SMB_ALERT    I38 @S9S_MB_2U_LIB.S9S_MB_2U(SCH_1):PAGE278
    13 PVCCINFAON_CPU1_EN_R @S9S_MB_2U_LIB.S9S_MB_2U(SCH_1):PVCCINFAON_CPU1_EN_R    I38 @S9S_MB_2U_LIB.S9S_MB_2U(SCH_1):PAGE278
    22 VSENSE_PVCCINFAON_CPU1_DN @S9S_MB_2U_LIB.S9S_MB_2U(SCH_1):VSENSE_PVCCINFAON_CPU1_DN    I38 @S9S_MB_2U_LIB.S9S_MB_2U(SCH_1):PAGE278
     9 SMB_DIO_PVCCINFAON_CPU1 @S9S_MB_2U_LIB.S9S_MB_2U(SCH_1):SMB_DIO_PVCCINFAON_CPU1    I38 @S9S_MB_2U_LIB.S9S_MB_2U(SCH_1):PAGE278
     5 NC_PVCCINFAON_CPU1_APWM4 @S9S_MB_2U_LIB.S9S_MB_2U(SCH_1):NC_PVCCINFAON_CPU1_APWM4    I38 @S9S_MB_2U_LIB.S9S_MB_2U(SCH_1):PAGE278
     6 NC_PVCCINFAON_CPU1_APWM3 @S9S_MB_2U_LIB.S9S_MB_2U(SCH_1):NC_PVCCINFAON_CPU1_APWM3    I38 @S9S_MB_2U_LIB.S9S_MB_2U(SCH_1):PAGE278
    21 SH_PVCCINFAON_CPU1_R @S9S_MB_2U_LIB.S9S_MB_2U(SCH_1):SH_PVCCINFAON_CPU1_R    I38 @S9S_MB_2U_LIB.S9S_MB_2U(SCH_1):PAGE278
     2 NC_PVCCINFAON_CPU1_APWM7 @S9S_MB_2U_LIB.S9S_MB_2U(SCH_1):NC_PVCCINFAON_CPU1_APWM7    I38 @S9S_MB_2U_LIB.S9S_MB_2U(SCH_1):PAGE278
    12 PWRGD_PVCCINFAON_CPU1_R @S9S_MB_2U_LIB.S9S_MB_2U(SCH_1):PWRGD_PVCCINFAON_CPU1_R    I38 @S9S_MB_2U_LIB.S9S_MB_2U(SCH_1):PAGE278
     7 PVCCINFAON_CPU1_APWM2 @S9S_MB_2U_LIB.S9S_MB_2U(SCH_1):PVCCINFAON_CPU1_APWM2    I38 @S9S_MB_2U_LIB.S9S_MB_2U(SCH_1):PAGE278
    40 PVCCINFAON_CPU1_VREF @S9S_MB_2U_LIB.S9S_MB_2U(SCH_1):PVCCINFAON_CPU1_VREF    I38 @S9S_MB_2U_LIB.S9S_MB_2U(SCH_1):PAGE278
    37 PVCCINFAON_CPU1_CSPIN @S9S_MB_2U_LIB.S9S_MB_2U(SCH_1):PVCCINFAON_CPU1_CSPIN    I38 @S9S_MB_2U_LIB.S9S_MB_2U(SCH_1):PAGE278
    38 PVCCINFAON_CPU1_VIN_CSNIN @S9S_MB_2U_LIB.S9S_MB_2U(SCH_1):PVCCINFAON_CPU1_VIN_CSNIN    I38 @S9S_MB_2U_LIB.S9S_MB_2U(SCH_1):PAGE278
    36 PVCCFA_EHV_CPU1_BTSEN @S9S_MB_2U_LIB.S9S_MB_2U(SCH_1):PVCCFA_EHV_CPU1_BTSEN    I38 @S9S_MB_2U_LIB.S9S_MB_2U(SCH_1):PAGE278
    15 PVCCINFAON_CPU1_PIN_ALERT @S9S_MB_2U_LIB.S9S_MB_2U(SCH_1):PVCCINFAON_CPU1_PIN_ALERT    I38 @S9S_MB_2U_LIB.S9S_MB_2U(SCH_1):PAGE278
    32 SH_PVCCFA_EHV_CPU1_R @S9S_MB_2U_LIB.S9S_MB_2U(SCH_1):SH_PVCCFA_EHV_CPU1_R    I38 @S9S_MB_2U_LIB.S9S_MB_2U(SCH_1):PAGE278
    31 VSENSE_PVCCFA_EHV_CPU1_DN @S9S_MB_2U_LIB.S9S_MB_2U(SCH_1):VSENSE_PVCCFA_EHV_CPU1_DN    I38 @S9S_MB_2U_LIB.S9S_MB_2U(SCH_1):PAGE278
    29 NC_PVCCINFAON_CPU1_ACSP7 @S9S_MB_2U_LIB.S9S_MB_2U(SCH_1):NC_PVCCINFAON_CPU1_ACSP7    I38 @S9S_MB_2U_LIB.S9S_MB_2U(SCH_1):PAGE278
     8 PVCCINFAON_CPU1_APWM1 @S9S_MB_2U_LIB.S9S_MB_2U(SCH_1):PVCCINFAON_CPU1_APWM1    I38 @S9S_MB_2U_LIB.S9S_MB_2U(SCH_1):PAGE278
     4 NC_PVCCINFAON_CPU1_APWM5 @S9S_MB_2U_LIB.S9S_MB_2U(SCH_1):NC_PVCCINFAON_CPU1_APWM5    I38 @S9S_MB_2U_LIB.S9S_MB_2U(SCH_1):PAGE278
    27 NC_PVCCINFAON_CPU1_ACSP5 @S9S_MB_2U_LIB.S9S_MB_2U(SCH_1):NC_PVCCINFAON_CPU1_ACSP5    I38 @S9S_MB_2U_LIB.S9S_MB_2U(SCH_1):PAGE278
     3 NC_PVCCINFAON_CPU1_APWM6 @S9S_MB_2U_LIB.S9S_MB_2U(SCH_1):NC_PVCCINFAON_CPU1_APWM6    I38 @S9S_MB_2U_LIB.S9S_MB_2U(SCH_1):PAGE278
    28 NC_PVCCINFAON_CPU1_ACSP6 @S9S_MB_2U_LIB.S9S_MB_2U(SCH_1):NC_PVCCINFAON_CPU1_ACSP6    I38 @S9S_MB_2U_LIB.S9S_MB_2U(SCH_1):PAGE278
    33 PVCCINFAON_CPU1_VR_FAULT @S9S_MB_2U_LIB.S9S_MB_2U(SCH_1):PVCCINFAON_CPU1_VR_FAULT    I38 @S9S_MB_2U_LIB.S9S_MB_2U(SCH_1):PAGE278
    TH    GND @S9S_MB_2U_LIB.S9S_MB_2U(SCH_1):GND    I38 @S9S_MB_2U_LIB.S9S_MB_2U(SCH_1):PAGE278
    34 PVCCINFAON_CPU1_ADDR @S9S_MB_2U_LIB.S9S_MB_2U(SCH_1):PVCCINFAON_CPU1_ADDR    I38 @S9S_MB_2U_LIB.S9S_MB_2U(SCH_1):PAGE278
    35 PVCCINFAON_CPU1_ATSEN @S9S_MB_2U_LIB.S9S_MB_2U(SCH_1):PVCCINFAON_CPU1_ATSEN    I38 @S9S_MB_2U_LIB.S9S_MB_2U(SCH_1):PAGE278
     1 PVCCFA_EHV_CPU1_BPWM1 @S9S_MB_2U_LIB.S9S_MB_2U(SCH_1):PVCCFA_EHV_CPU1_BPWM1    I38 @S9S_MB_2U_LIB.S9S_MB_2U(SCH_1):PAGE278
    30 PVCCFA_EHV_CPU1_BCSP1 @S9S_MB_2U_LIB.S9S_MB_2U(SCH_1):PVCCFA_EHV_CPU1_BCSP1    I38 @S9S_MB_2U_LIB.S9S_MB_2U(SCH_1):PAGE278

PU23_P1_8 ISL99390FRZTR5935-ISL99390FRZ-A
    34 PVCCIN_CPU1_PWM8 @S9S_MB_2U_LIB.S9S_MB_2U(SCH_1):PVCCIN_CPU1_PWM8    I11 @S9S_MB_2U_LIB.S9S_MB_2U(SCH_1):PAGE274
    39 PVCCIN_CPU1_VREF @S9S_MB_2U_LIB.S9S_MB_2U(SCH_1):PVCCIN_CPU1_VREF    I11 @S9S_MB_2U_LIB.S9S_MB_2U(SCH_1):PAGE274
     3 PVCCIN_CPU1_VDD8 @S9S_MB_2U_LIB.S9S_MB_2U(SCH_1):PVCCIN_CPU1_VDD8    I11 @S9S_MB_2U_LIB.S9S_MB_2U(SCH_1):PAGE274
     2    GND @S9S_MB_2U_LIB.S9S_MB_2U(SCH_1):GND    I11 @S9S_MB_2U_LIB.S9S_MB_2U(SCH_1):PAGE274
    33 SW_PVCCIN_CPU1_BOOT8 @S9S_MB_2U_LIB.S9S_MB_2U(SCH_1):SW_PVCCIN_CPU1_BOOT8    I11 @S9S_MB_2U_LIB.S9S_MB_2U(SCH_1):PAGE274
 25_29 SW_P12V_PVCCIN_CPU1_FLT @S9S_MB_2U_LIB.S9S_MB_2U(SCH_1):SW_P12V_PVCCIN_CPU1_FLT    I11 @S9S_MB_2U_LIB.S9S_MB_2U(SCH_1):PAGE274
    32 SW_PVCCIN_CPU1_BOOTR8 @S9S_MB_2U_LIB.S9S_MB_2U(SCH_1):SW_PVCCIN_CPU1_BOOTR8    I11 @S9S_MB_2U_LIB.S9S_MB_2U(SCH_1):PAGE274
     4 PVCCIN_CPU1_PVCC @S9S_MB_2U_LIB.S9S_MB_2U(SCH_1):PVCCIN_CPU1_PVCC    I11 @S9S_MB_2U_LIB.S9S_MB_2U(SCH_1):PAGE274
    36 PVCCIN_CPU1_ATSEN @S9S_MB_2U_LIB.S9S_MB_2U(SCH_1):PVCCIN_CPU1_ATSEN    I11 @S9S_MB_2U_LIB.S9S_MB_2U(SCH_1):PAGE274
    38 PVCCIN_CPU1_IMON8 @S9S_MB_2U_LIB.S9S_MB_2U(SCH_1):PVCCIN_CPU1_IMON8    I11 @S9S_MB_2U_LIB.S9S_MB_2U(SCH_1):PAGE274
    37 PVCCIN_CPU1_LSET8 @S9S_MB_2U_LIB.S9S_MB_2U(SCH_1):PVCCIN_CPU1_LSET8    I11 @S9S_MB_2U_LIB.S9S_MB_2U(SCH_1):PAGE274
 10_19 SW_PVCCIN_CPU1_SW8 @S9S_MB_2U_LIB.S9S_MB_2U(SCH_1):SW_PVCCIN_CPU1_SW8    I11 @S9S_MB_2U_LIB.S9S_MB_2U(SCH_1):PAGE274
     5    GND @S9S_MB_2U_LIB.S9S_MB_2U(SCH_1):GND    I11 @S9S_MB_2U_LIB.S9S_MB_2U(SCH_1):PAGE274
    30 SW_P12V_PVCCIN_CPU1_FLT @S9S_MB_2U_LIB.S9S_MB_2U(SCH_1):SW_P12V_PVCCIN_CPU1_FLT    I11 @S9S_MB_2U_LIB.S9S_MB_2U(SCH_1):PAGE274
     1 PVCCIN_CPU1_VOS8 @S9S_MB_2U_LIB.S9S_MB_2U(SCH_1):PVCCIN_CPU1_VOS8    I11 @S9S_MB_2U_LIB.S9S_MB_2U(SCH_1):PAGE274
    40    GND @S9S_MB_2U_LIB.S9S_MB_2U(SCH_1):GND    I11 @S9S_MB_2U_LIB.S9S_MB_2U(SCH_1):PAGE274
    35 PVCCIN_CPU1_VDD8 @S9S_MB_2U_LIB.S9S_MB_2U(SCH_1):PVCCIN_CPU1_VDD8    I11 @S9S_MB_2U_LIB.S9S_MB_2U(SCH_1):PAGE274
    31     NC     NC    I11 @S9S_MB_2U_LIB.S9S_MB_2U(SCH_1):PAGE274
     6     NC     NC    I11 @S9S_MB_2U_LIB.S9S_MB_2U(SCH_1):PAGE274
    41     NC     NC    I11 @S9S_MB_2U_LIB.S9S_MB_2U(SCH_1):PAGE274
7_9-20_24    GND @S9S_MB_2U_LIB.S9S_MB_2U(SCH_1):GND    I11 @S9S_MB_2U_LIB.S9S_MB_2U(SCH_1):PAGE274

PU24_P1_7 ISL99390FRZTR5935-ISL99390FRZ-A
    34 PVCCIN_CPU1_PWM7 @S9S_MB_2U_LIB.S9S_MB_2U(SCH_1):PVCCIN_CPU1_PWM7    I20 @S9S_MB_2U_LIB.S9S_MB_2U(SCH_1):PAGE274
    39 PVCCIN_CPU1_VREF @S9S_MB_2U_LIB.S9S_MB_2U(SCH_1):PVCCIN_CPU1_VREF    I20 @S9S_MB_2U_LIB.S9S_MB_2U(SCH_1):PAGE274
     3 PVCCIN_CPU1_VDD7 @S9S_MB_2U_LIB.S9S_MB_2U(SCH_1):PVCCIN_CPU1_VDD7    I20 @S9S_MB_2U_LIB.S9S_MB_2U(SCH_1):PAGE274
     2    GND @S9S_MB_2U_LIB.S9S_MB_2U(SCH_1):GND    I20 @S9S_MB_2U_LIB.S9S_MB_2U(SCH_1):PAGE274
    33 SW_PVCCIN_CPU1_BOOT7 @S9S_MB_2U_LIB.S9S_MB_2U(SCH_1):SW_PVCCIN_CPU1_BOOT7    I20 @S9S_MB_2U_LIB.S9S_MB_2U(SCH_1):PAGE274
 25_29 SW_P12V_PVCCIN_CPU1_FLT @S9S_MB_2U_LIB.S9S_MB_2U(SCH_1):SW_P12V_PVCCIN_CPU1_FLT    I20 @S9S_MB_2U_LIB.S9S_MB_2U(SCH_1):PAGE274
    32 SW_PVCCIN_CPU1_BOOTR7 @S9S_MB_2U_LIB.S9S_MB_2U(SCH_1):SW_PVCCIN_CPU1_BOOTR7    I20 @S9S_MB_2U_LIB.S9S_MB_2U(SCH_1):PAGE274
     4 PVCCIN_CPU1_PVCC @S9S_MB_2U_LIB.S9S_MB_2U(SCH_1):PVCCIN_CPU1_PVCC    I20 @S9S_MB_2U_LIB.S9S_MB_2U(SCH_1):PAGE274
    36 PVCCIN_CPU1_ATSEN @S9S_MB_2U_LIB.S9S_MB_2U(SCH_1):PVCCIN_CPU1_ATSEN    I20 @S9S_MB_2U_LIB.S9S_MB_2U(SCH_1):PAGE274
    38 PVCCIN_CPU1_IMON7 @S9S_MB_2U_LIB.S9S_MB_2U(SCH_1):PVCCIN_CPU1_IMON7    I20 @S9S_MB_2U_LIB.S9S_MB_2U(SCH_1):PAGE274
    37 PVCCIN_CPU1_LSET7 @S9S_MB_2U_LIB.S9S_MB_2U(SCH_1):PVCCIN_CPU1_LSET7    I20 @S9S_MB_2U_LIB.S9S_MB_2U(SCH_1):PAGE274
 10_19 SW_PVCCIN_CPU1_SW7 @S9S_MB_2U_LIB.S9S_MB_2U(SCH_1):SW_PVCCIN_CPU1_SW7    I20 @S9S_MB_2U_LIB.S9S_MB_2U(SCH_1):PAGE274
     5    GND @S9S_MB_2U_LIB.S9S_MB_2U(SCH_1):GND    I20 @S9S_MB_2U_LIB.S9S_MB_2U(SCH_1):PAGE274
    30 SW_P12V_PVCCIN_CPU1_FLT @S9S_MB_2U_LIB.S9S_MB_2U(SCH_1):SW_P12V_PVCCIN_CPU1_FLT    I20 @S9S_MB_2U_LIB.S9S_MB_2U(SCH_1):PAGE274
     1 PVCCIN_CPU1_VOS7 @S9S_MB_2U_LIB.S9S_MB_2U(SCH_1):PVCCIN_CPU1_VOS7    I20 @S9S_MB_2U_LIB.S9S_MB_2U(SCH_1):PAGE274
    40    GND @S9S_MB_2U_LIB.S9S_MB_2U(SCH_1):GND    I20 @S9S_MB_2U_LIB.S9S_MB_2U(SCH_1):PAGE274
    35 PVCCIN_CPU1_VDD7 @S9S_MB_2U_LIB.S9S_MB_2U(SCH_1):PVCCIN_CPU1_VDD7    I20 @S9S_MB_2U_LIB.S9S_MB_2U(SCH_1):PAGE274
    31     NC     NC    I20 @S9S_MB_2U_LIB.S9S_MB_2U(SCH_1):PAGE274
     6     NC     NC    I20 @S9S_MB_2U_LIB.S9S_MB_2U(SCH_1):PAGE274
    41     NC     NC    I20 @S9S_MB_2U_LIB.S9S_MB_2U(SCH_1):PAGE274
7_9-20_24    GND @S9S_MB_2U_LIB.S9S_MB_2U(SCH_1):GND    I20 @S9S_MB_2U_LIB.S9S_MB_2U(SCH_1):PAGE274

PU25_P1_6 ISL99390FRZTR5935-ISL99390FRZ-A
    34 PVCCIN_CPU1_PWM6 @S9S_MB_2U_LIB.S9S_MB_2U(SCH_1):PVCCIN_CPU1_PWM6    I16 @S9S_MB_2U_LIB.S9S_MB_2U(SCH_1):PAGE273
    39 PVCCIN_CPU1_VREF @S9S_MB_2U_LIB.S9S_MB_2U(SCH_1):PVCCIN_CPU1_VREF    I16 @S9S_MB_2U_LIB.S9S_MB_2U(SCH_1):PAGE273
     3 PVCCIN_CPU1_VDD6 @S9S_MB_2U_LIB.S9S_MB_2U(SCH_1):PVCCIN_CPU1_VDD6    I16 @S9S_MB_2U_LIB.S9S_MB_2U(SCH_1):PAGE273
     2    GND @S9S_MB_2U_LIB.S9S_MB_2U(SCH_1):GND    I16 @S9S_MB_2U_LIB.S9S_MB_2U(SCH_1):PAGE273
    33 SW_PVCCIN_CPU1_BOOT6 @S9S_MB_2U_LIB.S9S_MB_2U(SCH_1):SW_PVCCIN_CPU1_BOOT6    I16 @S9S_MB_2U_LIB.S9S_MB_2U(SCH_1):PAGE273
 25_29 SW_P12V_PVCCIN_CPU1_FLT @S9S_MB_2U_LIB.S9S_MB_2U(SCH_1):SW_P12V_PVCCIN_CPU1_FLT    I16 @S9S_MB_2U_LIB.S9S_MB_2U(SCH_1):PAGE273
    32 SW_PVCCIN_CPU1_BOOTR6 @S9S_MB_2U_LIB.S9S_MB_2U(SCH_1):SW_PVCCIN_CPU1_BOOTR6    I16 @S9S_MB_2U_LIB.S9S_MB_2U(SCH_1):PAGE273
     4 PVCCIN_CPU1_PVCC @S9S_MB_2U_LIB.S9S_MB_2U(SCH_1):PVCCIN_CPU1_PVCC    I16 @S9S_MB_2U_LIB.S9S_MB_2U(SCH_1):PAGE273
    36 PVCCIN_CPU1_ATSEN @S9S_MB_2U_LIB.S9S_MB_2U(SCH_1):PVCCIN_CPU1_ATSEN    I16 @S9S_MB_2U_LIB.S9S_MB_2U(SCH_1):PAGE273
    38 PVCCIN_CPU1_IMON6 @S9S_MB_2U_LIB.S9S_MB_2U(SCH_1):PVCCIN_CPU1_IMON6    I16 @S9S_MB_2U_LIB.S9S_MB_2U(SCH_1):PAGE273
    37 PVCCIN_CPU1_LSET6 @S9S_MB_2U_LIB.S9S_MB_2U(SCH_1):PVCCIN_CPU1_LSET6    I16 @S9S_MB_2U_LIB.S9S_MB_2U(SCH_1):PAGE273
 10_19 SW_PVCCIN_CPU1_SW6 @S9S_MB_2U_LIB.S9S_MB_2U(SCH_1):SW_PVCCIN_CPU1_SW6    I16 @S9S_MB_2U_LIB.S9S_MB_2U(SCH_1):PAGE273
     5    GND @S9S_MB_2U_LIB.S9S_MB_2U(SCH_1):GND    I16 @S9S_MB_2U_LIB.S9S_MB_2U(SCH_1):PAGE273
    30 SW_P12V_PVCCIN_CPU1_FLT @S9S_MB_2U_LIB.S9S_MB_2U(SCH_1):SW_P12V_PVCCIN_CPU1_FLT    I16 @S9S_MB_2U_LIB.S9S_MB_2U(SCH_1):PAGE273
     1 PVCCIN_CPU1_VOS6 @S9S_MB_2U_LIB.S9S_MB_2U(SCH_1):PVCCIN_CPU1_VOS6    I16 @S9S_MB_2U_LIB.S9S_MB_2U(SCH_1):PAGE273
    40    GND @S9S_MB_2U_LIB.S9S_MB_2U(SCH_1):GND    I16 @S9S_MB_2U_LIB.S9S_MB_2U(SCH_1):PAGE273
    35 PVCCIN_CPU1_VDD6 @S9S_MB_2U_LIB.S9S_MB_2U(SCH_1):PVCCIN_CPU1_VDD6    I16 @S9S_MB_2U_LIB.S9S_MB_2U(SCH_1):PAGE273
    31     NC     NC    I16 @S9S_MB_2U_LIB.S9S_MB_2U(SCH_1):PAGE273
     6     NC     NC    I16 @S9S_MB_2U_LIB.S9S_MB_2U(SCH_1):PAGE273
    41     NC     NC    I16 @S9S_MB_2U_LIB.S9S_MB_2U(SCH_1):PAGE273
7_9-20_24    GND @S9S_MB_2U_LIB.S9S_MB_2U(SCH_1):GND    I16 @S9S_MB_2U_LIB.S9S_MB_2U(SCH_1):PAGE273

PU26_P1_5 ISL99390FRZTR5935-ISL99390FRZ-A
    34 PVCCIN_CPU1_PWM5 @S9S_MB_2U_LIB.S9S_MB_2U(SCH_1):PVCCIN_CPU1_PWM5    I23 @S9S_MB_2U_LIB.S9S_MB_2U(SCH_1):PAGE273
    39 PVCCIN_CPU1_VREF @S9S_MB_2U_LIB.S9S_MB_2U(SCH_1):PVCCIN_CPU1_VREF    I23 @S9S_MB_2U_LIB.S9S_MB_2U(SCH_1):PAGE273
     3 PVCCIN_CPU1_VDD5 @S9S_MB_2U_LIB.S9S_MB_2U(SCH_1):PVCCIN_CPU1_VDD5    I23 @S9S_MB_2U_LIB.S9S_MB_2U(SCH_1):PAGE273
     2    GND @S9S_MB_2U_LIB.S9S_MB_2U(SCH_1):GND    I23 @S9S_MB_2U_LIB.S9S_MB_2U(SCH_1):PAGE273
    33 SW_PVCCIN_CPU1_BOOT5 @S9S_MB_2U_LIB.S9S_MB_2U(SCH_1):SW_PVCCIN_CPU1_BOOT5    I23 @S9S_MB_2U_LIB.S9S_MB_2U(SCH_1):PAGE273
 25_29 SW_P12V_PVCCIN_CPU1_FLT @S9S_MB_2U_LIB.S9S_MB_2U(SCH_1):SW_P12V_PVCCIN_CPU1_FLT    I23 @S9S_MB_2U_LIB.S9S_MB_2U(SCH_1):PAGE273
    32 SW_PVCCIN_CPU1_BOOTR5 @S9S_MB_2U_LIB.S9S_MB_2U(SCH_1):SW_PVCCIN_CPU1_BOOTR5    I23 @S9S_MB_2U_LIB.S9S_MB_2U(SCH_1):PAGE273
     4 PVCCIN_CPU1_PVCC @S9S_MB_2U_LIB.S9S_MB_2U(SCH_1):PVCCIN_CPU1_PVCC    I23 @S9S_MB_2U_LIB.S9S_MB_2U(SCH_1):PAGE273
    36 PVCCIN_CPU1_ATSEN @S9S_MB_2U_LIB.S9S_MB_2U(SCH_1):PVCCIN_CPU1_ATSEN    I23 @S9S_MB_2U_LIB.S9S_MB_2U(SCH_1):PAGE273
    38 PVCCIN_CPU1_IMON5 @S9S_MB_2U_LIB.S9S_MB_2U(SCH_1):PVCCIN_CPU1_IMON5    I23 @S9S_MB_2U_LIB.S9S_MB_2U(SCH_1):PAGE273
    37 PVCCIN_CPU1_LSET5 @S9S_MB_2U_LIB.S9S_MB_2U(SCH_1):PVCCIN_CPU1_LSET5    I23 @S9S_MB_2U_LIB.S9S_MB_2U(SCH_1):PAGE273
 10_19 SW_PVCCIN_CPU1_SW5 @S9S_MB_2U_LIB.S9S_MB_2U(SCH_1):SW_PVCCIN_CPU1_SW5    I23 @S9S_MB_2U_LIB.S9S_MB_2U(SCH_1):PAGE273
     5    GND @S9S_MB_2U_LIB.S9S_MB_2U(SCH_1):GND    I23 @S9S_MB_2U_LIB.S9S_MB_2U(SCH_1):PAGE273
    30 SW_P12V_PVCCIN_CPU1_FLT @S9S_MB_2U_LIB.S9S_MB_2U(SCH_1):SW_P12V_PVCCIN_CPU1_FLT    I23 @S9S_MB_2U_LIB.S9S_MB_2U(SCH_1):PAGE273
     1 PVCCIN_CPU1_VOS5 @S9S_MB_2U_LIB.S9S_MB_2U(SCH_1):PVCCIN_CPU1_VOS5    I23 @S9S_MB_2U_LIB.S9S_MB_2U(SCH_1):PAGE273
    40    GND @S9S_MB_2U_LIB.S9S_MB_2U(SCH_1):GND    I23 @S9S_MB_2U_LIB.S9S_MB_2U(SCH_1):PAGE273
    35 PVCCIN_CPU1_VDD5 @S9S_MB_2U_LIB.S9S_MB_2U(SCH_1):PVCCIN_CPU1_VDD5    I23 @S9S_MB_2U_LIB.S9S_MB_2U(SCH_1):PAGE273
    31     NC     NC    I23 @S9S_MB_2U_LIB.S9S_MB_2U(SCH_1):PAGE273
     6     NC     NC    I23 @S9S_MB_2U_LIB.S9S_MB_2U(SCH_1):PAGE273
    41     NC     NC    I23 @S9S_MB_2U_LIB.S9S_MB_2U(SCH_1):PAGE273
7_9-20_24    GND @S9S_MB_2U_LIB.S9S_MB_2U(SCH_1):GND    I23 @S9S_MB_2U_LIB.S9S_MB_2U(SCH_1):PAGE273

PU27_P1_4 ISL99390FRZTR5935-ISL99390FRZ-A
    34 PVCCIN_CPU1_PWM4 @S9S_MB_2U_LIB.S9S_MB_2U(SCH_1):PVCCIN_CPU1_PWM4    I10 @S9S_MB_2U_LIB.S9S_MB_2U(SCH_1):PAGE272
    39 PVCCIN_CPU1_VREF @S9S_MB_2U_LIB.S9S_MB_2U(SCH_1):PVCCIN_CPU1_VREF    I10 @S9S_MB_2U_LIB.S9S_MB_2U(SCH_1):PAGE272
     3 PVCCIN_CPU1_VDD4 @S9S_MB_2U_LIB.S9S_MB_2U(SCH_1):PVCCIN_CPU1_VDD4    I10 @S9S_MB_2U_LIB.S9S_MB_2U(SCH_1):PAGE272
     2    GND @S9S_MB_2U_LIB.S9S_MB_2U(SCH_1):GND    I10 @S9S_MB_2U_LIB.S9S_MB_2U(SCH_1):PAGE272
    33 SW_PVCCIN_CPU1_BOOT4 @S9S_MB_2U_LIB.S9S_MB_2U(SCH_1):SW_PVCCIN_CPU1_BOOT4    I10 @S9S_MB_2U_LIB.S9S_MB_2U(SCH_1):PAGE272
 25_29 SW_P12V_PVCCIN_CPU1_FLT @S9S_MB_2U_LIB.S9S_MB_2U(SCH_1):SW_P12V_PVCCIN_CPU1_FLT    I10 @S9S_MB_2U_LIB.S9S_MB_2U(SCH_1):PAGE272
    32 SW_PVCCIN_CPU1_BOOTR4 @S9S_MB_2U_LIB.S9S_MB_2U(SCH_1):SW_PVCCIN_CPU1_BOOTR4    I10 @S9S_MB_2U_LIB.S9S_MB_2U(SCH_1):PAGE272
     4 PVCCIN_CPU1_PVCC @S9S_MB_2U_LIB.S9S_MB_2U(SCH_1):PVCCIN_CPU1_PVCC    I10 @S9S_MB_2U_LIB.S9S_MB_2U(SCH_1):PAGE272
    36 PVCCIN_CPU1_ATSEN @S9S_MB_2U_LIB.S9S_MB_2U(SCH_1):PVCCIN_CPU1_ATSEN    I10 @S9S_MB_2U_LIB.S9S_MB_2U(SCH_1):PAGE272
    38 PVCCIN_CPU1_IMON4 @S9S_MB_2U_LIB.S9S_MB_2U(SCH_1):PVCCIN_CPU1_IMON4    I10 @S9S_MB_2U_LIB.S9S_MB_2U(SCH_1):PAGE272
    37 PVCCIN_CPU1_LSET4 @S9S_MB_2U_LIB.S9S_MB_2U(SCH_1):PVCCIN_CPU1_LSET4    I10 @S9S_MB_2U_LIB.S9S_MB_2U(SCH_1):PAGE272
 10_19 SW_PVCCIN_CPU1_SW4 @S9S_MB_2U_LIB.S9S_MB_2U(SCH_1):SW_PVCCIN_CPU1_SW4    I10 @S9S_MB_2U_LIB.S9S_MB_2U(SCH_1):PAGE272
     5    GND @S9S_MB_2U_LIB.S9S_MB_2U(SCH_1):GND    I10 @S9S_MB_2U_LIB.S9S_MB_2U(SCH_1):PAGE272
    30 SW_P12V_PVCCIN_CPU1_FLT @S9S_MB_2U_LIB.S9S_MB_2U(SCH_1):SW_P12V_PVCCIN_CPU1_FLT    I10 @S9S_MB_2U_LIB.S9S_MB_2U(SCH_1):PAGE272
     1 PVCCIN_CPU1_VOS4 @S9S_MB_2U_LIB.S9S_MB_2U(SCH_1):PVCCIN_CPU1_VOS4    I10 @S9S_MB_2U_LIB.S9S_MB_2U(SCH_1):PAGE272
    40    GND @S9S_MB_2U_LIB.S9S_MB_2U(SCH_1):GND    I10 @S9S_MB_2U_LIB.S9S_MB_2U(SCH_1):PAGE272
    35 PVCCIN_CPU1_VDD4 @S9S_MB_2U_LIB.S9S_MB_2U(SCH_1):PVCCIN_CPU1_VDD4    I10 @S9S_MB_2U_LIB.S9S_MB_2U(SCH_1):PAGE272
    31     NC     NC    I10 @S9S_MB_2U_LIB.S9S_MB_2U(SCH_1):PAGE272
     6     NC     NC    I10 @S9S_MB_2U_LIB.S9S_MB_2U(SCH_1):PAGE272
    41     NC     NC    I10 @S9S_MB_2U_LIB.S9S_MB_2U(SCH_1):PAGE272
7_9-20_24    GND @S9S_MB_2U_LIB.S9S_MB_2U(SCH_1):GND    I10 @S9S_MB_2U_LIB.S9S_MB_2U(SCH_1):PAGE272

PU28_P1_3 ISL99390FRZTR5935-ISL99390FRZ-A
    34 PVCCIN_CPU1_PWM3 @S9S_MB_2U_LIB.S9S_MB_2U(SCH_1):PVCCIN_CPU1_PWM3    I66 @S9S_MB_2U_LIB.S9S_MB_2U(SCH_1):PAGE272
    39 PVCCIN_CPU1_VREF @S9S_MB_2U_LIB.S9S_MB_2U(SCH_1):PVCCIN_CPU1_VREF    I66 @S9S_MB_2U_LIB.S9S_MB_2U(SCH_1):PAGE272
     3 PVCCIN_CPU1_VDD3 @S9S_MB_2U_LIB.S9S_MB_2U(SCH_1):PVCCIN_CPU1_VDD3    I66 @S9S_MB_2U_LIB.S9S_MB_2U(SCH_1):PAGE272
     2    GND @S9S_MB_2U_LIB.S9S_MB_2U(SCH_1):GND    I66 @S9S_MB_2U_LIB.S9S_MB_2U(SCH_1):PAGE272
    33 SW_PVCCIN_CPU1_BOOT3 @S9S_MB_2U_LIB.S9S_MB_2U(SCH_1):SW_PVCCIN_CPU1_BOOT3    I66 @S9S_MB_2U_LIB.S9S_MB_2U(SCH_1):PAGE272
 25_29 SW_P12V_PVCCIN_CPU1_FLT @S9S_MB_2U_LIB.S9S_MB_2U(SCH_1):SW_P12V_PVCCIN_CPU1_FLT    I66 @S9S_MB_2U_LIB.S9S_MB_2U(SCH_1):PAGE272
    32 SW_PVCCIN_CPU1_BOOTR3 @S9S_MB_2U_LIB.S9S_MB_2U(SCH_1):SW_PVCCIN_CPU1_BOOTR3    I66 @S9S_MB_2U_LIB.S9S_MB_2U(SCH_1):PAGE272
     4 PVCCIN_CPU1_PVCC @S9S_MB_2U_LIB.S9S_MB_2U(SCH_1):PVCCIN_CPU1_PVCC    I66 @S9S_MB_2U_LIB.S9S_MB_2U(SCH_1):PAGE272
    36 PVCCIN_CPU1_ATSEN @S9S_MB_2U_LIB.S9S_MB_2U(SCH_1):PVCCIN_CPU1_ATSEN    I66 @S9S_MB_2U_LIB.S9S_MB_2U(SCH_1):PAGE272
    38 PVCCIN_CPU1_IMON3 @S9S_MB_2U_LIB.S9S_MB_2U(SCH_1):PVCCIN_CPU1_IMON3    I66 @S9S_MB_2U_LIB.S9S_MB_2U(SCH_1):PAGE272
    37 PVCCIN_CPU1_LSET3 @S9S_MB_2U_LIB.S9S_MB_2U(SCH_1):PVCCIN_CPU1_LSET3    I66 @S9S_MB_2U_LIB.S9S_MB_2U(SCH_1):PAGE272
 10_19 SW_PVCCIN_CPU1_SW3 @S9S_MB_2U_LIB.S9S_MB_2U(SCH_1):SW_PVCCIN_CPU1_SW3    I66 @S9S_MB_2U_LIB.S9S_MB_2U(SCH_1):PAGE272
     5    GND @S9S_MB_2U_LIB.S9S_MB_2U(SCH_1):GND    I66 @S9S_MB_2U_LIB.S9S_MB_2U(SCH_1):PAGE272
    30 SW_P12V_PVCCIN_CPU1_FLT @S9S_MB_2U_LIB.S9S_MB_2U(SCH_1):SW_P12V_PVCCIN_CPU1_FLT    I66 @S9S_MB_2U_LIB.S9S_MB_2U(SCH_1):PAGE272
     1 PVCCIN_CPU1_VOS3 @S9S_MB_2U_LIB.S9S_MB_2U(SCH_1):PVCCIN_CPU1_VOS3    I66 @S9S_MB_2U_LIB.S9S_MB_2U(SCH_1):PAGE272
    40    GND @S9S_MB_2U_LIB.S9S_MB_2U(SCH_1):GND    I66 @S9S_MB_2U_LIB.S9S_MB_2U(SCH_1):PAGE272
    35 PVCCIN_CPU1_VDD3 @S9S_MB_2U_LIB.S9S_MB_2U(SCH_1):PVCCIN_CPU1_VDD3    I66 @S9S_MB_2U_LIB.S9S_MB_2U(SCH_1):PAGE272
    31     NC     NC    I66 @S9S_MB_2U_LIB.S9S_MB_2U(SCH_1):PAGE272
     6     NC     NC    I66 @S9S_MB_2U_LIB.S9S_MB_2U(SCH_1):PAGE272
    41     NC     NC    I66 @S9S_MB_2U_LIB.S9S_MB_2U(SCH_1):PAGE272
7_9-20_24    GND @S9S_MB_2U_LIB.S9S_MB_2U(SCH_1):GND    I66 @S9S_MB_2U_LIB.S9S_MB_2U(SCH_1):PAGE272

PU29 RAA229126GNPHA0-RAA229126GNP#HA
    27 PVCCIN_CPU1_IMON1 @S9S_MB_2U_LIB.S9S_MB_2U(SCH_1):PVCCIN_CPU1_IMON1    I33 @S9S_MB_2U_LIB.S9S_MB_2U(SCH_1):PAGE270
    47 PVCCIN_CPU1_VCC @S9S_MB_2U_LIB.S9S_MB_2U(SCH_1):PVCCIN_CPU1_VCC    I33 @S9S_MB_2U_LIB.S9S_MB_2U(SCH_1):PAGE270
    24 PVCCFA_EHV_FIVRA_CPU1_EN_R @S9S_MB_2U_LIB.S9S_MB_2U(SCH_1):PVCCFA_EHV_FIVRA_CPU1_EN_R    I33 @S9S_MB_2U_LIB.S9S_MB_2U(SCH_1):PAGE270
    14 SMB_CLK_PVCCIN_CPU1 @S9S_MB_2U_LIB.S9S_MB_2U(SCH_1):SMB_CLK_PVCCIN_CPU1    I33 @S9S_MB_2U_LIB.S9S_MB_2U(SCH_1):PAGE270
    22 SVID_DIO_PVCCIN_CPU1_R @S9S_MB_2U_LIB.S9S_MB_2U(SCH_1):SVID_DIO_PVCCIN_CPU1_R    I33 @S9S_MB_2U_LIB.S9S_MB_2U(SCH_1):PAGE270
    32 PVCCIN_CPU1_IMON6 @S9S_MB_2U_LIB.S9S_MB_2U(SCH_1):PVCCIN_CPU1_IMON6    I33 @S9S_MB_2U_LIB.S9S_MB_2U(SCH_1):PAGE270
    23 SVID_ALERT_PVCCIN_CPU1_R @S9S_MB_2U_LIB.S9S_MB_2U(SCH_1):SVID_ALERT_PVCCIN_CPU1_R    I33 @S9S_MB_2U_LIB.S9S_MB_2U(SCH_1):PAGE270
    18 IRQ_PVCCIN_CPU1_VRHOT_N @S9S_MB_2U_LIB.S9S_MB_2U(SCH_1):IRQ_PVCCIN_CPU1_VRHOT_N    I33 @S9S_MB_2U_LIB.S9S_MB_2U(SCH_1):PAGE270
    33 PVCCIN_CPU1_IMON7 @S9S_MB_2U_LIB.S9S_MB_2U(SCH_1):PVCCIN_CPU1_IMON7    I33 @S9S_MB_2U_LIB.S9S_MB_2U(SCH_1):PAGE270
    34 PVCCIN_CPU1_IMON8 @S9S_MB_2U_LIB.S9S_MB_2U(SCH_1):PVCCIN_CPU1_IMON8    I33 @S9S_MB_2U_LIB.S9S_MB_2U(SCH_1):PAGE270
    20 PWRGD_PVCCFA_EHV_FIVRA_CPU1_R @S9S_MB_2U_LIB.S9S_MB_2U(SCH_1):PWRGD_PVCCFA_EHV_FIVRA_CPU1_R    I33 @S9S_MB_2U_LIB.S9S_MB_2U(SCH_1):PAGE270
    21 SVID_CLK_PVCCIN_CPU1_R @S9S_MB_2U_LIB.S9S_MB_2U(SCH_1):SVID_CLK_PVCCIN_CPU1_R    I33 @S9S_MB_2U_LIB.S9S_MB_2U(SCH_1):PAGE270
    15 NC_PVCCIN_CPU1_SMB_ALERT @S9S_MB_2U_LIB.S9S_MB_2U(SCH_1):NC_PVCCIN_CPU1_SMB_ALERT    I33 @S9S_MB_2U_LIB.S9S_MB_2U(SCH_1):PAGE270
    17 PVCCIN_CPU1_EN_R @S9S_MB_2U_LIB.S9S_MB_2U(SCH_1):PVCCIN_CPU1_EN_R    I33 @S9S_MB_2U_LIB.S9S_MB_2U(SCH_1):PAGE270
    26 VSENSE_PVCCIN_CPU1_DN @S9S_MB_2U_LIB.S9S_MB_2U(SCH_1):VSENSE_PVCCIN_CPU1_DN    I33 @S9S_MB_2U_LIB.S9S_MB_2U(SCH_1):PAGE270
    13 SMB_DIO_PVCCIN_CPU1 @S9S_MB_2U_LIB.S9S_MB_2U(SCH_1):SMB_DIO_PVCCIN_CPU1    I33 @S9S_MB_2U_LIB.S9S_MB_2U(SCH_1):PAGE270
     5 PVCCIN_CPU1_PWM8 @S9S_MB_2U_LIB.S9S_MB_2U(SCH_1):PVCCIN_CPU1_PWM8    I33 @S9S_MB_2U_LIB.S9S_MB_2U(SCH_1):PAGE270
     6 PVCCIN_CPU1_PWM7 @S9S_MB_2U_LIB.S9S_MB_2U(SCH_1):PVCCIN_CPU1_PWM7    I33 @S9S_MB_2U_LIB.S9S_MB_2U(SCH_1):PAGE270
    25 SH_PVCCIN_CPU1_R @S9S_MB_2U_LIB.S9S_MB_2U(SCH_1):SH_PVCCIN_CPU1_R    I33 @S9S_MB_2U_LIB.S9S_MB_2U(SCH_1):PAGE270
     2 PVCCFA_EHV_FIVRA_CPU1_PWM2 @S9S_MB_2U_LIB.S9S_MB_2U(SCH_1):PVCCFA_EHV_FIVRA_CPU1_PWM2    I33 @S9S_MB_2U_LIB.S9S_MB_2U(SCH_1):PAGE270
    16 PWRGD_PVCCIN_CPU1_R @S9S_MB_2U_LIB.S9S_MB_2U(SCH_1):PWRGD_PVCCIN_CPU1_R    I33 @S9S_MB_2U_LIB.S9S_MB_2U(SCH_1):PAGE270
     7 PVCCIN_CPU1_PWM6 @S9S_MB_2U_LIB.S9S_MB_2U(SCH_1):PVCCIN_CPU1_PWM6    I33 @S9S_MB_2U_LIB.S9S_MB_2U(SCH_1):PAGE270
    48 PVCCIN_CPU1_VREF @S9S_MB_2U_LIB.S9S_MB_2U(SCH_1):PVCCIN_CPU1_VREF    I33 @S9S_MB_2U_LIB.S9S_MB_2U(SCH_1):PAGE270
    45 PVCCIN_CPU1_CSPIN @S9S_MB_2U_LIB.S9S_MB_2U(SCH_1):PVCCIN_CPU1_CSPIN    I33 @S9S_MB_2U_LIB.S9S_MB_2U(SCH_1):PAGE270
    46 PVCCIN_CPU1_VIN_CSNIN @S9S_MB_2U_LIB.S9S_MB_2U(SCH_1):PVCCIN_CPU1_VIN_CSNIN    I33 @S9S_MB_2U_LIB.S9S_MB_2U(SCH_1):PAGE270
    44 PVCCFA_EHV_FIVRA_CPU1_BTSEN @S9S_MB_2U_LIB.S9S_MB_2U(SCH_1):PVCCFA_EHV_FIVRA_CPU1_BTSEN    I33 @S9S_MB_2U_LIB.S9S_MB_2U(SCH_1):PAGE270
    19 PVCCIN_CPU1_PIN_ALERT @S9S_MB_2U_LIB.S9S_MB_2U(SCH_1):PVCCIN_CPU1_PIN_ALERT    I33 @S9S_MB_2U_LIB.S9S_MB_2U(SCH_1):PAGE270
    40 SH_PVCCFA_EHV_FIVRA_CPU1_R @S9S_MB_2U_LIB.S9S_MB_2U(SCH_1):SH_PVCCFA_EHV_FIVRA_CPU1_R    I33 @S9S_MB_2U_LIB.S9S_MB_2U(SCH_1):PAGE270
    39 VSENSE_PVCCFA_EHV_FIVRA_CPU1_DN @S9S_MB_2U_LIB.S9S_MB_2U(SCH_1):VSENSE_PVCCFA_EHV_FIVRA_CPU1_DN    I33 @S9S_MB_2U_LIB.S9S_MB_2U(SCH_1):PAGE270
    37 PVCCFA_EHV_FIVRA_CPU1_IMON2 @S9S_MB_2U_LIB.S9S_MB_2U(SCH_1):PVCCFA_EHV_FIVRA_CPU1_IMON2    I33 @S9S_MB_2U_LIB.S9S_MB_2U(SCH_1):PAGE270
    12 PVCCIN_CPU1_PWM1 @S9S_MB_2U_LIB.S9S_MB_2U(SCH_1):PVCCIN_CPU1_PWM1    I33 @S9S_MB_2U_LIB.S9S_MB_2U(SCH_1):PAGE270
     4 PVCCFA_EHV_FIVRA_CPU1_PWM4 @S9S_MB_2U_LIB.S9S_MB_2U(SCH_1):PVCCFA_EHV_FIVRA_CPU1_PWM4    I33 @S9S_MB_2U_LIB.S9S_MB_2U(SCH_1):PAGE270
    35 PVCCFA_EHV_FIVRA_CPU1_IMON4 @S9S_MB_2U_LIB.S9S_MB_2U(SCH_1):PVCCFA_EHV_FIVRA_CPU1_IMON4    I33 @S9S_MB_2U_LIB.S9S_MB_2U(SCH_1):PAGE270
     3 PVCCFA_EHV_FIVRA_CPU1_PWM3 @S9S_MB_2U_LIB.S9S_MB_2U(SCH_1):PVCCFA_EHV_FIVRA_CPU1_PWM3    I33 @S9S_MB_2U_LIB.S9S_MB_2U(SCH_1):PAGE270
    36 PVCCFA_EHV_FIVRA_CPU1_IMON3 @S9S_MB_2U_LIB.S9S_MB_2U(SCH_1):PVCCFA_EHV_FIVRA_CPU1_IMON3    I33 @S9S_MB_2U_LIB.S9S_MB_2U(SCH_1):PAGE270
    41 PVCCIN_CPU1_VR_FAULT @S9S_MB_2U_LIB.S9S_MB_2U(SCH_1):PVCCIN_CPU1_VR_FAULT    I33 @S9S_MB_2U_LIB.S9S_MB_2U(SCH_1):PAGE270
    TH    GND @S9S_MB_2U_LIB.S9S_MB_2U(SCH_1):GND    I33 @S9S_MB_2U_LIB.S9S_MB_2U(SCH_1):PAGE270
    42 PVCCIN_CPU1_ADDR @S9S_MB_2U_LIB.S9S_MB_2U(SCH_1):PVCCIN_CPU1_ADDR    I33 @S9S_MB_2U_LIB.S9S_MB_2U(SCH_1):PAGE270
    43 PVCCIN_CPU1_ATSEN @S9S_MB_2U_LIB.S9S_MB_2U(SCH_1):PVCCIN_CPU1_ATSEN    I33 @S9S_MB_2U_LIB.S9S_MB_2U(SCH_1):PAGE270
     1 PVCCFA_EHV_FIVRA_CPU1_PWM1 @S9S_MB_2U_LIB.S9S_MB_2U(SCH_1):PVCCFA_EHV_FIVRA_CPU1_PWM1    I33 @S9S_MB_2U_LIB.S9S_MB_2U(SCH_1):PAGE270
    38 PVCCFA_EHV_FIVRA_CPU1_IMON1 @S9S_MB_2U_LIB.S9S_MB_2U(SCH_1):PVCCFA_EHV_FIVRA_CPU1_IMON1    I33 @S9S_MB_2U_LIB.S9S_MB_2U(SCH_1):PAGE270
     8 PVCCIN_CPU1_PWM5 @S9S_MB_2U_LIB.S9S_MB_2U(SCH_1):PVCCIN_CPU1_PWM5    I33 @S9S_MB_2U_LIB.S9S_MB_2U(SCH_1):PAGE270
    31 PVCCIN_CPU1_IMON5 @S9S_MB_2U_LIB.S9S_MB_2U(SCH_1):PVCCIN_CPU1_IMON5    I33 @S9S_MB_2U_LIB.S9S_MB_2U(SCH_1):PAGE270
     9 PVCCIN_CPU1_PWM4 @S9S_MB_2U_LIB.S9S_MB_2U(SCH_1):PVCCIN_CPU1_PWM4    I33 @S9S_MB_2U_LIB.S9S_MB_2U(SCH_1):PAGE270
    30 PVCCIN_CPU1_IMON4 @S9S_MB_2U_LIB.S9S_MB_2U(SCH_1):PVCCIN_CPU1_IMON4    I33 @S9S_MB_2U_LIB.S9S_MB_2U(SCH_1):PAGE270
    10 PVCCIN_CPU1_PWM3 @S9S_MB_2U_LIB.S9S_MB_2U(SCH_1):PVCCIN_CPU1_PWM3    I33 @S9S_MB_2U_LIB.S9S_MB_2U(SCH_1):PAGE270
    29 PVCCIN_CPU1_IMON3 @S9S_MB_2U_LIB.S9S_MB_2U(SCH_1):PVCCIN_CPU1_IMON3    I33 @S9S_MB_2U_LIB.S9S_MB_2U(SCH_1):PAGE270
    11 PVCCIN_CPU1_PWM2 @S9S_MB_2U_LIB.S9S_MB_2U(SCH_1):PVCCIN_CPU1_PWM2    I33 @S9S_MB_2U_LIB.S9S_MB_2U(SCH_1):PAGE270
    28 PVCCIN_CPU1_IMON2 @S9S_MB_2U_LIB.S9S_MB_2U(SCH_1):PVCCIN_CPU1_IMON2    I33 @S9S_MB_2U_LIB.S9S_MB_2U(SCH_1):PAGE270

PU30_P1_2 ISL99390FRZTR5935-ISL99390FRZ-A
    34 PVCCIN_CPU1_PWM2 @S9S_MB_2U_LIB.S9S_MB_2U(SCH_1):PVCCIN_CPU1_PWM2     I7 @S9S_MB_2U_LIB.S9S_MB_2U(SCH_1):PAGE271
    39 PVCCIN_CPU1_VREF @S9S_MB_2U_LIB.S9S_MB_2U(SCH_1):PVCCIN_CPU1_VREF     I7 @S9S_MB_2U_LIB.S9S_MB_2U(SCH_1):PAGE271
     3 PVCCIN_CPU1_VDD2 @S9S_MB_2U_LIB.S9S_MB_2U(SCH_1):PVCCIN_CPU1_VDD2     I7 @S9S_MB_2U_LIB.S9S_MB_2U(SCH_1):PAGE271
     2    GND @S9S_MB_2U_LIB.S9S_MB_2U(SCH_1):GND     I7 @S9S_MB_2U_LIB.S9S_MB_2U(SCH_1):PAGE271
    33 SW_PVCCIN_CPU1_BOOT2 @S9S_MB_2U_LIB.S9S_MB_2U(SCH_1):SW_PVCCIN_CPU1_BOOT2     I7 @S9S_MB_2U_LIB.S9S_MB_2U(SCH_1):PAGE271
 25_29 SW_P12V_PVCCIN_CPU1_FLT @S9S_MB_2U_LIB.S9S_MB_2U(SCH_1):SW_P12V_PVCCIN_CPU1_FLT     I7 @S9S_MB_2U_LIB.S9S_MB_2U(SCH_1):PAGE271
    32 SW_PVCCIN_CPU1_BOOTR2 @S9S_MB_2U_LIB.S9S_MB_2U(SCH_1):SW_PVCCIN_CPU1_BOOTR2     I7 @S9S_MB_2U_LIB.S9S_MB_2U(SCH_1):PAGE271
     4 PVCCIN_CPU1_PVCC @S9S_MB_2U_LIB.S9S_MB_2U(SCH_1):PVCCIN_CPU1_PVCC     I7 @S9S_MB_2U_LIB.S9S_MB_2U(SCH_1):PAGE271
    36 PVCCIN_CPU1_ATSEN @S9S_MB_2U_LIB.S9S_MB_2U(SCH_1):PVCCIN_CPU1_ATSEN     I7 @S9S_MB_2U_LIB.S9S_MB_2U(SCH_1):PAGE271
    38 PVCCIN_CPU1_IMON2 @S9S_MB_2U_LIB.S9S_MB_2U(SCH_1):PVCCIN_CPU1_IMON2     I7 @S9S_MB_2U_LIB.S9S_MB_2U(SCH_1):PAGE271
    37 PVCCIN_CPU1_LSET2 @S9S_MB_2U_LIB.S9S_MB_2U(SCH_1):PVCCIN_CPU1_LSET2     I7 @S9S_MB_2U_LIB.S9S_MB_2U(SCH_1):PAGE271
 10_19 SW_PVCCIN_CPU1_SW2 @S9S_MB_2U_LIB.S9S_MB_2U(SCH_1):SW_PVCCIN_CPU1_SW2     I7 @S9S_MB_2U_LIB.S9S_MB_2U(SCH_1):PAGE271
     5    GND @S9S_MB_2U_LIB.S9S_MB_2U(SCH_1):GND     I7 @S9S_MB_2U_LIB.S9S_MB_2U(SCH_1):PAGE271
    30 SW_P12V_PVCCIN_CPU1_FLT @S9S_MB_2U_LIB.S9S_MB_2U(SCH_1):SW_P12V_PVCCIN_CPU1_FLT     I7 @S9S_MB_2U_LIB.S9S_MB_2U(SCH_1):PAGE271
     1 PVCCIN_CPU1_VOS2 @S9S_MB_2U_LIB.S9S_MB_2U(SCH_1):PVCCIN_CPU1_VOS2     I7 @S9S_MB_2U_LIB.S9S_MB_2U(SCH_1):PAGE271
    40    GND @S9S_MB_2U_LIB.S9S_MB_2U(SCH_1):GND     I7 @S9S_MB_2U_LIB.S9S_MB_2U(SCH_1):PAGE271
    35 PVCCIN_CPU1_VDD2 @S9S_MB_2U_LIB.S9S_MB_2U(SCH_1):PVCCIN_CPU1_VDD2     I7 @S9S_MB_2U_LIB.S9S_MB_2U(SCH_1):PAGE271
    31     NC     NC     I7 @S9S_MB_2U_LIB.S9S_MB_2U(SCH_1):PAGE271
     6     NC     NC     I7 @S9S_MB_2U_LIB.S9S_MB_2U(SCH_1):PAGE271
    41     NC     NC     I7 @S9S_MB_2U_LIB.S9S_MB_2U(SCH_1):PAGE271
7_9-20_24    GND @S9S_MB_2U_LIB.S9S_MB_2U(SCH_1):GND     I7 @S9S_MB_2U_LIB.S9S_MB_2U(SCH_1):PAGE271

PU31_P1_1 ISL99390FRZTR5935-ISL99390FRZ-A
    34 PVCCIN_CPU1_PWM1 @S9S_MB_2U_LIB.S9S_MB_2U(SCH_1):PVCCIN_CPU1_PWM1    I40 @S9S_MB_2U_LIB.S9S_MB_2U(SCH_1):PAGE271
    39 PVCCIN_CPU1_VREF @S9S_MB_2U_LIB.S9S_MB_2U(SCH_1):PVCCIN_CPU1_VREF    I40 @S9S_MB_2U_LIB.S9S_MB_2U(SCH_1):PAGE271
     3 PVCCIN_CPU1_VDD1 @S9S_MB_2U_LIB.S9S_MB_2U(SCH_1):PVCCIN_CPU1_VDD1    I40 @S9S_MB_2U_LIB.S9S_MB_2U(SCH_1):PAGE271
     2    GND @S9S_MB_2U_LIB.S9S_MB_2U(SCH_1):GND    I40 @S9S_MB_2U_LIB.S9S_MB_2U(SCH_1):PAGE271
    33 SW_PVCCIN_CPU1_BOOT1 @S9S_MB_2U_LIB.S9S_MB_2U(SCH_1):SW_PVCCIN_CPU1_BOOT1    I40 @S9S_MB_2U_LIB.S9S_MB_2U(SCH_1):PAGE271
 25_29 SW_P12V_PVCCIN_CPU1_FLT @S9S_MB_2U_LIB.S9S_MB_2U(SCH_1):SW_P12V_PVCCIN_CPU1_FLT    I40 @S9S_MB_2U_LIB.S9S_MB_2U(SCH_1):PAGE271
    32 SW_PVCCIN_CPU1_BOOTR1 @S9S_MB_2U_LIB.S9S_MB_2U(SCH_1):SW_PVCCIN_CPU1_BOOTR1    I40 @S9S_MB_2U_LIB.S9S_MB_2U(SCH_1):PAGE271
     4 PVCCIN_CPU1_PVCC @S9S_MB_2U_LIB.S9S_MB_2U(SCH_1):PVCCIN_CPU1_PVCC    I40 @S9S_MB_2U_LIB.S9S_MB_2U(SCH_1):PAGE271
    36 PVCCIN_CPU1_ATSEN @S9S_MB_2U_LIB.S9S_MB_2U(SCH_1):PVCCIN_CPU1_ATSEN    I40 @S9S_MB_2U_LIB.S9S_MB_2U(SCH_1):PAGE271
    38 PVCCIN_CPU1_IMON1 @S9S_MB_2U_LIB.S9S_MB_2U(SCH_1):PVCCIN_CPU1_IMON1    I40 @S9S_MB_2U_LIB.S9S_MB_2U(SCH_1):PAGE271
    37 PVCCIN_CPU1_LSET1 @S9S_MB_2U_LIB.S9S_MB_2U(SCH_1):PVCCIN_CPU1_LSET1    I40 @S9S_MB_2U_LIB.S9S_MB_2U(SCH_1):PAGE271
 10_19 SW_PVCCIN_CPU1_SW1 @S9S_MB_2U_LIB.S9S_MB_2U(SCH_1):SW_PVCCIN_CPU1_SW1    I40 @S9S_MB_2U_LIB.S9S_MB_2U(SCH_1):PAGE271
     5    GND @S9S_MB_2U_LIB.S9S_MB_2U(SCH_1):GND    I40 @S9S_MB_2U_LIB.S9S_MB_2U(SCH_1):PAGE271
    30 SW_P12V_PVCCIN_CPU1_FLT @S9S_MB_2U_LIB.S9S_MB_2U(SCH_1):SW_P12V_PVCCIN_CPU1_FLT    I40 @S9S_MB_2U_LIB.S9S_MB_2U(SCH_1):PAGE271
     1 PVCCIN_CPU1_VOS1 @S9S_MB_2U_LIB.S9S_MB_2U(SCH_1):PVCCIN_CPU1_VOS1    I40 @S9S_MB_2U_LIB.S9S_MB_2U(SCH_1):PAGE271
    40    GND @S9S_MB_2U_LIB.S9S_MB_2U(SCH_1):GND    I40 @S9S_MB_2U_LIB.S9S_MB_2U(SCH_1):PAGE271
    35 PVCCIN_CPU1_VDD1 @S9S_MB_2U_LIB.S9S_MB_2U(SCH_1):PVCCIN_CPU1_VDD1    I40 @S9S_MB_2U_LIB.S9S_MB_2U(SCH_1):PAGE271
    31     NC     NC    I40 @S9S_MB_2U_LIB.S9S_MB_2U(SCH_1):PAGE271
     6     NC     NC    I40 @S9S_MB_2U_LIB.S9S_MB_2U(SCH_1):PAGE271
    41     NC     NC    I40 @S9S_MB_2U_LIB.S9S_MB_2U(SCH_1):PAGE271
7_9-20_24    GND @S9S_MB_2U_LIB.S9S_MB_2U(SCH_1):GND    I40 @S9S_MB_2U_LIB.S9S_MB_2U(SCH_1):PAGE271

PU35 ISL69260IRAZT-ISL69260IRAZ-T,SA
    23 PVCCD_HV_CPU0_ACSP1 @S9S_MB_2U_LIB.S9S_MB_2U(SCH_1):PVCCD_HV_CPU0_ACSP1    I53 @S9S_MB_2U_LIB.S9S_MB_2U(SCH_1):PAGE264
    39 PVCCD_HV_CPU0_VCC @S9S_MB_2U_LIB.S9S_MB_2U(SCH_1):PVCCD_HV_CPU0_VCC    I53 @S9S_MB_2U_LIB.S9S_MB_2U(SCH_1):PAGE264
    20    GND @S9S_MB_2U_LIB.S9S_MB_2U(SCH_1):GND    I53 @S9S_MB_2U_LIB.S9S_MB_2U(SCH_1):PAGE264
    10 SMB_CLK_PVCCD_HV_CPU0 @S9S_MB_2U_LIB.S9S_MB_2U(SCH_1):SMB_CLK_PVCCD_HV_CPU0    I53 @S9S_MB_2U_LIB.S9S_MB_2U(SCH_1):PAGE264
    18 SVID_DIO_PVCCD_HV_CPU0_R @S9S_MB_2U_LIB.S9S_MB_2U(SCH_1):SVID_DIO_PVCCD_HV_CPU0_R    I53 @S9S_MB_2U_LIB.S9S_MB_2U(SCH_1):PAGE264
    24 NC_PVCCD_HV_CPU0_ACSP2 @S9S_MB_2U_LIB.S9S_MB_2U(SCH_1):NC_PVCCD_HV_CPU0_ACSP2    I53 @S9S_MB_2U_LIB.S9S_MB_2U(SCH_1):PAGE264
    19 SVID_ALERT_PVCCD_HV_CPU0_R @S9S_MB_2U_LIB.S9S_MB_2U(SCH_1):SVID_ALERT_PVCCD_HV_CPU0_R    I53 @S9S_MB_2U_LIB.S9S_MB_2U(SCH_1):PAGE264
    14 IRQ_PVCCD_CPU0_VRHOT_LVC3_R_N @S9S_MB_2U_LIB.S9S_MB_2U(SCH_1):IRQ_PVCCD_CPU0_VRHOT_LVC3_R_N    I53 @S9S_MB_2U_LIB.S9S_MB_2U(SCH_1):PAGE264
    25 NC_PVCCD_HV_CPU0_ACSP3 @S9S_MB_2U_LIB.S9S_MB_2U(SCH_1):NC_PVCCD_HV_CPU0_ACSP3    I53 @S9S_MB_2U_LIB.S9S_MB_2U(SCH_1):PAGE264
    26 NC_PVCCD_HV_CPU0_ACSP4 @S9S_MB_2U_LIB.S9S_MB_2U(SCH_1):NC_PVCCD_HV_CPU0_ACSP4    I53 @S9S_MB_2U_LIB.S9S_MB_2U(SCH_1):PAGE264
    16 NC_PVCCD_HV_CPU0_BVR_RDY @S9S_MB_2U_LIB.S9S_MB_2U(SCH_1):NC_PVCCD_HV_CPU0_BVR_RDY    I53 @S9S_MB_2U_LIB.S9S_MB_2U(SCH_1):PAGE264
    17 SVID_CLK_PVCCD_HV_CPU0_R @S9S_MB_2U_LIB.S9S_MB_2U(SCH_1):SVID_CLK_PVCCD_HV_CPU0_R    I53 @S9S_MB_2U_LIB.S9S_MB_2U(SCH_1):PAGE264
    11 NC_PVCCD_HV_CPU0_SMB_ALERT @S9S_MB_2U_LIB.S9S_MB_2U(SCH_1):NC_PVCCD_HV_CPU0_SMB_ALERT    I53 @S9S_MB_2U_LIB.S9S_MB_2U(SCH_1):PAGE264
    13 PVCCD_HV_CPU0_EN_R @S9S_MB_2U_LIB.S9S_MB_2U(SCH_1):PVCCD_HV_CPU0_EN_R    I53 @S9S_MB_2U_LIB.S9S_MB_2U(SCH_1):PAGE264
    22 VSENSE_PVCCD_HV_CPU0_DN @S9S_MB_2U_LIB.S9S_MB_2U(SCH_1):VSENSE_PVCCD_HV_CPU0_DN    I53 @S9S_MB_2U_LIB.S9S_MB_2U(SCH_1):PAGE264
     9 SMB_DIO_PVCCD_HV_CPU0 @S9S_MB_2U_LIB.S9S_MB_2U(SCH_1):SMB_DIO_PVCCD_HV_CPU0    I53 @S9S_MB_2U_LIB.S9S_MB_2U(SCH_1):PAGE264
     5 NC_PVCCD_HV_CPU0_APWM4 @S9S_MB_2U_LIB.S9S_MB_2U(SCH_1):NC_PVCCD_HV_CPU0_APWM4    I53 @S9S_MB_2U_LIB.S9S_MB_2U(SCH_1):PAGE264
     6 NC_PVCCD_HV_CPU0_APWM3 @S9S_MB_2U_LIB.S9S_MB_2U(SCH_1):NC_PVCCD_HV_CPU0_APWM3    I53 @S9S_MB_2U_LIB.S9S_MB_2U(SCH_1):PAGE264
    21 SH_PVCCD_HV_CPU0_R @S9S_MB_2U_LIB.S9S_MB_2U(SCH_1):SH_PVCCD_HV_CPU0_R    I53 @S9S_MB_2U_LIB.S9S_MB_2U(SCH_1):PAGE264
     2 NC_PVCCD_HV_CPU0_APWM7 @S9S_MB_2U_LIB.S9S_MB_2U(SCH_1):NC_PVCCD_HV_CPU0_APWM7    I53 @S9S_MB_2U_LIB.S9S_MB_2U(SCH_1):PAGE264
    12 PWRGD_PVCCD_HV_CPU0_R @S9S_MB_2U_LIB.S9S_MB_2U(SCH_1):PWRGD_PVCCD_HV_CPU0_R    I53 @S9S_MB_2U_LIB.S9S_MB_2U(SCH_1):PAGE264
     7 NC_PVCCD_HV_CPU0_APWM2 @S9S_MB_2U_LIB.S9S_MB_2U(SCH_1):NC_PVCCD_HV_CPU0_APWM2    I53 @S9S_MB_2U_LIB.S9S_MB_2U(SCH_1):PAGE264
    40 PVCCD_HV_CPU0_VREF @S9S_MB_2U_LIB.S9S_MB_2U(SCH_1):PVCCD_HV_CPU0_VREF    I53 @S9S_MB_2U_LIB.S9S_MB_2U(SCH_1):PAGE264
    37 PVCCD_HV_CPU0_ISENSE_P @S9S_MB_2U_LIB.S9S_MB_2U(SCH_1):PVCCD_HV_CPU0_ISENSE_P    I53 @S9S_MB_2U_LIB.S9S_MB_2U(SCH_1):PAGE264
    38 PVCCD_HV_CPU0_ISENSE_N @S9S_MB_2U_LIB.S9S_MB_2U(SCH_1):PVCCD_HV_CPU0_ISENSE_N    I53 @S9S_MB_2U_LIB.S9S_MB_2U(SCH_1):PAGE264
    36 PVCCD_HV_CPU0_ISYS_R @S9S_MB_2U_LIB.S9S_MB_2U(SCH_1):PVCCD_HV_CPU0_ISYS_R    I53 @S9S_MB_2U_LIB.S9S_MB_2U(SCH_1):PAGE264
    15 PVCCD_HV_CPU0_PIN_ALT @S9S_MB_2U_LIB.S9S_MB_2U(SCH_1):PVCCD_HV_CPU0_PIN_ALT    I53 @S9S_MB_2U_LIB.S9S_MB_2U(SCH_1):PAGE264
    32    GND @S9S_MB_2U_LIB.S9S_MB_2U(SCH_1):GND    I53 @S9S_MB_2U_LIB.S9S_MB_2U(SCH_1):PAGE264
    31    GND @S9S_MB_2U_LIB.S9S_MB_2U(SCH_1):GND    I53 @S9S_MB_2U_LIB.S9S_MB_2U(SCH_1):PAGE264
    29 NC_PVCCD_HV_CPU0_ACSP7 @S9S_MB_2U_LIB.S9S_MB_2U(SCH_1):NC_PVCCD_HV_CPU0_ACSP7    I53 @S9S_MB_2U_LIB.S9S_MB_2U(SCH_1):PAGE264
     8 PVCCD_HV_CPU0_APWM1 @S9S_MB_2U_LIB.S9S_MB_2U(SCH_1):PVCCD_HV_CPU0_APWM1    I53 @S9S_MB_2U_LIB.S9S_MB_2U(SCH_1):PAGE264
     4 NC_PVCCD_HV_CPU0_APWM5 @S9S_MB_2U_LIB.S9S_MB_2U(SCH_1):NC_PVCCD_HV_CPU0_APWM5    I53 @S9S_MB_2U_LIB.S9S_MB_2U(SCH_1):PAGE264
    27 NC_PVCCD_HV_CPU0_ACSP5 @S9S_MB_2U_LIB.S9S_MB_2U(SCH_1):NC_PVCCD_HV_CPU0_ACSP5    I53 @S9S_MB_2U_LIB.S9S_MB_2U(SCH_1):PAGE264
     3 NC_PVCCD_HV_CPU0_APWM6 @S9S_MB_2U_LIB.S9S_MB_2U(SCH_1):NC_PVCCD_HV_CPU0_APWM6    I53 @S9S_MB_2U_LIB.S9S_MB_2U(SCH_1):PAGE264
    28 NC_PVCCD_HV_CPU0_ACSP6 @S9S_MB_2U_LIB.S9S_MB_2U(SCH_1):NC_PVCCD_HV_CPU0_ACSP6    I53 @S9S_MB_2U_LIB.S9S_MB_2U(SCH_1):PAGE264
    33 PVCCD_HV_CPU0_FAULT @S9S_MB_2U_LIB.S9S_MB_2U(SCH_1):PVCCD_HV_CPU0_FAULT    I53 @S9S_MB_2U_LIB.S9S_MB_2U(SCH_1):PAGE264
    TH    GND @S9S_MB_2U_LIB.S9S_MB_2U(SCH_1):GND    I53 @S9S_MB_2U_LIB.S9S_MB_2U(SCH_1):PAGE264
    34 PVCCD_HV_CPU0_ADDR @S9S_MB_2U_LIB.S9S_MB_2U(SCH_1):PVCCD_HV_CPU0_ADDR    I53 @S9S_MB_2U_LIB.S9S_MB_2U(SCH_1):PAGE264
    35 PVCCD_HV_CPU0_ATSEN @S9S_MB_2U_LIB.S9S_MB_2U(SCH_1):PVCCD_HV_CPU0_ATSEN    I53 @S9S_MB_2U_LIB.S9S_MB_2U(SCH_1):PAGE264
     1 NC_PVCCD_HV_CPU0_APWM8 @S9S_MB_2U_LIB.S9S_MB_2U(SCH_1):NC_PVCCD_HV_CPU0_APWM8    I53 @S9S_MB_2U_LIB.S9S_MB_2U(SCH_1):PAGE264
    30 NC_PVCCD_HV_CPU0_ACSP8 @S9S_MB_2U_LIB.S9S_MB_2U(SCH_1):NC_PVCCD_HV_CPU0_ACSP8    I53 @S9S_MB_2U_LIB.S9S_MB_2U(SCH_1):PAGE264

PU36 ISL99390FRZTR5935-ISL99390FRZ-A
    34 PVCCD_HV_CPU0_APWM1 @S9S_MB_2U_LIB.S9S_MB_2U(SCH_1):PVCCD_HV_CPU0_APWM1     I8 @S9S_MB_2U_LIB.S9S_MB_2U(SCH_1):PAGE265
    39 PVCCD_HV_CPU0_VREF @S9S_MB_2U_LIB.S9S_MB_2U(SCH_1):PVCCD_HV_CPU0_VREF     I8 @S9S_MB_2U_LIB.S9S_MB_2U(SCH_1):PAGE265
     3 PVCCD_HV_CPU0_VDD1 @S9S_MB_2U_LIB.S9S_MB_2U(SCH_1):PVCCD_HV_CPU0_VDD1     I8 @S9S_MB_2U_LIB.S9S_MB_2U(SCH_1):PAGE265
     2    GND @S9S_MB_2U_LIB.S9S_MB_2U(SCH_1):GND     I8 @S9S_MB_2U_LIB.S9S_MB_2U(SCH_1):PAGE265
    33 SW_PVCCD_HV_CPU0_BOOT1 @S9S_MB_2U_LIB.S9S_MB_2U(SCH_1):SW_PVCCD_HV_CPU0_BOOT1     I8 @S9S_MB_2U_LIB.S9S_MB_2U(SCH_1):PAGE265
 25_29 SW_P12V_PVCCINFAON_CPU0_FLT @S9S_MB_2U_LIB.S9S_MB_2U(SCH_1):SW_P12V_PVCCINFAON_CPU0_FLT     I8 @S9S_MB_2U_LIB.S9S_MB_2U(SCH_1):PAGE265
    32 SW_PVCCD_HV_CPU0_BOOTR1 @S9S_MB_2U_LIB.S9S_MB_2U(SCH_1):SW_PVCCD_HV_CPU0_BOOTR1     I8 @S9S_MB_2U_LIB.S9S_MB_2U(SCH_1):PAGE265
     4 PVCCFA_EHV_CPU0_PVCC @S9S_MB_2U_LIB.S9S_MB_2U(SCH_1):PVCCFA_EHV_CPU0_PVCC     I8 @S9S_MB_2U_LIB.S9S_MB_2U(SCH_1):PAGE265
    36 PVCCD_HV_CPU0_ATSEN @S9S_MB_2U_LIB.S9S_MB_2U(SCH_1):PVCCD_HV_CPU0_ATSEN     I8 @S9S_MB_2U_LIB.S9S_MB_2U(SCH_1):PAGE265
    38 PVCCD_HV_CPU0_ACSP1 @S9S_MB_2U_LIB.S9S_MB_2U(SCH_1):PVCCD_HV_CPU0_ACSP1     I8 @S9S_MB_2U_LIB.S9S_MB_2U(SCH_1):PAGE265
    37 PVCCD_HV_CPU0_LSET1 @S9S_MB_2U_LIB.S9S_MB_2U(SCH_1):PVCCD_HV_CPU0_LSET1     I8 @S9S_MB_2U_LIB.S9S_MB_2U(SCH_1):PAGE265
 10_19 SW_PVCCD_HV_CPU0_SW1 @S9S_MB_2U_LIB.S9S_MB_2U(SCH_1):SW_PVCCD_HV_CPU0_SW1     I8 @S9S_MB_2U_LIB.S9S_MB_2U(SCH_1):PAGE265
     5    GND @S9S_MB_2U_LIB.S9S_MB_2U(SCH_1):GND     I8 @S9S_MB_2U_LIB.S9S_MB_2U(SCH_1):PAGE265
    30 SW_P12V_PVCCINFAON_CPU0_FLT @S9S_MB_2U_LIB.S9S_MB_2U(SCH_1):SW_P12V_PVCCINFAON_CPU0_FLT     I8 @S9S_MB_2U_LIB.S9S_MB_2U(SCH_1):PAGE265
     1 PVCCD_HV_CPU0_VOS @S9S_MB_2U_LIB.S9S_MB_2U(SCH_1):PVCCD_HV_CPU0_VOS     I8 @S9S_MB_2U_LIB.S9S_MB_2U(SCH_1):PAGE265
    40    GND @S9S_MB_2U_LIB.S9S_MB_2U(SCH_1):GND     I8 @S9S_MB_2U_LIB.S9S_MB_2U(SCH_1):PAGE265
    35 PVCCD_HV_CPU0_VDD1 @S9S_MB_2U_LIB.S9S_MB_2U(SCH_1):PVCCD_HV_CPU0_VDD1     I8 @S9S_MB_2U_LIB.S9S_MB_2U(SCH_1):PAGE265
    31     NC     NC     I8 @S9S_MB_2U_LIB.S9S_MB_2U(SCH_1):PAGE265
     6     NC     NC     I8 @S9S_MB_2U_LIB.S9S_MB_2U(SCH_1):PAGE265
    41     NC     NC     I8 @S9S_MB_2U_LIB.S9S_MB_2U(SCH_1):PAGE265
7_9-20_24    GND @S9S_MB_2U_LIB.S9S_MB_2U(SCH_1):GND     I8 @S9S_MB_2U_LIB.S9S_MB_2U(SCH_1):PAGE265

PU42 RAA2213404GNPHB0-RAA2213404GNPA
    21 PVCCFA_EHV_CPU0_BPWM1 @S9S_MB_2U_LIB.S9S_MB_2U(SCH_1):PVCCFA_EHV_CPU0_BPWM1    I14 @S9S_MB_2U_LIB.S9S_MB_2U(SCH_1):PAGE262
    24 PVCCINFAON_CPU0_VREF @S9S_MB_2U_LIB.S9S_MB_2U(SCH_1):PVCCINFAON_CPU0_VREF    I14 @S9S_MB_2U_LIB.S9S_MB_2U(SCH_1):PAGE262
    23    GND @S9S_MB_2U_LIB.S9S_MB_2U(SCH_1):GND    I14 @S9S_MB_2U_LIB.S9S_MB_2U(SCH_1):PAGE262
    20 SW_PVCCFA_EHV_CPU0_BOOT1 @S9S_MB_2U_LIB.S9S_MB_2U(SCH_1):SW_PVCCFA_EHV_CPU0_BOOT1    I14 @S9S_MB_2U_LIB.S9S_MB_2U(SCH_1):PAGE262
16_18-28 SW_P12V_PVCCINFAON_CPU0_FLT @S9S_MB_2U_LIB.S9S_MB_2U(SCH_1):SW_P12V_PVCCINFAON_CPU0_FLT    I14 @S9S_MB_2U_LIB.S9S_MB_2U(SCH_1):PAGE262
    19 SW_PVCCFA_EHV_CPU0_BOOTR1 @S9S_MB_2U_LIB.S9S_MB_2U(SCH_1):SW_PVCCFA_EHV_CPU0_BOOTR1    I14 @S9S_MB_2U_LIB.S9S_MB_2U(SCH_1):PAGE262
     4 PVCCFA_EHV_CPU0_VDD1 @S9S_MB_2U_LIB.S9S_MB_2U(SCH_1):PVCCFA_EHV_CPU0_VDD1    I14 @S9S_MB_2U_LIB.S9S_MB_2U(SCH_1):PAGE262
     1 PVCCFA_EHV_CPU0_BTSEN @S9S_MB_2U_LIB.S9S_MB_2U(SCH_1):PVCCFA_EHV_CPU0_BTSEN    I14 @S9S_MB_2U_LIB.S9S_MB_2U(SCH_1):PAGE262
    25 PVCCFA_EHV_CPU0_BCSP1 @S9S_MB_2U_LIB.S9S_MB_2U(SCH_1):PVCCFA_EHV_CPU0_BCSP1    I14 @S9S_MB_2U_LIB.S9S_MB_2U(SCH_1):PAGE262
6_7-13_15-29    GND @S9S_MB_2U_LIB.S9S_MB_2U(SCH_1):GND    I14 @S9S_MB_2U_LIB.S9S_MB_2U(SCH_1):PAGE262
    27     NC     NC    I14 @S9S_MB_2U_LIB.S9S_MB_2U(SCH_1):PAGE262
  8_12 SW_PVCCFA_EHV_CPU0_SW1 @S9S_MB_2U_LIB.S9S_MB_2U(SCH_1):SW_PVCCFA_EHV_CPU0_SW1    I14 @S9S_MB_2U_LIB.S9S_MB_2U(SCH_1):PAGE262
     2 PVCCFA_EHV_CPU0_FAULT @S9S_MB_2U_LIB.S9S_MB_2U(SCH_1):PVCCFA_EHV_CPU0_FAULT    I14 @S9S_MB_2U_LIB.S9S_MB_2U(SCH_1):PAGE262
    26    GND @S9S_MB_2U_LIB.S9S_MB_2U(SCH_1):GND    I14 @S9S_MB_2U_LIB.S9S_MB_2U(SCH_1):PAGE262
    22 PVCCFA_EHV_CPU0_NC2 @S9S_MB_2U_LIB.S9S_MB_2U(SCH_1):PVCCFA_EHV_CPU0_NC2    I14 @S9S_MB_2U_LIB.S9S_MB_2U(SCH_1):PAGE262
     5 PVCCFA_EHV_CPU0_LSET1 @S9S_MB_2U_LIB.S9S_MB_2U(SCH_1):PVCCFA_EHV_CPU0_LSET1    I14 @S9S_MB_2U_LIB.S9S_MB_2U(SCH_1):PAGE262
     3 PVCCFA_EHV_CPU0_NC1 @S9S_MB_2U_LIB.S9S_MB_2U(SCH_1):PVCCFA_EHV_CPU0_NC1    I14 @S9S_MB_2U_LIB.S9S_MB_2U(SCH_1):PAGE262

PU43_P0_1 ISL99390FRZTR5935-ISL99390FRZ-A
    34 PVCCINFAON_CPU0_APWM1 @S9S_MB_2U_LIB.S9S_MB_2U(SCH_1):PVCCINFAON_CPU0_APWM1    I79 @S9S_MB_2U_LIB.S9S_MB_2U(SCH_1):PAGE261
    39 PVCCINFAON_CPU0_VREF @S9S_MB_2U_LIB.S9S_MB_2U(SCH_1):PVCCINFAON_CPU0_VREF    I79 @S9S_MB_2U_LIB.S9S_MB_2U(SCH_1):PAGE261
     3 PVCCINFAON_CPU0_VDD1 @S9S_MB_2U_LIB.S9S_MB_2U(SCH_1):PVCCINFAON_CPU0_VDD1    I79 @S9S_MB_2U_LIB.S9S_MB_2U(SCH_1):PAGE261
     2    GND @S9S_MB_2U_LIB.S9S_MB_2U(SCH_1):GND    I79 @S9S_MB_2U_LIB.S9S_MB_2U(SCH_1):PAGE261
    33 SW_PVCCINFAON_CPU0_BOOT1 @S9S_MB_2U_LIB.S9S_MB_2U(SCH_1):SW_PVCCINFAON_CPU0_BOOT1    I79 @S9S_MB_2U_LIB.S9S_MB_2U(SCH_1):PAGE261
 25_29 SW_P12V_PVCCINFAON_CPU0_FLT @S9S_MB_2U_LIB.S9S_MB_2U(SCH_1):SW_P12V_PVCCINFAON_CPU0_FLT    I79 @S9S_MB_2U_LIB.S9S_MB_2U(SCH_1):PAGE261
    32 SW_PVCCINFAON_CPU0_BOOTR1 @S9S_MB_2U_LIB.S9S_MB_2U(SCH_1):SW_PVCCINFAON_CPU0_BOOTR1    I79 @S9S_MB_2U_LIB.S9S_MB_2U(SCH_1):PAGE261
     4 PVCCFA_EHV_CPU0_PVCC @S9S_MB_2U_LIB.S9S_MB_2U(SCH_1):PVCCFA_EHV_CPU0_PVCC    I79 @S9S_MB_2U_LIB.S9S_MB_2U(SCH_1):PAGE261
    36 PVCCINFAON_CPU0_ATSEN @S9S_MB_2U_LIB.S9S_MB_2U(SCH_1):PVCCINFAON_CPU0_ATSEN    I79 @S9S_MB_2U_LIB.S9S_MB_2U(SCH_1):PAGE261
    38 PVCCINFAON_CPU0_ACSP1 @S9S_MB_2U_LIB.S9S_MB_2U(SCH_1):PVCCINFAON_CPU0_ACSP1    I79 @S9S_MB_2U_LIB.S9S_MB_2U(SCH_1):PAGE261
    37 PVCCINFAON_CPU0_LSET1 @S9S_MB_2U_LIB.S9S_MB_2U(SCH_1):PVCCINFAON_CPU0_LSET1    I79 @S9S_MB_2U_LIB.S9S_MB_2U(SCH_1):PAGE261
 10_19 SW_PVCCINFAON_CPU0_SW1 @S9S_MB_2U_LIB.S9S_MB_2U(SCH_1):SW_PVCCINFAON_CPU0_SW1    I79 @S9S_MB_2U_LIB.S9S_MB_2U(SCH_1):PAGE261
     5    GND @S9S_MB_2U_LIB.S9S_MB_2U(SCH_1):GND    I79 @S9S_MB_2U_LIB.S9S_MB_2U(SCH_1):PAGE261
    30 SW_P12V_PVCCINFAON_CPU0_FLT @S9S_MB_2U_LIB.S9S_MB_2U(SCH_1):SW_P12V_PVCCINFAON_CPU0_FLT    I79 @S9S_MB_2U_LIB.S9S_MB_2U(SCH_1):PAGE261
     1 PVCCINFAON_CPU0_VOS1 @S9S_MB_2U_LIB.S9S_MB_2U(SCH_1):PVCCINFAON_CPU0_VOS1    I79 @S9S_MB_2U_LIB.S9S_MB_2U(SCH_1):PAGE261
    40    GND @S9S_MB_2U_LIB.S9S_MB_2U(SCH_1):GND    I79 @S9S_MB_2U_LIB.S9S_MB_2U(SCH_1):PAGE261
    35 PVCCINFAON_CPU0_VDD1 @S9S_MB_2U_LIB.S9S_MB_2U(SCH_1):PVCCINFAON_CPU0_VDD1    I79 @S9S_MB_2U_LIB.S9S_MB_2U(SCH_1):PAGE261
    31     NC     NC    I79 @S9S_MB_2U_LIB.S9S_MB_2U(SCH_1):PAGE261
     6     NC     NC    I79 @S9S_MB_2U_LIB.S9S_MB_2U(SCH_1):PAGE261
    41     NC     NC    I79 @S9S_MB_2U_LIB.S9S_MB_2U(SCH_1):PAGE261
7_9-20_24    GND @S9S_MB_2U_LIB.S9S_MB_2U(SCH_1):GND    I79 @S9S_MB_2U_LIB.S9S_MB_2U(SCH_1):PAGE261

PU44_P0_2 ISL99390FRZTR5935-ISL99390FRZ-A
    34 PVCCINFAON_CPU0_APWM2 @S9S_MB_2U_LIB.S9S_MB_2U(SCH_1):PVCCINFAON_CPU0_APWM2    I12 @S9S_MB_2U_LIB.S9S_MB_2U(SCH_1):PAGE261
    39 PVCCINFAON_CPU0_VREF @S9S_MB_2U_LIB.S9S_MB_2U(SCH_1):PVCCINFAON_CPU0_VREF    I12 @S9S_MB_2U_LIB.S9S_MB_2U(SCH_1):PAGE261
     3 PVCCINFAON_CPU0_VDD2 @S9S_MB_2U_LIB.S9S_MB_2U(SCH_1):PVCCINFAON_CPU0_VDD2    I12 @S9S_MB_2U_LIB.S9S_MB_2U(SCH_1):PAGE261
     2    GND @S9S_MB_2U_LIB.S9S_MB_2U(SCH_1):GND    I12 @S9S_MB_2U_LIB.S9S_MB_2U(SCH_1):PAGE261
    33 SW_PVCCINFAON_CPU0_BOOT2 @S9S_MB_2U_LIB.S9S_MB_2U(SCH_1):SW_PVCCINFAON_CPU0_BOOT2    I12 @S9S_MB_2U_LIB.S9S_MB_2U(SCH_1):PAGE261
 25_29 SW_P12V_PVCCINFAON_CPU0_FLT @S9S_MB_2U_LIB.S9S_MB_2U(SCH_1):SW_P12V_PVCCINFAON_CPU0_FLT    I12 @S9S_MB_2U_LIB.S9S_MB_2U(SCH_1):PAGE261
    32 SW_PVCCINFAON_CPU0_BOOTR2 @S9S_MB_2U_LIB.S9S_MB_2U(SCH_1):SW_PVCCINFAON_CPU0_BOOTR2    I12 @S9S_MB_2U_LIB.S9S_MB_2U(SCH_1):PAGE261
     4 PVCCFA_EHV_CPU0_PVCC @S9S_MB_2U_LIB.S9S_MB_2U(SCH_1):PVCCFA_EHV_CPU0_PVCC    I12 @S9S_MB_2U_LIB.S9S_MB_2U(SCH_1):PAGE261
    36 PVCCINFAON_CPU0_ATSEN @S9S_MB_2U_LIB.S9S_MB_2U(SCH_1):PVCCINFAON_CPU0_ATSEN    I12 @S9S_MB_2U_LIB.S9S_MB_2U(SCH_1):PAGE261
    38 PVCCINFAON_CPU0_ACSP2 @S9S_MB_2U_LIB.S9S_MB_2U(SCH_1):PVCCINFAON_CPU0_ACSP2    I12 @S9S_MB_2U_LIB.S9S_MB_2U(SCH_1):PAGE261
    37 PVCCINFAON_CPU0_LSET2 @S9S_MB_2U_LIB.S9S_MB_2U(SCH_1):PVCCINFAON_CPU0_LSET2    I12 @S9S_MB_2U_LIB.S9S_MB_2U(SCH_1):PAGE261
 10_19 SW_PVCCINFAON_CPU0_SW2 @S9S_MB_2U_LIB.S9S_MB_2U(SCH_1):SW_PVCCINFAON_CPU0_SW2    I12 @S9S_MB_2U_LIB.S9S_MB_2U(SCH_1):PAGE261
     5    GND @S9S_MB_2U_LIB.S9S_MB_2U(SCH_1):GND    I12 @S9S_MB_2U_LIB.S9S_MB_2U(SCH_1):PAGE261
    30 SW_P12V_PVCCINFAON_CPU0_FLT @S9S_MB_2U_LIB.S9S_MB_2U(SCH_1):SW_P12V_PVCCINFAON_CPU0_FLT    I12 @S9S_MB_2U_LIB.S9S_MB_2U(SCH_1):PAGE261
     1 PVCCINFAON_CPU0_VOS2 @S9S_MB_2U_LIB.S9S_MB_2U(SCH_1):PVCCINFAON_CPU0_VOS2    I12 @S9S_MB_2U_LIB.S9S_MB_2U(SCH_1):PAGE261
    40    GND @S9S_MB_2U_LIB.S9S_MB_2U(SCH_1):GND    I12 @S9S_MB_2U_LIB.S9S_MB_2U(SCH_1):PAGE261
    35 PVCCINFAON_CPU0_VDD2 @S9S_MB_2U_LIB.S9S_MB_2U(SCH_1):PVCCINFAON_CPU0_VDD2    I12 @S9S_MB_2U_LIB.S9S_MB_2U(SCH_1):PAGE261
    31     NC     NC    I12 @S9S_MB_2U_LIB.S9S_MB_2U(SCH_1):PAGE261
     6     NC     NC    I12 @S9S_MB_2U_LIB.S9S_MB_2U(SCH_1):PAGE261
    41     NC     NC    I12 @S9S_MB_2U_LIB.S9S_MB_2U(SCH_1):PAGE261
7_9-20_24    GND @S9S_MB_2U_LIB.S9S_MB_2U(SCH_1):GND    I12 @S9S_MB_2U_LIB.S9S_MB_2U(SCH_1):PAGE261

PU49 RAA2213404GNPHB0-RAA2213404GNPA
    21 PVCCFA_EHV_CPU1_BPWM1 @S9S_MB_2U_LIB.S9S_MB_2U(SCH_1):PVCCFA_EHV_CPU1_BPWM1    I14 @S9S_MB_2U_LIB.S9S_MB_2U(SCH_1):PAGE280
    24 PVCCINFAON_CPU1_VREF @S9S_MB_2U_LIB.S9S_MB_2U(SCH_1):PVCCINFAON_CPU1_VREF    I14 @S9S_MB_2U_LIB.S9S_MB_2U(SCH_1):PAGE280
    23    GND @S9S_MB_2U_LIB.S9S_MB_2U(SCH_1):GND    I14 @S9S_MB_2U_LIB.S9S_MB_2U(SCH_1):PAGE280
    20 SW_PVCCFA_EHV_CPU1_BOOT1 @S9S_MB_2U_LIB.S9S_MB_2U(SCH_1):SW_PVCCFA_EHV_CPU1_BOOT1    I14 @S9S_MB_2U_LIB.S9S_MB_2U(SCH_1):PAGE280
16_18-28 SW_P12V_PVCCINFAON_CPU1_FLT @S9S_MB_2U_LIB.S9S_MB_2U(SCH_1):SW_P12V_PVCCINFAON_CPU1_FLT    I14 @S9S_MB_2U_LIB.S9S_MB_2U(SCH_1):PAGE280
    19 SW_PVCCFA_EHV_CPU1_BOOTR1 @S9S_MB_2U_LIB.S9S_MB_2U(SCH_1):SW_PVCCFA_EHV_CPU1_BOOTR1    I14 @S9S_MB_2U_LIB.S9S_MB_2U(SCH_1):PAGE280
     4 PVCCFA_EHV_CPU1_VDD1 @S9S_MB_2U_LIB.S9S_MB_2U(SCH_1):PVCCFA_EHV_CPU1_VDD1    I14 @S9S_MB_2U_LIB.S9S_MB_2U(SCH_1):PAGE280
     1 PVCCFA_EHV_CPU1_BTSEN @S9S_MB_2U_LIB.S9S_MB_2U(SCH_1):PVCCFA_EHV_CPU1_BTSEN    I14 @S9S_MB_2U_LIB.S9S_MB_2U(SCH_1):PAGE280
    25 PVCCFA_EHV_CPU1_BCSP1 @S9S_MB_2U_LIB.S9S_MB_2U(SCH_1):PVCCFA_EHV_CPU1_BCSP1    I14 @S9S_MB_2U_LIB.S9S_MB_2U(SCH_1):PAGE280
6_7-13_15-29    GND @S9S_MB_2U_LIB.S9S_MB_2U(SCH_1):GND    I14 @S9S_MB_2U_LIB.S9S_MB_2U(SCH_1):PAGE280
    27     NC     NC    I14 @S9S_MB_2U_LIB.S9S_MB_2U(SCH_1):PAGE280
  8_12 SW_PVCCFA_EHV_CPU1_SW1 @S9S_MB_2U_LIB.S9S_MB_2U(SCH_1):SW_PVCCFA_EHV_CPU1_SW1    I14 @S9S_MB_2U_LIB.S9S_MB_2U(SCH_1):PAGE280
     2 PVCCFA_EHV_CPU1_FAULT @S9S_MB_2U_LIB.S9S_MB_2U(SCH_1):PVCCFA_EHV_CPU1_FAULT    I14 @S9S_MB_2U_LIB.S9S_MB_2U(SCH_1):PAGE280
    26    GND @S9S_MB_2U_LIB.S9S_MB_2U(SCH_1):GND    I14 @S9S_MB_2U_LIB.S9S_MB_2U(SCH_1):PAGE280
    22 PVCCFA_EHV_CPU1_NC2 @S9S_MB_2U_LIB.S9S_MB_2U(SCH_1):PVCCFA_EHV_CPU1_NC2    I14 @S9S_MB_2U_LIB.S9S_MB_2U(SCH_1):PAGE280
     5 PVCCFA_EHV_CPU1_LSET1 @S9S_MB_2U_LIB.S9S_MB_2U(SCH_1):PVCCFA_EHV_CPU1_LSET1    I14 @S9S_MB_2U_LIB.S9S_MB_2U(SCH_1):PAGE280
     3 PVCCFA_EHV_CPU1_NC1 @S9S_MB_2U_LIB.S9S_MB_2U(SCH_1):PVCCFA_EHV_CPU1_NC1    I14 @S9S_MB_2U_LIB.S9S_MB_2U(SCH_1):PAGE280

PU50_P1_1 ISL99390FRZTR5935-ISL99390FRZ-A
    34 PVCCINFAON_CPU1_APWM1 @S9S_MB_2U_LIB.S9S_MB_2U(SCH_1):PVCCINFAON_CPU1_APWM1    I38 @S9S_MB_2U_LIB.S9S_MB_2U(SCH_1):PAGE279
    39 PVCCINFAON_CPU1_VREF @S9S_MB_2U_LIB.S9S_MB_2U(SCH_1):PVCCINFAON_CPU1_VREF    I38 @S9S_MB_2U_LIB.S9S_MB_2U(SCH_1):PAGE279
     3 PVCCINFAON_CPU1_VDD1 @S9S_MB_2U_LIB.S9S_MB_2U(SCH_1):PVCCINFAON_CPU1_VDD1    I38 @S9S_MB_2U_LIB.S9S_MB_2U(SCH_1):PAGE279
     2    GND @S9S_MB_2U_LIB.S9S_MB_2U(SCH_1):GND    I38 @S9S_MB_2U_LIB.S9S_MB_2U(SCH_1):PAGE279
    33 SW_PVCCINFAON_CPU1_BOOT1 @S9S_MB_2U_LIB.S9S_MB_2U(SCH_1):SW_PVCCINFAON_CPU1_BOOT1    I38 @S9S_MB_2U_LIB.S9S_MB_2U(SCH_1):PAGE279
 25_29 SW_P12V_PVCCINFAON_CPU1_FLT @S9S_MB_2U_LIB.S9S_MB_2U(SCH_1):SW_P12V_PVCCINFAON_CPU1_FLT    I38 @S9S_MB_2U_LIB.S9S_MB_2U(SCH_1):PAGE279
    32 SW_PVCCINFAON_CPU1_BOOTR1 @S9S_MB_2U_LIB.S9S_MB_2U(SCH_1):SW_PVCCINFAON_CPU1_BOOTR1    I38 @S9S_MB_2U_LIB.S9S_MB_2U(SCH_1):PAGE279
     4 PVCCFA_EHV_CPU1_PVCC @S9S_MB_2U_LIB.S9S_MB_2U(SCH_1):PVCCFA_EHV_CPU1_PVCC    I38 @S9S_MB_2U_LIB.S9S_MB_2U(SCH_1):PAGE279
    36 PVCCINFAON_CPU1_ATSEN @S9S_MB_2U_LIB.S9S_MB_2U(SCH_1):PVCCINFAON_CPU1_ATSEN    I38 @S9S_MB_2U_LIB.S9S_MB_2U(SCH_1):PAGE279
    38 PVCCINFAON_CPU1_ACSP1 @S9S_MB_2U_LIB.S9S_MB_2U(SCH_1):PVCCINFAON_CPU1_ACSP1    I38 @S9S_MB_2U_LIB.S9S_MB_2U(SCH_1):PAGE279
    37 PVCCINFAON_CPU1_LSET1 @S9S_MB_2U_LIB.S9S_MB_2U(SCH_1):PVCCINFAON_CPU1_LSET1    I38 @S9S_MB_2U_LIB.S9S_MB_2U(SCH_1):PAGE279
 10_19 SW_PVCCINFAON_CPU1_SW1 @S9S_MB_2U_LIB.S9S_MB_2U(SCH_1):SW_PVCCINFAON_CPU1_SW1    I38 @S9S_MB_2U_LIB.S9S_MB_2U(SCH_1):PAGE279
     5    GND @S9S_MB_2U_LIB.S9S_MB_2U(SCH_1):GND    I38 @S9S_MB_2U_LIB.S9S_MB_2U(SCH_1):PAGE279
    30 SW_P12V_PVCCINFAON_CPU1_FLT @S9S_MB_2U_LIB.S9S_MB_2U(SCH_1):SW_P12V_PVCCINFAON_CPU1_FLT    I38 @S9S_MB_2U_LIB.S9S_MB_2U(SCH_1):PAGE279
     1 PVCCINFAON_CPU1_VOS1 @S9S_MB_2U_LIB.S9S_MB_2U(SCH_1):PVCCINFAON_CPU1_VOS1    I38 @S9S_MB_2U_LIB.S9S_MB_2U(SCH_1):PAGE279
    40    GND @S9S_MB_2U_LIB.S9S_MB_2U(SCH_1):GND    I38 @S9S_MB_2U_LIB.S9S_MB_2U(SCH_1):PAGE279
    35 PVCCINFAON_CPU1_VDD1 @S9S_MB_2U_LIB.S9S_MB_2U(SCH_1):PVCCINFAON_CPU1_VDD1    I38 @S9S_MB_2U_LIB.S9S_MB_2U(SCH_1):PAGE279
    31     NC     NC    I38 @S9S_MB_2U_LIB.S9S_MB_2U(SCH_1):PAGE279
     6     NC     NC    I38 @S9S_MB_2U_LIB.S9S_MB_2U(SCH_1):PAGE279
    41     NC     NC    I38 @S9S_MB_2U_LIB.S9S_MB_2U(SCH_1):PAGE279
7_9-20_24    GND @S9S_MB_2U_LIB.S9S_MB_2U(SCH_1):GND    I38 @S9S_MB_2U_LIB.S9S_MB_2U(SCH_1):PAGE279

PU51_P1_2 ISL99390FRZTR5935-ISL99390FRZ-A
    34 PVCCINFAON_CPU1_APWM2 @S9S_MB_2U_LIB.S9S_MB_2U(SCH_1):PVCCINFAON_CPU1_APWM2    I29 @S9S_MB_2U_LIB.S9S_MB_2U(SCH_1):PAGE279
    39 PVCCINFAON_CPU1_VREF @S9S_MB_2U_LIB.S9S_MB_2U(SCH_1):PVCCINFAON_CPU1_VREF    I29 @S9S_MB_2U_LIB.S9S_MB_2U(SCH_1):PAGE279
     3 PVCCINFAON_CPU1_VDD2 @S9S_MB_2U_LIB.S9S_MB_2U(SCH_1):PVCCINFAON_CPU1_VDD2    I29 @S9S_MB_2U_LIB.S9S_MB_2U(SCH_1):PAGE279
     2    GND @S9S_MB_2U_LIB.S9S_MB_2U(SCH_1):GND    I29 @S9S_MB_2U_LIB.S9S_MB_2U(SCH_1):PAGE279
    33 SW_PVCCINFAON_CPU1_BOOT2 @S9S_MB_2U_LIB.S9S_MB_2U(SCH_1):SW_PVCCINFAON_CPU1_BOOT2    I29 @S9S_MB_2U_LIB.S9S_MB_2U(SCH_1):PAGE279
 25_29 SW_P12V_PVCCINFAON_CPU1_FLT @S9S_MB_2U_LIB.S9S_MB_2U(SCH_1):SW_P12V_PVCCINFAON_CPU1_FLT    I29 @S9S_MB_2U_LIB.S9S_MB_2U(SCH_1):PAGE279
    32 SW_PVCCINFAON_CPU1_BOOTR2 @S9S_MB_2U_LIB.S9S_MB_2U(SCH_1):SW_PVCCINFAON_CPU1_BOOTR2    I29 @S9S_MB_2U_LIB.S9S_MB_2U(SCH_1):PAGE279
     4 PVCCFA_EHV_CPU1_PVCC @S9S_MB_2U_LIB.S9S_MB_2U(SCH_1):PVCCFA_EHV_CPU1_PVCC    I29 @S9S_MB_2U_LIB.S9S_MB_2U(SCH_1):PAGE279
    36 PVCCINFAON_CPU1_ATSEN @S9S_MB_2U_LIB.S9S_MB_2U(SCH_1):PVCCINFAON_CPU1_ATSEN    I29 @S9S_MB_2U_LIB.S9S_MB_2U(SCH_1):PAGE279
    38 PVCCINFAON_CPU1_ACSP2 @S9S_MB_2U_LIB.S9S_MB_2U(SCH_1):PVCCINFAON_CPU1_ACSP2    I29 @S9S_MB_2U_LIB.S9S_MB_2U(SCH_1):PAGE279
    37 PVCCINFAON_CPU1_LSET2 @S9S_MB_2U_LIB.S9S_MB_2U(SCH_1):PVCCINFAON_CPU1_LSET2    I29 @S9S_MB_2U_LIB.S9S_MB_2U(SCH_1):PAGE279
 10_19 SW_PVCCINFAON_CPU1_SW2 @S9S_MB_2U_LIB.S9S_MB_2U(SCH_1):SW_PVCCINFAON_CPU1_SW2    I29 @S9S_MB_2U_LIB.S9S_MB_2U(SCH_1):PAGE279
     5    GND @S9S_MB_2U_LIB.S9S_MB_2U(SCH_1):GND    I29 @S9S_MB_2U_LIB.S9S_MB_2U(SCH_1):PAGE279
    30 SW_P12V_PVCCINFAON_CPU1_FLT @S9S_MB_2U_LIB.S9S_MB_2U(SCH_1):SW_P12V_PVCCINFAON_CPU1_FLT    I29 @S9S_MB_2U_LIB.S9S_MB_2U(SCH_1):PAGE279
     1 PVCCINFAON_CPU1_VOS2 @S9S_MB_2U_LIB.S9S_MB_2U(SCH_1):PVCCINFAON_CPU1_VOS2    I29 @S9S_MB_2U_LIB.S9S_MB_2U(SCH_1):PAGE279
    40    GND @S9S_MB_2U_LIB.S9S_MB_2U(SCH_1):GND    I29 @S9S_MB_2U_LIB.S9S_MB_2U(SCH_1):PAGE279
    35 PVCCINFAON_CPU1_VDD2 @S9S_MB_2U_LIB.S9S_MB_2U(SCH_1):PVCCINFAON_CPU1_VDD2    I29 @S9S_MB_2U_LIB.S9S_MB_2U(SCH_1):PAGE279
    31     NC     NC    I29 @S9S_MB_2U_LIB.S9S_MB_2U(SCH_1):PAGE279
     6     NC     NC    I29 @S9S_MB_2U_LIB.S9S_MB_2U(SCH_1):PAGE279
    41     NC     NC    I29 @S9S_MB_2U_LIB.S9S_MB_2U(SCH_1):PAGE279
7_9-20_24    GND @S9S_MB_2U_LIB.S9S_MB_2U(SCH_1):GND    I29 @S9S_MB_2U_LIB.S9S_MB_2U(SCH_1):PAGE279

PU69_P0_1 ISL99390FRZTR5935-ISL99390FRZ-A
    34 PVCCFA_EHV_FIVRA_CPU0_PWM1 @S9S_MB_2U_LIB.S9S_MB_2U(SCH_1):PVCCFA_EHV_FIVRA_CPU0_PWM1    I25 @S9S_MB_2U_LIB.S9S_MB_2U(SCH_1):PAGE257
    39 PVCCIN_CPU0_VREF @S9S_MB_2U_LIB.S9S_MB_2U(SCH_1):PVCCIN_CPU0_VREF    I25 @S9S_MB_2U_LIB.S9S_MB_2U(SCH_1):PAGE257
     3 PVCCFA_EHV_FIVRA_CPU0_VDD1 @S9S_MB_2U_LIB.S9S_MB_2U(SCH_1):PVCCFA_EHV_FIVRA_CPU0_VDD1    I25 @S9S_MB_2U_LIB.S9S_MB_2U(SCH_1):PAGE257
     2    GND @S9S_MB_2U_LIB.S9S_MB_2U(SCH_1):GND    I25 @S9S_MB_2U_LIB.S9S_MB_2U(SCH_1):PAGE257
    33 SW_PVCCFA_EHV_FIVRA_CPU0_BOOT1 @S9S_MB_2U_LIB.S9S_MB_2U(SCH_1):SW_PVCCFA_EHV_FIVRA_CPU0_BOOT1    I25 @S9S_MB_2U_LIB.S9S_MB_2U(SCH_1):PAGE257
 25_29 SW_P12V_PVCCFA_EHV_FIVRA_CPU0_R @S9S_MB_2U_LIB.S9S_MB_2U(SCH_1):SW_P12V_PVCCFA_EHV_FIVRA_CPU0_R    I25 @S9S_MB_2U_LIB.S9S_MB_2U(SCH_1):PAGE257
    32 SW_PVCCFA_EHV_FIVRA_CPU0_BOOTR1 @S9S_MB_2U_LIB.S9S_MB_2U(SCH_1):SW_PVCCFA_EHV_FIVRA_CPU0_BOOTR1    I25 @S9S_MB_2U_LIB.S9S_MB_2U(SCH_1):PAGE257
     4 PVCCFA_EHV_FIVRA_CPU0_PVCC1 @S9S_MB_2U_LIB.S9S_MB_2U(SCH_1):PVCCFA_EHV_FIVRA_CPU0_PVCC1    I25 @S9S_MB_2U_LIB.S9S_MB_2U(SCH_1):PAGE257
    36 PVCCFA_EHV_FIVRA_CPU0_BTSEN @S9S_MB_2U_LIB.S9S_MB_2U(SCH_1):PVCCFA_EHV_FIVRA_CPU0_BTSEN    I25 @S9S_MB_2U_LIB.S9S_MB_2U(SCH_1):PAGE257
    38 PVCCFA_EHV_FIVRA_CPU0_IMON1 @S9S_MB_2U_LIB.S9S_MB_2U(SCH_1):PVCCFA_EHV_FIVRA_CPU0_IMON1    I25 @S9S_MB_2U_LIB.S9S_MB_2U(SCH_1):PAGE257
    37 PVCCFA_EHV_FIVRA_CPU0_LSET1 @S9S_MB_2U_LIB.S9S_MB_2U(SCH_1):PVCCFA_EHV_FIVRA_CPU0_LSET1    I25 @S9S_MB_2U_LIB.S9S_MB_2U(SCH_1):PAGE257
 10_19 SW_PVCCFA_EHV_FIVRA_CPU0_SW1 @S9S_MB_2U_LIB.S9S_MB_2U(SCH_1):SW_PVCCFA_EHV_FIVRA_CPU0_SW1    I25 @S9S_MB_2U_LIB.S9S_MB_2U(SCH_1):PAGE257
     5    GND @S9S_MB_2U_LIB.S9S_MB_2U(SCH_1):GND    I25 @S9S_MB_2U_LIB.S9S_MB_2U(SCH_1):PAGE257
    30 SW_P12V_PVCCFA_EHV_FIVRA_CPU0_R @S9S_MB_2U_LIB.S9S_MB_2U(SCH_1):SW_P12V_PVCCFA_EHV_FIVRA_CPU0_R    I25 @S9S_MB_2U_LIB.S9S_MB_2U(SCH_1):PAGE257
     1 PVCCFA_EHV_FIVRA_CPU0_VOS1 @S9S_MB_2U_LIB.S9S_MB_2U(SCH_1):PVCCFA_EHV_FIVRA_CPU0_VOS1    I25 @S9S_MB_2U_LIB.S9S_MB_2U(SCH_1):PAGE257
    40    GND @S9S_MB_2U_LIB.S9S_MB_2U(SCH_1):GND    I25 @S9S_MB_2U_LIB.S9S_MB_2U(SCH_1):PAGE257
    35 PVCCFA_EHV_FIVRA_CPU0_VDD1 @S9S_MB_2U_LIB.S9S_MB_2U(SCH_1):PVCCFA_EHV_FIVRA_CPU0_VDD1    I25 @S9S_MB_2U_LIB.S9S_MB_2U(SCH_1):PAGE257
    31     NC     NC    I25 @S9S_MB_2U_LIB.S9S_MB_2U(SCH_1):PAGE257
     6     NC     NC    I25 @S9S_MB_2U_LIB.S9S_MB_2U(SCH_1):PAGE257
    41     NC     NC    I25 @S9S_MB_2U_LIB.S9S_MB_2U(SCH_1):PAGE257
7_9-20_24    GND @S9S_MB_2U_LIB.S9S_MB_2U(SCH_1):GND    I25 @S9S_MB_2U_LIB.S9S_MB_2U(SCH_1):PAGE257

PU70_P0_2 ISL99390FRZTR5935-ISL99390FRZ-A
    34 PVCCFA_EHV_FIVRA_CPU0_PWM2 @S9S_MB_2U_LIB.S9S_MB_2U(SCH_1):PVCCFA_EHV_FIVRA_CPU0_PWM2    I16 @S9S_MB_2U_LIB.S9S_MB_2U(SCH_1):PAGE257
    39 PVCCIN_CPU0_VREF @S9S_MB_2U_LIB.S9S_MB_2U(SCH_1):PVCCIN_CPU0_VREF    I16 @S9S_MB_2U_LIB.S9S_MB_2U(SCH_1):PAGE257
     3 PVCCFA_EHV_FIVRA_CPU0_VDD2 @S9S_MB_2U_LIB.S9S_MB_2U(SCH_1):PVCCFA_EHV_FIVRA_CPU0_VDD2    I16 @S9S_MB_2U_LIB.S9S_MB_2U(SCH_1):PAGE257
     2    GND @S9S_MB_2U_LIB.S9S_MB_2U(SCH_1):GND    I16 @S9S_MB_2U_LIB.S9S_MB_2U(SCH_1):PAGE257
    33 SW_PVCCFA_EHV_FIVRA_CPU0_BOOT2 @S9S_MB_2U_LIB.S9S_MB_2U(SCH_1):SW_PVCCFA_EHV_FIVRA_CPU0_BOOT2    I16 @S9S_MB_2U_LIB.S9S_MB_2U(SCH_1):PAGE257
 25_29 SW_P12V_PVCCFA_EHV_FIVRA_CPU0_L @S9S_MB_2U_LIB.S9S_MB_2U(SCH_1):SW_P12V_PVCCFA_EHV_FIVRA_CPU0_L    I16 @S9S_MB_2U_LIB.S9S_MB_2U(SCH_1):PAGE257
    32 SW_PVCCFA_EHV_FIVRA_CPU0_BOOTR2 @S9S_MB_2U_LIB.S9S_MB_2U(SCH_1):SW_PVCCFA_EHV_FIVRA_CPU0_BOOTR2    I16 @S9S_MB_2U_LIB.S9S_MB_2U(SCH_1):PAGE257
     4 PVCCFA_EHV_FIVRA_CPU0_PVCC2 @S9S_MB_2U_LIB.S9S_MB_2U(SCH_1):PVCCFA_EHV_FIVRA_CPU0_PVCC2    I16 @S9S_MB_2U_LIB.S9S_MB_2U(SCH_1):PAGE257
    36 PVCCFA_EHV_FIVRA_CPU0_BTSEN @S9S_MB_2U_LIB.S9S_MB_2U(SCH_1):PVCCFA_EHV_FIVRA_CPU0_BTSEN    I16 @S9S_MB_2U_LIB.S9S_MB_2U(SCH_1):PAGE257
    38 PVCCFA_EHV_FIVRA_CPU0_IMON2 @S9S_MB_2U_LIB.S9S_MB_2U(SCH_1):PVCCFA_EHV_FIVRA_CPU0_IMON2    I16 @S9S_MB_2U_LIB.S9S_MB_2U(SCH_1):PAGE257
    37 PVCCFA_EHV_FIVRA_CPU0_LSET2 @S9S_MB_2U_LIB.S9S_MB_2U(SCH_1):PVCCFA_EHV_FIVRA_CPU0_LSET2    I16 @S9S_MB_2U_LIB.S9S_MB_2U(SCH_1):PAGE257
 10_19 SW_PVCCFA_EHV_FIVRA_CPU0_SW2 @S9S_MB_2U_LIB.S9S_MB_2U(SCH_1):SW_PVCCFA_EHV_FIVRA_CPU0_SW2    I16 @S9S_MB_2U_LIB.S9S_MB_2U(SCH_1):PAGE257
     5    GND @S9S_MB_2U_LIB.S9S_MB_2U(SCH_1):GND    I16 @S9S_MB_2U_LIB.S9S_MB_2U(SCH_1):PAGE257
    30 SW_P12V_PVCCFA_EHV_FIVRA_CPU0_L @S9S_MB_2U_LIB.S9S_MB_2U(SCH_1):SW_P12V_PVCCFA_EHV_FIVRA_CPU0_L    I16 @S9S_MB_2U_LIB.S9S_MB_2U(SCH_1):PAGE257
     1 PVCCFA_EHV_FIVRA_CPU0_VOS2 @S9S_MB_2U_LIB.S9S_MB_2U(SCH_1):PVCCFA_EHV_FIVRA_CPU0_VOS2    I16 @S9S_MB_2U_LIB.S9S_MB_2U(SCH_1):PAGE257
    40    GND @S9S_MB_2U_LIB.S9S_MB_2U(SCH_1):GND    I16 @S9S_MB_2U_LIB.S9S_MB_2U(SCH_1):PAGE257
    35 PVCCFA_EHV_FIVRA_CPU0_VDD2 @S9S_MB_2U_LIB.S9S_MB_2U(SCH_1):PVCCFA_EHV_FIVRA_CPU0_VDD2    I16 @S9S_MB_2U_LIB.S9S_MB_2U(SCH_1):PAGE257
    31     NC     NC    I16 @S9S_MB_2U_LIB.S9S_MB_2U(SCH_1):PAGE257
     6     NC     NC    I16 @S9S_MB_2U_LIB.S9S_MB_2U(SCH_1):PAGE257
    41     NC     NC    I16 @S9S_MB_2U_LIB.S9S_MB_2U(SCH_1):PAGE257
7_9-20_24    GND @S9S_MB_2U_LIB.S9S_MB_2U(SCH_1):GND    I16 @S9S_MB_2U_LIB.S9S_MB_2U(SCH_1):PAGE257

PU71_P0_3 ISL99390FRZTR5935-ISL99390FRZ-A
    34 PVCCFA_EHV_FIVRA_CPU0_PWM3 @S9S_MB_2U_LIB.S9S_MB_2U(SCH_1):PVCCFA_EHV_FIVRA_CPU0_PWM3    I82 @S9S_MB_2U_LIB.S9S_MB_2U(SCH_1):PAGE258
    39 PVCCIN_CPU0_VREF @S9S_MB_2U_LIB.S9S_MB_2U(SCH_1):PVCCIN_CPU0_VREF    I82 @S9S_MB_2U_LIB.S9S_MB_2U(SCH_1):PAGE258
     3 PVCCFA_EHV_FIVRA_CPU0_VDD3 @S9S_MB_2U_LIB.S9S_MB_2U(SCH_1):PVCCFA_EHV_FIVRA_CPU0_VDD3    I82 @S9S_MB_2U_LIB.S9S_MB_2U(SCH_1):PAGE258
     2    GND @S9S_MB_2U_LIB.S9S_MB_2U(SCH_1):GND    I82 @S9S_MB_2U_LIB.S9S_MB_2U(SCH_1):PAGE258
    33 SW_PVCCFA_EHV_FIVRA_CPU0_BOOT3 @S9S_MB_2U_LIB.S9S_MB_2U(SCH_1):SW_PVCCFA_EHV_FIVRA_CPU0_BOOT3    I82 @S9S_MB_2U_LIB.S9S_MB_2U(SCH_1):PAGE258
 25_29 SW_P12V_PVCCFA_EHV_FIVRA_CPU0_R @S9S_MB_2U_LIB.S9S_MB_2U(SCH_1):SW_P12V_PVCCFA_EHV_FIVRA_CPU0_R    I82 @S9S_MB_2U_LIB.S9S_MB_2U(SCH_1):PAGE258
    32 SW_PVCCFA_EHV_FIVRA_CPU0_BOOTR3 @S9S_MB_2U_LIB.S9S_MB_2U(SCH_1):SW_PVCCFA_EHV_FIVRA_CPU0_BOOTR3    I82 @S9S_MB_2U_LIB.S9S_MB_2U(SCH_1):PAGE258
     4 PVCCFA_EHV_FIVRA_CPU0_PVCC1 @S9S_MB_2U_LIB.S9S_MB_2U(SCH_1):PVCCFA_EHV_FIVRA_CPU0_PVCC1    I82 @S9S_MB_2U_LIB.S9S_MB_2U(SCH_1):PAGE258
    36 PVCCFA_EHV_FIVRA_CPU0_BTSEN @S9S_MB_2U_LIB.S9S_MB_2U(SCH_1):PVCCFA_EHV_FIVRA_CPU0_BTSEN    I82 @S9S_MB_2U_LIB.S9S_MB_2U(SCH_1):PAGE258
    38 PVCCFA_EHV_FIVRA_CPU0_IMON3 @S9S_MB_2U_LIB.S9S_MB_2U(SCH_1):PVCCFA_EHV_FIVRA_CPU0_IMON3    I82 @S9S_MB_2U_LIB.S9S_MB_2U(SCH_1):PAGE258
    37 PVCCFA_EHV_FIVRA_CPU0_LSET3 @S9S_MB_2U_LIB.S9S_MB_2U(SCH_1):PVCCFA_EHV_FIVRA_CPU0_LSET3    I82 @S9S_MB_2U_LIB.S9S_MB_2U(SCH_1):PAGE258
 10_19 SW_PVCCFA_EHV_FIVRA_CPU0_SW3 @S9S_MB_2U_LIB.S9S_MB_2U(SCH_1):SW_PVCCFA_EHV_FIVRA_CPU0_SW3    I82 @S9S_MB_2U_LIB.S9S_MB_2U(SCH_1):PAGE258
     5    GND @S9S_MB_2U_LIB.S9S_MB_2U(SCH_1):GND    I82 @S9S_MB_2U_LIB.S9S_MB_2U(SCH_1):PAGE258
    30 SW_P12V_PVCCFA_EHV_FIVRA_CPU0_R @S9S_MB_2U_LIB.S9S_MB_2U(SCH_1):SW_P12V_PVCCFA_EHV_FIVRA_CPU0_R    I82 @S9S_MB_2U_LIB.S9S_MB_2U(SCH_1):PAGE258
     1 PVCCFA_EHV_FIVRA_CPU0_VOS3 @S9S_MB_2U_LIB.S9S_MB_2U(SCH_1):PVCCFA_EHV_FIVRA_CPU0_VOS3    I82 @S9S_MB_2U_LIB.S9S_MB_2U(SCH_1):PAGE258
    40    GND @S9S_MB_2U_LIB.S9S_MB_2U(SCH_1):GND    I82 @S9S_MB_2U_LIB.S9S_MB_2U(SCH_1):PAGE258
    35 PVCCFA_EHV_FIVRA_CPU0_VDD3 @S9S_MB_2U_LIB.S9S_MB_2U(SCH_1):PVCCFA_EHV_FIVRA_CPU0_VDD3    I82 @S9S_MB_2U_LIB.S9S_MB_2U(SCH_1):PAGE258
    31     NC     NC    I82 @S9S_MB_2U_LIB.S9S_MB_2U(SCH_1):PAGE258
     6     NC     NC    I82 @S9S_MB_2U_LIB.S9S_MB_2U(SCH_1):PAGE258
    41     NC     NC    I82 @S9S_MB_2U_LIB.S9S_MB_2U(SCH_1):PAGE258
7_9-20_24    GND @S9S_MB_2U_LIB.S9S_MB_2U(SCH_1):GND    I82 @S9S_MB_2U_LIB.S9S_MB_2U(SCH_1):PAGE258

PU72_P0_4 ISL99390FRZTR5935-ISL99390FRZ-A
    34 PVCCFA_EHV_FIVRA_CPU0_PWM4 @S9S_MB_2U_LIB.S9S_MB_2U(SCH_1):PVCCFA_EHV_FIVRA_CPU0_PWM4    I10 @S9S_MB_2U_LIB.S9S_MB_2U(SCH_1):PAGE258
    39 PVCCIN_CPU0_VREF @S9S_MB_2U_LIB.S9S_MB_2U(SCH_1):PVCCIN_CPU0_VREF    I10 @S9S_MB_2U_LIB.S9S_MB_2U(SCH_1):PAGE258
     3 PVCCFA_EHV_FIVRA_CPU0_VDD4 @S9S_MB_2U_LIB.S9S_MB_2U(SCH_1):PVCCFA_EHV_FIVRA_CPU0_VDD4    I10 @S9S_MB_2U_LIB.S9S_MB_2U(SCH_1):PAGE258
     2    GND @S9S_MB_2U_LIB.S9S_MB_2U(SCH_1):GND    I10 @S9S_MB_2U_LIB.S9S_MB_2U(SCH_1):PAGE258
    33 SW_PVCCFA_EHV_FIVRA_CPU0_BOOT4 @S9S_MB_2U_LIB.S9S_MB_2U(SCH_1):SW_PVCCFA_EHV_FIVRA_CPU0_BOOT4    I10 @S9S_MB_2U_LIB.S9S_MB_2U(SCH_1):PAGE258
 25_29 SW_P12V_PVCCFA_EHV_FIVRA_CPU0_L @S9S_MB_2U_LIB.S9S_MB_2U(SCH_1):SW_P12V_PVCCFA_EHV_FIVRA_CPU0_L    I10 @S9S_MB_2U_LIB.S9S_MB_2U(SCH_1):PAGE258
    32 SW_PVCCFA_EHV_FIVRA_CPU0_BOOTR4 @S9S_MB_2U_LIB.S9S_MB_2U(SCH_1):SW_PVCCFA_EHV_FIVRA_CPU0_BOOTR4    I10 @S9S_MB_2U_LIB.S9S_MB_2U(SCH_1):PAGE258
     4 PVCCFA_EHV_FIVRA_CPU0_PVCC2 @S9S_MB_2U_LIB.S9S_MB_2U(SCH_1):PVCCFA_EHV_FIVRA_CPU0_PVCC2    I10 @S9S_MB_2U_LIB.S9S_MB_2U(SCH_1):PAGE258
    36 PVCCFA_EHV_FIVRA_CPU0_BTSEN @S9S_MB_2U_LIB.S9S_MB_2U(SCH_1):PVCCFA_EHV_FIVRA_CPU0_BTSEN    I10 @S9S_MB_2U_LIB.S9S_MB_2U(SCH_1):PAGE258
    38 PVCCFA_EHV_FIVRA_CPU0_IMON4 @S9S_MB_2U_LIB.S9S_MB_2U(SCH_1):PVCCFA_EHV_FIVRA_CPU0_IMON4    I10 @S9S_MB_2U_LIB.S9S_MB_2U(SCH_1):PAGE258
    37 PVCCFA_EHV_FIVRA_CPU0_LSET4 @S9S_MB_2U_LIB.S9S_MB_2U(SCH_1):PVCCFA_EHV_FIVRA_CPU0_LSET4    I10 @S9S_MB_2U_LIB.S9S_MB_2U(SCH_1):PAGE258
 10_19 SW_PVCCFA_EHV_FIVRA_CPU0_SW4 @S9S_MB_2U_LIB.S9S_MB_2U(SCH_1):SW_PVCCFA_EHV_FIVRA_CPU0_SW4    I10 @S9S_MB_2U_LIB.S9S_MB_2U(SCH_1):PAGE258
     5    GND @S9S_MB_2U_LIB.S9S_MB_2U(SCH_1):GND    I10 @S9S_MB_2U_LIB.S9S_MB_2U(SCH_1):PAGE258
    30 SW_P12V_PVCCFA_EHV_FIVRA_CPU0_L @S9S_MB_2U_LIB.S9S_MB_2U(SCH_1):SW_P12V_PVCCFA_EHV_FIVRA_CPU0_L    I10 @S9S_MB_2U_LIB.S9S_MB_2U(SCH_1):PAGE258
     1 PVCCFA_EHV_FIVRA_CPU0_VOS4 @S9S_MB_2U_LIB.S9S_MB_2U(SCH_1):PVCCFA_EHV_FIVRA_CPU0_VOS4    I10 @S9S_MB_2U_LIB.S9S_MB_2U(SCH_1):PAGE258
    40    GND @S9S_MB_2U_LIB.S9S_MB_2U(SCH_1):GND    I10 @S9S_MB_2U_LIB.S9S_MB_2U(SCH_1):PAGE258
    35 PVCCFA_EHV_FIVRA_CPU0_VDD4 @S9S_MB_2U_LIB.S9S_MB_2U(SCH_1):PVCCFA_EHV_FIVRA_CPU0_VDD4    I10 @S9S_MB_2U_LIB.S9S_MB_2U(SCH_1):PAGE258
    31     NC     NC    I10 @S9S_MB_2U_LIB.S9S_MB_2U(SCH_1):PAGE258
     6     NC     NC    I10 @S9S_MB_2U_LIB.S9S_MB_2U(SCH_1):PAGE258
    41     NC     NC    I10 @S9S_MB_2U_LIB.S9S_MB_2U(SCH_1):PAGE258
7_9-20_24    GND @S9S_MB_2U_LIB.S9S_MB_2U(SCH_1):GND    I10 @S9S_MB_2U_LIB.S9S_MB_2U(SCH_1):PAGE258

PU73 RS53319LR-RS53319LR,SMLF,IC,ALA
    10 SW_P12V_AUX_P1V05_PCH_AUX_FLT @S9S_MB_2U_LIB.S9S_MB_2U(SCH_1):SW_P12V_AUX_P1V05_PCH_AUX_FLT    I11 @S9S_MB_2U_LIB.S9S_MB_2U(SCH_1):PAGE248
     9 PWRGD_P1V05_PCH_AUX_R @S9S_MB_2U_LIB.S9S_MB_2U(SCH_1):PWRGD_P1V05_PCH_AUX_R    I11 @S9S_MB_2U_LIB.S9S_MB_2U(SCH_1):PAGE248
 11_18    GND @S9S_MB_2U_LIB.S9S_MB_2U(SCH_1):GND    I11 @S9S_MB_2U_LIB.S9S_MB_2U(SCH_1):PAGE248
     8 FM_P1V05_PCH_AUX_R_EN @S9S_MB_2U_LIB.S9S_MB_2U(SCH_1):FM_P1V05_PCH_AUX_R_EN    I11 @S9S_MB_2U_LIB.S9S_MB_2U(SCH_1):PAGE248
     1 SW_P1V05_PCH_AUX_BST @S9S_MB_2U_LIB.S9S_MB_2U(SCH_1):SW_P1V05_PCH_AUX_BST    I11 @S9S_MB_2U_LIB.S9S_MB_2U(SCH_1):PAGE248
     7 P1V05_PCH_AUX_FB @S9S_MB_2U_LIB.S9S_MB_2U(SCH_1):P1V05_PCH_AUX_FB    I11 @S9S_MB_2U_LIB.S9S_MB_2U(SCH_1):PAGE248
     2    GND @S9S_MB_2U_LIB.S9S_MB_2U(SCH_1):GND    I11 @S9S_MB_2U_LIB.S9S_MB_2U(SCH_1):PAGE248
    19 P1V05_PCH_AUX_VCC @S9S_MB_2U_LIB.S9S_MB_2U(SCH_1):P1V05_PCH_AUX_VCC    I11 @S9S_MB_2U_LIB.S9S_MB_2U(SCH_1):PAGE248
     6 SH_P1V05_PCH_AUX_N @S9S_MB_2U_LIB.S9S_MB_2U(SCH_1):SH_P1V05_PCH_AUX_N    I11 @S9S_MB_2U_LIB.S9S_MB_2U(SCH_1):PAGE248
    20 SW_P1V05_PCH_AUX_SW @S9S_MB_2U_LIB.S9S_MB_2U(SCH_1):SW_P1V05_PCH_AUX_SW    I11 @S9S_MB_2U_LIB.S9S_MB_2U(SCH_1):PAGE248
     5 P1V05_PCH_AUX_REF @S9S_MB_2U_LIB.S9S_MB_2U(SCH_1):P1V05_PCH_AUX_REF    I11 @S9S_MB_2U_LIB.S9S_MB_2U(SCH_1):PAGE248
     4 P1V05_PCH_AUX_MODE @S9S_MB_2U_LIB.S9S_MB_2U(SCH_1):P1V05_PCH_AUX_MODE    I11 @S9S_MB_2U_LIB.S9S_MB_2U(SCH_1):PAGE248
     3 P1V05_PCH_AUX_CS @S9S_MB_2U_LIB.S9S_MB_2U(SCH_1):P1V05_PCH_AUX_CS    I11 @S9S_MB_2U_LIB.S9S_MB_2U(SCH_1):PAGE248
    21 SW_P12V_AUX_P1V05_PCH_AUX_FLT @S9S_MB_2U_LIB.S9S_MB_2U(SCH_1):SW_P12V_AUX_P1V05_PCH_AUX_FLT    I11 @S9S_MB_2U_LIB.S9S_MB_2U(SCH_1):PAGE248

PU74 NB682GDZ-NB682GD-Z,SMLF,IC,AL0A
     1 SW_P1V8_PCH_AUX_FLT @S9S_MB_2U_LIB.S9S_MB_2U(SCH_1):SW_P1V8_PCH_AUX_FLT    I26 @S9S_MB_2U_LIB.S9S_MB_2U(SCH_1):PAGE249
    13 PWRGD_P1V8_PCH_AUX_R @S9S_MB_2U_LIB.S9S_MB_2U(SCH_1):PWRGD_P1V8_PCH_AUX_R    I26 @S9S_MB_2U_LIB.S9S_MB_2U(SCH_1):PAGE249
     2    GND @S9S_MB_2U_LIB.S9S_MB_2U(SCH_1):GND    I26 @S9S_MB_2U_LIB.S9S_MB_2U(SCH_1):PAGE249
     5 FM_PCH_P1V8_AUX_EN_R @S9S_MB_2U_LIB.S9S_MB_2U(SCH_1):FM_PCH_P1V8_AUX_EN_R    I26 @S9S_MB_2U_LIB.S9S_MB_2U(SCH_1):PAGE249
     9 SW_P1V8_PCH_AUX_BST @S9S_MB_2U_LIB.S9S_MB_2U(SCH_1):SW_P1V8_PCH_AUX_BST    I26 @S9S_MB_2U_LIB.S9S_MB_2U(SCH_1):PAGE249
    11    GND @S9S_MB_2U_LIB.S9S_MB_2U(SCH_1):GND    I26 @S9S_MB_2U_LIB.S9S_MB_2U(SCH_1):PAGE249
     6 P1V8_PCH_AUX_VCC @S9S_MB_2U_LIB.S9S_MB_2U(SCH_1):P1V8_PCH_AUX_VCC    I26 @S9S_MB_2U_LIB.S9S_MB_2U(SCH_1):PAGE249
     3 P1V8_PCH_AUX_VCC @S9S_MB_2U_LIB.S9S_MB_2U(SCH_1):P1V8_PCH_AUX_VCC    I26 @S9S_MB_2U_LIB.S9S_MB_2U(SCH_1):PAGE249
     4    GND @S9S_MB_2U_LIB.S9S_MB_2U(SCH_1):GND    I26 @S9S_MB_2U_LIB.S9S_MB_2U(SCH_1):PAGE249
     7 P1V8_PCH_AUX_MODE @S9S_MB_2U_LIB.S9S_MB_2U(SCH_1):P1V8_PCH_AUX_MODE    I26 @S9S_MB_2U_LIB.S9S_MB_2U(SCH_1):PAGE249
    12 P1V8_PCH_AUX @S9S_MB_2U_LIB.S9S_MB_2U(SCH_1):P1V8_PCH_AUX    I26 @S9S_MB_2U_LIB.S9S_MB_2U(SCH_1):PAGE249
     8 SW_P1V8_PCH_AUX_SW @S9S_MB_2U_LIB.S9S_MB_2U(SCH_1):SW_P1V8_PCH_AUX_SW    I26 @S9S_MB_2U_LIB.S9S_MB_2U(SCH_1):PAGE249
    10 P1V8_PCH_AUX_VCC @S9S_MB_2U_LIB.S9S_MB_2U(SCH_1):P1V8_PCH_AUX_VCC    I26 @S9S_MB_2U_LIB.S9S_MB_2U(SCH_1):PAGE249

PU75_P1_1 ISL99390FRZTR5935-ISL99390FRZ-A
    34 PVCCFA_EHV_FIVRA_CPU1_PWM1 @S9S_MB_2U_LIB.S9S_MB_2U(SCH_1):PVCCFA_EHV_FIVRA_CPU1_PWM1    I89 @S9S_MB_2U_LIB.S9S_MB_2U(SCH_1):PAGE275
    39 PVCCIN_CPU1_VREF @S9S_MB_2U_LIB.S9S_MB_2U(SCH_1):PVCCIN_CPU1_VREF    I89 @S9S_MB_2U_LIB.S9S_MB_2U(SCH_1):PAGE275
     3 PVCCFA_EHV_FIVRA_CPU1_VDD1 @S9S_MB_2U_LIB.S9S_MB_2U(SCH_1):PVCCFA_EHV_FIVRA_CPU1_VDD1    I89 @S9S_MB_2U_LIB.S9S_MB_2U(SCH_1):PAGE275
     2    GND @S9S_MB_2U_LIB.S9S_MB_2U(SCH_1):GND    I89 @S9S_MB_2U_LIB.S9S_MB_2U(SCH_1):PAGE275
    33 SW_PVCCFA_EHV_FIVRA_CPU1_BOOT1 @S9S_MB_2U_LIB.S9S_MB_2U(SCH_1):SW_PVCCFA_EHV_FIVRA_CPU1_BOOT1    I89 @S9S_MB_2U_LIB.S9S_MB_2U(SCH_1):PAGE275
 25_29 SW_P12V_PVCCFA_EHV_FIVRA_CPU1_R @S9S_MB_2U_LIB.S9S_MB_2U(SCH_1):SW_P12V_PVCCFA_EHV_FIVRA_CPU1_R    I89 @S9S_MB_2U_LIB.S9S_MB_2U(SCH_1):PAGE275
    32 SW_PVCCFA_EHV_FIVRA_CPU1_BOOTR1 @S9S_MB_2U_LIB.S9S_MB_2U(SCH_1):SW_PVCCFA_EHV_FIVRA_CPU1_BOOTR1    I89 @S9S_MB_2U_LIB.S9S_MB_2U(SCH_1):PAGE275
     4 PVCCFA_EHV_FIVRA_CPU1_PVCC1 @S9S_MB_2U_LIB.S9S_MB_2U(SCH_1):PVCCFA_EHV_FIVRA_CPU1_PVCC1    I89 @S9S_MB_2U_LIB.S9S_MB_2U(SCH_1):PAGE275
    36 PVCCFA_EHV_FIVRA_CPU1_BTSEN @S9S_MB_2U_LIB.S9S_MB_2U(SCH_1):PVCCFA_EHV_FIVRA_CPU1_BTSEN    I89 @S9S_MB_2U_LIB.S9S_MB_2U(SCH_1):PAGE275
    38 PVCCFA_EHV_FIVRA_CPU1_IMON1 @S9S_MB_2U_LIB.S9S_MB_2U(SCH_1):PVCCFA_EHV_FIVRA_CPU1_IMON1    I89 @S9S_MB_2U_LIB.S9S_MB_2U(SCH_1):PAGE275
    37 PVCCFA_EHV_FIVRA_CPU1_LSET1 @S9S_MB_2U_LIB.S9S_MB_2U(SCH_1):PVCCFA_EHV_FIVRA_CPU1_LSET1    I89 @S9S_MB_2U_LIB.S9S_MB_2U(SCH_1):PAGE275
 10_19 SW_PVCCFA_EHV_FIVRA_CPU1_SW1 @S9S_MB_2U_LIB.S9S_MB_2U(SCH_1):SW_PVCCFA_EHV_FIVRA_CPU1_SW1    I89 @S9S_MB_2U_LIB.S9S_MB_2U(SCH_1):PAGE275
     5    GND @S9S_MB_2U_LIB.S9S_MB_2U(SCH_1):GND    I89 @S9S_MB_2U_LIB.S9S_MB_2U(SCH_1):PAGE275
    30 SW_P12V_PVCCFA_EHV_FIVRA_CPU1_R @S9S_MB_2U_LIB.S9S_MB_2U(SCH_1):SW_P12V_PVCCFA_EHV_FIVRA_CPU1_R    I89 @S9S_MB_2U_LIB.S9S_MB_2U(SCH_1):PAGE275
     1 PVCCFA_EHV_FIVRA_CPU1_VOS1 @S9S_MB_2U_LIB.S9S_MB_2U(SCH_1):PVCCFA_EHV_FIVRA_CPU1_VOS1    I89 @S9S_MB_2U_LIB.S9S_MB_2U(SCH_1):PAGE275
    40    GND @S9S_MB_2U_LIB.S9S_MB_2U(SCH_1):GND    I89 @S9S_MB_2U_LIB.S9S_MB_2U(SCH_1):PAGE275
    35 PVCCFA_EHV_FIVRA_CPU1_VDD1 @S9S_MB_2U_LIB.S9S_MB_2U(SCH_1):PVCCFA_EHV_FIVRA_CPU1_VDD1    I89 @S9S_MB_2U_LIB.S9S_MB_2U(SCH_1):PAGE275
    31     NC     NC    I89 @S9S_MB_2U_LIB.S9S_MB_2U(SCH_1):PAGE275
     6     NC     NC    I89 @S9S_MB_2U_LIB.S9S_MB_2U(SCH_1):PAGE275
    41     NC     NC    I89 @S9S_MB_2U_LIB.S9S_MB_2U(SCH_1):PAGE275
7_9-20_24    GND @S9S_MB_2U_LIB.S9S_MB_2U(SCH_1):GND    I89 @S9S_MB_2U_LIB.S9S_MB_2U(SCH_1):PAGE275

PU76_P1_2 ISL99390FRZTR5935-ISL99390FRZ-A
    34 PVCCFA_EHV_FIVRA_CPU1_PWM2 @S9S_MB_2U_LIB.S9S_MB_2U(SCH_1):PVCCFA_EHV_FIVRA_CPU1_PWM2     I9 @S9S_MB_2U_LIB.S9S_MB_2U(SCH_1):PAGE275
    39 PVCCIN_CPU1_VREF @S9S_MB_2U_LIB.S9S_MB_2U(SCH_1):PVCCIN_CPU1_VREF     I9 @S9S_MB_2U_LIB.S9S_MB_2U(SCH_1):PAGE275
     3 PVCCFA_EHV_FIVRA_CPU1_VDD2 @S9S_MB_2U_LIB.S9S_MB_2U(SCH_1):PVCCFA_EHV_FIVRA_CPU1_VDD2     I9 @S9S_MB_2U_LIB.S9S_MB_2U(SCH_1):PAGE275
     2    GND @S9S_MB_2U_LIB.S9S_MB_2U(SCH_1):GND     I9 @S9S_MB_2U_LIB.S9S_MB_2U(SCH_1):PAGE275
    33 SW_PVCCFA_EHV_FIVRA_CPU1_BOOT2 @S9S_MB_2U_LIB.S9S_MB_2U(SCH_1):SW_PVCCFA_EHV_FIVRA_CPU1_BOOT2     I9 @S9S_MB_2U_LIB.S9S_MB_2U(SCH_1):PAGE275
 25_29 SW_P12V_PVCCFA_EHV_FIVRA_CPU1_L @S9S_MB_2U_LIB.S9S_MB_2U(SCH_1):SW_P12V_PVCCFA_EHV_FIVRA_CPU1_L     I9 @S9S_MB_2U_LIB.S9S_MB_2U(SCH_1):PAGE275
    32 SW_PVCCFA_EHV_FIVRA_CPU1_BOOTR2 @S9S_MB_2U_LIB.S9S_MB_2U(SCH_1):SW_PVCCFA_EHV_FIVRA_CPU1_BOOTR2     I9 @S9S_MB_2U_LIB.S9S_MB_2U(SCH_1):PAGE275
     4 PVCCFA_EHV_FIVRA_CPU1_PVCC2 @S9S_MB_2U_LIB.S9S_MB_2U(SCH_1):PVCCFA_EHV_FIVRA_CPU1_PVCC2     I9 @S9S_MB_2U_LIB.S9S_MB_2U(SCH_1):PAGE275
    36 PVCCFA_EHV_FIVRA_CPU1_BTSEN @S9S_MB_2U_LIB.S9S_MB_2U(SCH_1):PVCCFA_EHV_FIVRA_CPU1_BTSEN     I9 @S9S_MB_2U_LIB.S9S_MB_2U(SCH_1):PAGE275
    38 PVCCFA_EHV_FIVRA_CPU1_IMON2 @S9S_MB_2U_LIB.S9S_MB_2U(SCH_1):PVCCFA_EHV_FIVRA_CPU1_IMON2     I9 @S9S_MB_2U_LIB.S9S_MB_2U(SCH_1):PAGE275
    37 PVCCFA_EHV_FIVRA_CPU1_LSET2 @S9S_MB_2U_LIB.S9S_MB_2U(SCH_1):PVCCFA_EHV_FIVRA_CPU1_LSET2     I9 @S9S_MB_2U_LIB.S9S_MB_2U(SCH_1):PAGE275
 10_19 SW_PVCCFA_EHV_FIVRA_CPU1_SW2 @S9S_MB_2U_LIB.S9S_MB_2U(SCH_1):SW_PVCCFA_EHV_FIVRA_CPU1_SW2     I9 @S9S_MB_2U_LIB.S9S_MB_2U(SCH_1):PAGE275
     5    GND @S9S_MB_2U_LIB.S9S_MB_2U(SCH_1):GND     I9 @S9S_MB_2U_LIB.S9S_MB_2U(SCH_1):PAGE275
    30 SW_P12V_PVCCFA_EHV_FIVRA_CPU1_L @S9S_MB_2U_LIB.S9S_MB_2U(SCH_1):SW_P12V_PVCCFA_EHV_FIVRA_CPU1_L     I9 @S9S_MB_2U_LIB.S9S_MB_2U(SCH_1):PAGE275
     1 PVCCFA_EHV_FIVRA_CPU1_VOS2 @S9S_MB_2U_LIB.S9S_MB_2U(SCH_1):PVCCFA_EHV_FIVRA_CPU1_VOS2     I9 @S9S_MB_2U_LIB.S9S_MB_2U(SCH_1):PAGE275
    40    GND @S9S_MB_2U_LIB.S9S_MB_2U(SCH_1):GND     I9 @S9S_MB_2U_LIB.S9S_MB_2U(SCH_1):PAGE275
    35 PVCCFA_EHV_FIVRA_CPU1_VDD2 @S9S_MB_2U_LIB.S9S_MB_2U(SCH_1):PVCCFA_EHV_FIVRA_CPU1_VDD2     I9 @S9S_MB_2U_LIB.S9S_MB_2U(SCH_1):PAGE275
    31     NC     NC     I9 @S9S_MB_2U_LIB.S9S_MB_2U(SCH_1):PAGE275
     6     NC     NC     I9 @S9S_MB_2U_LIB.S9S_MB_2U(SCH_1):PAGE275
    41     NC     NC     I9 @S9S_MB_2U_LIB.S9S_MB_2U(SCH_1):PAGE275
7_9-20_24    GND @S9S_MB_2U_LIB.S9S_MB_2U(SCH_1):GND     I9 @S9S_MB_2U_LIB.S9S_MB_2U(SCH_1):PAGE275

PU77_P1_3 ISL99390FRZTR5935-ISL99390FRZ-A
    34 PVCCFA_EHV_FIVRA_CPU1_PWM3 @S9S_MB_2U_LIB.S9S_MB_2U(SCH_1):PVCCFA_EHV_FIVRA_CPU1_PWM3    I24 @S9S_MB_2U_LIB.S9S_MB_2U(SCH_1):PAGE276
    39 PVCCIN_CPU1_VREF @S9S_MB_2U_LIB.S9S_MB_2U(SCH_1):PVCCIN_CPU1_VREF    I24 @S9S_MB_2U_LIB.S9S_MB_2U(SCH_1):PAGE276
     3 PVCCFA_EHV_FIVRA_CPU1_VDD3 @S9S_MB_2U_LIB.S9S_MB_2U(SCH_1):PVCCFA_EHV_FIVRA_CPU1_VDD3    I24 @S9S_MB_2U_LIB.S9S_MB_2U(SCH_1):PAGE276
     2    GND @S9S_MB_2U_LIB.S9S_MB_2U(SCH_1):GND    I24 @S9S_MB_2U_LIB.S9S_MB_2U(SCH_1):PAGE276
    33 SW_PVCCFA_EHV_FIVRA_CPU1_BOOT3 @S9S_MB_2U_LIB.S9S_MB_2U(SCH_1):SW_PVCCFA_EHV_FIVRA_CPU1_BOOT3    I24 @S9S_MB_2U_LIB.S9S_MB_2U(SCH_1):PAGE276
 25_29 SW_P12V_PVCCFA_EHV_FIVRA_CPU1_R @S9S_MB_2U_LIB.S9S_MB_2U(SCH_1):SW_P12V_PVCCFA_EHV_FIVRA_CPU1_R    I24 @S9S_MB_2U_LIB.S9S_MB_2U(SCH_1):PAGE276
    32 SW_PVCCFA_EHV_FIVRA_CPU1_BOOTR3 @S9S_MB_2U_LIB.S9S_MB_2U(SCH_1):SW_PVCCFA_EHV_FIVRA_CPU1_BOOTR3    I24 @S9S_MB_2U_LIB.S9S_MB_2U(SCH_1):PAGE276
     4 PVCCFA_EHV_FIVRA_CPU1_PVCC1 @S9S_MB_2U_LIB.S9S_MB_2U(SCH_1):PVCCFA_EHV_FIVRA_CPU1_PVCC1    I24 @S9S_MB_2U_LIB.S9S_MB_2U(SCH_1):PAGE276
    36 PVCCFA_EHV_FIVRA_CPU1_BTSEN @S9S_MB_2U_LIB.S9S_MB_2U(SCH_1):PVCCFA_EHV_FIVRA_CPU1_BTSEN    I24 @S9S_MB_2U_LIB.S9S_MB_2U(SCH_1):PAGE276
    38 PVCCFA_EHV_FIVRA_CPU1_IMON3 @S9S_MB_2U_LIB.S9S_MB_2U(SCH_1):PVCCFA_EHV_FIVRA_CPU1_IMON3    I24 @S9S_MB_2U_LIB.S9S_MB_2U(SCH_1):PAGE276
    37 PVCCFA_EHV_FIVRA_CPU1_LSET3 @S9S_MB_2U_LIB.S9S_MB_2U(SCH_1):PVCCFA_EHV_FIVRA_CPU1_LSET3    I24 @S9S_MB_2U_LIB.S9S_MB_2U(SCH_1):PAGE276
 10_19 SW_PVCCFA_EHV_FIVRA_CPU1_SW3 @S9S_MB_2U_LIB.S9S_MB_2U(SCH_1):SW_PVCCFA_EHV_FIVRA_CPU1_SW3    I24 @S9S_MB_2U_LIB.S9S_MB_2U(SCH_1):PAGE276
     5    GND @S9S_MB_2U_LIB.S9S_MB_2U(SCH_1):GND    I24 @S9S_MB_2U_LIB.S9S_MB_2U(SCH_1):PAGE276
    30 SW_P12V_PVCCFA_EHV_FIVRA_CPU1_R @S9S_MB_2U_LIB.S9S_MB_2U(SCH_1):SW_P12V_PVCCFA_EHV_FIVRA_CPU1_R    I24 @S9S_MB_2U_LIB.S9S_MB_2U(SCH_1):PAGE276
     1 PVCCFA_EHV_FIVRA_CPU1_VOS3 @S9S_MB_2U_LIB.S9S_MB_2U(SCH_1):PVCCFA_EHV_FIVRA_CPU1_VOS3    I24 @S9S_MB_2U_LIB.S9S_MB_2U(SCH_1):PAGE276
    40    GND @S9S_MB_2U_LIB.S9S_MB_2U(SCH_1):GND    I24 @S9S_MB_2U_LIB.S9S_MB_2U(SCH_1):PAGE276
    35 PVCCFA_EHV_FIVRA_CPU1_VDD3 @S9S_MB_2U_LIB.S9S_MB_2U(SCH_1):PVCCFA_EHV_FIVRA_CPU1_VDD3    I24 @S9S_MB_2U_LIB.S9S_MB_2U(SCH_1):PAGE276
    31     NC     NC    I24 @S9S_MB_2U_LIB.S9S_MB_2U(SCH_1):PAGE276
     6     NC     NC    I24 @S9S_MB_2U_LIB.S9S_MB_2U(SCH_1):PAGE276
    41     NC     NC    I24 @S9S_MB_2U_LIB.S9S_MB_2U(SCH_1):PAGE276
7_9-20_24    GND @S9S_MB_2U_LIB.S9S_MB_2U(SCH_1):GND    I24 @S9S_MB_2U_LIB.S9S_MB_2U(SCH_1):PAGE276

PU78_P1_4 ISL99390FRZTR5935-ISL99390FRZ-A
    34 PVCCFA_EHV_FIVRA_CPU1_PWM4 @S9S_MB_2U_LIB.S9S_MB_2U(SCH_1):PVCCFA_EHV_FIVRA_CPU1_PWM4    I15 @S9S_MB_2U_LIB.S9S_MB_2U(SCH_1):PAGE276
    39 PVCCIN_CPU1_VREF @S9S_MB_2U_LIB.S9S_MB_2U(SCH_1):PVCCIN_CPU1_VREF    I15 @S9S_MB_2U_LIB.S9S_MB_2U(SCH_1):PAGE276
     3 PVCCFA_EHV_FIVRA_CPU1_VDD4 @S9S_MB_2U_LIB.S9S_MB_2U(SCH_1):PVCCFA_EHV_FIVRA_CPU1_VDD4    I15 @S9S_MB_2U_LIB.S9S_MB_2U(SCH_1):PAGE276
     2    GND @S9S_MB_2U_LIB.S9S_MB_2U(SCH_1):GND    I15 @S9S_MB_2U_LIB.S9S_MB_2U(SCH_1):PAGE276
    33 SW_PVCCFA_EHV_FIVRA_CPU1_BOOT4 @S9S_MB_2U_LIB.S9S_MB_2U(SCH_1):SW_PVCCFA_EHV_FIVRA_CPU1_BOOT4    I15 @S9S_MB_2U_LIB.S9S_MB_2U(SCH_1):PAGE276
 25_29 SW_P12V_PVCCFA_EHV_FIVRA_CPU1_L @S9S_MB_2U_LIB.S9S_MB_2U(SCH_1):SW_P12V_PVCCFA_EHV_FIVRA_CPU1_L    I15 @S9S_MB_2U_LIB.S9S_MB_2U(SCH_1):PAGE276
    32 SW_PVCCFA_EHV_FIVRA_CPU1_BOOTR4 @S9S_MB_2U_LIB.S9S_MB_2U(SCH_1):SW_PVCCFA_EHV_FIVRA_CPU1_BOOTR4    I15 @S9S_MB_2U_LIB.S9S_MB_2U(SCH_1):PAGE276
     4 PVCCFA_EHV_FIVRA_CPU1_PVCC2 @S9S_MB_2U_LIB.S9S_MB_2U(SCH_1):PVCCFA_EHV_FIVRA_CPU1_PVCC2    I15 @S9S_MB_2U_LIB.S9S_MB_2U(SCH_1):PAGE276
    36 PVCCFA_EHV_FIVRA_CPU1_BTSEN @S9S_MB_2U_LIB.S9S_MB_2U(SCH_1):PVCCFA_EHV_FIVRA_CPU1_BTSEN    I15 @S9S_MB_2U_LIB.S9S_MB_2U(SCH_1):PAGE276
    38 PVCCFA_EHV_FIVRA_CPU1_IMON4 @S9S_MB_2U_LIB.S9S_MB_2U(SCH_1):PVCCFA_EHV_FIVRA_CPU1_IMON4    I15 @S9S_MB_2U_LIB.S9S_MB_2U(SCH_1):PAGE276
    37 PVCCFA_EHV_FIVRA_CPU1_LSET4 @S9S_MB_2U_LIB.S9S_MB_2U(SCH_1):PVCCFA_EHV_FIVRA_CPU1_LSET4    I15 @S9S_MB_2U_LIB.S9S_MB_2U(SCH_1):PAGE276
 10_19 SW_PVCCFA_EHV_FIVRA_CPU1_SW4 @S9S_MB_2U_LIB.S9S_MB_2U(SCH_1):SW_PVCCFA_EHV_FIVRA_CPU1_SW4    I15 @S9S_MB_2U_LIB.S9S_MB_2U(SCH_1):PAGE276
     5    GND @S9S_MB_2U_LIB.S9S_MB_2U(SCH_1):GND    I15 @S9S_MB_2U_LIB.S9S_MB_2U(SCH_1):PAGE276
    30 SW_P12V_PVCCFA_EHV_FIVRA_CPU1_L @S9S_MB_2U_LIB.S9S_MB_2U(SCH_1):SW_P12V_PVCCFA_EHV_FIVRA_CPU1_L    I15 @S9S_MB_2U_LIB.S9S_MB_2U(SCH_1):PAGE276
     1 PVCCFA_EHV_FIVRA_CPU1_VOS4 @S9S_MB_2U_LIB.S9S_MB_2U(SCH_1):PVCCFA_EHV_FIVRA_CPU1_VOS4    I15 @S9S_MB_2U_LIB.S9S_MB_2U(SCH_1):PAGE276
    40    GND @S9S_MB_2U_LIB.S9S_MB_2U(SCH_1):GND    I15 @S9S_MB_2U_LIB.S9S_MB_2U(SCH_1):PAGE276
    35 PVCCFA_EHV_FIVRA_CPU1_VDD4 @S9S_MB_2U_LIB.S9S_MB_2U(SCH_1):PVCCFA_EHV_FIVRA_CPU1_VDD4    I15 @S9S_MB_2U_LIB.S9S_MB_2U(SCH_1):PAGE276
    31     NC     NC    I15 @S9S_MB_2U_LIB.S9S_MB_2U(SCH_1):PAGE276
     6     NC     NC    I15 @S9S_MB_2U_LIB.S9S_MB_2U(SCH_1):PAGE276
    41     NC     NC    I15 @S9S_MB_2U_LIB.S9S_MB_2U(SCH_1):PAGE276
7_9-20_24    GND @S9S_MB_2U_LIB.S9S_MB_2U(SCH_1):GND    I15 @S9S_MB_2U_LIB.S9S_MB_2U(SCH_1):PAGE276

PU79 RS53318LR-RS53318LR,SMLF,IC,ALA
    10 SW_P12V_PVCCIN_CPU0_FLT @S9S_MB_2U_LIB.S9S_MB_2U(SCH_1):SW_P12V_PVCCIN_CPU0_FLT    I19 @S9S_MB_2U_LIB.S9S_MB_2U(SCH_1):PAGE267
     9 PWRGD_PVPP_HBM_CPU0_R @S9S_MB_2U_LIB.S9S_MB_2U(SCH_1):PWRGD_PVPP_HBM_CPU0_R    I19 @S9S_MB_2U_LIB.S9S_MB_2U(SCH_1):PAGE267
 11_18    GND @S9S_MB_2U_LIB.S9S_MB_2U(SCH_1):GND    I19 @S9S_MB_2U_LIB.S9S_MB_2U(SCH_1):PAGE267
     8 FM_PVPP_HBM_CPU0_EN @S9S_MB_2U_LIB.S9S_MB_2U(SCH_1):FM_PVPP_HBM_CPU0_EN    I19 @S9S_MB_2U_LIB.S9S_MB_2U(SCH_1):PAGE267
     1 SW_PVPP_HBM_CPU0_BST @S9S_MB_2U_LIB.S9S_MB_2U(SCH_1):SW_PVPP_HBM_CPU0_BST    I19 @S9S_MB_2U_LIB.S9S_MB_2U(SCH_1):PAGE267
     7 PVPP_HBM_CPU0_FB @S9S_MB_2U_LIB.S9S_MB_2U(SCH_1):PVPP_HBM_CPU0_FB    I19 @S9S_MB_2U_LIB.S9S_MB_2U(SCH_1):PAGE267
     2    GND @S9S_MB_2U_LIB.S9S_MB_2U(SCH_1):GND    I19 @S9S_MB_2U_LIB.S9S_MB_2U(SCH_1):PAGE267
    19 PVPP_HBM_CPU0_VCC @S9S_MB_2U_LIB.S9S_MB_2U(SCH_1):PVPP_HBM_CPU0_VCC    I19 @S9S_MB_2U_LIB.S9S_MB_2U(SCH_1):PAGE267
     6 SH_PVPP_HBM_CPU0_N @S9S_MB_2U_LIB.S9S_MB_2U(SCH_1):SH_PVPP_HBM_CPU0_N    I19 @S9S_MB_2U_LIB.S9S_MB_2U(SCH_1):PAGE267
    20 SW_PVPP_HBM_CPU0_SW @S9S_MB_2U_LIB.S9S_MB_2U(SCH_1):SW_PVPP_HBM_CPU0_SW    I19 @S9S_MB_2U_LIB.S9S_MB_2U(SCH_1):PAGE267
     5 PVPP_HBM_CPU0_REF @S9S_MB_2U_LIB.S9S_MB_2U(SCH_1):PVPP_HBM_CPU0_REF    I19 @S9S_MB_2U_LIB.S9S_MB_2U(SCH_1):PAGE267
     4 PVPP_HBM_CPU0_MODE @S9S_MB_2U_LIB.S9S_MB_2U(SCH_1):PVPP_HBM_CPU0_MODE    I19 @S9S_MB_2U_LIB.S9S_MB_2U(SCH_1):PAGE267
     3 PVPP_HBM_CPU0_CS @S9S_MB_2U_LIB.S9S_MB_2U(SCH_1):PVPP_HBM_CPU0_CS    I19 @S9S_MB_2U_LIB.S9S_MB_2U(SCH_1):PAGE267
    21 SW_P12V_PVCCIN_CPU0_FLT @S9S_MB_2U_LIB.S9S_MB_2U(SCH_1):SW_P12V_PVCCIN_CPU0_FLT    I19 @S9S_MB_2U_LIB.S9S_MB_2U(SCH_1):PAGE267

PU80 RS53318LR-RS53318LR,SMLF,IC,ALA
    10 SW_P12V_PVCCIN_CPU1_FLT @S9S_MB_2U_LIB.S9S_MB_2U(SCH_1):SW_P12V_PVCCIN_CPU1_FLT    I25 @S9S_MB_2U_LIB.S9S_MB_2U(SCH_1):PAGE285
     9 PWRGD_PVPP_HBM_CPU1_R @S9S_MB_2U_LIB.S9S_MB_2U(SCH_1):PWRGD_PVPP_HBM_CPU1_R    I25 @S9S_MB_2U_LIB.S9S_MB_2U(SCH_1):PAGE285
 11_18    GND @S9S_MB_2U_LIB.S9S_MB_2U(SCH_1):GND    I25 @S9S_MB_2U_LIB.S9S_MB_2U(SCH_1):PAGE285
     8 FM_PVPP_HBM_CPU1_EN @S9S_MB_2U_LIB.S9S_MB_2U(SCH_1):FM_PVPP_HBM_CPU1_EN    I25 @S9S_MB_2U_LIB.S9S_MB_2U(SCH_1):PAGE285
     1 SW_PVPP_HBM_CPU1_BST @S9S_MB_2U_LIB.S9S_MB_2U(SCH_1):SW_PVPP_HBM_CPU1_BST    I25 @S9S_MB_2U_LIB.S9S_MB_2U(SCH_1):PAGE285
     7 PVPP_HBM_CPU1_FB @S9S_MB_2U_LIB.S9S_MB_2U(SCH_1):PVPP_HBM_CPU1_FB    I25 @S9S_MB_2U_LIB.S9S_MB_2U(SCH_1):PAGE285
     2    GND @S9S_MB_2U_LIB.S9S_MB_2U(SCH_1):GND    I25 @S9S_MB_2U_LIB.S9S_MB_2U(SCH_1):PAGE285
    19 PVPP_HBM_CPU1_VCC @S9S_MB_2U_LIB.S9S_MB_2U(SCH_1):PVPP_HBM_CPU1_VCC    I25 @S9S_MB_2U_LIB.S9S_MB_2U(SCH_1):PAGE285
     6 SH_PVPP_HBM_CPU1_N @S9S_MB_2U_LIB.S9S_MB_2U(SCH_1):SH_PVPP_HBM_CPU1_N    I25 @S9S_MB_2U_LIB.S9S_MB_2U(SCH_1):PAGE285
    20 SW_PVPP_HBM_CPU1_SW @S9S_MB_2U_LIB.S9S_MB_2U(SCH_1):SW_PVPP_HBM_CPU1_SW    I25 @S9S_MB_2U_LIB.S9S_MB_2U(SCH_1):PAGE285
     5 PVPP_HBM_CPU1_REF @S9S_MB_2U_LIB.S9S_MB_2U(SCH_1):PVPP_HBM_CPU1_REF    I25 @S9S_MB_2U_LIB.S9S_MB_2U(SCH_1):PAGE285
     4 PVPP_HBM_CPU1_MODE @S9S_MB_2U_LIB.S9S_MB_2U(SCH_1):PVPP_HBM_CPU1_MODE    I25 @S9S_MB_2U_LIB.S9S_MB_2U(SCH_1):PAGE285
     3 PVPP_HBM_CPU1_CS @S9S_MB_2U_LIB.S9S_MB_2U(SCH_1):PVPP_HBM_CPU1_CS    I25 @S9S_MB_2U_LIB.S9S_MB_2U(SCH_1):PAGE285
    21 SW_P12V_PVCCIN_CPU1_FLT @S9S_MB_2U_LIB.S9S_MB_2U(SCH_1):SW_P12V_PVCCIN_CPU1_FLT    I25 @S9S_MB_2U_LIB.S9S_MB_2U(SCH_1):PAGE285

PU81 RS53317LR-RS53317LR,SMLF,IC,ALA
     3 SW_P12V_PVCCINFAON_CPU0_FLT @S9S_MB_2U_LIB.S9S_MB_2U(SCH_1):SW_P12V_PVCCINFAON_CPU0_FLT    I22 @S9S_MB_2U_LIB.S9S_MB_2U(SCH_1):PAGE268
     9 PWRGD_PVNN_MAIN_CPU0_R @S9S_MB_2U_LIB.S9S_MB_2U(SCH_1):PWRGD_PVNN_MAIN_CPU0_R    I22 @S9S_MB_2U_LIB.S9S_MB_2U(SCH_1):PAGE268
    14    GND @S9S_MB_2U_LIB.S9S_MB_2U(SCH_1):GND    I22 @S9S_MB_2U_LIB.S9S_MB_2U(SCH_1):PAGE268
     5 FM_PVNN_MAIN_CPU0_EN @S9S_MB_2U_LIB.S9S_MB_2U(SCH_1):FM_PVNN_MAIN_CPU0_EN    I22 @S9S_MB_2U_LIB.S9S_MB_2U(SCH_1):PAGE268
    10 SW_PVNN_MAIN_CPU0_BST @S9S_MB_2U_LIB.S9S_MB_2U(SCH_1):SW_PVNN_MAIN_CPU0_BST    I22 @S9S_MB_2U_LIB.S9S_MB_2U(SCH_1):PAGE268
     6 PVNN_MAIN_CPU0_FB @S9S_MB_2U_LIB.S9S_MB_2U(SCH_1):PVNN_MAIN_CPU0_FB    I22 @S9S_MB_2U_LIB.S9S_MB_2U(SCH_1):PAGE268
     7    GND @S9S_MB_2U_LIB.S9S_MB_2U(SCH_1):GND    I22 @S9S_MB_2U_LIB.S9S_MB_2U(SCH_1):PAGE268
    13 PVNN_MAIN_CPU0_VCC @S9S_MB_2U_LIB.S9S_MB_2U(SCH_1):PVNN_MAIN_CPU0_VCC    I22 @S9S_MB_2U_LIB.S9S_MB_2U(SCH_1):PAGE268
     1    GND @S9S_MB_2U_LIB.S9S_MB_2U(SCH_1):GND    I22 @S9S_MB_2U_LIB.S9S_MB_2U(SCH_1):PAGE268
    11 SW_PVNN_MAIN_CPU0_SW @S9S_MB_2U_LIB.S9S_MB_2U(SCH_1):SW_PVNN_MAIN_CPU0_SW    I22 @S9S_MB_2U_LIB.S9S_MB_2U(SCH_1):PAGE268
     8 PVNN_MAIN_CPU0_REF @S9S_MB_2U_LIB.S9S_MB_2U(SCH_1):PVNN_MAIN_CPU0_REF    I22 @S9S_MB_2U_LIB.S9S_MB_2U(SCH_1):PAGE268
    12 PVNN_MAIN_CPU0_MODE @S9S_MB_2U_LIB.S9S_MB_2U(SCH_1):PVNN_MAIN_CPU0_MODE    I22 @S9S_MB_2U_LIB.S9S_MB_2U(SCH_1):PAGE268
     4 PVNN_MAIN_CPU0_CS @S9S_MB_2U_LIB.S9S_MB_2U(SCH_1):PVNN_MAIN_CPU0_CS    I22 @S9S_MB_2U_LIB.S9S_MB_2U(SCH_1):PAGE268
     2 SW_PVNN_MAIN_CPU0_SW @S9S_MB_2U_LIB.S9S_MB_2U(SCH_1):SW_PVNN_MAIN_CPU0_SW    I22 @S9S_MB_2U_LIB.S9S_MB_2U(SCH_1):PAGE268

PU82 RS53317LR-RS53317LR,SMLF,IC,ALA
     3 SW_P12V_PVCCINFAON_CPU1_FLT @S9S_MB_2U_LIB.S9S_MB_2U(SCH_1):SW_P12V_PVCCINFAON_CPU1_FLT    I20 @S9S_MB_2U_LIB.S9S_MB_2U(SCH_1):PAGE286
     9 PWRGD_PVNN_MAIN_CPU1_R @S9S_MB_2U_LIB.S9S_MB_2U(SCH_1):PWRGD_PVNN_MAIN_CPU1_R    I20 @S9S_MB_2U_LIB.S9S_MB_2U(SCH_1):PAGE286
    14    GND @S9S_MB_2U_LIB.S9S_MB_2U(SCH_1):GND    I20 @S9S_MB_2U_LIB.S9S_MB_2U(SCH_1):PAGE286
     5 FM_PVNN_MAIN_CPU1_EN @S9S_MB_2U_LIB.S9S_MB_2U(SCH_1):FM_PVNN_MAIN_CPU1_EN    I20 @S9S_MB_2U_LIB.S9S_MB_2U(SCH_1):PAGE286
    10 SW_PVNN_MAIN_CPU1_BST @S9S_MB_2U_LIB.S9S_MB_2U(SCH_1):SW_PVNN_MAIN_CPU1_BST    I20 @S9S_MB_2U_LIB.S9S_MB_2U(SCH_1):PAGE286
     6 PVNN_MAIN_CPU1_FB @S9S_MB_2U_LIB.S9S_MB_2U(SCH_1):PVNN_MAIN_CPU1_FB    I20 @S9S_MB_2U_LIB.S9S_MB_2U(SCH_1):PAGE286
     7    GND @S9S_MB_2U_LIB.S9S_MB_2U(SCH_1):GND    I20 @S9S_MB_2U_LIB.S9S_MB_2U(SCH_1):PAGE286
    13 PVNN_MAIN_CPU1_VCC @S9S_MB_2U_LIB.S9S_MB_2U(SCH_1):PVNN_MAIN_CPU1_VCC    I20 @S9S_MB_2U_LIB.S9S_MB_2U(SCH_1):PAGE286
     1    GND @S9S_MB_2U_LIB.S9S_MB_2U(SCH_1):GND    I20 @S9S_MB_2U_LIB.S9S_MB_2U(SCH_1):PAGE286
    11 SW_PVNN_MAIN_CPU1_SW @S9S_MB_2U_LIB.S9S_MB_2U(SCH_1):SW_PVNN_MAIN_CPU1_SW    I20 @S9S_MB_2U_LIB.S9S_MB_2U(SCH_1):PAGE286
     8 PVNN_MAIN_CPU1_REF @S9S_MB_2U_LIB.S9S_MB_2U(SCH_1):PVNN_MAIN_CPU1_REF    I20 @S9S_MB_2U_LIB.S9S_MB_2U(SCH_1):PAGE286
    12 PVNN_MAIN_CPU1_MODE @S9S_MB_2U_LIB.S9S_MB_2U(SCH_1):PVNN_MAIN_CPU1_MODE    I20 @S9S_MB_2U_LIB.S9S_MB_2U(SCH_1):PAGE286
     4 PVNN_MAIN_CPU1_CS @S9S_MB_2U_LIB.S9S_MB_2U(SCH_1):PVNN_MAIN_CPU1_CS    I20 @S9S_MB_2U_LIB.S9S_MB_2U(SCH_1):PAGE286
     2 SW_PVNN_MAIN_CPU1_SW @S9S_MB_2U_LIB.S9S_MB_2U(SCH_1):SW_PVNN_MAIN_CPU1_SW    I20 @S9S_MB_2U_LIB.S9S_MB_2U(SCH_1):PAGE286

PU173 MOSFET_N_SMLF-BSS138K,BSS138K,B
     G FM_HBM2_HBM3_VPP_SEL @S9S_MB_2U_LIB.S9S_MB_2U(SCH_1):FM_HBM2_HBM3_VPP_SEL    I31 @S9S_MB_2U_LIB.S9S_MB_2U(SCH_1):PAGE267
     D FM_HBM_VPP_SEL_CPU0_D @S9S_MB_2U_LIB.S9S_MB_2U(SCH_1):FM_HBM_VPP_SEL_CPU0_D    I31 @S9S_MB_2U_LIB.S9S_MB_2U(SCH_1):PAGE267
     S SH_PVPP_HBM_CPU0_N @S9S_MB_2U_LIB.S9S_MB_2U(SCH_1):SH_PVPP_HBM_CPU0_N    I31 @S9S_MB_2U_LIB.S9S_MB_2U(SCH_1):PAGE267

PU174 MOSFET_N_SMLF-BSS138K,BSS138K,B
     G FM_HBM2_HBM3_VPP_SEL @S9S_MB_2U_LIB.S9S_MB_2U(SCH_1):FM_HBM2_HBM3_VPP_SEL    I29 @S9S_MB_2U_LIB.S9S_MB_2U(SCH_1):PAGE285
     D FM_HBM_VPP_SEL_CPU1_D @S9S_MB_2U_LIB.S9S_MB_2U(SCH_1):FM_HBM_VPP_SEL_CPU1_D    I29 @S9S_MB_2U_LIB.S9S_MB_2U(SCH_1):PAGE285
     S SH_PVPP_HBM_CPU1_N @S9S_MB_2U_LIB.S9S_MB_2U(SCH_1):SH_PVPP_HBM_CPU1_N    I29 @S9S_MB_2U_LIB.S9S_MB_2U(SCH_1):PAGE285

PU181 RS53318LR-RS53318LR,SMLF,IC,ALA
    10 SW_P5V_AUX_FLT @S9S_MB_2U_LIB.S9S_MB_2U(SCH_1):SW_P5V_AUX_FLT    I20 @S9S_MB_2U_LIB.S9S_MB_2U(SCH_1):PAGE244
     9 PWRGD_P5V_AUX_R @S9S_MB_2U_LIB.S9S_MB_2U(SCH_1):PWRGD_P5V_AUX_R    I20 @S9S_MB_2U_LIB.S9S_MB_2U(SCH_1):PAGE244
 11_18    GND @S9S_MB_2U_LIB.S9S_MB_2U(SCH_1):GND    I20 @S9S_MB_2U_LIB.S9S_MB_2U(SCH_1):PAGE244
     8 PWRGD_P3V3_AUX @S9S_MB_2U_LIB.S9S_MB_2U(SCH_1):PWRGD_P3V3_AUX    I20 @S9S_MB_2U_LIB.S9S_MB_2U(SCH_1):PAGE244
     1 SW_P5V_AUX_BST @S9S_MB_2U_LIB.S9S_MB_2U(SCH_1):SW_P5V_AUX_BST    I20 @S9S_MB_2U_LIB.S9S_MB_2U(SCH_1):PAGE244
     7 P5V_AUX_FB @S9S_MB_2U_LIB.S9S_MB_2U(SCH_1):P5V_AUX_FB    I20 @S9S_MB_2U_LIB.S9S_MB_2U(SCH_1):PAGE244
     2    GND @S9S_MB_2U_LIB.S9S_MB_2U(SCH_1):GND    I20 @S9S_MB_2U_LIB.S9S_MB_2U(SCH_1):PAGE244
    19 P5V_AUX_VCC @S9S_MB_2U_LIB.S9S_MB_2U(SCH_1):P5V_AUX_VCC    I20 @S9S_MB_2U_LIB.S9S_MB_2U(SCH_1):PAGE244
     6    GND @S9S_MB_2U_LIB.S9S_MB_2U(SCH_1):GND    I20 @S9S_MB_2U_LIB.S9S_MB_2U(SCH_1):PAGE244
    20 SW_P5V_AUX_SW @S9S_MB_2U_LIB.S9S_MB_2U(SCH_1):SW_P5V_AUX_SW    I20 @S9S_MB_2U_LIB.S9S_MB_2U(SCH_1):PAGE244
     5 P5V_AUX_REF @S9S_MB_2U_LIB.S9S_MB_2U(SCH_1):P5V_AUX_REF    I20 @S9S_MB_2U_LIB.S9S_MB_2U(SCH_1):PAGE244
     4 P5V_AUX_MODE @S9S_MB_2U_LIB.S9S_MB_2U(SCH_1):P5V_AUX_MODE    I20 @S9S_MB_2U_LIB.S9S_MB_2U(SCH_1):PAGE244
     3 P5V_AUX_CS @S9S_MB_2U_LIB.S9S_MB_2U(SCH_1):P5V_AUX_CS    I20 @S9S_MB_2U_LIB.S9S_MB_2U(SCH_1):PAGE244
    21 SW_P5V_AUX_FLT @S9S_MB_2U_LIB.S9S_MB_2U(SCH_1):SW_P5V_AUX_FLT    I20 @S9S_MB_2U_LIB.S9S_MB_2U(SCH_1):PAGE244

PU200 MAX15090BEWIT-MAX15090BEWI+T,SB
    A2 P3V3_OCP_VCC_2 @S9S_MB_2U_LIB.S9S_MB_2U(SCH_1):P3V3_OCP_VCC_2    I90 @S9S_MB_2U_LIB.S9S_MB_2U(SCH_1):PAGE131
    A3 P3V3_AUX @S9S_MB_2U_LIB.S9S_MB_2U(SCH_1):P3V3_AUX    I90 @S9S_MB_2U_LIB.S9S_MB_2U(SCH_1):PAGE131
    A5 P3V3_AUX @S9S_MB_2U_LIB.S9S_MB_2U(SCH_1):P3V3_AUX    I90 @S9S_MB_2U_LIB.S9S_MB_2U(SCH_1):PAGE131
    B3 P3V3_AUX @S9S_MB_2U_LIB.S9S_MB_2U(SCH_1):P3V3_AUX    I90 @S9S_MB_2U_LIB.S9S_MB_2U(SCH_1):PAGE131
    B5 P3V3_AUX @S9S_MB_2U_LIB.S9S_MB_2U(SCH_1):P3V3_AUX    I90 @S9S_MB_2U_LIB.S9S_MB_2U(SCH_1):PAGE131
    C3 P3V3_AUX @S9S_MB_2U_LIB.S9S_MB_2U(SCH_1):P3V3_AUX    I90 @S9S_MB_2U_LIB.S9S_MB_2U(SCH_1):PAGE131
    C5 P3V3_AUX @S9S_MB_2U_LIB.S9S_MB_2U(SCH_1):P3V3_AUX    I90 @S9S_MB_2U_LIB.S9S_MB_2U(SCH_1):PAGE131
    D5 P3V3_AUX @S9S_MB_2U_LIB.S9S_MB_2U(SCH_1):P3V3_AUX    I90 @S9S_MB_2U_LIB.S9S_MB_2U(SCH_1):PAGE131
    B1 P3V3_OCP_CB_2 @S9S_MB_2U_LIB.S9S_MB_2U(SCH_1):P3V3_OCP_CB_2    I90 @S9S_MB_2U_LIB.S9S_MB_2U(SCH_1):PAGE131
    B7    GND @S9S_MB_2U_LIB.S9S_MB_2U(SCH_1):GND    I90 @S9S_MB_2U_LIB.S9S_MB_2U(SCH_1):PAGE131
    D1 P3V3_OCP_REG_2 @S9S_MB_2U_LIB.S9S_MB_2U(SCH_1):P3V3_OCP_REG_2    I90 @S9S_MB_2U_LIB.S9S_MB_2U(SCH_1):PAGE131
    D2 P3V3_OCP_UV_2 @S9S_MB_2U_LIB.S9S_MB_2U(SCH_1):P3V3_OCP_UV_2    I90 @S9S_MB_2U_LIB.S9S_MB_2U(SCH_1):PAGE131
    D3 P3V3_OCP_OV_2 @S9S_MB_2U_LIB.S9S_MB_2U(SCH_1):P3V3_OCP_OV_2    I90 @S9S_MB_2U_LIB.S9S_MB_2U(SCH_1):PAGE131
    A1 P3V3_OCP_SENSE_2 @S9S_MB_2U_LIB.S9S_MB_2U(SCH_1):P3V3_OCP_SENSE_2    I90 @S9S_MB_2U_LIB.S9S_MB_2U(SCH_1):PAGE131
    A4 P3V3_OCP_V3_2_R @S9S_MB_2U_LIB.S9S_MB_2U(SCH_1):P3V3_OCP_V3_2_R    I90 @S9S_MB_2U_LIB.S9S_MB_2U(SCH_1):PAGE131
    B4 P3V3_OCP_V3_2_R @S9S_MB_2U_LIB.S9S_MB_2U(SCH_1):P3V3_OCP_V3_2_R    I90 @S9S_MB_2U_LIB.S9S_MB_2U(SCH_1):PAGE131
    B6 P3V3_OCP_V3_2_R @S9S_MB_2U_LIB.S9S_MB_2U(SCH_1):P3V3_OCP_V3_2_R    I90 @S9S_MB_2U_LIB.S9S_MB_2U(SCH_1):PAGE131
    C4 P3V3_OCP_V3_2_R @S9S_MB_2U_LIB.S9S_MB_2U(SCH_1):P3V3_OCP_V3_2_R    I90 @S9S_MB_2U_LIB.S9S_MB_2U(SCH_1):PAGE131
    C6 P3V3_OCP_V3_2_R @S9S_MB_2U_LIB.S9S_MB_2U(SCH_1):P3V3_OCP_V3_2_R    I90 @S9S_MB_2U_LIB.S9S_MB_2U(SCH_1):PAGE131
    D4 P3V3_OCP_V3_2_R @S9S_MB_2U_LIB.S9S_MB_2U(SCH_1):P3V3_OCP_V3_2_R    I90 @S9S_MB_2U_LIB.S9S_MB_2U(SCH_1):PAGE131
    D6 P3V3_OCP_V3_2_R @S9S_MB_2U_LIB.S9S_MB_2U(SCH_1):P3V3_OCP_V3_2_R    I90 @S9S_MB_2U_LIB.S9S_MB_2U(SCH_1):PAGE131
    A6 P3V3_OCP_GATE_2 @S9S_MB_2U_LIB.S9S_MB_2U(SCH_1):P3V3_OCP_GATE_2    I90 @S9S_MB_2U_LIB.S9S_MB_2U(SCH_1):PAGE131
    A7    GND @S9S_MB_2U_LIB.S9S_MB_2U(SCH_1):GND    I90 @S9S_MB_2U_LIB.S9S_MB_2U(SCH_1):PAGE131
    B2    GND @S9S_MB_2U_LIB.S9S_MB_2U(SCH_1):GND    I90 @S9S_MB_2U_LIB.S9S_MB_2U(SCH_1):PAGE131
    C1    GND @S9S_MB_2U_LIB.S9S_MB_2U(SCH_1):GND    I90 @S9S_MB_2U_LIB.S9S_MB_2U(SCH_1):PAGE131
    C2    GND @S9S_MB_2U_LIB.S9S_MB_2U(SCH_1):GND    I90 @S9S_MB_2U_LIB.S9S_MB_2U(SCH_1):PAGE131
    C7 P3V3_OCP_FAULT_2 @S9S_MB_2U_LIB.S9S_MB_2U(SCH_1):P3V3_OCP_FAULT_2    I90 @S9S_MB_2U_LIB.S9S_MB_2U(SCH_1):PAGE131
    D7 P3V3_OCP_PWRGD_2 @S9S_MB_2U_LIB.S9S_MB_2U(SCH_1):P3V3_OCP_PWRGD_2    I90 @S9S_MB_2U_LIB.S9S_MB_2U(SCH_1):PAGE131

PU201 MAX15090BEWIT-MAX15090BEWI+T,SA
    A2 P12V_OCP_VCC_2 @S9S_MB_2U_LIB.S9S_MB_2U(SCH_1):P12V_OCP_VCC_2    I63 @S9S_MB_2U_LIB.S9S_MB_2U(SCH_1):PAGE131
    A3 P12V_AUX @S9S_MB_2U_LIB.S9S_MB_2U(SCH_1):P12V_AUX    I63 @S9S_MB_2U_LIB.S9S_MB_2U(SCH_1):PAGE131
    A5 P12V_AUX @S9S_MB_2U_LIB.S9S_MB_2U(SCH_1):P12V_AUX    I63 @S9S_MB_2U_LIB.S9S_MB_2U(SCH_1):PAGE131
    B3 P12V_AUX @S9S_MB_2U_LIB.S9S_MB_2U(SCH_1):P12V_AUX    I63 @S9S_MB_2U_LIB.S9S_MB_2U(SCH_1):PAGE131
    B5 P12V_AUX @S9S_MB_2U_LIB.S9S_MB_2U(SCH_1):P12V_AUX    I63 @S9S_MB_2U_LIB.S9S_MB_2U(SCH_1):PAGE131
    C3 P12V_AUX @S9S_MB_2U_LIB.S9S_MB_2U(SCH_1):P12V_AUX    I63 @S9S_MB_2U_LIB.S9S_MB_2U(SCH_1):PAGE131
    C5 P12V_AUX @S9S_MB_2U_LIB.S9S_MB_2U(SCH_1):P12V_AUX    I63 @S9S_MB_2U_LIB.S9S_MB_2U(SCH_1):PAGE131
    D5 P12V_AUX @S9S_MB_2U_LIB.S9S_MB_2U(SCH_1):P12V_AUX    I63 @S9S_MB_2U_LIB.S9S_MB_2U(SCH_1):PAGE131
    B1 P12V_OCP_CB_2 @S9S_MB_2U_LIB.S9S_MB_2U(SCH_1):P12V_OCP_CB_2    I63 @S9S_MB_2U_LIB.S9S_MB_2U(SCH_1):PAGE131
    B7    GND @S9S_MB_2U_LIB.S9S_MB_2U(SCH_1):GND    I63 @S9S_MB_2U_LIB.S9S_MB_2U(SCH_1):PAGE131
    D1 P12V_OCP_REG_2 @S9S_MB_2U_LIB.S9S_MB_2U(SCH_1):P12V_OCP_REG_2    I63 @S9S_MB_2U_LIB.S9S_MB_2U(SCH_1):PAGE131
    D2 P12V_OCP_UV_2 @S9S_MB_2U_LIB.S9S_MB_2U(SCH_1):P12V_OCP_UV_2    I63 @S9S_MB_2U_LIB.S9S_MB_2U(SCH_1):PAGE131
    D3 P12V_OCP_OV_2 @S9S_MB_2U_LIB.S9S_MB_2U(SCH_1):P12V_OCP_OV_2    I63 @S9S_MB_2U_LIB.S9S_MB_2U(SCH_1):PAGE131
    A1 P12V_OCP_SENSE_2 @S9S_MB_2U_LIB.S9S_MB_2U(SCH_1):P12V_OCP_SENSE_2    I63 @S9S_MB_2U_LIB.S9S_MB_2U(SCH_1):PAGE131
    A4 P12V_OCP_V3_2 @S9S_MB_2U_LIB.S9S_MB_2U(SCH_1):P12V_OCP_V3_2    I63 @S9S_MB_2U_LIB.S9S_MB_2U(SCH_1):PAGE131
    B4 P12V_OCP_V3_2 @S9S_MB_2U_LIB.S9S_MB_2U(SCH_1):P12V_OCP_V3_2    I63 @S9S_MB_2U_LIB.S9S_MB_2U(SCH_1):PAGE131
    B6 P12V_OCP_V3_2 @S9S_MB_2U_LIB.S9S_MB_2U(SCH_1):P12V_OCP_V3_2    I63 @S9S_MB_2U_LIB.S9S_MB_2U(SCH_1):PAGE131
    C4 P12V_OCP_V3_2 @S9S_MB_2U_LIB.S9S_MB_2U(SCH_1):P12V_OCP_V3_2    I63 @S9S_MB_2U_LIB.S9S_MB_2U(SCH_1):PAGE131
    C6 P12V_OCP_V3_2 @S9S_MB_2U_LIB.S9S_MB_2U(SCH_1):P12V_OCP_V3_2    I63 @S9S_MB_2U_LIB.S9S_MB_2U(SCH_1):PAGE131
    D4 P12V_OCP_V3_2 @S9S_MB_2U_LIB.S9S_MB_2U(SCH_1):P12V_OCP_V3_2    I63 @S9S_MB_2U_LIB.S9S_MB_2U(SCH_1):PAGE131
    D6 P12V_OCP_V3_2 @S9S_MB_2U_LIB.S9S_MB_2U(SCH_1):P12V_OCP_V3_2    I63 @S9S_MB_2U_LIB.S9S_MB_2U(SCH_1):PAGE131
    A6 P12V_OCP_GATE_2 @S9S_MB_2U_LIB.S9S_MB_2U(SCH_1):P12V_OCP_GATE_2    I63 @S9S_MB_2U_LIB.S9S_MB_2U(SCH_1):PAGE131
    A7    GND @S9S_MB_2U_LIB.S9S_MB_2U(SCH_1):GND    I63 @S9S_MB_2U_LIB.S9S_MB_2U(SCH_1):PAGE131
    B2    GND @S9S_MB_2U_LIB.S9S_MB_2U(SCH_1):GND    I63 @S9S_MB_2U_LIB.S9S_MB_2U(SCH_1):PAGE131
    C1    GND @S9S_MB_2U_LIB.S9S_MB_2U(SCH_1):GND    I63 @S9S_MB_2U_LIB.S9S_MB_2U(SCH_1):PAGE131
    C2    GND @S9S_MB_2U_LIB.S9S_MB_2U(SCH_1):GND    I63 @S9S_MB_2U_LIB.S9S_MB_2U(SCH_1):PAGE131
    C7 P12V_OCP_FAULT_2 @S9S_MB_2U_LIB.S9S_MB_2U(SCH_1):P12V_OCP_FAULT_2    I63 @S9S_MB_2U_LIB.S9S_MB_2U(SCH_1):PAGE131
    D7 P12V_OCP_PWRGD_2 @S9S_MB_2U_LIB.S9S_MB_2U(SCH_1):P12V_OCP_PWRGD_2    I63 @S9S_MB_2U_LIB.S9S_MB_2U(SCH_1):PAGE131

PU202 MAX15090BEWIT-MAX15090BEWI+T,SB
    A2 P3V3_OCP_VCC_1 @S9S_MB_2U_LIB.S9S_MB_2U(SCH_1):P3V3_OCP_VCC_1    I61 @S9S_MB_2U_LIB.S9S_MB_2U(SCH_1):PAGE153
    A3 P3V3_AUX @S9S_MB_2U_LIB.S9S_MB_2U(SCH_1):P3V3_AUX    I61 @S9S_MB_2U_LIB.S9S_MB_2U(SCH_1):PAGE153
    A5 P3V3_AUX @S9S_MB_2U_LIB.S9S_MB_2U(SCH_1):P3V3_AUX    I61 @S9S_MB_2U_LIB.S9S_MB_2U(SCH_1):PAGE153
    B3 P3V3_AUX @S9S_MB_2U_LIB.S9S_MB_2U(SCH_1):P3V3_AUX    I61 @S9S_MB_2U_LIB.S9S_MB_2U(SCH_1):PAGE153
    B5 P3V3_AUX @S9S_MB_2U_LIB.S9S_MB_2U(SCH_1):P3V3_AUX    I61 @S9S_MB_2U_LIB.S9S_MB_2U(SCH_1):PAGE153
    C3 P3V3_AUX @S9S_MB_2U_LIB.S9S_MB_2U(SCH_1):P3V3_AUX    I61 @S9S_MB_2U_LIB.S9S_MB_2U(SCH_1):PAGE153
    C5 P3V3_AUX @S9S_MB_2U_LIB.S9S_MB_2U(SCH_1):P3V3_AUX    I61 @S9S_MB_2U_LIB.S9S_MB_2U(SCH_1):PAGE153
    D5 P3V3_AUX @S9S_MB_2U_LIB.S9S_MB_2U(SCH_1):P3V3_AUX    I61 @S9S_MB_2U_LIB.S9S_MB_2U(SCH_1):PAGE153
    B1 P3V3_OCP_CB_1 @S9S_MB_2U_LIB.S9S_MB_2U(SCH_1):P3V3_OCP_CB_1    I61 @S9S_MB_2U_LIB.S9S_MB_2U(SCH_1):PAGE153
    B7    GND @S9S_MB_2U_LIB.S9S_MB_2U(SCH_1):GND    I61 @S9S_MB_2U_LIB.S9S_MB_2U(SCH_1):PAGE153
    D1 P3V3_OCP_REG_1 @S9S_MB_2U_LIB.S9S_MB_2U(SCH_1):P3V3_OCP_REG_1    I61 @S9S_MB_2U_LIB.S9S_MB_2U(SCH_1):PAGE153
    D2 P3V3_OCP_UV_1 @S9S_MB_2U_LIB.S9S_MB_2U(SCH_1):P3V3_OCP_UV_1    I61 @S9S_MB_2U_LIB.S9S_MB_2U(SCH_1):PAGE153
    D3 P3V3_OCP_OV_1 @S9S_MB_2U_LIB.S9S_MB_2U(SCH_1):P3V3_OCP_OV_1    I61 @S9S_MB_2U_LIB.S9S_MB_2U(SCH_1):PAGE153
    A1 P3V3_OCP_SENSE_1 @S9S_MB_2U_LIB.S9S_MB_2U(SCH_1):P3V3_OCP_SENSE_1    I61 @S9S_MB_2U_LIB.S9S_MB_2U(SCH_1):PAGE153
    A4 P3V3_OCP_SFF_R @S9S_MB_2U_LIB.S9S_MB_2U(SCH_1):P3V3_OCP_SFF_R    I61 @S9S_MB_2U_LIB.S9S_MB_2U(SCH_1):PAGE153
    B4 P3V3_OCP_SFF_R @S9S_MB_2U_LIB.S9S_MB_2U(SCH_1):P3V3_OCP_SFF_R    I61 @S9S_MB_2U_LIB.S9S_MB_2U(SCH_1):PAGE153
    B6 P3V3_OCP_SFF_R @S9S_MB_2U_LIB.S9S_MB_2U(SCH_1):P3V3_OCP_SFF_R    I61 @S9S_MB_2U_LIB.S9S_MB_2U(SCH_1):PAGE153
    C4 P3V3_OCP_SFF_R @S9S_MB_2U_LIB.S9S_MB_2U(SCH_1):P3V3_OCP_SFF_R    I61 @S9S_MB_2U_LIB.S9S_MB_2U(SCH_1):PAGE153
    C6 P3V3_OCP_SFF_R @S9S_MB_2U_LIB.S9S_MB_2U(SCH_1):P3V3_OCP_SFF_R    I61 @S9S_MB_2U_LIB.S9S_MB_2U(SCH_1):PAGE153
    D4 P3V3_OCP_SFF_R @S9S_MB_2U_LIB.S9S_MB_2U(SCH_1):P3V3_OCP_SFF_R    I61 @S9S_MB_2U_LIB.S9S_MB_2U(SCH_1):PAGE153
    D6 P3V3_OCP_SFF_R @S9S_MB_2U_LIB.S9S_MB_2U(SCH_1):P3V3_OCP_SFF_R    I61 @S9S_MB_2U_LIB.S9S_MB_2U(SCH_1):PAGE153
    A6 P3V3_OCP_GATE_PU202_1 @S9S_MB_2U_LIB.S9S_MB_2U(SCH_1):P3V3_OCP_GATE_PU202_1    I61 @S9S_MB_2U_LIB.S9S_MB_2U(SCH_1):PAGE153
    A7    GND @S9S_MB_2U_LIB.S9S_MB_2U(SCH_1):GND    I61 @S9S_MB_2U_LIB.S9S_MB_2U(SCH_1):PAGE153
    B2    GND @S9S_MB_2U_LIB.S9S_MB_2U(SCH_1):GND    I61 @S9S_MB_2U_LIB.S9S_MB_2U(SCH_1):PAGE153
    C1    GND @S9S_MB_2U_LIB.S9S_MB_2U(SCH_1):GND    I61 @S9S_MB_2U_LIB.S9S_MB_2U(SCH_1):PAGE153
    C2    GND @S9S_MB_2U_LIB.S9S_MB_2U(SCH_1):GND    I61 @S9S_MB_2U_LIB.S9S_MB_2U(SCH_1):PAGE153
    C7 P3V3_OCP_FAULT_1 @S9S_MB_2U_LIB.S9S_MB_2U(SCH_1):P3V3_OCP_FAULT_1    I61 @S9S_MB_2U_LIB.S9S_MB_2U(SCH_1):PAGE153
    D7 P3V3_OCP_PWRGD_1 @S9S_MB_2U_LIB.S9S_MB_2U(SCH_1):P3V3_OCP_PWRGD_1    I61 @S9S_MB_2U_LIB.S9S_MB_2U(SCH_1):PAGE153

PU203 MAX15090BEWIT-MAX15090BEWI+T,SA
    A2 P12V_OCP_VCC_1 @S9S_MB_2U_LIB.S9S_MB_2U(SCH_1):P12V_OCP_VCC_1    I51 @S9S_MB_2U_LIB.S9S_MB_2U(SCH_1):PAGE153
    A3 P12V_AUX @S9S_MB_2U_LIB.S9S_MB_2U(SCH_1):P12V_AUX    I51 @S9S_MB_2U_LIB.S9S_MB_2U(SCH_1):PAGE153
    A5 P12V_AUX @S9S_MB_2U_LIB.S9S_MB_2U(SCH_1):P12V_AUX    I51 @S9S_MB_2U_LIB.S9S_MB_2U(SCH_1):PAGE153
    B3 P12V_AUX @S9S_MB_2U_LIB.S9S_MB_2U(SCH_1):P12V_AUX    I51 @S9S_MB_2U_LIB.S9S_MB_2U(SCH_1):PAGE153
    B5 P12V_AUX @S9S_MB_2U_LIB.S9S_MB_2U(SCH_1):P12V_AUX    I51 @S9S_MB_2U_LIB.S9S_MB_2U(SCH_1):PAGE153
    C3 P12V_AUX @S9S_MB_2U_LIB.S9S_MB_2U(SCH_1):P12V_AUX    I51 @S9S_MB_2U_LIB.S9S_MB_2U(SCH_1):PAGE153
    C5 P12V_AUX @S9S_MB_2U_LIB.S9S_MB_2U(SCH_1):P12V_AUX    I51 @S9S_MB_2U_LIB.S9S_MB_2U(SCH_1):PAGE153
    D5 P12V_AUX @S9S_MB_2U_LIB.S9S_MB_2U(SCH_1):P12V_AUX    I51 @S9S_MB_2U_LIB.S9S_MB_2U(SCH_1):PAGE153
    B1 P12V_OCP_CB_1 @S9S_MB_2U_LIB.S9S_MB_2U(SCH_1):P12V_OCP_CB_1    I51 @S9S_MB_2U_LIB.S9S_MB_2U(SCH_1):PAGE153
    B7    GND @S9S_MB_2U_LIB.S9S_MB_2U(SCH_1):GND    I51 @S9S_MB_2U_LIB.S9S_MB_2U(SCH_1):PAGE153
    D1 P12V_OCP_REG_1 @S9S_MB_2U_LIB.S9S_MB_2U(SCH_1):P12V_OCP_REG_1    I51 @S9S_MB_2U_LIB.S9S_MB_2U(SCH_1):PAGE153
    D2 P12V_OCP_UV_1 @S9S_MB_2U_LIB.S9S_MB_2U(SCH_1):P12V_OCP_UV_1    I51 @S9S_MB_2U_LIB.S9S_MB_2U(SCH_1):PAGE153
    D3 P12V_OCP_OV_1 @S9S_MB_2U_LIB.S9S_MB_2U(SCH_1):P12V_OCP_OV_1    I51 @S9S_MB_2U_LIB.S9S_MB_2U(SCH_1):PAGE153
    A1 P12V_OCP_SENSE_1 @S9S_MB_2U_LIB.S9S_MB_2U(SCH_1):P12V_OCP_SENSE_1    I51 @S9S_MB_2U_LIB.S9S_MB_2U(SCH_1):PAGE153
    A4 P12V_OCP_SFF @S9S_MB_2U_LIB.S9S_MB_2U(SCH_1):P12V_OCP_SFF    I51 @S9S_MB_2U_LIB.S9S_MB_2U(SCH_1):PAGE153
    B4 P12V_OCP_SFF @S9S_MB_2U_LIB.S9S_MB_2U(SCH_1):P12V_OCP_SFF    I51 @S9S_MB_2U_LIB.S9S_MB_2U(SCH_1):PAGE153
    B6 P12V_OCP_SFF @S9S_MB_2U_LIB.S9S_MB_2U(SCH_1):P12V_OCP_SFF    I51 @S9S_MB_2U_LIB.S9S_MB_2U(SCH_1):PAGE153
    C4 P12V_OCP_SFF @S9S_MB_2U_LIB.S9S_MB_2U(SCH_1):P12V_OCP_SFF    I51 @S9S_MB_2U_LIB.S9S_MB_2U(SCH_1):PAGE153
    C6 P12V_OCP_SFF @S9S_MB_2U_LIB.S9S_MB_2U(SCH_1):P12V_OCP_SFF    I51 @S9S_MB_2U_LIB.S9S_MB_2U(SCH_1):PAGE153
    D4 P12V_OCP_SFF @S9S_MB_2U_LIB.S9S_MB_2U(SCH_1):P12V_OCP_SFF    I51 @S9S_MB_2U_LIB.S9S_MB_2U(SCH_1):PAGE153
    D6 P12V_OCP_SFF @S9S_MB_2U_LIB.S9S_MB_2U(SCH_1):P12V_OCP_SFF    I51 @S9S_MB_2U_LIB.S9S_MB_2U(SCH_1):PAGE153
    A6 P12V_OCP_GATE_1 @S9S_MB_2U_LIB.S9S_MB_2U(SCH_1):P12V_OCP_GATE_1    I51 @S9S_MB_2U_LIB.S9S_MB_2U(SCH_1):PAGE153
    A7    GND @S9S_MB_2U_LIB.S9S_MB_2U(SCH_1):GND    I51 @S9S_MB_2U_LIB.S9S_MB_2U(SCH_1):PAGE153
    B2    GND @S9S_MB_2U_LIB.S9S_MB_2U(SCH_1):GND    I51 @S9S_MB_2U_LIB.S9S_MB_2U(SCH_1):PAGE153
    C1    GND @S9S_MB_2U_LIB.S9S_MB_2U(SCH_1):GND    I51 @S9S_MB_2U_LIB.S9S_MB_2U(SCH_1):PAGE153
    C2    GND @S9S_MB_2U_LIB.S9S_MB_2U(SCH_1):GND    I51 @S9S_MB_2U_LIB.S9S_MB_2U(SCH_1):PAGE153
    C7 P12V_OCP_FAULT_1 @S9S_MB_2U_LIB.S9S_MB_2U(SCH_1):P12V_OCP_FAULT_1    I51 @S9S_MB_2U_LIB.S9S_MB_2U(SCH_1):PAGE153
    D7 P12V_OCP_PWRGD_1 @S9S_MB_2U_LIB.S9S_MB_2U(SCH_1):P12V_OCP_PWRGD_1    I51 @S9S_MB_2U_LIB.S9S_MB_2U(SCH_1):PAGE153

PU204 RS31312R-RS31312R,SMLF,IC,AL03A
    20 P12V_OCP_SFF @S9S_MB_2U_LIB.S9S_MB_2U(SCH_1):P12V_OCP_SFF    I70 @S9S_MB_2U_LIB.S9S_MB_2U(SCH_1):PAGE236
 21_22 P12V_AUX @S9S_MB_2U_LIB.S9S_MB_2U(SCH_1):P12V_AUX    I70 @S9S_MB_2U_LIB.S9S_MB_2U(SCH_1):PAGE236
    19 P12V_OCP_SFF @S9S_MB_2U_LIB.S9S_MB_2U(SCH_1):P12V_OCP_SFF    I70 @S9S_MB_2U_LIB.S9S_MB_2U(SCH_1):PAGE236
    18 P12V_OCP_SFF @S9S_MB_2U_LIB.S9S_MB_2U(SCH_1):P12V_OCP_SFF    I70 @S9S_MB_2U_LIB.S9S_MB_2U(SCH_1):PAGE236
    17 P12V_OCP_SFF @S9S_MB_2U_LIB.S9S_MB_2U(SCH_1):P12V_OCP_SFF    I70 @S9S_MB_2U_LIB.S9S_MB_2U(SCH_1):PAGE236
    16 P12V_OCP_SFF @S9S_MB_2U_LIB.S9S_MB_2U(SCH_1):P12V_OCP_SFF    I70 @S9S_MB_2U_LIB.S9S_MB_2U(SCH_1):PAGE236
    15 P12V_OCP_SFF @S9S_MB_2U_LIB.S9S_MB_2U(SCH_1):P12V_OCP_SFF    I70 @S9S_MB_2U_LIB.S9S_MB_2U(SCH_1):PAGE236
    14 P12V_OCP_SFF @S9S_MB_2U_LIB.S9S_MB_2U(SCH_1):P12V_OCP_SFF    I70 @S9S_MB_2U_LIB.S9S_MB_2U(SCH_1):PAGE236
    12 P12V_OCP_AVIN_PD_1 @S9S_MB_2U_LIB.S9S_MB_2U(SCH_1):P12V_OCP_AVIN_PD_1    I70 @S9S_MB_2U_LIB.S9S_MB_2U(SCH_1):PAGE236
    13 P12V_OCP_SFF @S9S_MB_2U_LIB.S9S_MB_2U(SCH_1):P12V_OCP_SFF    I70 @S9S_MB_2U_LIB.S9S_MB_2U(SCH_1):PAGE236
    11 P12V_OCP_OV_FB_1 @S9S_MB_2U_LIB.S9S_MB_2U(SCH_1):P12V_OCP_OV_FB_1    I70 @S9S_MB_2U_LIB.S9S_MB_2U(SCH_1):PAGE236
    10 HP_LVC3_OCP_V3_1_P12V_PWRGD @S9S_MB_2U_LIB.S9S_MB_2U(SCH_1):HP_LVC3_OCP_V3_1_P12V_PWRGD    I70 @S9S_MB_2U_LIB.S9S_MB_2U(SCH_1):PAGE236
     9 P12V_OCP_FLTB_1 @S9S_MB_2U_LIB.S9S_MB_2U(SCH_1):P12V_OCP_FLTB_1    I70 @S9S_MB_2U_LIB.S9S_MB_2U(SCH_1):PAGE236
     8 P12V_OCP_IMON_1 @S9S_MB_2U_LIB.S9S_MB_2U(SCH_1):P12V_OCP_IMON_1    I70 @S9S_MB_2U_LIB.S9S_MB_2U(SCH_1):PAGE236
    23 P12V_AUX @S9S_MB_2U_LIB.S9S_MB_2U(SCH_1):P12V_AUX    I70 @S9S_MB_2U_LIB.S9S_MB_2U(SCH_1):PAGE236
    24 P12V_AUX @S9S_MB_2U_LIB.S9S_MB_2U(SCH_1):P12V_AUX    I70 @S9S_MB_2U_LIB.S9S_MB_2U(SCH_1):PAGE236
    25 P12V_AUX @S9S_MB_2U_LIB.S9S_MB_2U(SCH_1):P12V_AUX    I70 @S9S_MB_2U_LIB.S9S_MB_2U(SCH_1):PAGE236
    26 P12V_AUX @S9S_MB_2U_LIB.S9S_MB_2U(SCH_1):P12V_AUX    I70 @S9S_MB_2U_LIB.S9S_MB_2U(SCH_1):PAGE236
     1 P12V_OCP_EN_1_R2 @S9S_MB_2U_LIB.S9S_MB_2U(SCH_1):P12V_OCP_EN_1_R2    I70 @S9S_MB_2U_LIB.S9S_MB_2U(SCH_1):PAGE236
     2    GND @S9S_MB_2U_LIB.S9S_MB_2U(SCH_1):GND    I70 @S9S_MB_2U_LIB.S9S_MB_2U(SCH_1):PAGE236
     3    GND @S9S_MB_2U_LIB.S9S_MB_2U(SCH_1):GND    I70 @S9S_MB_2U_LIB.S9S_MB_2U(SCH_1):PAGE236
     4 P12V_OCP_TIMER_1 @S9S_MB_2U_LIB.S9S_MB_2U(SCH_1):P12V_OCP_TIMER_1    I70 @S9S_MB_2U_LIB.S9S_MB_2U(SCH_1):PAGE236
     5 P12V_OCP_ISET_1 @S9S_MB_2U_LIB.S9S_MB_2U(SCH_1):P12V_OCP_ISET_1    I70 @S9S_MB_2U_LIB.S9S_MB_2U(SCH_1):PAGE236
     6 P12V_OCP_SS_1 @S9S_MB_2U_LIB.S9S_MB_2U(SCH_1):P12V_OCP_SS_1    I70 @S9S_MB_2U_LIB.S9S_MB_2U(SCH_1):PAGE236
     7    GND @S9S_MB_2U_LIB.S9S_MB_2U(SCH_1):GND    I70 @S9S_MB_2U_LIB.S9S_MB_2U(SCH_1):PAGE236

PU205 MP5016GQHLZ-MP5016GQH-L-Z,SMLFA
     9 P3V3_OCP_EN_1_R2 @S9S_MB_2U_LIB.S9S_MB_2U(SCH_1):P3V3_OCP_EN_1_R2    I50 @S9S_MB_2U_LIB.S9S_MB_2U(SCH_1):PAGE236
     5 P3V3_OCP_MODE_1 @S9S_MB_2U_LIB.S9S_MB_2U(SCH_1):P3V3_OCP_MODE_1    I50 @S9S_MB_2U_LIB.S9S_MB_2U(SCH_1):PAGE236
     4 P3V3_OCP_ILIMIT_1 @S9S_MB_2U_LIB.S9S_MB_2U(SCH_1):P3V3_OCP_ILIMIT_1    I50 @S9S_MB_2U_LIB.S9S_MB_2U(SCH_1):PAGE236
     3    GND @S9S_MB_2U_LIB.S9S_MB_2U(SCH_1):GND    I50 @S9S_MB_2U_LIB.S9S_MB_2U(SCH_1):PAGE236
   1_2 P3V3_AUX @S9S_MB_2U_LIB.S9S_MB_2U(SCH_1):P3V3_AUX    I50 @S9S_MB_2U_LIB.S9S_MB_2U(SCH_1):PAGE236
    10 P3V3_OCP_DVDT_1 @S9S_MB_2U_LIB.S9S_MB_2U(SCH_1):P3V3_OCP_DVDT_1    I50 @S9S_MB_2U_LIB.S9S_MB_2U(SCH_1):PAGE236
     8 P3V3_OCP_GATE_1 @S9S_MB_2U_LIB.S9S_MB_2U(SCH_1):P3V3_OCP_GATE_1    I50 @S9S_MB_2U_LIB.S9S_MB_2U(SCH_1):PAGE236
   6_7 P3V3_OCP_SFF_R @S9S_MB_2U_LIB.S9S_MB_2U(SCH_1):P3V3_OCP_SFF_R    I50 @S9S_MB_2U_LIB.S9S_MB_2U(SCH_1):PAGE236

PU206 RS31312R-RS31312R,SMLF,IC,AL03A
    20 P12V_OCP_V3_2 @S9S_MB_2U_LIB.S9S_MB_2U(SCH_1):P12V_OCP_V3_2    I70 @S9S_MB_2U_LIB.S9S_MB_2U(SCH_1):PAGE237
 21_22 P12V_AUX @S9S_MB_2U_LIB.S9S_MB_2U(SCH_1):P12V_AUX    I70 @S9S_MB_2U_LIB.S9S_MB_2U(SCH_1):PAGE237
    19 P12V_OCP_V3_2 @S9S_MB_2U_LIB.S9S_MB_2U(SCH_1):P12V_OCP_V3_2    I70 @S9S_MB_2U_LIB.S9S_MB_2U(SCH_1):PAGE237
    18 P12V_OCP_V3_2 @S9S_MB_2U_LIB.S9S_MB_2U(SCH_1):P12V_OCP_V3_2    I70 @S9S_MB_2U_LIB.S9S_MB_2U(SCH_1):PAGE237
    17 P12V_OCP_V3_2 @S9S_MB_2U_LIB.S9S_MB_2U(SCH_1):P12V_OCP_V3_2    I70 @S9S_MB_2U_LIB.S9S_MB_2U(SCH_1):PAGE237
    16 P12V_OCP_V3_2 @S9S_MB_2U_LIB.S9S_MB_2U(SCH_1):P12V_OCP_V3_2    I70 @S9S_MB_2U_LIB.S9S_MB_2U(SCH_1):PAGE237
    15 P12V_OCP_V3_2 @S9S_MB_2U_LIB.S9S_MB_2U(SCH_1):P12V_OCP_V3_2    I70 @S9S_MB_2U_LIB.S9S_MB_2U(SCH_1):PAGE237
    14 P12V_OCP_V3_2 @S9S_MB_2U_LIB.S9S_MB_2U(SCH_1):P12V_OCP_V3_2    I70 @S9S_MB_2U_LIB.S9S_MB_2U(SCH_1):PAGE237
    12 P12V_OCP_AVIN_PD_2 @S9S_MB_2U_LIB.S9S_MB_2U(SCH_1):P12V_OCP_AVIN_PD_2    I70 @S9S_MB_2U_LIB.S9S_MB_2U(SCH_1):PAGE237
    13 P12V_OCP_V3_2 @S9S_MB_2U_LIB.S9S_MB_2U(SCH_1):P12V_OCP_V3_2    I70 @S9S_MB_2U_LIB.S9S_MB_2U(SCH_1):PAGE237
    11 P12V_OCP_OV_FB_2 @S9S_MB_2U_LIB.S9S_MB_2U(SCH_1):P12V_OCP_OV_FB_2    I70 @S9S_MB_2U_LIB.S9S_MB_2U(SCH_1):PAGE237
    10 HP_LVC3_OCP_V3_2_P12V_PWRGD @S9S_MB_2U_LIB.S9S_MB_2U(SCH_1):HP_LVC3_OCP_V3_2_P12V_PWRGD    I70 @S9S_MB_2U_LIB.S9S_MB_2U(SCH_1):PAGE237
     9 P12V_OCP_FLTB_2 @S9S_MB_2U_LIB.S9S_MB_2U(SCH_1):P12V_OCP_FLTB_2    I70 @S9S_MB_2U_LIB.S9S_MB_2U(SCH_1):PAGE237
     8 P12V_OCP_IMON_2 @S9S_MB_2U_LIB.S9S_MB_2U(SCH_1):P12V_OCP_IMON_2    I70 @S9S_MB_2U_LIB.S9S_MB_2U(SCH_1):PAGE237
    23 P12V_AUX @S9S_MB_2U_LIB.S9S_MB_2U(SCH_1):P12V_AUX    I70 @S9S_MB_2U_LIB.S9S_MB_2U(SCH_1):PAGE237
    24 P12V_AUX @S9S_MB_2U_LIB.S9S_MB_2U(SCH_1):P12V_AUX    I70 @S9S_MB_2U_LIB.S9S_MB_2U(SCH_1):PAGE237
    25 P12V_AUX @S9S_MB_2U_LIB.S9S_MB_2U(SCH_1):P12V_AUX    I70 @S9S_MB_2U_LIB.S9S_MB_2U(SCH_1):PAGE237
    26 P12V_AUX @S9S_MB_2U_LIB.S9S_MB_2U(SCH_1):P12V_AUX    I70 @S9S_MB_2U_LIB.S9S_MB_2U(SCH_1):PAGE237
     1 P12V_OCP_V3_2_EN_2_R3 @S9S_MB_2U_LIB.S9S_MB_2U(SCH_1):P12V_OCP_V3_2_EN_2_R3    I70 @S9S_MB_2U_LIB.S9S_MB_2U(SCH_1):PAGE237
     2    GND @S9S_MB_2U_LIB.S9S_MB_2U(SCH_1):GND    I70 @S9S_MB_2U_LIB.S9S_MB_2U(SCH_1):PAGE237
     3    GND @S9S_MB_2U_LIB.S9S_MB_2U(SCH_1):GND    I70 @S9S_MB_2U_LIB.S9S_MB_2U(SCH_1):PAGE237
     4 P12V_OCP_TIMER_2 @S9S_MB_2U_LIB.S9S_MB_2U(SCH_1):P12V_OCP_TIMER_2    I70 @S9S_MB_2U_LIB.S9S_MB_2U(SCH_1):PAGE237
     5 P12V_OCP_ISET_2 @S9S_MB_2U_LIB.S9S_MB_2U(SCH_1):P12V_OCP_ISET_2    I70 @S9S_MB_2U_LIB.S9S_MB_2U(SCH_1):PAGE237
     6 P12V_OCP_SS_2 @S9S_MB_2U_LIB.S9S_MB_2U(SCH_1):P12V_OCP_SS_2    I70 @S9S_MB_2U_LIB.S9S_MB_2U(SCH_1):PAGE237
     7    GND @S9S_MB_2U_LIB.S9S_MB_2U(SCH_1):GND    I70 @S9S_MB_2U_LIB.S9S_MB_2U(SCH_1):PAGE237

PU207 MP5016GQHLZ-MP5016GQH-L-Z,SMLFA
     9 P3V3_OCP_EN_2 @S9S_MB_2U_LIB.S9S_MB_2U(SCH_1):P3V3_OCP_EN_2    I51 @S9S_MB_2U_LIB.S9S_MB_2U(SCH_1):PAGE237
     5 P3V3_OCP_MODE_2 @S9S_MB_2U_LIB.S9S_MB_2U(SCH_1):P3V3_OCP_MODE_2    I51 @S9S_MB_2U_LIB.S9S_MB_2U(SCH_1):PAGE237
     4 P3V3_OCP_ILIMIT_2 @S9S_MB_2U_LIB.S9S_MB_2U(SCH_1):P3V3_OCP_ILIMIT_2    I51 @S9S_MB_2U_LIB.S9S_MB_2U(SCH_1):PAGE237
     3    GND @S9S_MB_2U_LIB.S9S_MB_2U(SCH_1):GND    I51 @S9S_MB_2U_LIB.S9S_MB_2U(SCH_1):PAGE237
   1_2 P3V3_AUX @S9S_MB_2U_LIB.S9S_MB_2U(SCH_1):P3V3_AUX    I51 @S9S_MB_2U_LIB.S9S_MB_2U(SCH_1):PAGE237
    10 P3V3_OCP_DVDT_2 @S9S_MB_2U_LIB.S9S_MB_2U(SCH_1):P3V3_OCP_DVDT_2    I51 @S9S_MB_2U_LIB.S9S_MB_2U(SCH_1):PAGE237
     8 P3V3_OCP_GATE_PU207_2 @S9S_MB_2U_LIB.S9S_MB_2U(SCH_1):P3V3_OCP_GATE_PU207_2    I51 @S9S_MB_2U_LIB.S9S_MB_2U(SCH_1):PAGE237
   6_7 P3V3_OCP_V3_2_R @S9S_MB_2U_LIB.S9S_MB_2U(SCH_1):P3V3_OCP_V3_2_R    I51 @S9S_MB_2U_LIB.S9S_MB_2U(SCH_1):PAGE237

PU287 MP5991GLUZ-MP5991GLU-Z,SMLF,ICA
     9 P12V_PSU @S9S_MB_2U_LIB.S9S_MB_2U(SCH_1):P12V_PSU    I35 @S9S_MB_2U_LIB.S9S_MB_2U(SCH_1):PAGE301
    10 P12V_PSU @S9S_MB_2U_LIB.S9S_MB_2U(SCH_1):P12V_PSU    I35 @S9S_MB_2U_LIB.S9S_MB_2U(SCH_1):PAGE301
    11 P12V_PSU @S9S_MB_2U_LIB.S9S_MB_2U(SCH_1):P12V_PSU    I35 @S9S_MB_2U_LIB.S9S_MB_2U(SCH_1):PAGE301
    12 P12V_PSU @S9S_MB_2U_LIB.S9S_MB_2U(SCH_1):P12V_PSU    I35 @S9S_MB_2U_LIB.S9S_MB_2U(SCH_1):PAGE301
    13 P12V_PSU @S9S_MB_2U_LIB.S9S_MB_2U(SCH_1):P12V_PSU    I35 @S9S_MB_2U_LIB.S9S_MB_2U(SCH_1):PAGE301
     4 HSC_ON @S9S_MB_2U_LIB.S9S_MB_2U(SCH_1):HSC_ON    I35 @S9S_MB_2U_LIB.S9S_MB_2U(SCH_1):PAGE301
    24 HSC_OCREF @S9S_MB_2U_LIB.S9S_MB_2U(SCH_1):HSC_OCREF    I35 @S9S_MB_2U_LIB.S9S_MB_2U(SCH_1):PAGE301
    23 HSC_CS_1 @S9S_MB_2U_LIB.S9S_MB_2U(SCH_1):HSC_CS_1    I35 @S9S_MB_2U_LIB.S9S_MB_2U(SCH_1):PAGE301
    22 HSC_IMON @S9S_MB_2U_LIB.S9S_MB_2U(SCH_1):HSC_IMON    I35 @S9S_MB_2U_LIB.S9S_MB_2U(SCH_1):PAGE301
    21 HSC_VDD_R_1 @S9S_MB_2U_LIB.S9S_MB_2U(SCH_1):HSC_VDD_R_1    I35 @S9S_MB_2U_LIB.S9S_MB_2U(SCH_1):PAGE301
    20 AGND_HSC @S9S_MB_2U_LIB.S9S_MB_2U(SCH_1):AGND_HSC    I35 @S9S_MB_2U_LIB.S9S_MB_2U(SCH_1):PAGE301
    19 HSC_SS @S9S_MB_2U_LIB.S9S_MB_2U(SCH_1):HSC_SS    I35 @S9S_MB_2U_LIB.S9S_MB_2U(SCH_1):PAGE301
     5 HSC_FAULT @S9S_MB_2U_LIB.S9S_MB_2U(SCH_1):HSC_FAULT    I35 @S9S_MB_2U_LIB.S9S_MB_2U(SCH_1):PAGE301
    18 HSC_VTEMP @S9S_MB_2U_LIB.S9S_MB_2U(SCH_1):HSC_VTEMP    I35 @S9S_MB_2U_LIB.S9S_MB_2U(SCH_1):PAGE301
     1 P12V_AUX @S9S_MB_2U_LIB.S9S_MB_2U(SCH_1):P12V_AUX    I35 @S9S_MB_2U_LIB.S9S_MB_2U(SCH_1):PAGE301
     2 P12V_AUX @S9S_MB_2U_LIB.S9S_MB_2U(SCH_1):P12V_AUX    I35 @S9S_MB_2U_LIB.S9S_MB_2U(SCH_1):PAGE301
    25 P12V_AUX @S9S_MB_2U_LIB.S9S_MB_2U(SCH_1):P12V_AUX    I35 @S9S_MB_2U_LIB.S9S_MB_2U(SCH_1):PAGE301
    26 P12V_AUX @S9S_MB_2U_LIB.S9S_MB_2U(SCH_1):P12V_AUX    I35 @S9S_MB_2U_LIB.S9S_MB_2U(SCH_1):PAGE301
     3 HSC_D_OC_1 @S9S_MB_2U_LIB.S9S_MB_2U(SCH_1):HSC_D_OC_1    I35 @S9S_MB_2U_LIB.S9S_MB_2U(SCH_1):PAGE301
    14 P12V_PSU @S9S_MB_2U_LIB.S9S_MB_2U(SCH_1):P12V_PSU    I35 @S9S_MB_2U_LIB.S9S_MB_2U(SCH_1):PAGE301
    15 P12V_PSU @S9S_MB_2U_LIB.S9S_MB_2U(SCH_1):P12V_PSU    I35 @S9S_MB_2U_LIB.S9S_MB_2U(SCH_1):PAGE301
    16 P12V_PSU @S9S_MB_2U_LIB.S9S_MB_2U(SCH_1):P12V_PSU    I35 @S9S_MB_2U_LIB.S9S_MB_2U(SCH_1):PAGE301
    33 P12V_PSU @S9S_MB_2U_LIB.S9S_MB_2U(SCH_1):P12V_PSU    I35 @S9S_MB_2U_LIB.S9S_MB_2U(SCH_1):PAGE301
    27 P12V_AUX @S9S_MB_2U_LIB.S9S_MB_2U(SCH_1):P12V_AUX    I35 @S9S_MB_2U_LIB.S9S_MB_2U(SCH_1):PAGE301
    28 P12V_AUX @S9S_MB_2U_LIB.S9S_MB_2U(SCH_1):P12V_AUX    I35 @S9S_MB_2U_LIB.S9S_MB_2U(SCH_1):PAGE301
    29 P12V_AUX @S9S_MB_2U_LIB.S9S_MB_2U(SCH_1):P12V_AUX    I35 @S9S_MB_2U_LIB.S9S_MB_2U(SCH_1):PAGE301
    30 P12V_AUX @S9S_MB_2U_LIB.S9S_MB_2U(SCH_1):P12V_AUX    I35 @S9S_MB_2U_LIB.S9S_MB_2U(SCH_1):PAGE301
    31 P12V_AUX @S9S_MB_2U_LIB.S9S_MB_2U(SCH_1):P12V_AUX    I35 @S9S_MB_2U_LIB.S9S_MB_2U(SCH_1):PAGE301
    32 P12V_AUX @S9S_MB_2U_LIB.S9S_MB_2U(SCH_1):P12V_AUX    I35 @S9S_MB_2U_LIB.S9S_MB_2U(SCH_1):PAGE301
     8 HSC_MODE_1 @S9S_MB_2U_LIB.S9S_MB_2U(SCH_1):HSC_MODE_1    I35 @S9S_MB_2U_LIB.S9S_MB_2U(SCH_1):PAGE301
    17 HSC_SCREF_1 @S9S_MB_2U_LIB.S9S_MB_2U(SCH_1):HSC_SCREF_1    I35 @S9S_MB_2U_LIB.S9S_MB_2U(SCH_1):PAGE301
     6 HSC_FLT_TYPE_1 @S9S_MB_2U_LIB.S9S_MB_2U(SCH_1):HSC_FLT_TYPE_1    I35 @S9S_MB_2U_LIB.S9S_MB_2U(SCH_1):PAGE301
     7 HSC_NC1_1 @S9S_MB_2U_LIB.S9S_MB_2U(SCH_1):HSC_NC1_1    I35 @S9S_MB_2U_LIB.S9S_MB_2U(SCH_1):PAGE301

PU288 MP5991GLUZ-MP5991GLU-Z,SMLF,ICA
     9 P12V_PSU @S9S_MB_2U_LIB.S9S_MB_2U(SCH_1):P12V_PSU    I14 @S9S_MB_2U_LIB.S9S_MB_2U(SCH_1):PAGE301
    10 P12V_PSU @S9S_MB_2U_LIB.S9S_MB_2U(SCH_1):P12V_PSU    I14 @S9S_MB_2U_LIB.S9S_MB_2U(SCH_1):PAGE301
    11 P12V_PSU @S9S_MB_2U_LIB.S9S_MB_2U(SCH_1):P12V_PSU    I14 @S9S_MB_2U_LIB.S9S_MB_2U(SCH_1):PAGE301
    12 P12V_PSU @S9S_MB_2U_LIB.S9S_MB_2U(SCH_1):P12V_PSU    I14 @S9S_MB_2U_LIB.S9S_MB_2U(SCH_1):PAGE301
    13 P12V_PSU @S9S_MB_2U_LIB.S9S_MB_2U(SCH_1):P12V_PSU    I14 @S9S_MB_2U_LIB.S9S_MB_2U(SCH_1):PAGE301
     4 HSC_ON @S9S_MB_2U_LIB.S9S_MB_2U(SCH_1):HSC_ON    I14 @S9S_MB_2U_LIB.S9S_MB_2U(SCH_1):PAGE301
    24 HSC_OCREF @S9S_MB_2U_LIB.S9S_MB_2U(SCH_1):HSC_OCREF    I14 @S9S_MB_2U_LIB.S9S_MB_2U(SCH_1):PAGE301
    23 HSC_CS_2 @S9S_MB_2U_LIB.S9S_MB_2U(SCH_1):HSC_CS_2    I14 @S9S_MB_2U_LIB.S9S_MB_2U(SCH_1):PAGE301
    22 HSC_IMON @S9S_MB_2U_LIB.S9S_MB_2U(SCH_1):HSC_IMON    I14 @S9S_MB_2U_LIB.S9S_MB_2U(SCH_1):PAGE301
    21 HSC_VDD_R_2 @S9S_MB_2U_LIB.S9S_MB_2U(SCH_1):HSC_VDD_R_2    I14 @S9S_MB_2U_LIB.S9S_MB_2U(SCH_1):PAGE301
    20 AGND_HSC @S9S_MB_2U_LIB.S9S_MB_2U(SCH_1):AGND_HSC    I14 @S9S_MB_2U_LIB.S9S_MB_2U(SCH_1):PAGE301
    19 HSC_SS @S9S_MB_2U_LIB.S9S_MB_2U(SCH_1):HSC_SS    I14 @S9S_MB_2U_LIB.S9S_MB_2U(SCH_1):PAGE301
     5 HSC_FAULT @S9S_MB_2U_LIB.S9S_MB_2U(SCH_1):HSC_FAULT    I14 @S9S_MB_2U_LIB.S9S_MB_2U(SCH_1):PAGE301
    18 HSC_VTEMP @S9S_MB_2U_LIB.S9S_MB_2U(SCH_1):HSC_VTEMP    I14 @S9S_MB_2U_LIB.S9S_MB_2U(SCH_1):PAGE301
     1 P12V_AUX @S9S_MB_2U_LIB.S9S_MB_2U(SCH_1):P12V_AUX    I14 @S9S_MB_2U_LIB.S9S_MB_2U(SCH_1):PAGE301
     2 P12V_AUX @S9S_MB_2U_LIB.S9S_MB_2U(SCH_1):P12V_AUX    I14 @S9S_MB_2U_LIB.S9S_MB_2U(SCH_1):PAGE301
    25 P12V_AUX @S9S_MB_2U_LIB.S9S_MB_2U(SCH_1):P12V_AUX    I14 @S9S_MB_2U_LIB.S9S_MB_2U(SCH_1):PAGE301
    26 P12V_AUX @S9S_MB_2U_LIB.S9S_MB_2U(SCH_1):P12V_AUX    I14 @S9S_MB_2U_LIB.S9S_MB_2U(SCH_1):PAGE301
     3 HSC_D_OC_2 @S9S_MB_2U_LIB.S9S_MB_2U(SCH_1):HSC_D_OC_2    I14 @S9S_MB_2U_LIB.S9S_MB_2U(SCH_1):PAGE301
    14 P12V_PSU @S9S_MB_2U_LIB.S9S_MB_2U(SCH_1):P12V_PSU    I14 @S9S_MB_2U_LIB.S9S_MB_2U(SCH_1):PAGE301
    15 P12V_PSU @S9S_MB_2U_LIB.S9S_MB_2U(SCH_1):P12V_PSU    I14 @S9S_MB_2U_LIB.S9S_MB_2U(SCH_1):PAGE301
    16 P12V_PSU @S9S_MB_2U_LIB.S9S_MB_2U(SCH_1):P12V_PSU    I14 @S9S_MB_2U_LIB.S9S_MB_2U(SCH_1):PAGE301
    33 P12V_PSU @S9S_MB_2U_LIB.S9S_MB_2U(SCH_1):P12V_PSU    I14 @S9S_MB_2U_LIB.S9S_MB_2U(SCH_1):PAGE301
    27 P12V_AUX @S9S_MB_2U_LIB.S9S_MB_2U(SCH_1):P12V_AUX    I14 @S9S_MB_2U_LIB.S9S_MB_2U(SCH_1):PAGE301
    28 P12V_AUX @S9S_MB_2U_LIB.S9S_MB_2U(SCH_1):P12V_AUX    I14 @S9S_MB_2U_LIB.S9S_MB_2U(SCH_1):PAGE301
    29 P12V_AUX @S9S_MB_2U_LIB.S9S_MB_2U(SCH_1):P12V_AUX    I14 @S9S_MB_2U_LIB.S9S_MB_2U(SCH_1):PAGE301
    30 P12V_AUX @S9S_MB_2U_LIB.S9S_MB_2U(SCH_1):P12V_AUX    I14 @S9S_MB_2U_LIB.S9S_MB_2U(SCH_1):PAGE301
    31 P12V_AUX @S9S_MB_2U_LIB.S9S_MB_2U(SCH_1):P12V_AUX    I14 @S9S_MB_2U_LIB.S9S_MB_2U(SCH_1):PAGE301
    32 P12V_AUX @S9S_MB_2U_LIB.S9S_MB_2U(SCH_1):P12V_AUX    I14 @S9S_MB_2U_LIB.S9S_MB_2U(SCH_1):PAGE301
     8 HSC_MODE_2 @S9S_MB_2U_LIB.S9S_MB_2U(SCH_1):HSC_MODE_2    I14 @S9S_MB_2U_LIB.S9S_MB_2U(SCH_1):PAGE301
    17 HSC_SCREF_2 @S9S_MB_2U_LIB.S9S_MB_2U(SCH_1):HSC_SCREF_2    I14 @S9S_MB_2U_LIB.S9S_MB_2U(SCH_1):PAGE301
     6 HSC_FLT_TYPE_2 @S9S_MB_2U_LIB.S9S_MB_2U(SCH_1):HSC_FLT_TYPE_2    I14 @S9S_MB_2U_LIB.S9S_MB_2U(SCH_1):PAGE301
     7 HSC_NC1_2 @S9S_MB_2U_LIB.S9S_MB_2U(SCH_1):HSC_NC1_2    I14 @S9S_MB_2U_LIB.S9S_MB_2U(SCH_1):PAGE301

PU289 MP5990GMA1111Z-MP5990GMA-1111-A
    29 P12V_AUX @S9S_MB_2U_LIB.S9S_MB_2U(SCH_1):P12V_AUX    I56 @S9S_MB_2U_LIB.S9S_MB_2U(SCH_1):PAGE303
    28 P12V_AUX @S9S_MB_2U_LIB.S9S_MB_2U(SCH_1):P12V_AUX    I56 @S9S_MB_2U_LIB.S9S_MB_2U(SCH_1):PAGE303
    27 P12V_AUX @S9S_MB_2U_LIB.S9S_MB_2U(SCH_1):P12V_AUX    I56 @S9S_MB_2U_LIB.S9S_MB_2U(SCH_1):PAGE303
     2 P12V_PSU @S9S_MB_2U_LIB.S9S_MB_2U(SCH_1):P12V_PSU    I56 @S9S_MB_2U_LIB.S9S_MB_2U(SCH_1):PAGE303
    26 HSC_EN_R @S9S_MB_2U_LIB.S9S_MB_2U(SCH_1):HSC_EN_R    I56 @S9S_MB_2U_LIB.S9S_MB_2U(SCH_1):PAGE303
     3 P12V_PSU @S9S_MB_2U_LIB.S9S_MB_2U(SCH_1):P12V_PSU    I56 @S9S_MB_2U_LIB.S9S_MB_2U(SCH_1):PAGE303
     4 P12V_PSU @S9S_MB_2U_LIB.S9S_MB_2U(SCH_1):P12V_PSU    I56 @S9S_MB_2U_LIB.S9S_MB_2U(SCH_1):PAGE303
    18 AGND_HSC @S9S_MB_2U_LIB.S9S_MB_2U(SCH_1):AGND_HSC    I56 @S9S_MB_2U_LIB.S9S_MB_2U(SCH_1):PAGE303
    12 SMB_SML1_PMBUS_HSC_R_SDA @S9S_MB_2U_LIB.S9S_MB_2U(SCH_1):SMB_SML1_PMBUS_HSC_R_SDA    I56 @S9S_MB_2U_LIB.S9S_MB_2U(SCH_1):PAGE303
    14 HSC_VIN_UVW_N @S9S_MB_2U_LIB.S9S_MB_2U(SCH_1):HSC_VIN_UVW_N    I56 @S9S_MB_2U_LIB.S9S_MB_2U(SCH_1):PAGE303
    11 SMB_SML1_PMBUS_HSC_L_SCL @S9S_MB_2U_LIB.S9S_MB_2U(SCH_1):SMB_SML1_PMBUS_HSC_L_SCL    I56 @S9S_MB_2U_LIB.S9S_MB_2U(SCH_1):PAGE303
    37 HSC_D_OC_R @S9S_MB_2U_LIB.S9S_MB_2U(SCH_1):HSC_D_OC_R    I56 @S9S_MB_2U_LIB.S9S_MB_2U(SCH_1):PAGE303
    31 P12V_AUX @S9S_MB_2U_LIB.S9S_MB_2U(SCH_1):P12V_AUX    I56 @S9S_MB_2U_LIB.S9S_MB_2U(SCH_1):PAGE303
    35 P12V_AUX @S9S_MB_2U_LIB.S9S_MB_2U(SCH_1):P12V_AUX    I56 @S9S_MB_2U_LIB.S9S_MB_2U(SCH_1):PAGE303
    10 IRQ_SML1_PMBUS_ALERT @S9S_MB_2U_LIB.S9S_MB_2U(SCH_1):IRQ_SML1_PMBUS_ALERT    I56 @S9S_MB_2U_LIB.S9S_MB_2U(SCH_1):PAGE303
    39 HSC_FAULT @S9S_MB_2U_LIB.S9S_MB_2U(SCH_1):HSC_FAULT    I56 @S9S_MB_2U_LIB.S9S_MB_2U(SCH_1):PAGE303
     7 P12V_PSU @S9S_MB_2U_LIB.S9S_MB_2U(SCH_1):P12V_PSU    I56 @S9S_MB_2U_LIB.S9S_MB_2U(SCH_1):PAGE303
    33 P12V_AUX @S9S_MB_2U_LIB.S9S_MB_2U(SCH_1):P12V_AUX    I56 @S9S_MB_2U_LIB.S9S_MB_2U(SCH_1):PAGE303
    41 HSC_MODE @S9S_MB_2U_LIB.S9S_MB_2U(SCH_1):HSC_MODE    I56 @S9S_MB_2U_LIB.S9S_MB_2U(SCH_1):PAGE303
     8 P12V_PSU @S9S_MB_2U_LIB.S9S_MB_2U(SCH_1):P12V_PSU    I56 @S9S_MB_2U_LIB.S9S_MB_2U(SCH_1):PAGE303
    13 MB0_P12V_STBY_PWRGD @S9S_MB_2U_LIB.S9S_MB_2U(SCH_1):MB0_P12V_STBY_PWRGD    I56 @S9S_MB_2U_LIB.S9S_MB_2U(SCH_1):PAGE303
    34 P12V_AUX @S9S_MB_2U_LIB.S9S_MB_2U(SCH_1):P12V_AUX    I56 @S9S_MB_2U_LIB.S9S_MB_2U(SCH_1):PAGE303
    38 HSC_ON_R @S9S_MB_2U_LIB.S9S_MB_2U(SCH_1):HSC_ON_R    I56 @S9S_MB_2U_LIB.S9S_MB_2U(SCH_1):PAGE303
     5 P12V_PSU @S9S_MB_2U_LIB.S9S_MB_2U(SCH_1):P12V_PSU    I56 @S9S_MB_2U_LIB.S9S_MB_2U(SCH_1):PAGE303
     6 P12V_PSU @S9S_MB_2U_LIB.S9S_MB_2U(SCH_1):P12V_PSU    I56 @S9S_MB_2U_LIB.S9S_MB_2U(SCH_1):PAGE303
    15 HSC_VTEMP @S9S_MB_2U_LIB.S9S_MB_2U(SCH_1):HSC_VTEMP    I56 @S9S_MB_2U_LIB.S9S_MB_2U(SCH_1):PAGE303
    22 HSC_OCREF @S9S_MB_2U_LIB.S9S_MB_2U(SCH_1):HSC_OCREF    I56 @S9S_MB_2U_LIB.S9S_MB_2U(SCH_1):PAGE303
    25 HSC_SCREF @S9S_MB_2U_LIB.S9S_MB_2U(SCH_1):HSC_SCREF    I56 @S9S_MB_2U_LIB.S9S_MB_2U(SCH_1):PAGE303
    16 HSC_SS @S9S_MB_2U_LIB.S9S_MB_2U(SCH_1):HSC_SS    I56 @S9S_MB_2U_LIB.S9S_MB_2U(SCH_1):PAGE303
    32 P12V_AUX @S9S_MB_2U_LIB.S9S_MB_2U(SCH_1):P12V_AUX    I56 @S9S_MB_2U_LIB.S9S_MB_2U(SCH_1):PAGE303
    21 HSC_IMON @S9S_MB_2U_LIB.S9S_MB_2U(SCH_1):HSC_IMON    I56 @S9S_MB_2U_LIB.S9S_MB_2U(SCH_1):PAGE303
    20 HSC_CS @S9S_MB_2U_LIB.S9S_MB_2U(SCH_1):HSC_CS    I56 @S9S_MB_2U_LIB.S9S_MB_2U(SCH_1):PAGE303
    42 P12V_PSU @S9S_MB_2U_LIB.S9S_MB_2U(SCH_1):P12V_PSU    I56 @S9S_MB_2U_LIB.S9S_MB_2U(SCH_1):PAGE303
    36 P12V_AUX @S9S_MB_2U_LIB.S9S_MB_2U(SCH_1):P12V_AUX    I56 @S9S_MB_2U_LIB.S9S_MB_2U(SCH_1):PAGE303
    24 HSC_VOSEN @S9S_MB_2U_LIB.S9S_MB_2U(SCH_1):HSC_VOSEN    I56 @S9S_MB_2U_LIB.S9S_MB_2U(SCH_1):PAGE303
    30 P12V_AUX @S9S_MB_2U_LIB.S9S_MB_2U(SCH_1):P12V_AUX    I56 @S9S_MB_2U_LIB.S9S_MB_2U(SCH_1):PAGE303
     1 P12V_PSU @S9S_MB_2U_LIB.S9S_MB_2U(SCH_1):P12V_PSU    I56 @S9S_MB_2U_LIB.S9S_MB_2U(SCH_1):PAGE303
    44 AGND_HSC @S9S_MB_2U_LIB.S9S_MB_2U(SCH_1):AGND_HSC    I56 @S9S_MB_2U_LIB.S9S_MB_2U(SCH_1):PAGE303
    40 HSC_FLT_TYPE @S9S_MB_2U_LIB.S9S_MB_2U(SCH_1):HSC_FLT_TYPE    I56 @S9S_MB_2U_LIB.S9S_MB_2U(SCH_1):PAGE303
    43 P12V_PSU @S9S_MB_2U_LIB.S9S_MB_2U(SCH_1):P12V_PSU    I56 @S9S_MB_2U_LIB.S9S_MB_2U(SCH_1):PAGE303
     9 HSC_VSENSE @S9S_MB_2U_LIB.S9S_MB_2U(SCH_1):HSC_VSENSE    I56 @S9S_MB_2U_LIB.S9S_MB_2U(SCH_1):PAGE303
    17 HSC_VDD_R @S9S_MB_2U_LIB.S9S_MB_2U(SCH_1):HSC_VDD_R    I56 @S9S_MB_2U_LIB.S9S_MB_2U(SCH_1):PAGE303
    45 HSC_VDD_R @S9S_MB_2U_LIB.S9S_MB_2U(SCH_1):HSC_VDD_R    I56 @S9S_MB_2U_LIB.S9S_MB_2U(SCH_1):PAGE303
    19 HSC_VDD18 @S9S_MB_2U_LIB.S9S_MB_2U(SCH_1):HSC_VDD18    I56 @S9S_MB_2U_LIB.S9S_MB_2U(SCH_1):PAGE303
    23 HSC_ADDR @S9S_MB_2U_LIB.S9S_MB_2U(SCH_1):HSC_ADDR    I56 @S9S_MB_2U_LIB.S9S_MB_2U(SCH_1):PAGE303

PU292 RS31312R-RS31312R,SMLF,IC,AL03A
    20 P12V_E1S_0 @S9S_MB_2U_LIB.S9S_MB_2U(SCH_1):P12V_E1S_0    I49 @S9S_MB_2U_LIB.S9S_MB_2U(SCH_1):PAGE323
 21_22 P12V_AUX @S9S_MB_2U_LIB.S9S_MB_2U(SCH_1):P12V_AUX    I49 @S9S_MB_2U_LIB.S9S_MB_2U(SCH_1):PAGE323
    19 P12V_E1S_0 @S9S_MB_2U_LIB.S9S_MB_2U(SCH_1):P12V_E1S_0    I49 @S9S_MB_2U_LIB.S9S_MB_2U(SCH_1):PAGE323
    18 P12V_E1S_0 @S9S_MB_2U_LIB.S9S_MB_2U(SCH_1):P12V_E1S_0    I49 @S9S_MB_2U_LIB.S9S_MB_2U(SCH_1):PAGE323
    17 P12V_E1S_0 @S9S_MB_2U_LIB.S9S_MB_2U(SCH_1):P12V_E1S_0    I49 @S9S_MB_2U_LIB.S9S_MB_2U(SCH_1):PAGE323
    16 P12V_E1S_0 @S9S_MB_2U_LIB.S9S_MB_2U(SCH_1):P12V_E1S_0    I49 @S9S_MB_2U_LIB.S9S_MB_2U(SCH_1):PAGE323
    15 P12V_E1S_0 @S9S_MB_2U_LIB.S9S_MB_2U(SCH_1):P12V_E1S_0    I49 @S9S_MB_2U_LIB.S9S_MB_2U(SCH_1):PAGE323
    14 P12V_E1S_0 @S9S_MB_2U_LIB.S9S_MB_2U(SCH_1):P12V_E1S_0    I49 @S9S_MB_2U_LIB.S9S_MB_2U(SCH_1):PAGE323
    12 P12V_E1S_AVIN_PD_0 @S9S_MB_2U_LIB.S9S_MB_2U(SCH_1):P12V_E1S_AVIN_PD_0    I49 @S9S_MB_2U_LIB.S9S_MB_2U(SCH_1):PAGE323
    13 P12V_E1S_0 @S9S_MB_2U_LIB.S9S_MB_2U(SCH_1):P12V_E1S_0    I49 @S9S_MB_2U_LIB.S9S_MB_2U(SCH_1):PAGE323
    11 P12V_E1S_OV_FB_0 @S9S_MB_2U_LIB.S9S_MB_2U(SCH_1):P12V_E1S_OV_FB_0    I49 @S9S_MB_2U_LIB.S9S_MB_2U(SCH_1):PAGE323
    10 HP_LVC3_E1S_0_HSC_PWRGD @S9S_MB_2U_LIB.S9S_MB_2U(SCH_1):HP_LVC3_E1S_0_HSC_PWRGD    I49 @S9S_MB_2U_LIB.S9S_MB_2U(SCH_1):PAGE323
     9 P12V_E1S_FLTB_0 @S9S_MB_2U_LIB.S9S_MB_2U(SCH_1):P12V_E1S_FLTB_0    I49 @S9S_MB_2U_LIB.S9S_MB_2U(SCH_1):PAGE323
     8 P12V_E1S_IMON_0 @S9S_MB_2U_LIB.S9S_MB_2U(SCH_1):P12V_E1S_IMON_0    I49 @S9S_MB_2U_LIB.S9S_MB_2U(SCH_1):PAGE323
    23 P12V_AUX @S9S_MB_2U_LIB.S9S_MB_2U(SCH_1):P12V_AUX    I49 @S9S_MB_2U_LIB.S9S_MB_2U(SCH_1):PAGE323
    24 P12V_AUX @S9S_MB_2U_LIB.S9S_MB_2U(SCH_1):P12V_AUX    I49 @S9S_MB_2U_LIB.S9S_MB_2U(SCH_1):PAGE323
    25 P12V_AUX @S9S_MB_2U_LIB.S9S_MB_2U(SCH_1):P12V_AUX    I49 @S9S_MB_2U_LIB.S9S_MB_2U(SCH_1):PAGE323
    26 P12V_AUX @S9S_MB_2U_LIB.S9S_MB_2U(SCH_1):P12V_AUX    I49 @S9S_MB_2U_LIB.S9S_MB_2U(SCH_1):PAGE323
     1 P12V_E1S_EN_0_R2 @S9S_MB_2U_LIB.S9S_MB_2U(SCH_1):P12V_E1S_EN_0_R2    I49 @S9S_MB_2U_LIB.S9S_MB_2U(SCH_1):PAGE323
     2    GND @S9S_MB_2U_LIB.S9S_MB_2U(SCH_1):GND    I49 @S9S_MB_2U_LIB.S9S_MB_2U(SCH_1):PAGE323
     3    GND @S9S_MB_2U_LIB.S9S_MB_2U(SCH_1):GND    I49 @S9S_MB_2U_LIB.S9S_MB_2U(SCH_1):PAGE323
     4 P12V_E1S_TIMER_0 @S9S_MB_2U_LIB.S9S_MB_2U(SCH_1):P12V_E1S_TIMER_0    I49 @S9S_MB_2U_LIB.S9S_MB_2U(SCH_1):PAGE323
     5 P12V_E1S_ISET_0 @S9S_MB_2U_LIB.S9S_MB_2U(SCH_1):P12V_E1S_ISET_0    I49 @S9S_MB_2U_LIB.S9S_MB_2U(SCH_1):PAGE323
     6 P12V_E1S_SS_0 @S9S_MB_2U_LIB.S9S_MB_2U(SCH_1):P12V_E1S_SS_0    I49 @S9S_MB_2U_LIB.S9S_MB_2U(SCH_1):PAGE323
     7    GND @S9S_MB_2U_LIB.S9S_MB_2U(SCH_1):GND    I49 @S9S_MB_2U_LIB.S9S_MB_2U(SCH_1):PAGE323

PU293 MP5016GQHLZ-MP5016GQH-L-Z,SMLFA
     9 P3V3_E1S_EN_0_R2 @S9S_MB_2U_LIB.S9S_MB_2U(SCH_1):P3V3_E1S_EN_0_R2    I31 @S9S_MB_2U_LIB.S9S_MB_2U(SCH_1):PAGE323
     5 P3V3_E1S_MODE_0 @S9S_MB_2U_LIB.S9S_MB_2U(SCH_1):P3V3_E1S_MODE_0    I31 @S9S_MB_2U_LIB.S9S_MB_2U(SCH_1):PAGE323
     4 P3V3_E1S_ILIMIT_0 @S9S_MB_2U_LIB.S9S_MB_2U(SCH_1):P3V3_E1S_ILIMIT_0    I31 @S9S_MB_2U_LIB.S9S_MB_2U(SCH_1):PAGE323
     3    GND @S9S_MB_2U_LIB.S9S_MB_2U(SCH_1):GND    I31 @S9S_MB_2U_LIB.S9S_MB_2U(SCH_1):PAGE323
   1_2 P3V3_AUX @S9S_MB_2U_LIB.S9S_MB_2U(SCH_1):P3V3_AUX    I31 @S9S_MB_2U_LIB.S9S_MB_2U(SCH_1):PAGE323
    10 P3V3_E1S_DVDT_0 @S9S_MB_2U_LIB.S9S_MB_2U(SCH_1):P3V3_E1S_DVDT_0    I31 @S9S_MB_2U_LIB.S9S_MB_2U(SCH_1):PAGE323
     8 P3V3_E1S_GATE_0_PU293 @S9S_MB_2U_LIB.S9S_MB_2U(SCH_1):P3V3_E1S_GATE_0_PU293    I31 @S9S_MB_2U_LIB.S9S_MB_2U(SCH_1):PAGE323
   6_7 P3V3_E1S_0_R @S9S_MB_2U_LIB.S9S_MB_2U(SCH_1):P3V3_E1S_0_R    I31 @S9S_MB_2U_LIB.S9S_MB_2U(SCH_1):PAGE323

PU294 MAX15090BEWIT-MAX15090BEWI+T,SA
    A2 P12V_E1S_VCC_0 @S9S_MB_2U_LIB.S9S_MB_2U(SCH_1):P12V_E1S_VCC_0    I62 @S9S_MB_2U_LIB.S9S_MB_2U(SCH_1):PAGE324
    A3 P12V_AUX @S9S_MB_2U_LIB.S9S_MB_2U(SCH_1):P12V_AUX    I62 @S9S_MB_2U_LIB.S9S_MB_2U(SCH_1):PAGE324
    A5 P12V_AUX @S9S_MB_2U_LIB.S9S_MB_2U(SCH_1):P12V_AUX    I62 @S9S_MB_2U_LIB.S9S_MB_2U(SCH_1):PAGE324
    B3 P12V_AUX @S9S_MB_2U_LIB.S9S_MB_2U(SCH_1):P12V_AUX    I62 @S9S_MB_2U_LIB.S9S_MB_2U(SCH_1):PAGE324
    B5 P12V_AUX @S9S_MB_2U_LIB.S9S_MB_2U(SCH_1):P12V_AUX    I62 @S9S_MB_2U_LIB.S9S_MB_2U(SCH_1):PAGE324
    C3 P12V_AUX @S9S_MB_2U_LIB.S9S_MB_2U(SCH_1):P12V_AUX    I62 @S9S_MB_2U_LIB.S9S_MB_2U(SCH_1):PAGE324
    C5 P12V_AUX @S9S_MB_2U_LIB.S9S_MB_2U(SCH_1):P12V_AUX    I62 @S9S_MB_2U_LIB.S9S_MB_2U(SCH_1):PAGE324
    D5 P12V_AUX @S9S_MB_2U_LIB.S9S_MB_2U(SCH_1):P12V_AUX    I62 @S9S_MB_2U_LIB.S9S_MB_2U(SCH_1):PAGE324
    B1 P12V_E1S_CB_0 @S9S_MB_2U_LIB.S9S_MB_2U(SCH_1):P12V_E1S_CB_0    I62 @S9S_MB_2U_LIB.S9S_MB_2U(SCH_1):PAGE324
    B7    GND @S9S_MB_2U_LIB.S9S_MB_2U(SCH_1):GND    I62 @S9S_MB_2U_LIB.S9S_MB_2U(SCH_1):PAGE324
    D1 P12V_E1S_REG_0 @S9S_MB_2U_LIB.S9S_MB_2U(SCH_1):P12V_E1S_REG_0    I62 @S9S_MB_2U_LIB.S9S_MB_2U(SCH_1):PAGE324
    D2 P12V_E1S_UV_0 @S9S_MB_2U_LIB.S9S_MB_2U(SCH_1):P12V_E1S_UV_0    I62 @S9S_MB_2U_LIB.S9S_MB_2U(SCH_1):PAGE324
    D3 P12V_E1S_OV_0 @S9S_MB_2U_LIB.S9S_MB_2U(SCH_1):P12V_E1S_OV_0    I62 @S9S_MB_2U_LIB.S9S_MB_2U(SCH_1):PAGE324
    A1 P12V_E1S_SENSE_0 @S9S_MB_2U_LIB.S9S_MB_2U(SCH_1):P12V_E1S_SENSE_0    I62 @S9S_MB_2U_LIB.S9S_MB_2U(SCH_1):PAGE324
    A4 P12V_E1S_0 @S9S_MB_2U_LIB.S9S_MB_2U(SCH_1):P12V_E1S_0    I62 @S9S_MB_2U_LIB.S9S_MB_2U(SCH_1):PAGE324
    B4 P12V_E1S_0 @S9S_MB_2U_LIB.S9S_MB_2U(SCH_1):P12V_E1S_0    I62 @S9S_MB_2U_LIB.S9S_MB_2U(SCH_1):PAGE324
    B6 P12V_E1S_0 @S9S_MB_2U_LIB.S9S_MB_2U(SCH_1):P12V_E1S_0    I62 @S9S_MB_2U_LIB.S9S_MB_2U(SCH_1):PAGE324
    C4 P12V_E1S_0 @S9S_MB_2U_LIB.S9S_MB_2U(SCH_1):P12V_E1S_0    I62 @S9S_MB_2U_LIB.S9S_MB_2U(SCH_1):PAGE324
    C6 P12V_E1S_0 @S9S_MB_2U_LIB.S9S_MB_2U(SCH_1):P12V_E1S_0    I62 @S9S_MB_2U_LIB.S9S_MB_2U(SCH_1):PAGE324
    D4 P12V_E1S_0 @S9S_MB_2U_LIB.S9S_MB_2U(SCH_1):P12V_E1S_0    I62 @S9S_MB_2U_LIB.S9S_MB_2U(SCH_1):PAGE324
    D6 P12V_E1S_0 @S9S_MB_2U_LIB.S9S_MB_2U(SCH_1):P12V_E1S_0    I62 @S9S_MB_2U_LIB.S9S_MB_2U(SCH_1):PAGE324
    A6 P12V_E1S_GATE_0 @S9S_MB_2U_LIB.S9S_MB_2U(SCH_1):P12V_E1S_GATE_0    I62 @S9S_MB_2U_LIB.S9S_MB_2U(SCH_1):PAGE324
    A7    GND @S9S_MB_2U_LIB.S9S_MB_2U(SCH_1):GND    I62 @S9S_MB_2U_LIB.S9S_MB_2U(SCH_1):PAGE324
    B2    GND @S9S_MB_2U_LIB.S9S_MB_2U(SCH_1):GND    I62 @S9S_MB_2U_LIB.S9S_MB_2U(SCH_1):PAGE324
    C1    GND @S9S_MB_2U_LIB.S9S_MB_2U(SCH_1):GND    I62 @S9S_MB_2U_LIB.S9S_MB_2U(SCH_1):PAGE324
    C2    GND @S9S_MB_2U_LIB.S9S_MB_2U(SCH_1):GND    I62 @S9S_MB_2U_LIB.S9S_MB_2U(SCH_1):PAGE324
    C7 P12V_E1S_FAULT_0 @S9S_MB_2U_LIB.S9S_MB_2U(SCH_1):P12V_E1S_FAULT_0    I62 @S9S_MB_2U_LIB.S9S_MB_2U(SCH_1):PAGE324
    D7 P12V_E1S_PWRGD_0 @S9S_MB_2U_LIB.S9S_MB_2U(SCH_1):P12V_E1S_PWRGD_0    I62 @S9S_MB_2U_LIB.S9S_MB_2U(SCH_1):PAGE324

PU295 MAX15090BEWIT-MAX15090BEWI+T,SB
    A2 P3V3_E1S_VCC_0 @S9S_MB_2U_LIB.S9S_MB_2U(SCH_1):P3V3_E1S_VCC_0    I35 @S9S_MB_2U_LIB.S9S_MB_2U(SCH_1):PAGE324
    A3 P3V3_AUX @S9S_MB_2U_LIB.S9S_MB_2U(SCH_1):P3V3_AUX    I35 @S9S_MB_2U_LIB.S9S_MB_2U(SCH_1):PAGE324
    A5 P3V3_AUX @S9S_MB_2U_LIB.S9S_MB_2U(SCH_1):P3V3_AUX    I35 @S9S_MB_2U_LIB.S9S_MB_2U(SCH_1):PAGE324
    B3 P3V3_AUX @S9S_MB_2U_LIB.S9S_MB_2U(SCH_1):P3V3_AUX    I35 @S9S_MB_2U_LIB.S9S_MB_2U(SCH_1):PAGE324
    B5 P3V3_AUX @S9S_MB_2U_LIB.S9S_MB_2U(SCH_1):P3V3_AUX    I35 @S9S_MB_2U_LIB.S9S_MB_2U(SCH_1):PAGE324
    C3 P3V3_AUX @S9S_MB_2U_LIB.S9S_MB_2U(SCH_1):P3V3_AUX    I35 @S9S_MB_2U_LIB.S9S_MB_2U(SCH_1):PAGE324
    C5 P3V3_AUX @S9S_MB_2U_LIB.S9S_MB_2U(SCH_1):P3V3_AUX    I35 @S9S_MB_2U_LIB.S9S_MB_2U(SCH_1):PAGE324
    D5 P3V3_AUX @S9S_MB_2U_LIB.S9S_MB_2U(SCH_1):P3V3_AUX    I35 @S9S_MB_2U_LIB.S9S_MB_2U(SCH_1):PAGE324
    B1 P3V3_E1S_CB_0 @S9S_MB_2U_LIB.S9S_MB_2U(SCH_1):P3V3_E1S_CB_0    I35 @S9S_MB_2U_LIB.S9S_MB_2U(SCH_1):PAGE324
    B7    GND @S9S_MB_2U_LIB.S9S_MB_2U(SCH_1):GND    I35 @S9S_MB_2U_LIB.S9S_MB_2U(SCH_1):PAGE324
    D1 P3V3_E1S_REG_0 @S9S_MB_2U_LIB.S9S_MB_2U(SCH_1):P3V3_E1S_REG_0    I35 @S9S_MB_2U_LIB.S9S_MB_2U(SCH_1):PAGE324
    D2 P3V3_E1S_UV_0 @S9S_MB_2U_LIB.S9S_MB_2U(SCH_1):P3V3_E1S_UV_0    I35 @S9S_MB_2U_LIB.S9S_MB_2U(SCH_1):PAGE324
    D3 P3V3_E1S_OV_0 @S9S_MB_2U_LIB.S9S_MB_2U(SCH_1):P3V3_E1S_OV_0    I35 @S9S_MB_2U_LIB.S9S_MB_2U(SCH_1):PAGE324
    A1 P3V3_E1S_SENSE_0 @S9S_MB_2U_LIB.S9S_MB_2U(SCH_1):P3V3_E1S_SENSE_0    I35 @S9S_MB_2U_LIB.S9S_MB_2U(SCH_1):PAGE324
    A4 P3V3_E1S_0_R @S9S_MB_2U_LIB.S9S_MB_2U(SCH_1):P3V3_E1S_0_R    I35 @S9S_MB_2U_LIB.S9S_MB_2U(SCH_1):PAGE324
    B4 P3V3_E1S_0_R @S9S_MB_2U_LIB.S9S_MB_2U(SCH_1):P3V3_E1S_0_R    I35 @S9S_MB_2U_LIB.S9S_MB_2U(SCH_1):PAGE324
    B6 P3V3_E1S_0_R @S9S_MB_2U_LIB.S9S_MB_2U(SCH_1):P3V3_E1S_0_R    I35 @S9S_MB_2U_LIB.S9S_MB_2U(SCH_1):PAGE324
    C4 P3V3_E1S_0_R @S9S_MB_2U_LIB.S9S_MB_2U(SCH_1):P3V3_E1S_0_R    I35 @S9S_MB_2U_LIB.S9S_MB_2U(SCH_1):PAGE324
    C6 P3V3_E1S_0_R @S9S_MB_2U_LIB.S9S_MB_2U(SCH_1):P3V3_E1S_0_R    I35 @S9S_MB_2U_LIB.S9S_MB_2U(SCH_1):PAGE324
    D4 P3V3_E1S_0_R @S9S_MB_2U_LIB.S9S_MB_2U(SCH_1):P3V3_E1S_0_R    I35 @S9S_MB_2U_LIB.S9S_MB_2U(SCH_1):PAGE324
    D6 P3V3_E1S_0_R @S9S_MB_2U_LIB.S9S_MB_2U(SCH_1):P3V3_E1S_0_R    I35 @S9S_MB_2U_LIB.S9S_MB_2U(SCH_1):PAGE324
    A6 P3V3_E1S_GATE_0 @S9S_MB_2U_LIB.S9S_MB_2U(SCH_1):P3V3_E1S_GATE_0    I35 @S9S_MB_2U_LIB.S9S_MB_2U(SCH_1):PAGE324
    A7    GND @S9S_MB_2U_LIB.S9S_MB_2U(SCH_1):GND    I35 @S9S_MB_2U_LIB.S9S_MB_2U(SCH_1):PAGE324
    B2    GND @S9S_MB_2U_LIB.S9S_MB_2U(SCH_1):GND    I35 @S9S_MB_2U_LIB.S9S_MB_2U(SCH_1):PAGE324
    C1    GND @S9S_MB_2U_LIB.S9S_MB_2U(SCH_1):GND    I35 @S9S_MB_2U_LIB.S9S_MB_2U(SCH_1):PAGE324
    C2    GND @S9S_MB_2U_LIB.S9S_MB_2U(SCH_1):GND    I35 @S9S_MB_2U_LIB.S9S_MB_2U(SCH_1):PAGE324
    C7 P3V3_E1S_FAULT_0 @S9S_MB_2U_LIB.S9S_MB_2U(SCH_1):P3V3_E1S_FAULT_0    I35 @S9S_MB_2U_LIB.S9S_MB_2U(SCH_1):PAGE324
    D7 P3V3_E1S_PWRGD_0 @S9S_MB_2U_LIB.S9S_MB_2U(SCH_1):P3V3_E1S_PWRGD_0    I35 @S9S_MB_2U_LIB.S9S_MB_2U(SCH_1):PAGE324

PU296 MP5991GLUZ-MP5991GLU-Z,SMLF,ICA
     9 P12V_PSU @S9S_MB_2U_LIB.S9S_MB_2U(SCH_1):P12V_PSU    I35 @S9S_MB_2U_LIB.S9S_MB_2U(SCH_1):PAGE325
    10 P12V_PSU @S9S_MB_2U_LIB.S9S_MB_2U(SCH_1):P12V_PSU    I35 @S9S_MB_2U_LIB.S9S_MB_2U(SCH_1):PAGE325
    11 P12V_PSU @S9S_MB_2U_LIB.S9S_MB_2U(SCH_1):P12V_PSU    I35 @S9S_MB_2U_LIB.S9S_MB_2U(SCH_1):PAGE325
    12 P12V_PSU @S9S_MB_2U_LIB.S9S_MB_2U(SCH_1):P12V_PSU    I35 @S9S_MB_2U_LIB.S9S_MB_2U(SCH_1):PAGE325
    13 P12V_PSU @S9S_MB_2U_LIB.S9S_MB_2U(SCH_1):P12V_PSU    I35 @S9S_MB_2U_LIB.S9S_MB_2U(SCH_1):PAGE325
     4 HSC_ON @S9S_MB_2U_LIB.S9S_MB_2U(SCH_1):HSC_ON    I35 @S9S_MB_2U_LIB.S9S_MB_2U(SCH_1):PAGE325
    24 HSC_OCREF @S9S_MB_2U_LIB.S9S_MB_2U(SCH_1):HSC_OCREF    I35 @S9S_MB_2U_LIB.S9S_MB_2U(SCH_1):PAGE325
    23 HSC_CS_3 @S9S_MB_2U_LIB.S9S_MB_2U(SCH_1):HSC_CS_3    I35 @S9S_MB_2U_LIB.S9S_MB_2U(SCH_1):PAGE325
    22 HSC_IMON @S9S_MB_2U_LIB.S9S_MB_2U(SCH_1):HSC_IMON    I35 @S9S_MB_2U_LIB.S9S_MB_2U(SCH_1):PAGE325
    21 HSC_VDD_R_3 @S9S_MB_2U_LIB.S9S_MB_2U(SCH_1):HSC_VDD_R_3    I35 @S9S_MB_2U_LIB.S9S_MB_2U(SCH_1):PAGE325
    20 AGND_HSC @S9S_MB_2U_LIB.S9S_MB_2U(SCH_1):AGND_HSC    I35 @S9S_MB_2U_LIB.S9S_MB_2U(SCH_1):PAGE325
    19 HSC_SS @S9S_MB_2U_LIB.S9S_MB_2U(SCH_1):HSC_SS    I35 @S9S_MB_2U_LIB.S9S_MB_2U(SCH_1):PAGE325
     5 HSC_FAULT @S9S_MB_2U_LIB.S9S_MB_2U(SCH_1):HSC_FAULT    I35 @S9S_MB_2U_LIB.S9S_MB_2U(SCH_1):PAGE325
    18 HSC_VTEMP @S9S_MB_2U_LIB.S9S_MB_2U(SCH_1):HSC_VTEMP    I35 @S9S_MB_2U_LIB.S9S_MB_2U(SCH_1):PAGE325
     1 P12V_AUX @S9S_MB_2U_LIB.S9S_MB_2U(SCH_1):P12V_AUX    I35 @S9S_MB_2U_LIB.S9S_MB_2U(SCH_1):PAGE325
     2 P12V_AUX @S9S_MB_2U_LIB.S9S_MB_2U(SCH_1):P12V_AUX    I35 @S9S_MB_2U_LIB.S9S_MB_2U(SCH_1):PAGE325
    25 P12V_AUX @S9S_MB_2U_LIB.S9S_MB_2U(SCH_1):P12V_AUX    I35 @S9S_MB_2U_LIB.S9S_MB_2U(SCH_1):PAGE325
    26 P12V_AUX @S9S_MB_2U_LIB.S9S_MB_2U(SCH_1):P12V_AUX    I35 @S9S_MB_2U_LIB.S9S_MB_2U(SCH_1):PAGE325
     3 HSC_D_OC_3 @S9S_MB_2U_LIB.S9S_MB_2U(SCH_1):HSC_D_OC_3    I35 @S9S_MB_2U_LIB.S9S_MB_2U(SCH_1):PAGE325
    14 P12V_PSU @S9S_MB_2U_LIB.S9S_MB_2U(SCH_1):P12V_PSU    I35 @S9S_MB_2U_LIB.S9S_MB_2U(SCH_1):PAGE325
    15 P12V_PSU @S9S_MB_2U_LIB.S9S_MB_2U(SCH_1):P12V_PSU    I35 @S9S_MB_2U_LIB.S9S_MB_2U(SCH_1):PAGE325
    16 P12V_PSU @S9S_MB_2U_LIB.S9S_MB_2U(SCH_1):P12V_PSU    I35 @S9S_MB_2U_LIB.S9S_MB_2U(SCH_1):PAGE325
    33 P12V_PSU @S9S_MB_2U_LIB.S9S_MB_2U(SCH_1):P12V_PSU    I35 @S9S_MB_2U_LIB.S9S_MB_2U(SCH_1):PAGE325
    27 P12V_AUX @S9S_MB_2U_LIB.S9S_MB_2U(SCH_1):P12V_AUX    I35 @S9S_MB_2U_LIB.S9S_MB_2U(SCH_1):PAGE325
    28 P12V_AUX @S9S_MB_2U_LIB.S9S_MB_2U(SCH_1):P12V_AUX    I35 @S9S_MB_2U_LIB.S9S_MB_2U(SCH_1):PAGE325
    29 P12V_AUX @S9S_MB_2U_LIB.S9S_MB_2U(SCH_1):P12V_AUX    I35 @S9S_MB_2U_LIB.S9S_MB_2U(SCH_1):PAGE325
    30 P12V_AUX @S9S_MB_2U_LIB.S9S_MB_2U(SCH_1):P12V_AUX    I35 @S9S_MB_2U_LIB.S9S_MB_2U(SCH_1):PAGE325
    31 P12V_AUX @S9S_MB_2U_LIB.S9S_MB_2U(SCH_1):P12V_AUX    I35 @S9S_MB_2U_LIB.S9S_MB_2U(SCH_1):PAGE325
    32 P12V_AUX @S9S_MB_2U_LIB.S9S_MB_2U(SCH_1):P12V_AUX    I35 @S9S_MB_2U_LIB.S9S_MB_2U(SCH_1):PAGE325
     8 HSC_MODE_3 @S9S_MB_2U_LIB.S9S_MB_2U(SCH_1):HSC_MODE_3    I35 @S9S_MB_2U_LIB.S9S_MB_2U(SCH_1):PAGE325
    17 HSC_SCREF_3 @S9S_MB_2U_LIB.S9S_MB_2U(SCH_1):HSC_SCREF_3    I35 @S9S_MB_2U_LIB.S9S_MB_2U(SCH_1):PAGE325
     6 HSC_FLT_TYPE_3 @S9S_MB_2U_LIB.S9S_MB_2U(SCH_1):HSC_FLT_TYPE_3    I35 @S9S_MB_2U_LIB.S9S_MB_2U(SCH_1):PAGE325
     7 HSC_NC1_3 @S9S_MB_2U_LIB.S9S_MB_2U(SCH_1):HSC_NC1_3    I35 @S9S_MB_2U_LIB.S9S_MB_2U(SCH_1):PAGE325

PU297 MP5991GLUZ-MP5991GLU-Z,SMLF,ICA
     9 P12V_PSU @S9S_MB_2U_LIB.S9S_MB_2U(SCH_1):P12V_PSU    I17 @S9S_MB_2U_LIB.S9S_MB_2U(SCH_1):PAGE325
    10 P12V_PSU @S9S_MB_2U_LIB.S9S_MB_2U(SCH_1):P12V_PSU    I17 @S9S_MB_2U_LIB.S9S_MB_2U(SCH_1):PAGE325
    11 P12V_PSU @S9S_MB_2U_LIB.S9S_MB_2U(SCH_1):P12V_PSU    I17 @S9S_MB_2U_LIB.S9S_MB_2U(SCH_1):PAGE325
    12 P12V_PSU @S9S_MB_2U_LIB.S9S_MB_2U(SCH_1):P12V_PSU    I17 @S9S_MB_2U_LIB.S9S_MB_2U(SCH_1):PAGE325
    13 P12V_PSU @S9S_MB_2U_LIB.S9S_MB_2U(SCH_1):P12V_PSU    I17 @S9S_MB_2U_LIB.S9S_MB_2U(SCH_1):PAGE325
     4 HSC_ON @S9S_MB_2U_LIB.S9S_MB_2U(SCH_1):HSC_ON    I17 @S9S_MB_2U_LIB.S9S_MB_2U(SCH_1):PAGE325
    24 HSC_OCREF @S9S_MB_2U_LIB.S9S_MB_2U(SCH_1):HSC_OCREF    I17 @S9S_MB_2U_LIB.S9S_MB_2U(SCH_1):PAGE325
    23 HSC_CS_4 @S9S_MB_2U_LIB.S9S_MB_2U(SCH_1):HSC_CS_4    I17 @S9S_MB_2U_LIB.S9S_MB_2U(SCH_1):PAGE325
    22 HSC_IMON @S9S_MB_2U_LIB.S9S_MB_2U(SCH_1):HSC_IMON    I17 @S9S_MB_2U_LIB.S9S_MB_2U(SCH_1):PAGE325
    21 HSC_VDD_R_4 @S9S_MB_2U_LIB.S9S_MB_2U(SCH_1):HSC_VDD_R_4    I17 @S9S_MB_2U_LIB.S9S_MB_2U(SCH_1):PAGE325
    20 AGND_HSC @S9S_MB_2U_LIB.S9S_MB_2U(SCH_1):AGND_HSC    I17 @S9S_MB_2U_LIB.S9S_MB_2U(SCH_1):PAGE325
    19 HSC_SS @S9S_MB_2U_LIB.S9S_MB_2U(SCH_1):HSC_SS    I17 @S9S_MB_2U_LIB.S9S_MB_2U(SCH_1):PAGE325
     5 HSC_FAULT @S9S_MB_2U_LIB.S9S_MB_2U(SCH_1):HSC_FAULT    I17 @S9S_MB_2U_LIB.S9S_MB_2U(SCH_1):PAGE325
    18 HSC_VTEMP @S9S_MB_2U_LIB.S9S_MB_2U(SCH_1):HSC_VTEMP    I17 @S9S_MB_2U_LIB.S9S_MB_2U(SCH_1):PAGE325
     1 P12V_AUX @S9S_MB_2U_LIB.S9S_MB_2U(SCH_1):P12V_AUX    I17 @S9S_MB_2U_LIB.S9S_MB_2U(SCH_1):PAGE325
     2 P12V_AUX @S9S_MB_2U_LIB.S9S_MB_2U(SCH_1):P12V_AUX    I17 @S9S_MB_2U_LIB.S9S_MB_2U(SCH_1):PAGE325
    25 P12V_AUX @S9S_MB_2U_LIB.S9S_MB_2U(SCH_1):P12V_AUX    I17 @S9S_MB_2U_LIB.S9S_MB_2U(SCH_1):PAGE325
    26 P12V_AUX @S9S_MB_2U_LIB.S9S_MB_2U(SCH_1):P12V_AUX    I17 @S9S_MB_2U_LIB.S9S_MB_2U(SCH_1):PAGE325
     3 HSC_D_OC_4 @S9S_MB_2U_LIB.S9S_MB_2U(SCH_1):HSC_D_OC_4    I17 @S9S_MB_2U_LIB.S9S_MB_2U(SCH_1):PAGE325
    14 P12V_PSU @S9S_MB_2U_LIB.S9S_MB_2U(SCH_1):P12V_PSU    I17 @S9S_MB_2U_LIB.S9S_MB_2U(SCH_1):PAGE325
    15 P12V_PSU @S9S_MB_2U_LIB.S9S_MB_2U(SCH_1):P12V_PSU    I17 @S9S_MB_2U_LIB.S9S_MB_2U(SCH_1):PAGE325
    16 P12V_PSU @S9S_MB_2U_LIB.S9S_MB_2U(SCH_1):P12V_PSU    I17 @S9S_MB_2U_LIB.S9S_MB_2U(SCH_1):PAGE325
    33 P12V_PSU @S9S_MB_2U_LIB.S9S_MB_2U(SCH_1):P12V_PSU    I17 @S9S_MB_2U_LIB.S9S_MB_2U(SCH_1):PAGE325
    27 P12V_AUX @S9S_MB_2U_LIB.S9S_MB_2U(SCH_1):P12V_AUX    I17 @S9S_MB_2U_LIB.S9S_MB_2U(SCH_1):PAGE325
    28 P12V_AUX @S9S_MB_2U_LIB.S9S_MB_2U(SCH_1):P12V_AUX    I17 @S9S_MB_2U_LIB.S9S_MB_2U(SCH_1):PAGE325
    29 P12V_AUX @S9S_MB_2U_LIB.S9S_MB_2U(SCH_1):P12V_AUX    I17 @S9S_MB_2U_LIB.S9S_MB_2U(SCH_1):PAGE325
    30 P12V_AUX @S9S_MB_2U_LIB.S9S_MB_2U(SCH_1):P12V_AUX    I17 @S9S_MB_2U_LIB.S9S_MB_2U(SCH_1):PAGE325
    31 P12V_AUX @S9S_MB_2U_LIB.S9S_MB_2U(SCH_1):P12V_AUX    I17 @S9S_MB_2U_LIB.S9S_MB_2U(SCH_1):PAGE325
    32 P12V_AUX @S9S_MB_2U_LIB.S9S_MB_2U(SCH_1):P12V_AUX    I17 @S9S_MB_2U_LIB.S9S_MB_2U(SCH_1):PAGE325
     8 HSC_MODE_4 @S9S_MB_2U_LIB.S9S_MB_2U(SCH_1):HSC_MODE_4    I17 @S9S_MB_2U_LIB.S9S_MB_2U(SCH_1):PAGE325
    17 HSC_SCREF_4 @S9S_MB_2U_LIB.S9S_MB_2U(SCH_1):HSC_SCREF_4    I17 @S9S_MB_2U_LIB.S9S_MB_2U(SCH_1):PAGE325
     6 HSC_FLT_TYPE_4 @S9S_MB_2U_LIB.S9S_MB_2U(SCH_1):HSC_FLT_TYPE_4    I17 @S9S_MB_2U_LIB.S9S_MB_2U(SCH_1):PAGE325
     7 HSC_NC1_4 @S9S_MB_2U_LIB.S9S_MB_2U(SCH_1):HSC_NC1_4    I17 @S9S_MB_2U_LIB.S9S_MB_2U(SCH_1):PAGE325

PU299 RS31312R-RS31312R,SMLF,IC,AL03A
    20 P12V_SCM_R @S9S_MB_2U_LIB.S9S_MB_2U(SCH_1):P12V_SCM_R    I90 @S9S_MB_2U_LIB.S9S_MB_2U(SCH_1):PAGE229
 21_22 P12V_AUX @S9S_MB_2U_LIB.S9S_MB_2U(SCH_1):P12V_AUX    I90 @S9S_MB_2U_LIB.S9S_MB_2U(SCH_1):PAGE229
    19 P12V_SCM_R @S9S_MB_2U_LIB.S9S_MB_2U(SCH_1):P12V_SCM_R    I90 @S9S_MB_2U_LIB.S9S_MB_2U(SCH_1):PAGE229
    18 P12V_SCM_R @S9S_MB_2U_LIB.S9S_MB_2U(SCH_1):P12V_SCM_R    I90 @S9S_MB_2U_LIB.S9S_MB_2U(SCH_1):PAGE229
    17 P12V_SCM_R @S9S_MB_2U_LIB.S9S_MB_2U(SCH_1):P12V_SCM_R    I90 @S9S_MB_2U_LIB.S9S_MB_2U(SCH_1):PAGE229
    16 P12V_SCM_R @S9S_MB_2U_LIB.S9S_MB_2U(SCH_1):P12V_SCM_R    I90 @S9S_MB_2U_LIB.S9S_MB_2U(SCH_1):PAGE229
    15 P12V_SCM_R @S9S_MB_2U_LIB.S9S_MB_2U(SCH_1):P12V_SCM_R    I90 @S9S_MB_2U_LIB.S9S_MB_2U(SCH_1):PAGE229
    14 P12V_SCM_R @S9S_MB_2U_LIB.S9S_MB_2U(SCH_1):P12V_SCM_R    I90 @S9S_MB_2U_LIB.S9S_MB_2U(SCH_1):PAGE229
    12 P12V_SCM_AVIN_PD @S9S_MB_2U_LIB.S9S_MB_2U(SCH_1):P12V_SCM_AVIN_PD    I90 @S9S_MB_2U_LIB.S9S_MB_2U(SCH_1):PAGE229
    13 P12V_SCM_R @S9S_MB_2U_LIB.S9S_MB_2U(SCH_1):P12V_SCM_R    I90 @S9S_MB_2U_LIB.S9S_MB_2U(SCH_1):PAGE229
    11 P12V_SCM_OV_FB @S9S_MB_2U_LIB.S9S_MB_2U(SCH_1):P12V_SCM_OV_FB    I90 @S9S_MB_2U_LIB.S9S_MB_2U(SCH_1):PAGE229
    10 HP_LVC3_SCM_HSC_PWRGD_R @S9S_MB_2U_LIB.S9S_MB_2U(SCH_1):HP_LVC3_SCM_HSC_PWRGD_R    I90 @S9S_MB_2U_LIB.S9S_MB_2U(SCH_1):PAGE229
     9 P12V_SCM_FLTB_N @S9S_MB_2U_LIB.S9S_MB_2U(SCH_1):P12V_SCM_FLTB_N    I90 @S9S_MB_2U_LIB.S9S_MB_2U(SCH_1):PAGE229
     8 P12V_SCM_IMON @S9S_MB_2U_LIB.S9S_MB_2U(SCH_1):P12V_SCM_IMON    I90 @S9S_MB_2U_LIB.S9S_MB_2U(SCH_1):PAGE229
    23 P12V_AUX @S9S_MB_2U_LIB.S9S_MB_2U(SCH_1):P12V_AUX    I90 @S9S_MB_2U_LIB.S9S_MB_2U(SCH_1):PAGE229
    24 P12V_AUX @S9S_MB_2U_LIB.S9S_MB_2U(SCH_1):P12V_AUX    I90 @S9S_MB_2U_LIB.S9S_MB_2U(SCH_1):PAGE229
    25 P12V_AUX @S9S_MB_2U_LIB.S9S_MB_2U(SCH_1):P12V_AUX    I90 @S9S_MB_2U_LIB.S9S_MB_2U(SCH_1):PAGE229
    26 P12V_AUX @S9S_MB_2U_LIB.S9S_MB_2U(SCH_1):P12V_AUX    I90 @S9S_MB_2U_LIB.S9S_MB_2U(SCH_1):PAGE229
     1 P12V_SCM_EN_R2 @S9S_MB_2U_LIB.S9S_MB_2U(SCH_1):P12V_SCM_EN_R2    I90 @S9S_MB_2U_LIB.S9S_MB_2U(SCH_1):PAGE229
     2    GND @S9S_MB_2U_LIB.S9S_MB_2U(SCH_1):GND    I90 @S9S_MB_2U_LIB.S9S_MB_2U(SCH_1):PAGE229
     3    GND @S9S_MB_2U_LIB.S9S_MB_2U(SCH_1):GND    I90 @S9S_MB_2U_LIB.S9S_MB_2U(SCH_1):PAGE229
     4 P12V_SCM_TIMER @S9S_MB_2U_LIB.S9S_MB_2U(SCH_1):P12V_SCM_TIMER    I90 @S9S_MB_2U_LIB.S9S_MB_2U(SCH_1):PAGE229
     5 P12V_SCM_ISET @S9S_MB_2U_LIB.S9S_MB_2U(SCH_1):P12V_SCM_ISET    I90 @S9S_MB_2U_LIB.S9S_MB_2U(SCH_1):PAGE229
     6 P12V_SCM_SS @S9S_MB_2U_LIB.S9S_MB_2U(SCH_1):P12V_SCM_SS    I90 @S9S_MB_2U_LIB.S9S_MB_2U(SCH_1):PAGE229
     7    GND @S9S_MB_2U_LIB.S9S_MB_2U(SCH_1):GND    I90 @S9S_MB_2U_LIB.S9S_MB_2U(SCH_1):PAGE229

PU300 MAX15090BEWIT-MAX15090BEWI+T,SA
    A2 P12V_SCM_VCC @S9S_MB_2U_LIB.S9S_MB_2U(SCH_1):P12V_SCM_VCC    I69 @S9S_MB_2U_LIB.S9S_MB_2U(SCH_1):PAGE229
    A3 P12V_AUX @S9S_MB_2U_LIB.S9S_MB_2U(SCH_1):P12V_AUX    I69 @S9S_MB_2U_LIB.S9S_MB_2U(SCH_1):PAGE229
    A5 P12V_AUX @S9S_MB_2U_LIB.S9S_MB_2U(SCH_1):P12V_AUX    I69 @S9S_MB_2U_LIB.S9S_MB_2U(SCH_1):PAGE229
    B3 P12V_AUX @S9S_MB_2U_LIB.S9S_MB_2U(SCH_1):P12V_AUX    I69 @S9S_MB_2U_LIB.S9S_MB_2U(SCH_1):PAGE229
    B5 P12V_AUX @S9S_MB_2U_LIB.S9S_MB_2U(SCH_1):P12V_AUX    I69 @S9S_MB_2U_LIB.S9S_MB_2U(SCH_1):PAGE229
    C3 P12V_AUX @S9S_MB_2U_LIB.S9S_MB_2U(SCH_1):P12V_AUX    I69 @S9S_MB_2U_LIB.S9S_MB_2U(SCH_1):PAGE229
    C5 P12V_AUX @S9S_MB_2U_LIB.S9S_MB_2U(SCH_1):P12V_AUX    I69 @S9S_MB_2U_LIB.S9S_MB_2U(SCH_1):PAGE229
    D5 P12V_AUX @S9S_MB_2U_LIB.S9S_MB_2U(SCH_1):P12V_AUX    I69 @S9S_MB_2U_LIB.S9S_MB_2U(SCH_1):PAGE229
    B1 P12V_SCM_CB @S9S_MB_2U_LIB.S9S_MB_2U(SCH_1):P12V_SCM_CB    I69 @S9S_MB_2U_LIB.S9S_MB_2U(SCH_1):PAGE229
    B7    GND @S9S_MB_2U_LIB.S9S_MB_2U(SCH_1):GND    I69 @S9S_MB_2U_LIB.S9S_MB_2U(SCH_1):PAGE229
    D1 P12V_SCM_REG @S9S_MB_2U_LIB.S9S_MB_2U(SCH_1):P12V_SCM_REG    I69 @S9S_MB_2U_LIB.S9S_MB_2U(SCH_1):PAGE229
    D2 P12V_SCM_UV @S9S_MB_2U_LIB.S9S_MB_2U(SCH_1):P12V_SCM_UV    I69 @S9S_MB_2U_LIB.S9S_MB_2U(SCH_1):PAGE229
    D3 P12V_SCM_OV @S9S_MB_2U_LIB.S9S_MB_2U(SCH_1):P12V_SCM_OV    I69 @S9S_MB_2U_LIB.S9S_MB_2U(SCH_1):PAGE229
    A1 P12V_SCM_SENSE @S9S_MB_2U_LIB.S9S_MB_2U(SCH_1):P12V_SCM_SENSE    I69 @S9S_MB_2U_LIB.S9S_MB_2U(SCH_1):PAGE229
    A4 P12V_SCM_R @S9S_MB_2U_LIB.S9S_MB_2U(SCH_1):P12V_SCM_R    I69 @S9S_MB_2U_LIB.S9S_MB_2U(SCH_1):PAGE229
    B4 P12V_SCM_R @S9S_MB_2U_LIB.S9S_MB_2U(SCH_1):P12V_SCM_R    I69 @S9S_MB_2U_LIB.S9S_MB_2U(SCH_1):PAGE229
    B6 P12V_SCM_R @S9S_MB_2U_LIB.S9S_MB_2U(SCH_1):P12V_SCM_R    I69 @S9S_MB_2U_LIB.S9S_MB_2U(SCH_1):PAGE229
    C4 P12V_SCM_R @S9S_MB_2U_LIB.S9S_MB_2U(SCH_1):P12V_SCM_R    I69 @S9S_MB_2U_LIB.S9S_MB_2U(SCH_1):PAGE229
    C6 P12V_SCM_R @S9S_MB_2U_LIB.S9S_MB_2U(SCH_1):P12V_SCM_R    I69 @S9S_MB_2U_LIB.S9S_MB_2U(SCH_1):PAGE229
    D4 P12V_SCM_R @S9S_MB_2U_LIB.S9S_MB_2U(SCH_1):P12V_SCM_R    I69 @S9S_MB_2U_LIB.S9S_MB_2U(SCH_1):PAGE229
    D6 P12V_SCM_R @S9S_MB_2U_LIB.S9S_MB_2U(SCH_1):P12V_SCM_R    I69 @S9S_MB_2U_LIB.S9S_MB_2U(SCH_1):PAGE229
    A6 P12V_SCM_GATE @S9S_MB_2U_LIB.S9S_MB_2U(SCH_1):P12V_SCM_GATE    I69 @S9S_MB_2U_LIB.S9S_MB_2U(SCH_1):PAGE229
    A7    GND @S9S_MB_2U_LIB.S9S_MB_2U(SCH_1):GND    I69 @S9S_MB_2U_LIB.S9S_MB_2U(SCH_1):PAGE229
    B2    GND @S9S_MB_2U_LIB.S9S_MB_2U(SCH_1):GND    I69 @S9S_MB_2U_LIB.S9S_MB_2U(SCH_1):PAGE229
    C1    GND @S9S_MB_2U_LIB.S9S_MB_2U(SCH_1):GND    I69 @S9S_MB_2U_LIB.S9S_MB_2U(SCH_1):PAGE229
    C2    GND @S9S_MB_2U_LIB.S9S_MB_2U(SCH_1):GND    I69 @S9S_MB_2U_LIB.S9S_MB_2U(SCH_1):PAGE229
    C7 P12V_SCM_FAULT_N @S9S_MB_2U_LIB.S9S_MB_2U(SCH_1):P12V_SCM_FAULT_N    I69 @S9S_MB_2U_LIB.S9S_MB_2U(SCH_1):PAGE229
    D7 P12V_SCM_PWRGD @S9S_MB_2U_LIB.S9S_MB_2U(SCH_1):P12V_SCM_PWRGD    I69 @S9S_MB_2U_LIB.S9S_MB_2U(SCH_1):PAGE229

 Q15 MOSFET_NCH_DUAL-PJT138K,SMLF,IA
     1    GND @S9S_MB_2U_LIB.S9S_MB_2U(SCH_1):GND   I104 @S9S_MB_2U_LIB.S9S_MB_2U(SCH_1):PAGE223
     2 FM_SMB_PEHPCPU0_PCIE_ALERT_R_N @S9S_MB_2U_LIB.S9S_MB_2U(SCH_1):FM_SMB_PEHPCPU0_PCIE_ALERT_R_N   I104 @S9S_MB_2U_LIB.S9S_MB_2U(SCH_1):PAGE223
     6 FM_SMB_CPU0_ALERT_R1 @S9S_MB_2U_LIB.S9S_MB_2U(SCH_1):FM_SMB_CPU0_ALERT_R1   I104 @S9S_MB_2U_LIB.S9S_MB_2U(SCH_1):PAGE223
     3 FM_PEHPCPU0_ALERT_N @S9S_MB_2U_LIB.S9S_MB_2U(SCH_1):FM_PEHPCPU0_ALERT_N   I108 @S9S_MB_2U_LIB.S9S_MB_2U(SCH_1):PAGE223
     5 FM_SMB_CPU0_ALERT_R1 @S9S_MB_2U_LIB.S9S_MB_2U(SCH_1):FM_SMB_CPU0_ALERT_R1   I108 @S9S_MB_2U_LIB.S9S_MB_2U(SCH_1):PAGE223
     4    GND @S9S_MB_2U_LIB.S9S_MB_2U(SCH_1):GND   I108 @S9S_MB_2U_LIB.S9S_MB_2U(SCH_1):PAGE223

 Q16 MOSFET_NCH_DUAL-PJT138K,SMLF,IA
     1    GND @S9S_MB_2U_LIB.S9S_MB_2U(SCH_1):GND   I106 @S9S_MB_2U_LIB.S9S_MB_2U(SCH_1):PAGE223
     2 FM_SMB_PEHPCPU1_PCIE_ALERT_R_N @S9S_MB_2U_LIB.S9S_MB_2U(SCH_1):FM_SMB_PEHPCPU1_PCIE_ALERT_R_N   I106 @S9S_MB_2U_LIB.S9S_MB_2U(SCH_1):PAGE223
     6 FM_SMB_CPU1_ALERT_R1 @S9S_MB_2U_LIB.S9S_MB_2U(SCH_1):FM_SMB_CPU1_ALERT_R1   I106 @S9S_MB_2U_LIB.S9S_MB_2U(SCH_1):PAGE223
     3 FM_PEHPCPU1_ALERT_N @S9S_MB_2U_LIB.S9S_MB_2U(SCH_1):FM_PEHPCPU1_ALERT_N   I109 @S9S_MB_2U_LIB.S9S_MB_2U(SCH_1):PAGE223
     5 FM_SMB_CPU1_ALERT_R1 @S9S_MB_2U_LIB.S9S_MB_2U(SCH_1):FM_SMB_CPU1_ALERT_R1   I109 @S9S_MB_2U_LIB.S9S_MB_2U(SCH_1):PAGE223
     4    GND @S9S_MB_2U_LIB.S9S_MB_2U(SCH_1):GND   I109 @S9S_MB_2U_LIB.S9S_MB_2U(SCH_1):PAGE223

 Q33 MOSFET_NCH_GDS_ESD_PROTECTED-2A
     D LED_CPU_RMCA_CATERR @S9S_MB_2U_LIB.S9S_MB_2U(SCH_1):LED_CPU_RMCA_CATERR   I272 @S9S_MB_2U_LIB.S9S_MB_2U(SCH_1):PAGE207
     G CPU_RMCA_CATERR_LVT3_N @S9S_MB_2U_LIB.S9S_MB_2U(SCH_1):CPU_RMCA_CATERR_LVT3_N   I272 @S9S_MB_2U_LIB.S9S_MB_2U(SCH_1):PAGE207
     S LED_CPU_RMCA_CATERR_R @S9S_MB_2U_LIB.S9S_MB_2U(SCH_1):LED_CPU_RMCA_CATERR_R   I272 @S9S_MB_2U_LIB.S9S_MB_2U(SCH_1):PAGE207

 Q34 MOSFET_NCH_GDS_ESD_PROTECTED-2A
     D RST_RTCRST_N @S9S_MB_2U_LIB.S9S_MB_2U(SCH_1):RST_RTCRST_N   I123 @S9S_MB_2U_LIB.S9S_MB_2U(SCH_1):PAGE177
     G RST_PFR_OVR_RTC @S9S_MB_2U_LIB.S9S_MB_2U(SCH_1):RST_PFR_OVR_RTC   I123 @S9S_MB_2U_LIB.S9S_MB_2U(SCH_1):PAGE177
     S    GND @S9S_MB_2U_LIB.S9S_MB_2U(SCH_1):GND   I123 @S9S_MB_2U_LIB.S9S_MB_2U(SCH_1):PAGE177

 Q35 MOSFET_NCH_GDS_ESD_PROTECTED-2A
     D RST_SRTCRST_N @S9S_MB_2U_LIB.S9S_MB_2U(SCH_1):RST_SRTCRST_N   I124 @S9S_MB_2U_LIB.S9S_MB_2U(SCH_1):PAGE177
     G RST_PFR_OVR_SRTC @S9S_MB_2U_LIB.S9S_MB_2U(SCH_1):RST_PFR_OVR_SRTC   I124 @S9S_MB_2U_LIB.S9S_MB_2U(SCH_1):PAGE177
     S    GND @S9S_MB_2U_LIB.S9S_MB_2U(SCH_1):GND   I124 @S9S_MB_2U_LIB.S9S_MB_2U(SCH_1):PAGE177

 Q37 MOSFET_NCH_DUAL-PJT138K,SMLF,IA
     1    GND @S9S_MB_2U_LIB.S9S_MB_2U(SCH_1):GND    I69 @S9S_MB_2U_LIB.S9S_MB_2U(SCH_1):PAGE246
     2 VR_P5V_EN @S9S_MB_2U_LIB.S9S_MB_2U(SCH_1):VR_P5V_EN    I69 @S9S_MB_2U_LIB.S9S_MB_2U(SCH_1):PAGE246
     6 VR_P5V_EN_N @S9S_MB_2U_LIB.S9S_MB_2U(SCH_1):VR_P5V_EN_N    I69 @S9S_MB_2U_LIB.S9S_MB_2U(SCH_1):PAGE246
     3 VR_P5V_EN_D_R1 @S9S_MB_2U_LIB.S9S_MB_2U(SCH_1):VR_P5V_EN_D_R1    I76 @S9S_MB_2U_LIB.S9S_MB_2U(SCH_1):PAGE246
     5 VR_P5V_EN_N @S9S_MB_2U_LIB.S9S_MB_2U(SCH_1):VR_P5V_EN_N    I76 @S9S_MB_2U_LIB.S9S_MB_2U(SCH_1):PAGE246
     4    GND @S9S_MB_2U_LIB.S9S_MB_2U(SCH_1):GND    I76 @S9S_MB_2U_LIB.S9S_MB_2U(SCH_1):PAGE246

 Q39 MOSFET_NCH_GDS_ESD_PROTECTED-2A
     D P12V_SCM_EN @S9S_MB_2U_LIB.S9S_MB_2U(SCH_1):P12V_SCM_EN     I9 @S9S_MB_2U_LIB.S9S_MB_2U(SCH_1):PAGE229
     G FM_SCM_PRSNT1_R_N @S9S_MB_2U_LIB.S9S_MB_2U(SCH_1):FM_SCM_PRSNT1_R_N     I9 @S9S_MB_2U_LIB.S9S_MB_2U(SCH_1):PAGE229
     S    GND @S9S_MB_2U_LIB.S9S_MB_2U(SCH_1):GND     I9 @S9S_MB_2U_LIB.S9S_MB_2U(SCH_1):PAGE229

 Q46 MOSFET_NCH_GDS_ESD_PROTECTED-2A
     D E1S_0_PRSNT @S9S_MB_2U_LIB.S9S_MB_2U(SCH_1):E1S_0_PRSNT   I316 @S9S_MB_2U_LIB.S9S_MB_2U(SCH_1):PAGE297
     G E1S_0_PRSNT_N @S9S_MB_2U_LIB.S9S_MB_2U(SCH_1):E1S_0_PRSNT_N   I316 @S9S_MB_2U_LIB.S9S_MB_2U(SCH_1):PAGE297
     S    GND @S9S_MB_2U_LIB.S9S_MB_2U(SCH_1):GND   I316 @S9S_MB_2U_LIB.S9S_MB_2U(SCH_1):PAGE297

 Q50 MOSFET_NCH_DUAL-PJT138K,SMLF,IA
     1    GND @S9S_MB_2U_LIB.S9S_MB_2U(SCH_1):GND    I43 @S9S_MB_2U_LIB.S9S_MB_2U(SCH_1):PAGE314
     2 PWRGD_P5V_AUX @S9S_MB_2U_LIB.S9S_MB_2U(SCH_1):PWRGD_P5V_AUX    I43 @S9S_MB_2U_LIB.S9S_MB_2U(SCH_1):PAGE314
     6 PWRGD_P5V_AUX_R1 @S9S_MB_2U_LIB.S9S_MB_2U(SCH_1):PWRGD_P5V_AUX_R1    I43 @S9S_MB_2U_LIB.S9S_MB_2U(SCH_1):PAGE314
     3 PWRGD_P5V_AUX_R2 @S9S_MB_2U_LIB.S9S_MB_2U(SCH_1):PWRGD_P5V_AUX_R2    I49 @S9S_MB_2U_LIB.S9S_MB_2U(SCH_1):PAGE314
     5 PWRGD_P5V_AUX_R1 @S9S_MB_2U_LIB.S9S_MB_2U(SCH_1):PWRGD_P5V_AUX_R1    I49 @S9S_MB_2U_LIB.S9S_MB_2U(SCH_1):PAGE314
     4    GND @S9S_MB_2U_LIB.S9S_MB_2U(SCH_1):GND    I49 @S9S_MB_2U_LIB.S9S_MB_2U(SCH_1):PAGE314

 Q52 MOSFET_NCH_GDS_ESD_PROTECTED-2A
     D FM_COMP_P3V3_AUX_VIN_R @S9S_MB_2U_LIB.S9S_MB_2U(SCH_1):FM_COMP_P3V3_AUX_VIN_R    I14 @S9S_MB_2U_LIB.S9S_MB_2U(SCH_1):PAGE232
     G PWRGD_P3V3_AUX_R2 @S9S_MB_2U_LIB.S9S_MB_2U(SCH_1):PWRGD_P3V3_AUX_R2    I14 @S9S_MB_2U_LIB.S9S_MB_2U(SCH_1):PAGE232
     S    GND @S9S_MB_2U_LIB.S9S_MB_2U(SCH_1):GND    I14 @S9S_MB_2U_LIB.S9S_MB_2U(SCH_1):PAGE232

 Q53 MOSFET_NCH_GDS_ESD_PROTECTED-2A
     D PWRGD_P3V3_AUX_R2 @S9S_MB_2U_LIB.S9S_MB_2U(SCH_1):PWRGD_P3V3_AUX_R2    I39 @S9S_MB_2U_LIB.S9S_MB_2U(SCH_1):PAGE232
     G PWRGD_P3V3_AUX @S9S_MB_2U_LIB.S9S_MB_2U(SCH_1):PWRGD_P3V3_AUX    I39 @S9S_MB_2U_LIB.S9S_MB_2U(SCH_1):PAGE232
     S    GND @S9S_MB_2U_LIB.S9S_MB_2U(SCH_1):GND    I39 @S9S_MB_2U_LIB.S9S_MB_2U(SCH_1):PAGE232

 Q54 MOSFET_NCH_GDS_ESD_PROTECTED-2A
     D P12V_AUX_BLEEDING @S9S_MB_2U_LIB.S9S_MB_2U(SCH_1):P12V_AUX_BLEEDING    I14 @S9S_MB_2U_LIB.S9S_MB_2U(SCH_1):PAGE234
     G FM_P12V_HSC_EN_R_N @S9S_MB_2U_LIB.S9S_MB_2U(SCH_1):FM_P12V_HSC_EN_R_N    I14 @S9S_MB_2U_LIB.S9S_MB_2U(SCH_1):PAGE234
     S    GND @S9S_MB_2U_LIB.S9S_MB_2U(SCH_1):GND    I14 @S9S_MB_2U_LIB.S9S_MB_2U(SCH_1):PAGE234

 Q56 MOSFET_NCH_1D3S-PSMNR58-30YLH,A
     3   P3V3 @S9S_MB_2U_LIB.S9S_MB_2U(SCH_1):P3V3    I51 @S9S_MB_2U_LIB.S9S_MB_2U(SCH_1):PAGE246
     5 P3V3_AUX @S9S_MB_2U_LIB.S9S_MB_2U(SCH_1):P3V3_AUX    I51 @S9S_MB_2U_LIB.S9S_MB_2U(SCH_1):PAGE246
     2   P3V3 @S9S_MB_2U_LIB.S9S_MB_2U(SCH_1):P3V3    I51 @S9S_MB_2U_LIB.S9S_MB_2U(SCH_1):PAGE246
     4 PWRGD_P5V_ISO_R @S9S_MB_2U_LIB.S9S_MB_2U(SCH_1):PWRGD_P5V_ISO_R    I51 @S9S_MB_2U_LIB.S9S_MB_2U(SCH_1):PAGE246
     1   P3V3 @S9S_MB_2U_LIB.S9S_MB_2U(SCH_1):P3V3    I51 @S9S_MB_2U_LIB.S9S_MB_2U(SCH_1):PAGE246

 Q57 MOSFET_NCH_1D3S-PSMNR58-30YLH,A
     3    P5V @S9S_MB_2U_LIB.S9S_MB_2U(SCH_1):P5V    I30 @S9S_MB_2U_LIB.S9S_MB_2U(SCH_1):PAGE246
     5 P5V_AUX @S9S_MB_2U_LIB.S9S_MB_2U(SCH_1):P5V_AUX    I30 @S9S_MB_2U_LIB.S9S_MB_2U(SCH_1):PAGE246
     2    P5V @S9S_MB_2U_LIB.S9S_MB_2U(SCH_1):P5V    I30 @S9S_MB_2U_LIB.S9S_MB_2U(SCH_1):PAGE246
     4 VR_P5V_EN_D_R @S9S_MB_2U_LIB.S9S_MB_2U(SCH_1):VR_P5V_EN_D_R    I30 @S9S_MB_2U_LIB.S9S_MB_2U(SCH_1):PAGE246
     1    P5V @S9S_MB_2U_LIB.S9S_MB_2U(SCH_1):P5V    I30 @S9S_MB_2U_LIB.S9S_MB_2U(SCH_1):PAGE246

 Q67 MOSFET_NCH_DUAL-PJT138K,SMLF,IA
     1    GND @S9S_MB_2U_LIB.S9S_MB_2U(SCH_1):GND    I33 @S9S_MB_2U_LIB.S9S_MB_2U(SCH_1):PAGE145
     2 BIC_MONITER @S9S_MB_2U_LIB.S9S_MB_2U(SCH_1):BIC_MONITER    I33 @S9S_MB_2U_LIB.S9S_MB_2U(SCH_1):PAGE145
     6 BIC_MONITER_N @S9S_MB_2U_LIB.S9S_MB_2U(SCH_1):BIC_MONITER_N    I33 @S9S_MB_2U_LIB.S9S_MB_2U(SCH_1):PAGE145
     3 BIC_MONITER_ISO @S9S_MB_2U_LIB.S9S_MB_2U(SCH_1):BIC_MONITER_ISO    I82 @S9S_MB_2U_LIB.S9S_MB_2U(SCH_1):PAGE145
     5 BIC_MONITER_N @S9S_MB_2U_LIB.S9S_MB_2U(SCH_1):BIC_MONITER_N    I82 @S9S_MB_2U_LIB.S9S_MB_2U(SCH_1):PAGE145
     4    GND @S9S_MB_2U_LIB.S9S_MB_2U(SCH_1):GND    I82 @S9S_MB_2U_LIB.S9S_MB_2U(SCH_1):PAGE145

 Q69 MOSFET_NCH_DUAL-PJT138K,SMLF,IA
     1    GND @S9S_MB_2U_LIB.S9S_MB_2U(SCH_1):GND   I117 @S9S_MB_2U_LIB.S9S_MB_2U(SCH_1):PAGE145
     2 RST_BMC_FROM_SWB_N @S9S_MB_2U_LIB.S9S_MB_2U(SCH_1):RST_BMC_FROM_SWB_N   I117 @S9S_MB_2U_LIB.S9S_MB_2U(SCH_1):PAGE145
     6 RST_BMC_FROM_SWB @S9S_MB_2U_LIB.S9S_MB_2U(SCH_1):RST_BMC_FROM_SWB   I117 @S9S_MB_2U_LIB.S9S_MB_2U(SCH_1):PAGE145
     3 RST_BMC_FROM_SWB_ISO_N @S9S_MB_2U_LIB.S9S_MB_2U(SCH_1):RST_BMC_FROM_SWB_ISO_N    I88 @S9S_MB_2U_LIB.S9S_MB_2U(SCH_1):PAGE145
     5 RST_BMC_FROM_SWB @S9S_MB_2U_LIB.S9S_MB_2U(SCH_1):RST_BMC_FROM_SWB    I88 @S9S_MB_2U_LIB.S9S_MB_2U(SCH_1):PAGE145
     4    GND @S9S_MB_2U_LIB.S9S_MB_2U(SCH_1):GND    I88 @S9S_MB_2U_LIB.S9S_MB_2U(SCH_1):PAGE145

 Q70 MOSFET_NCH_DUAL-PJT138K,SMLF,IA
     1    GND @S9S_MB_2U_LIB.S9S_MB_2U(SCH_1):GND    I35 @S9S_MB_2U_LIB.S9S_MB_2U(SCH_1):PAGE145
     2 FM_SWB_BIC_READY_N @S9S_MB_2U_LIB.S9S_MB_2U(SCH_1):FM_SWB_BIC_READY_N    I35 @S9S_MB_2U_LIB.S9S_MB_2U(SCH_1):PAGE145
     6 FM_SWB_BIC_READY @S9S_MB_2U_LIB.S9S_MB_2U(SCH_1):FM_SWB_BIC_READY    I35 @S9S_MB_2U_LIB.S9S_MB_2U(SCH_1):PAGE145
     3 FM_SWB_BIC_READY_ISO_N @S9S_MB_2U_LIB.S9S_MB_2U(SCH_1):FM_SWB_BIC_READY_ISO_N   I120 @S9S_MB_2U_LIB.S9S_MB_2U(SCH_1):PAGE145
     5 FM_SWB_BIC_READY @S9S_MB_2U_LIB.S9S_MB_2U(SCH_1):FM_SWB_BIC_READY   I120 @S9S_MB_2U_LIB.S9S_MB_2U(SCH_1):PAGE145
     4    GND @S9S_MB_2U_LIB.S9S_MB_2U(SCH_1):GND   I120 @S9S_MB_2U_LIB.S9S_MB_2U(SCH_1):PAGE145

 Q71 MOSFET_NCH_DUAL-PJT138K,SMLF,IA
     1    GND @S9S_MB_2U_LIB.S9S_MB_2U(SCH_1):GND   I118 @S9S_MB_2U_LIB.S9S_MB_2U(SCH_1):PAGE145
     2 FM_SWB_PWRGD @S9S_MB_2U_LIB.S9S_MB_2U(SCH_1):FM_SWB_PWRGD   I118 @S9S_MB_2U_LIB.S9S_MB_2U(SCH_1):PAGE145
     6 FM_SWB_PWRGD_N @S9S_MB_2U_LIB.S9S_MB_2U(SCH_1):FM_SWB_PWRGD_N   I118 @S9S_MB_2U_LIB.S9S_MB_2U(SCH_1):PAGE145
     3 FM_SWB_PWRGD_ISO @S9S_MB_2U_LIB.S9S_MB_2U(SCH_1):FM_SWB_PWRGD_ISO   I100 @S9S_MB_2U_LIB.S9S_MB_2U(SCH_1):PAGE145
     5 FM_SWB_PWRGD_N @S9S_MB_2U_LIB.S9S_MB_2U(SCH_1):FM_SWB_PWRGD_N   I100 @S9S_MB_2U_LIB.S9S_MB_2U(SCH_1):PAGE145
     4    GND @S9S_MB_2U_LIB.S9S_MB_2U(SCH_1):GND   I100 @S9S_MB_2U_LIB.S9S_MB_2U(SCH_1):PAGE145

 Q72 MOSFET_NCH_DUAL-PJT138K,SMLF,IA
     1    GND @S9S_MB_2U_LIB.S9S_MB_2U(SCH_1):GND    I37 @S9S_MB_2U_LIB.S9S_MB_2U(SCH_1):PAGE145
     2 FM_GPU_PWRGD @S9S_MB_2U_LIB.S9S_MB_2U(SCH_1):FM_GPU_PWRGD    I37 @S9S_MB_2U_LIB.S9S_MB_2U(SCH_1):PAGE145
     6 FM_GPU_PWRGD_N @S9S_MB_2U_LIB.S9S_MB_2U(SCH_1):FM_GPU_PWRGD_N    I37 @S9S_MB_2U_LIB.S9S_MB_2U(SCH_1):PAGE145
     3 FM_GPU_PWRGD_ISO @S9S_MB_2U_LIB.S9S_MB_2U(SCH_1):FM_GPU_PWRGD_ISO   I119 @S9S_MB_2U_LIB.S9S_MB_2U(SCH_1):PAGE145
     5 FM_GPU_PWRGD_N @S9S_MB_2U_LIB.S9S_MB_2U(SCH_1):FM_GPU_PWRGD_N   I119 @S9S_MB_2U_LIB.S9S_MB_2U(SCH_1):PAGE145
     4    GND @S9S_MB_2U_LIB.S9S_MB_2U(SCH_1):GND   I119 @S9S_MB_2U_LIB.S9S_MB_2U(SCH_1):PAGE145

 Q74 MOSFET_NCH_DUAL-PJT138K,SMLF,IA
     1    GND @S9S_MB_2U_LIB.S9S_MB_2U(SCH_1):GND   I121 @S9S_MB_2U_LIB.S9S_MB_2U(SCH_1):PAGE145
     2 FM_SMB_2_ALERT_GPU_N @S9S_MB_2U_LIB.S9S_MB_2U(SCH_1):FM_SMB_2_ALERT_GPU_N   I121 @S9S_MB_2U_LIB.S9S_MB_2U(SCH_1):PAGE145
     6 FM_SMB_2_ALERT_GPU @S9S_MB_2U_LIB.S9S_MB_2U(SCH_1):FM_SMB_2_ALERT_GPU   I121 @S9S_MB_2U_LIB.S9S_MB_2U(SCH_1):PAGE145
     3 FM_SMB_2_ALERT_GPU_ISO_N @S9S_MB_2U_LIB.S9S_MB_2U(SCH_1):FM_SMB_2_ALERT_GPU_ISO_N   I122 @S9S_MB_2U_LIB.S9S_MB_2U(SCH_1):PAGE145
     5 FM_SMB_2_ALERT_GPU @S9S_MB_2U_LIB.S9S_MB_2U(SCH_1):FM_SMB_2_ALERT_GPU   I122 @S9S_MB_2U_LIB.S9S_MB_2U(SCH_1):PAGE145
     4    GND @S9S_MB_2U_LIB.S9S_MB_2U(SCH_1):GND   I122 @S9S_MB_2U_LIB.S9S_MB_2U(SCH_1):PAGE145

 Q75 MOSFET_NCH_DUAL-PJT138K,SMLF,IA
     1    GND @S9S_MB_2U_LIB.S9S_MB_2U(SCH_1):GND   I152 @S9S_MB_2U_LIB.S9S_MB_2U(SCH_1):PAGE145
     2 FM_SMB_1_ALERT_GPU_N @S9S_MB_2U_LIB.S9S_MB_2U(SCH_1):FM_SMB_1_ALERT_GPU_N   I152 @S9S_MB_2U_LIB.S9S_MB_2U(SCH_1):PAGE145
     6 FM_SMB_1_ALERT_GPU @S9S_MB_2U_LIB.S9S_MB_2U(SCH_1):FM_SMB_1_ALERT_GPU   I152 @S9S_MB_2U_LIB.S9S_MB_2U(SCH_1):PAGE145
     3 FM_SMB_1_ALERT_GPU_ISO_N @S9S_MB_2U_LIB.S9S_MB_2U(SCH_1):FM_SMB_1_ALERT_GPU_ISO_N   I151 @S9S_MB_2U_LIB.S9S_MB_2U(SCH_1):PAGE145
     5 FM_SMB_1_ALERT_GPU @S9S_MB_2U_LIB.S9S_MB_2U(SCH_1):FM_SMB_1_ALERT_GPU   I151 @S9S_MB_2U_LIB.S9S_MB_2U(SCH_1):PAGE145
     4    GND @S9S_MB_2U_LIB.S9S_MB_2U(SCH_1):GND   I151 @S9S_MB_2U_LIB.S9S_MB_2U(SCH_1):PAGE145

 Q76 MOSFET_NCH_DUAL-PJT138K,SMLF,IA
     1    GND @S9S_MB_2U_LIB.S9S_MB_2U(SCH_1):GND    I17 @S9S_MB_2U_LIB.S9S_MB_2U(SCH_1):PAGE242
     2 PWRGD_P1V8_PCH_AUX @S9S_MB_2U_LIB.S9S_MB_2U(SCH_1):PWRGD_P1V8_PCH_AUX    I17 @S9S_MB_2U_LIB.S9S_MB_2U(SCH_1):PAGE242
     6 LED_PWRGD_P1V8_PCH_AUX_D @S9S_MB_2U_LIB.S9S_MB_2U(SCH_1):LED_PWRGD_P1V8_PCH_AUX_D    I17 @S9S_MB_2U_LIB.S9S_MB_2U(SCH_1):PAGE242
     3 LED_PWRGD_P1V05_PCH_AUX_D @S9S_MB_2U_LIB.S9S_MB_2U(SCH_1):LED_PWRGD_P1V05_PCH_AUX_D     I8 @S9S_MB_2U_LIB.S9S_MB_2U(SCH_1):PAGE242
     5 PWRGD_P1V05_PCH_AUX @S9S_MB_2U_LIB.S9S_MB_2U(SCH_1):PWRGD_P1V05_PCH_AUX     I8 @S9S_MB_2U_LIB.S9S_MB_2U(SCH_1):PAGE242
     4    GND @S9S_MB_2U_LIB.S9S_MB_2U(SCH_1):GND     I8 @S9S_MB_2U_LIB.S9S_MB_2U(SCH_1):PAGE242

 Q77 MOSFET_NCH_DUAL-PJT138K,SMLF,IA
     1    GND @S9S_MB_2U_LIB.S9S_MB_2U(SCH_1):GND     I6 @S9S_MB_2U_LIB.S9S_MB_2U(SCH_1):PAGE242
     2 RST_RSMRST_PLD_R_N @S9S_MB_2U_LIB.S9S_MB_2U(SCH_1):RST_RSMRST_PLD_R_N     I6 @S9S_MB_2U_LIB.S9S_MB_2U(SCH_1):PAGE242
     6 LED_RST_RSMRST_PLD_R_N_D @S9S_MB_2U_LIB.S9S_MB_2U(SCH_1):LED_RST_RSMRST_PLD_R_N_D     I6 @S9S_MB_2U_LIB.S9S_MB_2U(SCH_1):PAGE242
     3 LED_FM_PCH_SLP_S4_N_D @S9S_MB_2U_LIB.S9S_MB_2U(SCH_1):LED_FM_PCH_SLP_S4_N_D     I3 @S9S_MB_2U_LIB.S9S_MB_2U(SCH_1):PAGE242
     5 FM_PCH_SLP_S4_N @S9S_MB_2U_LIB.S9S_MB_2U(SCH_1):FM_PCH_SLP_S4_N     I3 @S9S_MB_2U_LIB.S9S_MB_2U(SCH_1):PAGE242
     4    GND @S9S_MB_2U_LIB.S9S_MB_2U(SCH_1):GND     I3 @S9S_MB_2U_LIB.S9S_MB_2U(SCH_1):PAGE242

 Q78 MOSFET_NCH_DUAL-PJT138K,SMLF,IA
     1    GND @S9S_MB_2U_LIB.S9S_MB_2U(SCH_1):GND    I34 @S9S_MB_2U_LIB.S9S_MB_2U(SCH_1):PAGE242
     2 FM_PCH_SLP_S3_N @S9S_MB_2U_LIB.S9S_MB_2U(SCH_1):FM_PCH_SLP_S3_N    I34 @S9S_MB_2U_LIB.S9S_MB_2U(SCH_1):PAGE242
     6 LED_FM_PCH_SLP_S3_N_D @S9S_MB_2U_LIB.S9S_MB_2U(SCH_1):LED_FM_PCH_SLP_S3_N_D    I34 @S9S_MB_2U_LIB.S9S_MB_2U(SCH_1):PAGE242
     3 LED_PWRGD_PS_PWROK_PLD_D @S9S_MB_2U_LIB.S9S_MB_2U(SCH_1):LED_PWRGD_PS_PWROK_PLD_D    I26 @S9S_MB_2U_LIB.S9S_MB_2U(SCH_1):PAGE242
     5 PWRGD_PS_PWROK_PLD @S9S_MB_2U_LIB.S9S_MB_2U(SCH_1):PWRGD_PS_PWROK_PLD    I26 @S9S_MB_2U_LIB.S9S_MB_2U(SCH_1):PAGE242
     4    GND @S9S_MB_2U_LIB.S9S_MB_2U(SCH_1):GND    I26 @S9S_MB_2U_LIB.S9S_MB_2U(SCH_1):PAGE242

 Q79 MOSFET_NCH_DUAL-PJT138K,SMLF,IA
     1    GND @S9S_MB_2U_LIB.S9S_MB_2U(SCH_1):GND     I8 @S9S_MB_2U_LIB.S9S_MB_2U(SCH_1):PAGE305
     2 PWRGD_PVCCD_HV_CPU0 @S9S_MB_2U_LIB.S9S_MB_2U(SCH_1):PWRGD_PVCCD_HV_CPU0     I8 @S9S_MB_2U_LIB.S9S_MB_2U(SCH_1):PAGE305
     6 LED_PWRGD_PVCCD_HV_CPU0_D @S9S_MB_2U_LIB.S9S_MB_2U(SCH_1):LED_PWRGD_PVCCD_HV_CPU0_D     I8 @S9S_MB_2U_LIB.S9S_MB_2U(SCH_1):PAGE305
     3 LED_PWRGD_PVPP_HBM_CPU0_D @S9S_MB_2U_LIB.S9S_MB_2U(SCH_1):LED_PWRGD_PVPP_HBM_CPU0_D     I7 @S9S_MB_2U_LIB.S9S_MB_2U(SCH_1):PAGE305
     5 PWRGD_PVPP_HBM_CPU0 @S9S_MB_2U_LIB.S9S_MB_2U(SCH_1):PWRGD_PVPP_HBM_CPU0     I7 @S9S_MB_2U_LIB.S9S_MB_2U(SCH_1):PAGE305
     4    GND @S9S_MB_2U_LIB.S9S_MB_2U(SCH_1):GND     I7 @S9S_MB_2U_LIB.S9S_MB_2U(SCH_1):PAGE305

 Q80 MOSFET_NCH_DUAL-PJT138K,SMLF,IA
     1    GND @S9S_MB_2U_LIB.S9S_MB_2U(SCH_1):GND     I4 @S9S_MB_2U_LIB.S9S_MB_2U(SCH_1):PAGE305
     2 PWRGD_PVCCFA_EHV_CPU0 @S9S_MB_2U_LIB.S9S_MB_2U(SCH_1):PWRGD_PVCCFA_EHV_CPU0     I4 @S9S_MB_2U_LIB.S9S_MB_2U(SCH_1):PAGE305
     6 LED_PWRGD_PVCCFA_EHV_CPU0_D @S9S_MB_2U_LIB.S9S_MB_2U(SCH_1):LED_PWRGD_PVCCFA_EHV_CPU0_D     I4 @S9S_MB_2U_LIB.S9S_MB_2U(SCH_1):PAGE305
     3 LED_PWRGD_PVCCFA_EHV_FIVRA_CP_1 @S9S_MB_2U_LIB.S9S_MB_2U(SCH_1):LED_PWRGD_PVCCFA_EHV_FIVRA_CPU0_D     I2 @S9S_MB_2U_LIB.S9S_MB_2U(SCH_1):PAGE305
     5 PWRGD_PVCCFA_EHV_FIVRA_CPU0 @S9S_MB_2U_LIB.S9S_MB_2U(SCH_1):PWRGD_PVCCFA_EHV_FIVRA_CPU0     I2 @S9S_MB_2U_LIB.S9S_MB_2U(SCH_1):PAGE305
     4    GND @S9S_MB_2U_LIB.S9S_MB_2U(SCH_1):GND     I2 @S9S_MB_2U_LIB.S9S_MB_2U(SCH_1):PAGE305

 Q81 MOSFET_NCH_DUAL-PJT138K,SMLF,IA
     1    GND @S9S_MB_2U_LIB.S9S_MB_2U(SCH_1):GND    I41 @S9S_MB_2U_LIB.S9S_MB_2U(SCH_1):PAGE305
     2 PWRGD_PVCCINFAON_CPU0 @S9S_MB_2U_LIB.S9S_MB_2U(SCH_1):PWRGD_PVCCINFAON_CPU0    I41 @S9S_MB_2U_LIB.S9S_MB_2U(SCH_1):PAGE305
     6 LED_PWRGD_PVCCINFAON_CPU0_D @S9S_MB_2U_LIB.S9S_MB_2U(SCH_1):LED_PWRGD_PVCCINFAON_CPU0_D    I41 @S9S_MB_2U_LIB.S9S_MB_2U(SCH_1):PAGE305
     3 LED_PWRGD_PVNN_MAIN_CPU0_D @S9S_MB_2U_LIB.S9S_MB_2U(SCH_1):LED_PWRGD_PVNN_MAIN_CPU0_D    I40 @S9S_MB_2U_LIB.S9S_MB_2U(SCH_1):PAGE305
     5 PWRGD_PVNN_MAIN_CPU0 @S9S_MB_2U_LIB.S9S_MB_2U(SCH_1):PWRGD_PVNN_MAIN_CPU0    I40 @S9S_MB_2U_LIB.S9S_MB_2U(SCH_1):PAGE305
     4    GND @S9S_MB_2U_LIB.S9S_MB_2U(SCH_1):GND    I40 @S9S_MB_2U_LIB.S9S_MB_2U(SCH_1):PAGE305

 Q83 MOSFET_NCH_DUAL-PJT138K,SMLF,IA
     1    GND @S9S_MB_2U_LIB.S9S_MB_2U(SCH_1):GND    I32 @S9S_MB_2U_LIB.S9S_MB_2U(SCH_1):PAGE305
     2 PWRGD_PVCCIN_CPU0 @S9S_MB_2U_LIB.S9S_MB_2U(SCH_1):PWRGD_PVCCIN_CPU0    I32 @S9S_MB_2U_LIB.S9S_MB_2U(SCH_1):PAGE305
     6 LED_PWRGD_PVCCIN_CPU0_D @S9S_MB_2U_LIB.S9S_MB_2U(SCH_1):LED_PWRGD_PVCCIN_CPU0_D    I32 @S9S_MB_2U_LIB.S9S_MB_2U(SCH_1):PAGE305
     3 LED_PWRGD_PVCCIN_CPU1_D @S9S_MB_2U_LIB.S9S_MB_2U(SCH_1):LED_PWRGD_PVCCIN_CPU1_D    I43 @S9S_MB_2U_LIB.S9S_MB_2U(SCH_1):PAGE306
     5 PWRGD_PVCCIN_CPU1 @S9S_MB_2U_LIB.S9S_MB_2U(SCH_1):PWRGD_PVCCIN_CPU1    I43 @S9S_MB_2U_LIB.S9S_MB_2U(SCH_1):PAGE306
     4    GND @S9S_MB_2U_LIB.S9S_MB_2U(SCH_1):GND    I43 @S9S_MB_2U_LIB.S9S_MB_2U(SCH_1):PAGE306

 Q84 MOSFET_NCH_DUAL-PJT138K,SMLF,IA
     1    GND @S9S_MB_2U_LIB.S9S_MB_2U(SCH_1):GND    I18 @S9S_MB_2U_LIB.S9S_MB_2U(SCH_1):PAGE306
     2 PWRGD_PVCCD_HV_CPU1 @S9S_MB_2U_LIB.S9S_MB_2U(SCH_1):PWRGD_PVCCD_HV_CPU1    I18 @S9S_MB_2U_LIB.S9S_MB_2U(SCH_1):PAGE306
     6 LED_PWRGD_PVCCD_HV_CPU1_D @S9S_MB_2U_LIB.S9S_MB_2U(SCH_1):LED_PWRGD_PVCCD_HV_CPU1_D    I18 @S9S_MB_2U_LIB.S9S_MB_2U(SCH_1):PAGE306
     3 LED_PWRGD_PVPP_HBM_CPU1_D @S9S_MB_2U_LIB.S9S_MB_2U(SCH_1):LED_PWRGD_PVPP_HBM_CPU1_D     I8 @S9S_MB_2U_LIB.S9S_MB_2U(SCH_1):PAGE306
     5 PWRGD_PVPP_HBM_CPU1 @S9S_MB_2U_LIB.S9S_MB_2U(SCH_1):PWRGD_PVPP_HBM_CPU1     I8 @S9S_MB_2U_LIB.S9S_MB_2U(SCH_1):PAGE306
     4    GND @S9S_MB_2U_LIB.S9S_MB_2U(SCH_1):GND     I8 @S9S_MB_2U_LIB.S9S_MB_2U(SCH_1):PAGE306

 Q85 MOSFET_NCH_DUAL-PJT138K,SMLF,IA
     1    GND @S9S_MB_2U_LIB.S9S_MB_2U(SCH_1):GND     I6 @S9S_MB_2U_LIB.S9S_MB_2U(SCH_1):PAGE306
     2 PWRGD_PVCCFA_EHV_CPU1 @S9S_MB_2U_LIB.S9S_MB_2U(SCH_1):PWRGD_PVCCFA_EHV_CPU1     I6 @S9S_MB_2U_LIB.S9S_MB_2U(SCH_1):PAGE306
     6 LED_PWRGD_PVCCFA_EHV_CPU1_D @S9S_MB_2U_LIB.S9S_MB_2U(SCH_1):LED_PWRGD_PVCCFA_EHV_CPU1_D     I6 @S9S_MB_2U_LIB.S9S_MB_2U(SCH_1):PAGE306
     3 LED_PWRGD_PVCCFA_EHV_FIVRA_CP_2 @S9S_MB_2U_LIB.S9S_MB_2U(SCH_1):LED_PWRGD_PVCCFA_EHV_FIVRA_CPU1_D     I3 @S9S_MB_2U_LIB.S9S_MB_2U(SCH_1):PAGE306
     5 PWRGD_PVCCFA_EHV_FIVRA_CPU1 @S9S_MB_2U_LIB.S9S_MB_2U(SCH_1):PWRGD_PVCCFA_EHV_FIVRA_CPU1     I3 @S9S_MB_2U_LIB.S9S_MB_2U(SCH_1):PAGE306
     4    GND @S9S_MB_2U_LIB.S9S_MB_2U(SCH_1):GND     I3 @S9S_MB_2U_LIB.S9S_MB_2U(SCH_1):PAGE306

 Q86 MOSFET_NCH_DUAL-PJT138K,SMLF,IA
     1    GND @S9S_MB_2U_LIB.S9S_MB_2U(SCH_1):GND    I35 @S9S_MB_2U_LIB.S9S_MB_2U(SCH_1):PAGE306
     2 PWRGD_PVCCINFAON_CPU1 @S9S_MB_2U_LIB.S9S_MB_2U(SCH_1):PWRGD_PVCCINFAON_CPU1    I35 @S9S_MB_2U_LIB.S9S_MB_2U(SCH_1):PAGE306
     6 LED_PWRGD_PVCCINFAON_CPU1_D @S9S_MB_2U_LIB.S9S_MB_2U(SCH_1):LED_PWRGD_PVCCINFAON_CPU1_D    I35 @S9S_MB_2U_LIB.S9S_MB_2U(SCH_1):PAGE306
     3 LED_PWRGD_PVNN_MAIN_CPU1_D @S9S_MB_2U_LIB.S9S_MB_2U(SCH_1):LED_PWRGD_PVNN_MAIN_CPU1_D    I27 @S9S_MB_2U_LIB.S9S_MB_2U(SCH_1):PAGE306
     5 PWRGD_PVNN_MAIN_CPU1 @S9S_MB_2U_LIB.S9S_MB_2U(SCH_1):PWRGD_PVNN_MAIN_CPU1    I27 @S9S_MB_2U_LIB.S9S_MB_2U(SCH_1):PAGE306
     4    GND @S9S_MB_2U_LIB.S9S_MB_2U(SCH_1):GND    I27 @S9S_MB_2U_LIB.S9S_MB_2U(SCH_1):PAGE306

 Q87 MOSFET_NCH_DUAL-PJT138K,SMLF,IA
     1    GND @S9S_MB_2U_LIB.S9S_MB_2U(SCH_1):GND    I17 @S9S_MB_2U_LIB.S9S_MB_2U(SCH_1):PAGE241
     2 PWRGD_PCH_PWROK_R @S9S_MB_2U_LIB.S9S_MB_2U(SCH_1):PWRGD_PCH_PWROK_R    I17 @S9S_MB_2U_LIB.S9S_MB_2U(SCH_1):PAGE241
     6 LED_PWRGD_PCH_PWROK_R_D @S9S_MB_2U_LIB.S9S_MB_2U(SCH_1):LED_PWRGD_PCH_PWROK_R_D    I17 @S9S_MB_2U_LIB.S9S_MB_2U(SCH_1):PAGE241
     3 LED_PWRGD_SYS_PWROK_R_D @S9S_MB_2U_LIB.S9S_MB_2U(SCH_1):LED_PWRGD_SYS_PWROK_R_D    I16 @S9S_MB_2U_LIB.S9S_MB_2U(SCH_1):PAGE241
     5 PWRGD_SYS_PWROK_R @S9S_MB_2U_LIB.S9S_MB_2U(SCH_1):PWRGD_SYS_PWROK_R    I16 @S9S_MB_2U_LIB.S9S_MB_2U(SCH_1):PAGE241
     4    GND @S9S_MB_2U_LIB.S9S_MB_2U(SCH_1):GND    I16 @S9S_MB_2U_LIB.S9S_MB_2U(SCH_1):PAGE241

 Q88 MOSFET_NCH_DUAL-PJT138K,SMLF,IA
     1    GND @S9S_MB_2U_LIB.S9S_MB_2U(SCH_1):GND     I8 @S9S_MB_2U_LIB.S9S_MB_2U(SCH_1):PAGE241
     2 PWRGD_CPUPWRGD_LVC2_R1 @S9S_MB_2U_LIB.S9S_MB_2U(SCH_1):PWRGD_CPUPWRGD_LVC2_R1     I8 @S9S_MB_2U_LIB.S9S_MB_2U(SCH_1):PAGE241
     6 LED_PWRGD_CPUPWRGD_GTL_D @S9S_MB_2U_LIB.S9S_MB_2U(SCH_1):LED_PWRGD_CPUPWRGD_GTL_D     I8 @S9S_MB_2U_LIB.S9S_MB_2U(SCH_1):PAGE241
     3 LED_RST_PLTRST_N_D @S9S_MB_2U_LIB.S9S_MB_2U(SCH_1):LED_RST_PLTRST_N_D    I42 @S9S_MB_2U_LIB.S9S_MB_2U(SCH_1):PAGE241
     5 RST_PLTRST_N @S9S_MB_2U_LIB.S9S_MB_2U(SCH_1):RST_PLTRST_N    I42 @S9S_MB_2U_LIB.S9S_MB_2U(SCH_1):PAGE241
     4    GND @S9S_MB_2U_LIB.S9S_MB_2U(SCH_1):GND    I42 @S9S_MB_2U_LIB.S9S_MB_2U(SCH_1):PAGE241

 Q95 MOSFET_NCH_DUAL-PJT138K,SMLF,IA
     1    GND @S9S_MB_2U_LIB.S9S_MB_2U(SCH_1):GND   I342 @S9S_MB_2U_LIB.S9S_MB_2U(SCH_1):PAGE182
     2 HDD_ACTIVITY_BUF @S9S_MB_2U_LIB.S9S_MB_2U(SCH_1):HDD_ACTIVITY_BUF   I342 @S9S_MB_2U_LIB.S9S_MB_2U(SCH_1):PAGE182
     6 HDD_ACTIVITY_BUF_N @S9S_MB_2U_LIB.S9S_MB_2U(SCH_1):HDD_ACTIVITY_BUF_N   I342 @S9S_MB_2U_LIB.S9S_MB_2U(SCH_1):PAGE182
     3 NC_Q95_D2 @S9S_MB_2U_LIB.S9S_MB_2U(SCH_1):NC_Q95_D2   I343 @S9S_MB_2U_LIB.S9S_MB_2U(SCH_1):PAGE182
     5 NC_Q95_G2 @S9S_MB_2U_LIB.S9S_MB_2U(SCH_1):NC_Q95_G2   I343 @S9S_MB_2U_LIB.S9S_MB_2U(SCH_1):PAGE182
     4 NC_Q95_S2 @S9S_MB_2U_LIB.S9S_MB_2U(SCH_1):NC_Q95_S2   I343 @S9S_MB_2U_LIB.S9S_MB_2U(SCH_1):PAGE182

 Q96 MOSFET_NCH_DUAL-PJT138K,SMLF,IA
     1    GND @S9S_MB_2U_LIB.S9S_MB_2U(SCH_1):GND   I154 @S9S_MB_2U_LIB.S9S_MB_2U(SCH_1):PAGE145
     2 GPU_FPGA_READY @S9S_MB_2U_LIB.S9S_MB_2U(SCH_1):GPU_FPGA_READY   I154 @S9S_MB_2U_LIB.S9S_MB_2U(SCH_1):PAGE145
     6 GPU_FPGA_READY_N @S9S_MB_2U_LIB.S9S_MB_2U(SCH_1):GPU_FPGA_READY_N   I154 @S9S_MB_2U_LIB.S9S_MB_2U(SCH_1):PAGE145
     3 GPU_FPGA_READY_ISO @S9S_MB_2U_LIB.S9S_MB_2U(SCH_1):GPU_FPGA_READY_ISO   I159 @S9S_MB_2U_LIB.S9S_MB_2U(SCH_1):PAGE145
     5 GPU_FPGA_READY_N @S9S_MB_2U_LIB.S9S_MB_2U(SCH_1):GPU_FPGA_READY_N   I159 @S9S_MB_2U_LIB.S9S_MB_2U(SCH_1):PAGE145
     4    GND @S9S_MB_2U_LIB.S9S_MB_2U(SCH_1):GND   I159 @S9S_MB_2U_LIB.S9S_MB_2U(SCH_1):PAGE145

 Q97 MOSFET_NCH_DUAL-NX6008NBKS,SMLA
     1    GND @S9S_MB_2U_LIB.S9S_MB_2U(SCH_1):GND    I71 @S9S_MB_2U_LIB.S9S_MB_2U(SCH_1):PAGE304
     2 RST_PLD_CPU0_DRAM_EF_N @S9S_MB_2U_LIB.S9S_MB_2U(SCH_1):RST_PLD_CPU0_DRAM_EF_N    I71 @S9S_MB_2U_LIB.S9S_MB_2U(SCH_1):PAGE304
     6 LED_RST_PLD_CPU0_DRAM_EF_N_D @S9S_MB_2U_LIB.S9S_MB_2U(SCH_1):LED_RST_PLD_CPU0_DRAM_EF_N_D    I71 @S9S_MB_2U_LIB.S9S_MB_2U(SCH_1):PAGE304
     3 LED_RST_PLD_CPU0_DRAM_GH_N_D @S9S_MB_2U_LIB.S9S_MB_2U(SCH_1):LED_RST_PLD_CPU0_DRAM_GH_N_D    I70 @S9S_MB_2U_LIB.S9S_MB_2U(SCH_1):PAGE304
     5 RST_PLD_CPU0_DRAM_GH_N @S9S_MB_2U_LIB.S9S_MB_2U(SCH_1):RST_PLD_CPU0_DRAM_GH_N    I70 @S9S_MB_2U_LIB.S9S_MB_2U(SCH_1):PAGE304
     4    GND @S9S_MB_2U_LIB.S9S_MB_2U(SCH_1):GND    I70 @S9S_MB_2U_LIB.S9S_MB_2U(SCH_1):PAGE304

 Q98 MOSFET_NCH_DUAL-NX6008NBKS,SMLA
     1    GND @S9S_MB_2U_LIB.S9S_MB_2U(SCH_1):GND    I68 @S9S_MB_2U_LIB.S9S_MB_2U(SCH_1):PAGE304
     2 RST_PLD_CPU0_DRAM_AB_N @S9S_MB_2U_LIB.S9S_MB_2U(SCH_1):RST_PLD_CPU0_DRAM_AB_N    I68 @S9S_MB_2U_LIB.S9S_MB_2U(SCH_1):PAGE304
     6 LED_RST_PLD_CPU0_DRAM_AB_N_D @S9S_MB_2U_LIB.S9S_MB_2U(SCH_1):LED_RST_PLD_CPU0_DRAM_AB_N_D    I68 @S9S_MB_2U_LIB.S9S_MB_2U(SCH_1):PAGE304
     3 LED_RST_PLD_CPU0_DRAM_CD_N_D @S9S_MB_2U_LIB.S9S_MB_2U(SCH_1):LED_RST_PLD_CPU0_DRAM_CD_N_D    I69 @S9S_MB_2U_LIB.S9S_MB_2U(SCH_1):PAGE304
     5 RST_PLD_CPU0_DRAM_CD_N @S9S_MB_2U_LIB.S9S_MB_2U(SCH_1):RST_PLD_CPU0_DRAM_CD_N    I69 @S9S_MB_2U_LIB.S9S_MB_2U(SCH_1):PAGE304
     4    GND @S9S_MB_2U_LIB.S9S_MB_2U(SCH_1):GND    I69 @S9S_MB_2U_LIB.S9S_MB_2U(SCH_1):PAGE304

 Q99 MOSFET_NCH_DUAL-NX6008NBKS,SMLA
     1    GND @S9S_MB_2U_LIB.S9S_MB_2U(SCH_1):GND    I72 @S9S_MB_2U_LIB.S9S_MB_2U(SCH_1):PAGE304
     2 RST_PLD_CPU1_DRAM_CD_N @S9S_MB_2U_LIB.S9S_MB_2U(SCH_1):RST_PLD_CPU1_DRAM_CD_N    I72 @S9S_MB_2U_LIB.S9S_MB_2U(SCH_1):PAGE304
     6 LED_RST_PLD_CPU1_DRAM_CD_N_D @S9S_MB_2U_LIB.S9S_MB_2U(SCH_1):LED_RST_PLD_CPU1_DRAM_CD_N_D    I72 @S9S_MB_2U_LIB.S9S_MB_2U(SCH_1):PAGE304

Q100 MOSFET_NCH_DUAL-NX6008NBKS,SMLA
     1    GND @S9S_MB_2U_LIB.S9S_MB_2U(SCH_1):GND    I74 @S9S_MB_2U_LIB.S9S_MB_2U(SCH_1):PAGE304
     2 RST_PLD_CPU1_DRAM_EF_N @S9S_MB_2U_LIB.S9S_MB_2U(SCH_1):RST_PLD_CPU1_DRAM_EF_N    I74 @S9S_MB_2U_LIB.S9S_MB_2U(SCH_1):PAGE304
     6 LED_RST_PLD_CPU1_DRAM_EF_N_D @S9S_MB_2U_LIB.S9S_MB_2U(SCH_1):LED_RST_PLD_CPU1_DRAM_EF_N_D    I74 @S9S_MB_2U_LIB.S9S_MB_2U(SCH_1):PAGE304
     3 LED_RST_PLD_CPU1_DRAM_GH_N_D @S9S_MB_2U_LIB.S9S_MB_2U(SCH_1):LED_RST_PLD_CPU1_DRAM_GH_N_D    I75 @S9S_MB_2U_LIB.S9S_MB_2U(SCH_1):PAGE304
     5 RST_PLD_CPU1_DRAM_GH_N @S9S_MB_2U_LIB.S9S_MB_2U(SCH_1):RST_PLD_CPU1_DRAM_GH_N    I75 @S9S_MB_2U_LIB.S9S_MB_2U(SCH_1):PAGE304
     4    GND @S9S_MB_2U_LIB.S9S_MB_2U(SCH_1):GND    I75 @S9S_MB_2U_LIB.S9S_MB_2U(SCH_1):PAGE304

Q101 MOSFET_NCH_DUAL-PJT138K,SMLF,IA
     1    GND @S9S_MB_2U_LIB.S9S_MB_2U(SCH_1):GND    I52 @S9S_MB_2U_LIB.S9S_MB_2U(SCH_1):PAGE299
     2 GPU_FPGA_THERM_OVERT_N @S9S_MB_2U_LIB.S9S_MB_2U(SCH_1):GPU_FPGA_THERM_OVERT_N    I52 @S9S_MB_2U_LIB.S9S_MB_2U(SCH_1):PAGE299
     6 GPU_FPGA_THERM_OVERT @S9S_MB_2U_LIB.S9S_MB_2U(SCH_1):GPU_FPGA_THERM_OVERT    I52 @S9S_MB_2U_LIB.S9S_MB_2U(SCH_1):PAGE299
     3 GPU_FPGA_THERM_OVERT_ISO_N @S9S_MB_2U_LIB.S9S_MB_2U(SCH_1):GPU_FPGA_THERM_OVERT_ISO_N    I57 @S9S_MB_2U_LIB.S9S_MB_2U(SCH_1):PAGE299
     5 GPU_FPGA_THERM_OVERT @S9S_MB_2U_LIB.S9S_MB_2U(SCH_1):GPU_FPGA_THERM_OVERT    I57 @S9S_MB_2U_LIB.S9S_MB_2U(SCH_1):PAGE299
     4    GND @S9S_MB_2U_LIB.S9S_MB_2U(SCH_1):GND    I57 @S9S_MB_2U_LIB.S9S_MB_2U(SCH_1):PAGE299

Q102 MOSFET_NCH_DUAL-PJT138K,SMLF,IA
     1    GND @S9S_MB_2U_LIB.S9S_MB_2U(SCH_1):GND    I40 @S9S_MB_2U_LIB.S9S_MB_2U(SCH_1):PAGE299
     2 GPU_BASE_HMC_READY @S9S_MB_2U_LIB.S9S_MB_2U(SCH_1):GPU_BASE_HMC_READY    I40 @S9S_MB_2U_LIB.S9S_MB_2U(SCH_1):PAGE299
     6 GPU_BASE_HMC_READY_N @S9S_MB_2U_LIB.S9S_MB_2U(SCH_1):GPU_BASE_HMC_READY_N    I40 @S9S_MB_2U_LIB.S9S_MB_2U(SCH_1):PAGE299
     3 GPU_BASE_HMC_READY_ISO @S9S_MB_2U_LIB.S9S_MB_2U(SCH_1):GPU_BASE_HMC_READY_ISO    I48 @S9S_MB_2U_LIB.S9S_MB_2U(SCH_1):PAGE299
     5 GPU_BASE_HMC_READY_N @S9S_MB_2U_LIB.S9S_MB_2U(SCH_1):GPU_BASE_HMC_READY_N    I48 @S9S_MB_2U_LIB.S9S_MB_2U(SCH_1):PAGE299
     4    GND @S9S_MB_2U_LIB.S9S_MB_2U(SCH_1):GND    I48 @S9S_MB_2U_LIB.S9S_MB_2U(SCH_1):PAGE299

Q103 MOSFET_NCH_DUAL-PJT138K,SMLF,IA
     1    GND @S9S_MB_2U_LIB.S9S_MB_2U(SCH_1):GND    I37 @S9S_MB_2U_LIB.S9S_MB_2U(SCH_1):PAGE299
     2 GPU_HMC_PRSNT_N @S9S_MB_2U_LIB.S9S_MB_2U(SCH_1):GPU_HMC_PRSNT_N    I37 @S9S_MB_2U_LIB.S9S_MB_2U(SCH_1):PAGE299
     6 GPU_HMC_PRSNT @S9S_MB_2U_LIB.S9S_MB_2U(SCH_1):GPU_HMC_PRSNT    I37 @S9S_MB_2U_LIB.S9S_MB_2U(SCH_1):PAGE299
     3 GPU_HMC_PRSNT_ISO_N @S9S_MB_2U_LIB.S9S_MB_2U(SCH_1):GPU_HMC_PRSNT_ISO_N    I43 @S9S_MB_2U_LIB.S9S_MB_2U(SCH_1):PAGE299
     5 GPU_HMC_PRSNT @S9S_MB_2U_LIB.S9S_MB_2U(SCH_1):GPU_HMC_PRSNT    I43 @S9S_MB_2U_LIB.S9S_MB_2U(SCH_1):PAGE299
     4    GND @S9S_MB_2U_LIB.S9S_MB_2U(SCH_1):GND    I43 @S9S_MB_2U_LIB.S9S_MB_2U(SCH_1):PAGE299

Q104 MOSFET_NCH_DUAL-PJT138K,SMLF,IA
     1    GND @S9S_MB_2U_LIB.S9S_MB_2U(SCH_1):GND    I21 @S9S_MB_2U_LIB.S9S_MB_2U(SCH_1):PAGE299
     2 GPU_FPGA_OVERT_N @S9S_MB_2U_LIB.S9S_MB_2U(SCH_1):GPU_FPGA_OVERT_N    I21 @S9S_MB_2U_LIB.S9S_MB_2U(SCH_1):PAGE299
     6 GPU_FPGA_OVERT @S9S_MB_2U_LIB.S9S_MB_2U(SCH_1):GPU_FPGA_OVERT    I21 @S9S_MB_2U_LIB.S9S_MB_2U(SCH_1):PAGE299
     3 GPU_FPGA_OVERT_ISO_N @S9S_MB_2U_LIB.S9S_MB_2U(SCH_1):GPU_FPGA_OVERT_ISO_N    I26 @S9S_MB_2U_LIB.S9S_MB_2U(SCH_1):PAGE299
     5 GPU_FPGA_OVERT @S9S_MB_2U_LIB.S9S_MB_2U(SCH_1):GPU_FPGA_OVERT    I26 @S9S_MB_2U_LIB.S9S_MB_2U(SCH_1):PAGE299
     4    GND @S9S_MB_2U_LIB.S9S_MB_2U(SCH_1):GND    I26 @S9S_MB_2U_LIB.S9S_MB_2U(SCH_1):PAGE299

Q105 MOSFET_NCH_DUAL-NX6008NBKS,SMLA
     1    GND @S9S_MB_2U_LIB.S9S_MB_2U(SCH_1):GND    I76 @S9S_MB_2U_LIB.S9S_MB_2U(SCH_1):PAGE304
     2 RST_PLD_CPU1_DRAM_AB_N @S9S_MB_2U_LIB.S9S_MB_2U(SCH_1):RST_PLD_CPU1_DRAM_AB_N    I76 @S9S_MB_2U_LIB.S9S_MB_2U(SCH_1):PAGE304
     6 LED_RST_PLD_CPU1_DRAM_AB_N_D @S9S_MB_2U_LIB.S9S_MB_2U(SCH_1):LED_RST_PLD_CPU1_DRAM_AB_N_D    I76 @S9S_MB_2U_LIB.S9S_MB_2U(SCH_1):PAGE304

Q106 MOSFET_NCH_DUAL-PJT138K,SMLF,IA
     1    GND @S9S_MB_2U_LIB.S9S_MB_2U(SCH_1):GND   I135 @S9S_MB_2U_LIB.S9S_MB_2U(SCH_1):PAGE299
     2 GPU_WP_HW_CTRL_N @S9S_MB_2U_LIB.S9S_MB_2U(SCH_1):GPU_WP_HW_CTRL_N   I135 @S9S_MB_2U_LIB.S9S_MB_2U(SCH_1):PAGE299
     6 GPU_WP_HW_CTRL_ISO @S9S_MB_2U_LIB.S9S_MB_2U(SCH_1):GPU_WP_HW_CTRL_ISO   I135 @S9S_MB_2U_LIB.S9S_MB_2U(SCH_1):PAGE299

Q107 MOSFET_NCH_DUAL-PJT138K,SMLF,IA
     1    GND @S9S_MB_2U_LIB.S9S_MB_2U(SCH_1):GND   I160 @S9S_MB_2U_LIB.S9S_MB_2U(SCH_1):PAGE299
     2 GPU_PRSNT_N @S9S_MB_2U_LIB.S9S_MB_2U(SCH_1):GPU_PRSNT_N   I160 @S9S_MB_2U_LIB.S9S_MB_2U(SCH_1):PAGE299
     6 GPU_PRSNT @S9S_MB_2U_LIB.S9S_MB_2U(SCH_1):GPU_PRSNT   I160 @S9S_MB_2U_LIB.S9S_MB_2U(SCH_1):PAGE299
     3 GPU_PRSNT_N_ISO @S9S_MB_2U_LIB.S9S_MB_2U(SCH_1):GPU_PRSNT_N_ISO   I157 @S9S_MB_2U_LIB.S9S_MB_2U(SCH_1):PAGE299
     5 GPU_PRSNT @S9S_MB_2U_LIB.S9S_MB_2U(SCH_1):GPU_PRSNT   I157 @S9S_MB_2U_LIB.S9S_MB_2U(SCH_1):PAGE299
     4    GND @S9S_MB_2U_LIB.S9S_MB_2U(SCH_1):GND   I157 @S9S_MB_2U_LIB.S9S_MB_2U(SCH_1):PAGE299

Q108 MOSFET_NCH_DUAL-PJT138K,SMLF,IA
     1    GND @S9S_MB_2U_LIB.S9S_MB_2U(SCH_1):GND   I169 @S9S_MB_2U_LIB.S9S_MB_2U(SCH_1):PAGE299
     2 GPU_FPGA_EROT_FATALERR_N @S9S_MB_2U_LIB.S9S_MB_2U(SCH_1):GPU_FPGA_EROT_FATALERR_N   I169 @S9S_MB_2U_LIB.S9S_MB_2U(SCH_1):PAGE299
     6 GPU_FPGA_EROT_FATALERR @S9S_MB_2U_LIB.S9S_MB_2U(SCH_1):GPU_FPGA_EROT_FATALERR   I169 @S9S_MB_2U_LIB.S9S_MB_2U(SCH_1):PAGE299
     3 GPU_FPGA_EROT_FATALERR_ISO_N @S9S_MB_2U_LIB.S9S_MB_2U(SCH_1):GPU_FPGA_EROT_FATALERR_ISO_N   I168 @S9S_MB_2U_LIB.S9S_MB_2U(SCH_1):PAGE299
     5 GPU_FPGA_EROT_FATALERR @S9S_MB_2U_LIB.S9S_MB_2U(SCH_1):GPU_FPGA_EROT_FATALERR   I168 @S9S_MB_2U_LIB.S9S_MB_2U(SCH_1):PAGE299
     4    GND @S9S_MB_2U_LIB.S9S_MB_2U(SCH_1):GND   I168 @S9S_MB_2U_LIB.S9S_MB_2U(SCH_1):PAGE299

Q118 MOSFET_NCH_DUAL-PJT138K,SMLF,EA
     1    GND @S9S_MB_2U_LIB.S9S_MB_2U(SCH_1):GND     I7 @S9S_MB_2U_LIB.S9S_MB_2U(SCH_1):PAGE131
     2 P12V_OCP_EN_2_R @S9S_MB_2U_LIB.S9S_MB_2U(SCH_1):P12V_OCP_EN_2_R     I7 @S9S_MB_2U_LIB.S9S_MB_2U(SCH_1):PAGE131
     6 P12V_OCP_2_EN_G @S9S_MB_2U_LIB.S9S_MB_2U(SCH_1):P12V_OCP_2_EN_G     I7 @S9S_MB_2U_LIB.S9S_MB_2U(SCH_1):PAGE131
     3 P12V_OCP_UV_2_R @S9S_MB_2U_LIB.S9S_MB_2U(SCH_1):P12V_OCP_UV_2_R    I16 @S9S_MB_2U_LIB.S9S_MB_2U(SCH_1):PAGE131
     5 P12V_OCP_2_EN_G @S9S_MB_2U_LIB.S9S_MB_2U(SCH_1):P12V_OCP_2_EN_G    I16 @S9S_MB_2U_LIB.S9S_MB_2U(SCH_1):PAGE131
     4    GND @S9S_MB_2U_LIB.S9S_MB_2U(SCH_1):GND    I16 @S9S_MB_2U_LIB.S9S_MB_2U(SCH_1):PAGE131

Q119 MOSFET_NCH_DUAL-PJT138K,SMLF,IA
     1    GND @S9S_MB_2U_LIB.S9S_MB_2U(SCH_1):GND    I38 @S9S_MB_2U_LIB.S9S_MB_2U(SCH_1):PAGE131
     2 P3V3_OCP_EN_2_R @S9S_MB_2U_LIB.S9S_MB_2U(SCH_1):P3V3_OCP_EN_2_R    I38 @S9S_MB_2U_LIB.S9S_MB_2U(SCH_1):PAGE131
     6 P3V3_OCP_2_EN_G @S9S_MB_2U_LIB.S9S_MB_2U(SCH_1):P3V3_OCP_2_EN_G    I38 @S9S_MB_2U_LIB.S9S_MB_2U(SCH_1):PAGE131
     3 P3V3_OCP_UV_2_R1 @S9S_MB_2U_LIB.S9S_MB_2U(SCH_1):P3V3_OCP_UV_2_R1    I42 @S9S_MB_2U_LIB.S9S_MB_2U(SCH_1):PAGE131
     5 P3V3_OCP_2_EN_G @S9S_MB_2U_LIB.S9S_MB_2U(SCH_1):P3V3_OCP_2_EN_G    I42 @S9S_MB_2U_LIB.S9S_MB_2U(SCH_1):PAGE131
     4    GND @S9S_MB_2U_LIB.S9S_MB_2U(SCH_1):GND    I42 @S9S_MB_2U_LIB.S9S_MB_2U(SCH_1):PAGE131

Q123 MOSFET_NCH_DUAL-PJT138K,SMLF,EA
     1    GND @S9S_MB_2U_LIB.S9S_MB_2U(SCH_1):GND     I9 @S9S_MB_2U_LIB.S9S_MB_2U(SCH_1):PAGE153
     2 P12V_OCP_EN_1_R @S9S_MB_2U_LIB.S9S_MB_2U(SCH_1):P12V_OCP_EN_1_R     I9 @S9S_MB_2U_LIB.S9S_MB_2U(SCH_1):PAGE153
     6 P12V_OCP_1_EN_G @S9S_MB_2U_LIB.S9S_MB_2U(SCH_1):P12V_OCP_1_EN_G     I9 @S9S_MB_2U_LIB.S9S_MB_2U(SCH_1):PAGE153
     3 P12V_OCP_UV_1_R @S9S_MB_2U_LIB.S9S_MB_2U(SCH_1):P12V_OCP_UV_1_R    I17 @S9S_MB_2U_LIB.S9S_MB_2U(SCH_1):PAGE153
     5 P12V_OCP_1_EN_G @S9S_MB_2U_LIB.S9S_MB_2U(SCH_1):P12V_OCP_1_EN_G    I17 @S9S_MB_2U_LIB.S9S_MB_2U(SCH_1):PAGE153
     4    GND @S9S_MB_2U_LIB.S9S_MB_2U(SCH_1):GND    I17 @S9S_MB_2U_LIB.S9S_MB_2U(SCH_1):PAGE153

Q124 MOSFET_NCH_DUAL-PJT138K,SMLF,IA
     1    GND @S9S_MB_2U_LIB.S9S_MB_2U(SCH_1):GND    I21 @S9S_MB_2U_LIB.S9S_MB_2U(SCH_1):PAGE153
     2 P3V3_OCP_EN_1_R @S9S_MB_2U_LIB.S9S_MB_2U(SCH_1):P3V3_OCP_EN_1_R    I21 @S9S_MB_2U_LIB.S9S_MB_2U(SCH_1):PAGE153
     6 P3V3_OCP_1_EN_G @S9S_MB_2U_LIB.S9S_MB_2U(SCH_1):P3V3_OCP_1_EN_G    I21 @S9S_MB_2U_LIB.S9S_MB_2U(SCH_1):PAGE153
     3 P3V3_OCP_UV_1_R1 @S9S_MB_2U_LIB.S9S_MB_2U(SCH_1):P3V3_OCP_UV_1_R1    I36 @S9S_MB_2U_LIB.S9S_MB_2U(SCH_1):PAGE153
     5 P3V3_OCP_1_EN_G @S9S_MB_2U_LIB.S9S_MB_2U(SCH_1):P3V3_OCP_1_EN_G    I36 @S9S_MB_2U_LIB.S9S_MB_2U(SCH_1):PAGE153
     4    GND @S9S_MB_2U_LIB.S9S_MB_2U(SCH_1):GND    I36 @S9S_MB_2U_LIB.S9S_MB_2U(SCH_1):PAGE153

Q125 MOSFET_NCH_DUAL-PJT138K,SMLF,EA
     1    GND @S9S_MB_2U_LIB.S9S_MB_2U(SCH_1):GND    I21 @S9S_MB_2U_LIB.S9S_MB_2U(SCH_1):PAGE229
     2 P12V_SCM_EN_R @S9S_MB_2U_LIB.S9S_MB_2U(SCH_1):P12V_SCM_EN_R    I21 @S9S_MB_2U_LIB.S9S_MB_2U(SCH_1):PAGE229
     6 P12V_SCM_EN_G @S9S_MB_2U_LIB.S9S_MB_2U(SCH_1):P12V_SCM_EN_G    I21 @S9S_MB_2U_LIB.S9S_MB_2U(SCH_1):PAGE229
     3 P12V_SCM_UV_R @S9S_MB_2U_LIB.S9S_MB_2U(SCH_1):P12V_SCM_UV_R    I26 @S9S_MB_2U_LIB.S9S_MB_2U(SCH_1):PAGE229
     5 P12V_SCM_EN_G @S9S_MB_2U_LIB.S9S_MB_2U(SCH_1):P12V_SCM_EN_G    I26 @S9S_MB_2U_LIB.S9S_MB_2U(SCH_1):PAGE229
     4    GND @S9S_MB_2U_LIB.S9S_MB_2U(SCH_1):GND    I26 @S9S_MB_2U_LIB.S9S_MB_2U(SCH_1):PAGE229

Q126 MOSFET_NCH_DUAL-PJT138K,SMLF,IA
     1    GND @S9S_MB_2U_LIB.S9S_MB_2U(SCH_1):GND     I3 @S9S_MB_2U_LIB.S9S_MB_2U(SCH_1):PAGE324
     2 P3V3_E1S_EN_1_R @S9S_MB_2U_LIB.S9S_MB_2U(SCH_1):P3V3_E1S_EN_1_R     I3 @S9S_MB_2U_LIB.S9S_MB_2U(SCH_1):PAGE324
     6 P3V3_E1S_0_EN_G @S9S_MB_2U_LIB.S9S_MB_2U(SCH_1):P3V3_E1S_0_EN_G     I3 @S9S_MB_2U_LIB.S9S_MB_2U(SCH_1):PAGE324
     3 P3V3_E1S_UV_0_R @S9S_MB_2U_LIB.S9S_MB_2U(SCH_1):P3V3_E1S_UV_0_R     I4 @S9S_MB_2U_LIB.S9S_MB_2U(SCH_1):PAGE324
     5 P3V3_E1S_0_EN_G @S9S_MB_2U_LIB.S9S_MB_2U(SCH_1):P3V3_E1S_0_EN_G     I4 @S9S_MB_2U_LIB.S9S_MB_2U(SCH_1):PAGE324
     4    GND @S9S_MB_2U_LIB.S9S_MB_2U(SCH_1):GND     I4 @S9S_MB_2U_LIB.S9S_MB_2U(SCH_1):PAGE324

Q127 MOSFET_NCH_DUAL-PJT138K,SMLF,EA
     1    GND @S9S_MB_2U_LIB.S9S_MB_2U(SCH_1):GND    I10 @S9S_MB_2U_LIB.S9S_MB_2U(SCH_1):PAGE324
     2 P12V_E1S_EN_0_R @S9S_MB_2U_LIB.S9S_MB_2U(SCH_1):P12V_E1S_EN_0_R    I10 @S9S_MB_2U_LIB.S9S_MB_2U(SCH_1):PAGE324
     6 P12V_E1S_0_EN_G @S9S_MB_2U_LIB.S9S_MB_2U(SCH_1):P12V_E1S_0_EN_G    I10 @S9S_MB_2U_LIB.S9S_MB_2U(SCH_1):PAGE324
     3 P12V_E1S_UV_0_R @S9S_MB_2U_LIB.S9S_MB_2U(SCH_1):P12V_E1S_UV_0_R    I24 @S9S_MB_2U_LIB.S9S_MB_2U(SCH_1):PAGE324
     5 P12V_E1S_0_EN_G @S9S_MB_2U_LIB.S9S_MB_2U(SCH_1):P12V_E1S_0_EN_G    I24 @S9S_MB_2U_LIB.S9S_MB_2U(SCH_1):PAGE324
     4    GND @S9S_MB_2U_LIB.S9S_MB_2U(SCH_1):GND    I24 @S9S_MB_2U_LIB.S9S_MB_2U(SCH_1):PAGE324

Q128 MOSFET_NCH_DUAL-PJT138K,SMLF,IA
     1    GND @S9S_MB_2U_LIB.S9S_MB_2U(SCH_1):GND    I11 @S9S_MB_2U_LIB.S9S_MB_2U(SCH_1):PAGE143
     2 GPU_3V3IO_RSVD0_FFU @S9S_MB_2U_LIB.S9S_MB_2U(SCH_1):GPU_3V3IO_RSVD0_FFU    I11 @S9S_MB_2U_LIB.S9S_MB_2U(SCH_1):PAGE143
     6 GPU_3V3IO_RSVD0_FFU_N @S9S_MB_2U_LIB.S9S_MB_2U(SCH_1):GPU_3V3IO_RSVD0_FFU_N    I11 @S9S_MB_2U_LIB.S9S_MB_2U(SCH_1):PAGE143
     3 GPU_3V3IO_RSVD0_FFU_ISO @S9S_MB_2U_LIB.S9S_MB_2U(SCH_1):GPU_3V3IO_RSVD0_FFU_ISO     I6 @S9S_MB_2U_LIB.S9S_MB_2U(SCH_1):PAGE143
     5 GPU_3V3IO_RSVD0_FFU_N @S9S_MB_2U_LIB.S9S_MB_2U(SCH_1):GPU_3V3IO_RSVD0_FFU_N     I6 @S9S_MB_2U_LIB.S9S_MB_2U(SCH_1):PAGE143
     4    GND @S9S_MB_2U_LIB.S9S_MB_2U(SCH_1):GND     I6 @S9S_MB_2U_LIB.S9S_MB_2U(SCH_1):PAGE143

Q129 MOSFET_NCH_DUAL-PJT138K,SMLF,IA
     1    GND @S9S_MB_2U_LIB.S9S_MB_2U(SCH_1):GND    I83 @S9S_MB_2U_LIB.S9S_MB_2U(SCH_1):PAGE143
     2 GPU_3V3IO_RSVD5_FFU @S9S_MB_2U_LIB.S9S_MB_2U(SCH_1):GPU_3V3IO_RSVD5_FFU    I83 @S9S_MB_2U_LIB.S9S_MB_2U(SCH_1):PAGE143
     6 GPU_3V3IO_RSVD5_FFU_N @S9S_MB_2U_LIB.S9S_MB_2U(SCH_1):GPU_3V3IO_RSVD5_FFU_N    I83 @S9S_MB_2U_LIB.S9S_MB_2U(SCH_1):PAGE143
     3 GPU_3V3IO_RSVD5_FFU_ISO @S9S_MB_2U_LIB.S9S_MB_2U(SCH_1):GPU_3V3IO_RSVD5_FFU_ISO    I77 @S9S_MB_2U_LIB.S9S_MB_2U(SCH_1):PAGE143
     5 GPU_3V3IO_RSVD5_FFU_N @S9S_MB_2U_LIB.S9S_MB_2U(SCH_1):GPU_3V3IO_RSVD5_FFU_N    I77 @S9S_MB_2U_LIB.S9S_MB_2U(SCH_1):PAGE143
     4    GND @S9S_MB_2U_LIB.S9S_MB_2U(SCH_1):GND    I77 @S9S_MB_2U_LIB.S9S_MB_2U(SCH_1):PAGE143

Q130 MOSFET_NCH_DUAL-PJT138K,SMLF,IA
     1    GND @S9S_MB_2U_LIB.S9S_MB_2U(SCH_1):GND    I74 @S9S_MB_2U_LIB.S9S_MB_2U(SCH_1):PAGE143
     2 GPU_3V3IO_RSVD3_FFU @S9S_MB_2U_LIB.S9S_MB_2U(SCH_1):GPU_3V3IO_RSVD3_FFU    I74 @S9S_MB_2U_LIB.S9S_MB_2U(SCH_1):PAGE143
     6 GPU_3V3IO_RSVD3_FFU_N @S9S_MB_2U_LIB.S9S_MB_2U(SCH_1):GPU_3V3IO_RSVD3_FFU_N    I74 @S9S_MB_2U_LIB.S9S_MB_2U(SCH_1):PAGE143
     3 GPU_3V3IO_RSVD3_FFU_ISO @S9S_MB_2U_LIB.S9S_MB_2U(SCH_1):GPU_3V3IO_RSVD3_FFU_ISO    I70 @S9S_MB_2U_LIB.S9S_MB_2U(SCH_1):PAGE143
     5 GPU_3V3IO_RSVD3_FFU_N @S9S_MB_2U_LIB.S9S_MB_2U(SCH_1):GPU_3V3IO_RSVD3_FFU_N    I70 @S9S_MB_2U_LIB.S9S_MB_2U(SCH_1):PAGE143
     4    GND @S9S_MB_2U_LIB.S9S_MB_2U(SCH_1):GND    I70 @S9S_MB_2U_LIB.S9S_MB_2U(SCH_1):PAGE143

Q131 MOSFET_NCH_DUAL-PJT138K,SMLF,IA
     1    GND @S9S_MB_2U_LIB.S9S_MB_2U(SCH_1):GND    I29 @S9S_MB_2U_LIB.S9S_MB_2U(SCH_1):PAGE143
     2 GPU_3V3IO_RSVD1_FFU @S9S_MB_2U_LIB.S9S_MB_2U(SCH_1):GPU_3V3IO_RSVD1_FFU    I29 @S9S_MB_2U_LIB.S9S_MB_2U(SCH_1):PAGE143
     6 GPU_3V3IO_RSVD1_FFU_N @S9S_MB_2U_LIB.S9S_MB_2U(SCH_1):GPU_3V3IO_RSVD1_FFU_N    I29 @S9S_MB_2U_LIB.S9S_MB_2U(SCH_1):PAGE143
     3 GPU_3V3IO_RSVD1_FFU_ISO @S9S_MB_2U_LIB.S9S_MB_2U(SCH_1):GPU_3V3IO_RSVD1_FFU_ISO    I19 @S9S_MB_2U_LIB.S9S_MB_2U(SCH_1):PAGE143
     5 GPU_3V3IO_RSVD1_FFU_N @S9S_MB_2U_LIB.S9S_MB_2U(SCH_1):GPU_3V3IO_RSVD1_FFU_N    I19 @S9S_MB_2U_LIB.S9S_MB_2U(SCH_1):PAGE143
     4    GND @S9S_MB_2U_LIB.S9S_MB_2U(SCH_1):GND    I19 @S9S_MB_2U_LIB.S9S_MB_2U(SCH_1):PAGE143

Q132 MOSFET_NCH_DUAL-PJT138K,SMLF,IA
     1    GND @S9S_MB_2U_LIB.S9S_MB_2U(SCH_1):GND    I44 @S9S_MB_2U_LIB.S9S_MB_2U(SCH_1):PAGE143
     2 PRSNT_CABLE_GPU_B3_N @S9S_MB_2U_LIB.S9S_MB_2U(SCH_1):PRSNT_CABLE_GPU_B3_N    I44 @S9S_MB_2U_LIB.S9S_MB_2U(SCH_1):PAGE143
     6 PRSNT_CABLE_GPU_B3 @S9S_MB_2U_LIB.S9S_MB_2U(SCH_1):PRSNT_CABLE_GPU_B3    I44 @S9S_MB_2U_LIB.S9S_MB_2U(SCH_1):PAGE143
     3 PRSNT_CABLE_GPU_B3_ISO_N @S9S_MB_2U_LIB.S9S_MB_2U(SCH_1):PRSNT_CABLE_GPU_B3_ISO_N    I35 @S9S_MB_2U_LIB.S9S_MB_2U(SCH_1):PAGE143
     5 PRSNT_CABLE_GPU_B3 @S9S_MB_2U_LIB.S9S_MB_2U(SCH_1):PRSNT_CABLE_GPU_B3    I35 @S9S_MB_2U_LIB.S9S_MB_2U(SCH_1):PAGE143
     4    GND @S9S_MB_2U_LIB.S9S_MB_2U(SCH_1):GND    I35 @S9S_MB_2U_LIB.S9S_MB_2U(SCH_1):PAGE143

Q133 MOSFET_NCH_DUAL-PJT138K,SMLF,IA
     1    GND @S9S_MB_2U_LIB.S9S_MB_2U(SCH_1):GND    I78 @S9S_MB_2U_LIB.S9S_MB_2U(SCH_1):PAGE143
     2 PRSNT_CABLE_GPU_A2_N @S9S_MB_2U_LIB.S9S_MB_2U(SCH_1):PRSNT_CABLE_GPU_A2_N    I78 @S9S_MB_2U_LIB.S9S_MB_2U(SCH_1):PAGE143
     6 PRSNT_CABLE_GPU_A2 @S9S_MB_2U_LIB.S9S_MB_2U(SCH_1):PRSNT_CABLE_GPU_A2    I78 @S9S_MB_2U_LIB.S9S_MB_2U(SCH_1):PAGE143
     3 PRSNT_CABLE_GPU_A2_ISO_N @S9S_MB_2U_LIB.S9S_MB_2U(SCH_1):PRSNT_CABLE_GPU_A2_ISO_N    I71 @S9S_MB_2U_LIB.S9S_MB_2U(SCH_1):PAGE143
     5 PRSNT_CABLE_GPU_A2 @S9S_MB_2U_LIB.S9S_MB_2U(SCH_1):PRSNT_CABLE_GPU_A2    I71 @S9S_MB_2U_LIB.S9S_MB_2U(SCH_1):PAGE143
     4    GND @S9S_MB_2U_LIB.S9S_MB_2U(SCH_1):GND    I71 @S9S_MB_2U_LIB.S9S_MB_2U(SCH_1):PAGE143

Q134 MOSFET_NCH_DUAL-PJT138K,SMLF,IA
     1    GND @S9S_MB_2U_LIB.S9S_MB_2U(SCH_1):GND    I99 @S9S_MB_2U_LIB.S9S_MB_2U(SCH_1):PAGE143
     2 PRSNT_CABLE_GPU_A1_N @S9S_MB_2U_LIB.S9S_MB_2U(SCH_1):PRSNT_CABLE_GPU_A1_N    I99 @S9S_MB_2U_LIB.S9S_MB_2U(SCH_1):PAGE143
     6 PRSNT_CABLE_GPU_A1 @S9S_MB_2U_LIB.S9S_MB_2U(SCH_1):PRSNT_CABLE_GPU_A1    I99 @S9S_MB_2U_LIB.S9S_MB_2U(SCH_1):PAGE143
     3 PRSNT_CABLE_GPU_A1_ISO_N @S9S_MB_2U_LIB.S9S_MB_2U(SCH_1):PRSNT_CABLE_GPU_A1_ISO_N   I107 @S9S_MB_2U_LIB.S9S_MB_2U(SCH_1):PAGE143
     5 PRSNT_CABLE_GPU_A1 @S9S_MB_2U_LIB.S9S_MB_2U(SCH_1):PRSNT_CABLE_GPU_A1   I107 @S9S_MB_2U_LIB.S9S_MB_2U(SCH_1):PAGE143
     4    GND @S9S_MB_2U_LIB.S9S_MB_2U(SCH_1):GND   I107 @S9S_MB_2U_LIB.S9S_MB_2U(SCH_1):PAGE143

Q135 MOSFET_NCH_DUAL-PJT138K,SMLF,IA
     1    GND @S9S_MB_2U_LIB.S9S_MB_2U(SCH_1):GND    I25 @S9S_MB_2U_LIB.S9S_MB_2U(SCH_1):PAGE139
     2 GPU_3V3IO_RSVD1 @S9S_MB_2U_LIB.S9S_MB_2U(SCH_1):GPU_3V3IO_RSVD1    I25 @S9S_MB_2U_LIB.S9S_MB_2U(SCH_1):PAGE139
     6 GPU_3V3IO_RSVD1_N @S9S_MB_2U_LIB.S9S_MB_2U(SCH_1):GPU_3V3IO_RSVD1_N    I25 @S9S_MB_2U_LIB.S9S_MB_2U(SCH_1):PAGE139
     3 GPU_3V3IO_RSVD1_ISO @S9S_MB_2U_LIB.S9S_MB_2U(SCH_1):GPU_3V3IO_RSVD1_ISO    I29 @S9S_MB_2U_LIB.S9S_MB_2U(SCH_1):PAGE139
     5 GPU_3V3IO_RSVD1_N @S9S_MB_2U_LIB.S9S_MB_2U(SCH_1):GPU_3V3IO_RSVD1_N    I29 @S9S_MB_2U_LIB.S9S_MB_2U(SCH_1):PAGE139
     4    GND @S9S_MB_2U_LIB.S9S_MB_2U(SCH_1):GND    I29 @S9S_MB_2U_LIB.S9S_MB_2U(SCH_1):PAGE139

Q136 MOSFET_NCH_DUAL-PJT138K,SMLF,IA
     1    GND @S9S_MB_2U_LIB.S9S_MB_2U(SCH_1):GND    I17 @S9S_MB_2U_LIB.S9S_MB_2U(SCH_1):PAGE139
     2 GPU_3V3IO_RSVD4 @S9S_MB_2U_LIB.S9S_MB_2U(SCH_1):GPU_3V3IO_RSVD4    I17 @S9S_MB_2U_LIB.S9S_MB_2U(SCH_1):PAGE139
     6 GPU_3V3IO_RSVD4_N @S9S_MB_2U_LIB.S9S_MB_2U(SCH_1):GPU_3V3IO_RSVD4_N    I17 @S9S_MB_2U_LIB.S9S_MB_2U(SCH_1):PAGE139
     3 GPU_3V3IO_RSVD4_ISO @S9S_MB_2U_LIB.S9S_MB_2U(SCH_1):GPU_3V3IO_RSVD4_ISO    I22 @S9S_MB_2U_LIB.S9S_MB_2U(SCH_1):PAGE139
     5 GPU_3V3IO_RSVD4_N @S9S_MB_2U_LIB.S9S_MB_2U(SCH_1):GPU_3V3IO_RSVD4_N    I22 @S9S_MB_2U_LIB.S9S_MB_2U(SCH_1):PAGE139
     4    GND @S9S_MB_2U_LIB.S9S_MB_2U(SCH_1):GND    I22 @S9S_MB_2U_LIB.S9S_MB_2U(SCH_1):PAGE139

Q137 MOSFET_NCH_DUAL-PJT138K,SMLF,IA
     1    GND @S9S_MB_2U_LIB.S9S_MB_2U(SCH_1):GND    I21 @S9S_MB_2U_LIB.S9S_MB_2U(SCH_1):PAGE139
     2 GPU_3V3IO_RSVD3 @S9S_MB_2U_LIB.S9S_MB_2U(SCH_1):GPU_3V3IO_RSVD3    I21 @S9S_MB_2U_LIB.S9S_MB_2U(SCH_1):PAGE139
     6 GPU_3V3IO_RSVD3_N @S9S_MB_2U_LIB.S9S_MB_2U(SCH_1):GPU_3V3IO_RSVD3_N    I21 @S9S_MB_2U_LIB.S9S_MB_2U(SCH_1):PAGE139
     3 GPU_3V3IO_RSVD3_ISO @S9S_MB_2U_LIB.S9S_MB_2U(SCH_1):GPU_3V3IO_RSVD3_ISO    I28 @S9S_MB_2U_LIB.S9S_MB_2U(SCH_1):PAGE139
     5 GPU_3V3IO_RSVD3_N @S9S_MB_2U_LIB.S9S_MB_2U(SCH_1):GPU_3V3IO_RSVD3_N    I28 @S9S_MB_2U_LIB.S9S_MB_2U(SCH_1):PAGE139
     4    GND @S9S_MB_2U_LIB.S9S_MB_2U(SCH_1):GND    I28 @S9S_MB_2U_LIB.S9S_MB_2U(SCH_1):PAGE139

Q138 BC847BPN-BC847BPN,SMLF,IC,BA00A
     2 H_CPU0_THERMTRIP_R_N @S9S_MB_2U_LIB.S9S_MB_2U(SCH_1):H_CPU0_THERMTRIP_R_N    I31 @S9S_MB_2U_LIB.S9S_MB_2U(SCH_1):PAGE121
     6 H_CPU0_THERMTRIP_VT_N @S9S_MB_2U_LIB.S9S_MB_2U(SCH_1):H_CPU0_THERMTRIP_VT_N    I31 @S9S_MB_2U_LIB.S9S_MB_2U(SCH_1):PAGE121
     1    GND @S9S_MB_2U_LIB.S9S_MB_2U(SCH_1):GND    I31 @S9S_MB_2U_LIB.S9S_MB_2U(SCH_1):PAGE121
     5 H_CPU0_THERMTRIP_VT_R_N @S9S_MB_2U_LIB.S9S_MB_2U(SCH_1):H_CPU0_THERMTRIP_VT_R_N    I17 @S9S_MB_2U_LIB.S9S_MB_2U(SCH_1):PAGE121
     3 H_CPU0_THERMTRIP_N @S9S_MB_2U_LIB.S9S_MB_2U(SCH_1):H_CPU0_THERMTRIP_N    I17 @S9S_MB_2U_LIB.S9S_MB_2U(SCH_1):PAGE121
     4 PVNN_TERM_CPU0 @S9S_MB_2U_LIB.S9S_MB_2U(SCH_1):PVNN_TERM_CPU0    I17 @S9S_MB_2U_LIB.S9S_MB_2U(SCH_1):PAGE121

Q139 BC847BPN-BC847BPN,SMLF,IC,BA00A
     2 H_CPU1_THERMTRIP_R_N @S9S_MB_2U_LIB.S9S_MB_2U(SCH_1):H_CPU1_THERMTRIP_R_N    I21 @S9S_MB_2U_LIB.S9S_MB_2U(SCH_1):PAGE121
     6 H_CPU1_THERMTRIP_VT_N @S9S_MB_2U_LIB.S9S_MB_2U(SCH_1):H_CPU1_THERMTRIP_VT_N    I21 @S9S_MB_2U_LIB.S9S_MB_2U(SCH_1):PAGE121
     1    GND @S9S_MB_2U_LIB.S9S_MB_2U(SCH_1):GND    I21 @S9S_MB_2U_LIB.S9S_MB_2U(SCH_1):PAGE121
     5 H_CPU1_THERMTRIP_VT_R_N @S9S_MB_2U_LIB.S9S_MB_2U(SCH_1):H_CPU1_THERMTRIP_VT_R_N     I8 @S9S_MB_2U_LIB.S9S_MB_2U(SCH_1):PAGE121
     3 H_CPU1_THERMTRIP_N @S9S_MB_2U_LIB.S9S_MB_2U(SCH_1):H_CPU1_THERMTRIP_N     I8 @S9S_MB_2U_LIB.S9S_MB_2U(SCH_1):PAGE121
     4 PVNN_TERM_CPU1 @S9S_MB_2U_LIB.S9S_MB_2U(SCH_1):PVNN_TERM_CPU1     I8 @S9S_MB_2U_LIB.S9S_MB_2U(SCH_1):PAGE121

Q140 BC847BPN-BC847BPN,SMLF,IC,BA00A
     2 H_CPU1_MEMTRIP_R @S9S_MB_2U_LIB.S9S_MB_2U(SCH_1):H_CPU1_MEMTRIP_R    I16 @S9S_MB_2U_LIB.S9S_MB_2U(SCH_1):PAGE123
     6 H_CPU1_MEMTRIP_VT_N @S9S_MB_2U_LIB.S9S_MB_2U(SCH_1):H_CPU1_MEMTRIP_VT_N    I16 @S9S_MB_2U_LIB.S9S_MB_2U(SCH_1):PAGE123
     1    GND @S9S_MB_2U_LIB.S9S_MB_2U(SCH_1):GND    I16 @S9S_MB_2U_LIB.S9S_MB_2U(SCH_1):PAGE123
     5 H_CPU1_MEMTRIP_OUT_VT_R_N @S9S_MB_2U_LIB.S9S_MB_2U(SCH_1):H_CPU1_MEMTRIP_OUT_VT_R_N    I11 @S9S_MB_2U_LIB.S9S_MB_2U(SCH_1):PAGE123
     3 H_CPU1_MEMTRIP @S9S_MB_2U_LIB.S9S_MB_2U(SCH_1):H_CPU1_MEMTRIP    I11 @S9S_MB_2U_LIB.S9S_MB_2U(SCH_1):PAGE123
     4 PVNN_TERM_CPU1 @S9S_MB_2U_LIB.S9S_MB_2U(SCH_1):PVNN_TERM_CPU1    I11 @S9S_MB_2U_LIB.S9S_MB_2U(SCH_1):PAGE123

Q141 BC847BPN-BC847BPN,SMLF,IC,BA00A
     2 H_CPU0_MEMTRIP_R @S9S_MB_2U_LIB.S9S_MB_2U(SCH_1):H_CPU0_MEMTRIP_R    I18 @S9S_MB_2U_LIB.S9S_MB_2U(SCH_1):PAGE123
     6 H_CPU0_MEMTRIP_VT_N @S9S_MB_2U_LIB.S9S_MB_2U(SCH_1):H_CPU0_MEMTRIP_VT_N    I18 @S9S_MB_2U_LIB.S9S_MB_2U(SCH_1):PAGE123
     1    GND @S9S_MB_2U_LIB.S9S_MB_2U(SCH_1):GND    I18 @S9S_MB_2U_LIB.S9S_MB_2U(SCH_1):PAGE123
     5 H_CPU0_MEMTRIP_OUT_VT_R_N @S9S_MB_2U_LIB.S9S_MB_2U(SCH_1):H_CPU0_MEMTRIP_OUT_VT_R_N    I12 @S9S_MB_2U_LIB.S9S_MB_2U(SCH_1):PAGE123
     3 H_CPU0_MEMTRIP @S9S_MB_2U_LIB.S9S_MB_2U(SCH_1):H_CPU0_MEMTRIP    I12 @S9S_MB_2U_LIB.S9S_MB_2U(SCH_1):PAGE123
     4 PVNN_TERM_CPU0 @S9S_MB_2U_LIB.S9S_MB_2U(SCH_1):PVNN_TERM_CPU0    I12 @S9S_MB_2U_LIB.S9S_MB_2U(SCH_1):PAGE123

Q142 BC847BPN-BC847BPN,SMLF,IC,BA00A
     2 H_CPU1_MEMHOT_OUT_R @S9S_MB_2U_LIB.S9S_MB_2U(SCH_1):H_CPU1_MEMHOT_OUT_R    I17 @S9S_MB_2U_LIB.S9S_MB_2U(SCH_1):PAGE122
     6 H_CPU1_MEMHOT_OUT_VT_N @S9S_MB_2U_LIB.S9S_MB_2U(SCH_1):H_CPU1_MEMHOT_OUT_VT_N    I17 @S9S_MB_2U_LIB.S9S_MB_2U(SCH_1):PAGE122
     1    GND @S9S_MB_2U_LIB.S9S_MB_2U(SCH_1):GND    I17 @S9S_MB_2U_LIB.S9S_MB_2U(SCH_1):PAGE122
     5 H_CPU1_MEMHOT_OUT_VT_R_N @S9S_MB_2U_LIB.S9S_MB_2U(SCH_1):H_CPU1_MEMHOT_OUT_VT_R_N    I10 @S9S_MB_2U_LIB.S9S_MB_2U(SCH_1):PAGE122
     3 H_CPU1_MEMHOT_OUT @S9S_MB_2U_LIB.S9S_MB_2U(SCH_1):H_CPU1_MEMHOT_OUT    I10 @S9S_MB_2U_LIB.S9S_MB_2U(SCH_1):PAGE122
     4 PVNN_TERM_CPU1 @S9S_MB_2U_LIB.S9S_MB_2U(SCH_1):PVNN_TERM_CPU1    I10 @S9S_MB_2U_LIB.S9S_MB_2U(SCH_1):PAGE122

Q143 BC847BPN-BC847BPN,SMLF,IC,BA00A
     2 H_CPU0_MEMHOT_OUT_R @S9S_MB_2U_LIB.S9S_MB_2U(SCH_1):H_CPU0_MEMHOT_OUT_R    I22 @S9S_MB_2U_LIB.S9S_MB_2U(SCH_1):PAGE122
     6 H_CPU0_MEMHOT_OUT_VT_N @S9S_MB_2U_LIB.S9S_MB_2U(SCH_1):H_CPU0_MEMHOT_OUT_VT_N    I22 @S9S_MB_2U_LIB.S9S_MB_2U(SCH_1):PAGE122
     1    GND @S9S_MB_2U_LIB.S9S_MB_2U(SCH_1):GND    I22 @S9S_MB_2U_LIB.S9S_MB_2U(SCH_1):PAGE122
     5 H_CPU0_MEMHOT_OUT_VT_R_N @S9S_MB_2U_LIB.S9S_MB_2U(SCH_1):H_CPU0_MEMHOT_OUT_VT_R_N    I12 @S9S_MB_2U_LIB.S9S_MB_2U(SCH_1):PAGE122
     3 H_CPU0_MEMHOT_OUT @S9S_MB_2U_LIB.S9S_MB_2U(SCH_1):H_CPU0_MEMHOT_OUT    I12 @S9S_MB_2U_LIB.S9S_MB_2U(SCH_1):PAGE122
     4 PVNN_TERM_CPU0 @S9S_MB_2U_LIB.S9S_MB_2U(SCH_1):PVNN_TERM_CPU0    I12 @S9S_MB_2U_LIB.S9S_MB_2U(SCH_1):PAGE122

Q144 MOSFET_NCH_DUAL-PJT138K,SMLF,IA
     1    GND @S9S_MB_2U_LIB.S9S_MB_2U(SCH_1):GND    I27 @S9S_MB_2U_LIB.S9S_MB_2U(SCH_1):PAGE213
     2 PWRGD_PS_PWROK_PLD @S9S_MB_2U_LIB.S9S_MB_2U(SCH_1):PWRGD_PS_PWROK_PLD    I27 @S9S_MB_2U_LIB.S9S_MB_2U(SCH_1):PAGE213
     6 PWRGD_PS_PWROK_PLD_N @S9S_MB_2U_LIB.S9S_MB_2U(SCH_1):PWRGD_PS_PWROK_PLD_N    I27 @S9S_MB_2U_LIB.S9S_MB_2U(SCH_1):PAGE213
     3 PWRGD_PS_PWROK_PLD_ISO @S9S_MB_2U_LIB.S9S_MB_2U(SCH_1):PWRGD_PS_PWROK_PLD_ISO    I21 @S9S_MB_2U_LIB.S9S_MB_2U(SCH_1):PAGE213
     5 PWRGD_PS_PWROK_PLD_N @S9S_MB_2U_LIB.S9S_MB_2U(SCH_1):PWRGD_PS_PWROK_PLD_N    I21 @S9S_MB_2U_LIB.S9S_MB_2U(SCH_1):PAGE213
     4    GND @S9S_MB_2U_LIB.S9S_MB_2U(SCH_1):GND    I21 @S9S_MB_2U_LIB.S9S_MB_2U(SCH_1):PAGE213

Q145 MOSFET_NCH_DUAL-PJT138K,SMLF,IA
     1    GND @S9S_MB_2U_LIB.S9S_MB_2U(SCH_1):GND    I53 @S9S_MB_2U_LIB.S9S_MB_2U(SCH_1):PAGE230
     2 HPDB_HSC_PWRGD @S9S_MB_2U_LIB.S9S_MB_2U(SCH_1):HPDB_HSC_PWRGD    I53 @S9S_MB_2U_LIB.S9S_MB_2U(SCH_1):PAGE230
     6 HPDB_HSC_PWRGD_N @S9S_MB_2U_LIB.S9S_MB_2U(SCH_1):HPDB_HSC_PWRGD_N    I53 @S9S_MB_2U_LIB.S9S_MB_2U(SCH_1):PAGE230
     3 HPDB_HSC_PWRGD_ISO @S9S_MB_2U_LIB.S9S_MB_2U(SCH_1):HPDB_HSC_PWRGD_ISO    I58 @S9S_MB_2U_LIB.S9S_MB_2U(SCH_1):PAGE230
     5 HPDB_HSC_PWRGD_N @S9S_MB_2U_LIB.S9S_MB_2U(SCH_1):HPDB_HSC_PWRGD_N    I58 @S9S_MB_2U_LIB.S9S_MB_2U(SCH_1):PAGE230
     4    GND @S9S_MB_2U_LIB.S9S_MB_2U(SCH_1):GND    I58 @S9S_MB_2U_LIB.S9S_MB_2U(SCH_1):PAGE230

Q146 MOSFET_NCH_DUAL-PJT138K,SMLF,IA
     1    GND @S9S_MB_2U_LIB.S9S_MB_2U(SCH_1):GND   I126 @S9S_MB_2U_LIB.S9S_MB_2U(SCH_1):PAGE143
     2 SWB_HSC_PWRGD @S9S_MB_2U_LIB.S9S_MB_2U(SCH_1):SWB_HSC_PWRGD   I126 @S9S_MB_2U_LIB.S9S_MB_2U(SCH_1):PAGE143
     6 SWB_HSC_PWRGD_N @S9S_MB_2U_LIB.S9S_MB_2U(SCH_1):SWB_HSC_PWRGD_N   I126 @S9S_MB_2U_LIB.S9S_MB_2U(SCH_1):PAGE143
     3 SWB_HSC_PWRGD_ISO @S9S_MB_2U_LIB.S9S_MB_2U(SCH_1):SWB_HSC_PWRGD_ISO   I121 @S9S_MB_2U_LIB.S9S_MB_2U(SCH_1):PAGE143
     5 SWB_HSC_PWRGD_N @S9S_MB_2U_LIB.S9S_MB_2U(SCH_1):SWB_HSC_PWRGD_N   I121 @S9S_MB_2U_LIB.S9S_MB_2U(SCH_1):PAGE143
     4    GND @S9S_MB_2U_LIB.S9S_MB_2U(SCH_1):GND   I121 @S9S_MB_2U_LIB.S9S_MB_2U(SCH_1):PAGE143

Q148 MOSFET_NCH_DUAL-PJT138K,SMLF,IA
     1    GND @S9S_MB_2U_LIB.S9S_MB_2U(SCH_1):GND    I61 @S9S_MB_2U_LIB.S9S_MB_2U(SCH_1):PAGE139
     2 HGX_DETECT_N @S9S_MB_2U_LIB.S9S_MB_2U(SCH_1):HGX_DETECT_N    I61 @S9S_MB_2U_LIB.S9S_MB_2U(SCH_1):PAGE139
     6 HGX_DETECT @S9S_MB_2U_LIB.S9S_MB_2U(SCH_1):HGX_DETECT    I61 @S9S_MB_2U_LIB.S9S_MB_2U(SCH_1):PAGE139
     3 HGX_DETECT_N_ISO @S9S_MB_2U_LIB.S9S_MB_2U(SCH_1):HGX_DETECT_N_ISO    I55 @S9S_MB_2U_LIB.S9S_MB_2U(SCH_1):PAGE139
     5 HGX_DETECT @S9S_MB_2U_LIB.S9S_MB_2U(SCH_1):HGX_DETECT    I55 @S9S_MB_2U_LIB.S9S_MB_2U(SCH_1):PAGE139
     4    GND @S9S_MB_2U_LIB.S9S_MB_2U(SCH_1):GND    I55 @S9S_MB_2U_LIB.S9S_MB_2U(SCH_1):PAGE139

Q150 MOSFET_NCH_DUAL-PJT138K,SMLF,IA
     1    GND @S9S_MB_2U_LIB.S9S_MB_2U(SCH_1):GND    I69 @S9S_MB_2U_LIB.S9S_MB_2U(SCH_1):PAGE241
     2 P12V_SCM_FAULT_R_N @S9S_MB_2U_LIB.S9S_MB_2U(SCH_1):P12V_SCM_FAULT_R_N    I69 @S9S_MB_2U_LIB.S9S_MB_2U(SCH_1):PAGE241
     6 LED_P12V_SCM_FAULT_D1 @S9S_MB_2U_LIB.S9S_MB_2U(SCH_1):LED_P12V_SCM_FAULT_D1    I69 @S9S_MB_2U_LIB.S9S_MB_2U(SCH_1):PAGE241
     3 LED_P12V_SCM_FAULT_D2 @S9S_MB_2U_LIB.S9S_MB_2U(SCH_1):LED_P12V_SCM_FAULT_D2    I72 @S9S_MB_2U_LIB.S9S_MB_2U(SCH_1):PAGE241
     5 LED_P12V_SCM_FAULT_D1 @S9S_MB_2U_LIB.S9S_MB_2U(SCH_1):LED_P12V_SCM_FAULT_D1    I72 @S9S_MB_2U_LIB.S9S_MB_2U(SCH_1):PAGE241
     4    GND @S9S_MB_2U_LIB.S9S_MB_2U(SCH_1):GND    I72 @S9S_MB_2U_LIB.S9S_MB_2U(SCH_1):PAGE241

Q151 MOSFET_NCH_DUAL-PJT138K,SMLF,IA
     1    GND @S9S_MB_2U_LIB.S9S_MB_2U(SCH_1):GND    I31 @S9S_MB_2U_LIB.S9S_MB_2U(SCH_1):PAGE147
     2 PRSNT_SWB_N @S9S_MB_2U_LIB.S9S_MB_2U(SCH_1):PRSNT_SWB_N    I31 @S9S_MB_2U_LIB.S9S_MB_2U(SCH_1):PAGE147
     6 PRSNT_SWB @S9S_MB_2U_LIB.S9S_MB_2U(SCH_1):PRSNT_SWB    I31 @S9S_MB_2U_LIB.S9S_MB_2U(SCH_1):PAGE147
     3 PRSNT_SWB_ISO_N @S9S_MB_2U_LIB.S9S_MB_2U(SCH_1):PRSNT_SWB_ISO_N    I20 @S9S_MB_2U_LIB.S9S_MB_2U(SCH_1):PAGE147
     5 PRSNT_SWB @S9S_MB_2U_LIB.S9S_MB_2U(SCH_1):PRSNT_SWB    I20 @S9S_MB_2U_LIB.S9S_MB_2U(SCH_1):PAGE147
     4    GND @S9S_MB_2U_LIB.S9S_MB_2U(SCH_1):GND    I20 @S9S_MB_2U_LIB.S9S_MB_2U(SCH_1):PAGE147

Q152 MOSFET_NCH_DUAL-PJT138K,SMLF,IA
     1    GND @S9S_MB_2U_LIB.S9S_MB_2U(SCH_1):GND    I38 @S9S_MB_2U_LIB.S9S_MB_2U(SCH_1):PAGE147
     2 PRSNT_CABLE_SWB_B2_N @S9S_MB_2U_LIB.S9S_MB_2U(SCH_1):PRSNT_CABLE_SWB_B2_N    I38 @S9S_MB_2U_LIB.S9S_MB_2U(SCH_1):PAGE147
     6 PRSNT_CABLE_SWB_B2 @S9S_MB_2U_LIB.S9S_MB_2U(SCH_1):PRSNT_CABLE_SWB_B2    I38 @S9S_MB_2U_LIB.S9S_MB_2U(SCH_1):PAGE147
     3 PRSNT_CABLE_SWB_B2_ISO_N @S9S_MB_2U_LIB.S9S_MB_2U(SCH_1):PRSNT_CABLE_SWB_B2_ISO_N    I26 @S9S_MB_2U_LIB.S9S_MB_2U(SCH_1):PAGE147
     5 PRSNT_CABLE_SWB_B2 @S9S_MB_2U_LIB.S9S_MB_2U(SCH_1):PRSNT_CABLE_SWB_B2    I26 @S9S_MB_2U_LIB.S9S_MB_2U(SCH_1):PAGE147
     4    GND @S9S_MB_2U_LIB.S9S_MB_2U(SCH_1):GND    I26 @S9S_MB_2U_LIB.S9S_MB_2U(SCH_1):PAGE147

Q153 MOSFET_NCH_DUAL-PJT138K,SMLF,IA
     1    GND @S9S_MB_2U_LIB.S9S_MB_2U(SCH_1):GND    I55 @S9S_MB_2U_LIB.S9S_MB_2U(SCH_1):PAGE147
     2 PRSNT_CABLE_SWB_B1_N @S9S_MB_2U_LIB.S9S_MB_2U(SCH_1):PRSNT_CABLE_SWB_B1_N    I55 @S9S_MB_2U_LIB.S9S_MB_2U(SCH_1):PAGE147
     6 PRSNT_CABLE_SWB_B1 @S9S_MB_2U_LIB.S9S_MB_2U(SCH_1):PRSNT_CABLE_SWB_B1    I55 @S9S_MB_2U_LIB.S9S_MB_2U(SCH_1):PAGE147
     3 PRSNT_CABLE_SWB_B1_ISO_N @S9S_MB_2U_LIB.S9S_MB_2U(SCH_1):PRSNT_CABLE_SWB_B1_ISO_N    I51 @S9S_MB_2U_LIB.S9S_MB_2U(SCH_1):PAGE147
     5 PRSNT_CABLE_SWB_B1 @S9S_MB_2U_LIB.S9S_MB_2U(SCH_1):PRSNT_CABLE_SWB_B1    I51 @S9S_MB_2U_LIB.S9S_MB_2U(SCH_1):PAGE147
     4    GND @S9S_MB_2U_LIB.S9S_MB_2U(SCH_1):GND    I51 @S9S_MB_2U_LIB.S9S_MB_2U(SCH_1):PAGE147

Q154 MOSFET_NCH_DUAL-PJT138K,SMLF,IA
     1    GND @S9S_MB_2U_LIB.S9S_MB_2U(SCH_1):GND    I71 @S9S_MB_2U_LIB.S9S_MB_2U(SCH_1):PAGE147
     2 PRSNT_CABLE_GPU_A3_N @S9S_MB_2U_LIB.S9S_MB_2U(SCH_1):PRSNT_CABLE_GPU_A3_N    I71 @S9S_MB_2U_LIB.S9S_MB_2U(SCH_1):PAGE147
     6 PRSNT_CABLE_GPU_A3 @S9S_MB_2U_LIB.S9S_MB_2U(SCH_1):PRSNT_CABLE_GPU_A3    I71 @S9S_MB_2U_LIB.S9S_MB_2U(SCH_1):PAGE147
     3 PRSNT_CABLE_GPU_A3_ISO_N @S9S_MB_2U_LIB.S9S_MB_2U(SCH_1):PRSNT_CABLE_GPU_A3_ISO_N    I62 @S9S_MB_2U_LIB.S9S_MB_2U(SCH_1):PAGE147
     5 PRSNT_CABLE_GPU_A3 @S9S_MB_2U_LIB.S9S_MB_2U(SCH_1):PRSNT_CABLE_GPU_A3    I62 @S9S_MB_2U_LIB.S9S_MB_2U(SCH_1):PAGE147
     4    GND @S9S_MB_2U_LIB.S9S_MB_2U(SCH_1):GND    I62 @S9S_MB_2U_LIB.S9S_MB_2U(SCH_1):PAGE147

Q236 MOSFET_NCH_DUAL-PJT138K,SMLF,IA
     1    GND @S9S_MB_2U_LIB.S9S_MB_2U(SCH_1):GND    I99 @S9S_MB_2U_LIB.S9S_MB_2U(SCH_1):PAGE246
     2 PWRGD_P5V @S9S_MB_2U_LIB.S9S_MB_2U(SCH_1):PWRGD_P5V    I99 @S9S_MB_2U_LIB.S9S_MB_2U(SCH_1):PAGE246
     6 PWRGD_P5V_N @S9S_MB_2U_LIB.S9S_MB_2U(SCH_1):PWRGD_P5V_N    I99 @S9S_MB_2U_LIB.S9S_MB_2U(SCH_1):PAGE246
     3 PWRGD_P5V_ISO @S9S_MB_2U_LIB.S9S_MB_2U(SCH_1):PWRGD_P5V_ISO    I98 @S9S_MB_2U_LIB.S9S_MB_2U(SCH_1):PAGE246
     5 PWRGD_P5V_N @S9S_MB_2U_LIB.S9S_MB_2U(SCH_1):PWRGD_P5V_N    I98 @S9S_MB_2U_LIB.S9S_MB_2U(SCH_1):PAGE246
     4    GND @S9S_MB_2U_LIB.S9S_MB_2U(SCH_1):GND    I98 @S9S_MB_2U_LIB.S9S_MB_2U(SCH_1):PAGE246

  R1 Q_RES_0402LF-10,1%,1/16W,CHIP,A
     1 H_CPU_PRDY_QS_GTL_N @S9S_MB_2U_LIB.S9S_MB_2U(SCH_1):H_CPU_PRDY_QS_GTL_N    I18 @S9S_MB_2U_LIB.S9S_MB_2U(SCH_1):PAGE13
     2 H_CPU0_PRDY_QS_GTL_R_N @S9S_MB_2U_LIB.S9S_MB_2U(SCH_1):H_CPU0_PRDY_QS_GTL_R_N    I18 @S9S_MB_2U_LIB.S9S_MB_2U(SCH_1):PAGE13

  R2 Q_RES_0402LF-100,1%,1/16W,CHIPA
     1 H_CPU_PREQ_QS_GTL_N @S9S_MB_2U_LIB.S9S_MB_2U(SCH_1):H_CPU_PREQ_QS_GTL_N    I16 @S9S_MB_2U_LIB.S9S_MB_2U(SCH_1):PAGE13
     2 H_CPU0_PREQ_QS_GTL_R_N @S9S_MB_2U_LIB.S9S_MB_2U(SCH_1):H_CPU0_PREQ_QS_GTL_R_N    I16 @S9S_MB_2U_LIB.S9S_MB_2U(SCH_1):PAGE13

  R3 Q_RES_0402LF-33.2,1%,1/16W,CHIA
     1 PECI_CPU_GTL @S9S_MB_2U_LIB.S9S_MB_2U(SCH_1):PECI_CPU_GTL    I21 @S9S_MB_2U_LIB.S9S_MB_2U(SCH_1):PAGE13
     2 PECI_CPU0_GTL_R @S9S_MB_2U_LIB.S9S_MB_2U(SCH_1):PECI_CPU0_GTL_R    I21 @S9S_MB_2U_LIB.S9S_MB_2U(SCH_1):PAGE13

  R4 Q_RES_0402LF-200,1%,1/16W,CHIPA
     1 JTAG_MUX_CPU0_GTL_TDI @S9S_MB_2U_LIB.S9S_MB_2U(SCH_1):JTAG_MUX_CPU0_GTL_TDI    I29 @S9S_MB_2U_LIB.S9S_MB_2U(SCH_1):PAGE13
     2 JTAG_DBP_CPU0_GTL_R_TDI @S9S_MB_2U_LIB.S9S_MB_2U(SCH_1):JTAG_DBP_CPU0_GTL_R_TDI    I29 @S9S_MB_2U_LIB.S9S_MB_2U(SCH_1):PAGE13

  R5 Q_RES_0402LF-100,1%,1/16W,CHIPA
     1 JTAG_DBP_CPU_GTL_TCK @S9S_MB_2U_LIB.S9S_MB_2U(SCH_1):JTAG_DBP_CPU_GTL_TCK    I24 @S9S_MB_2U_LIB.S9S_MB_2U(SCH_1):PAGE13
     2 JTAG_DBP_CPU0_GTL_R_TCK @S9S_MB_2U_LIB.S9S_MB_2U(SCH_1):JTAG_DBP_CPU0_GTL_R_TCK    I24 @S9S_MB_2U_LIB.S9S_MB_2U(SCH_1):PAGE13

  R6 Q_RES_0402LF-100,1%,1/16W,CHIPA
     1 JTAG_DBP_CPU_QS_GTL_TMS @S9S_MB_2U_LIB.S9S_MB_2U(SCH_1):JTAG_DBP_CPU_QS_GTL_TMS    I25 @S9S_MB_2U_LIB.S9S_MB_2U(SCH_1):PAGE13
     2 JTAG_DBP_CPU0_QS_GTL_R_TMS @S9S_MB_2U_LIB.S9S_MB_2U(SCH_1):JTAG_DBP_CPU0_QS_GTL_R_TMS    I25 @S9S_MB_2U_LIB.S9S_MB_2U(SCH_1):PAGE13

  R7 Q_RES_0402LF-33.2,1%,1/16W,CHIA
     1 H_CPU0_PMDOWN_PCH_R @S9S_MB_2U_LIB.S9S_MB_2U(SCH_1):H_CPU0_PMDOWN_PCH_R    I66 @S9S_MB_2U_LIB.S9S_MB_2U(SCH_1):PAGE14
     2 H_CPU0_PMDOWN_PCH @S9S_MB_2U_LIB.S9S_MB_2U(SCH_1):H_CPU0_PMDOWN_PCH    I66 @S9S_MB_2U_LIB.S9S_MB_2U(SCH_1):PAGE14

  R8 Q_RES_0402LF-10K,1%,1/16W,CHIPA
     1 P3V3_AUX @S9S_MB_2U_LIB.S9S_MB_2U(SCH_1):P3V3_AUX    I59 @S9S_MB_2U_LIB.S9S_MB_2U(SCH_1):PAGE192
     2 FM_PS_PWROK_DLY_R_SEL @S9S_MB_2U_LIB.S9S_MB_2U(SCH_1):FM_PS_PWROK_DLY_R_SEL    I59 @S9S_MB_2U_LIB.S9S_MB_2U(SCH_1):PAGE192

 R10 Q_RES_0402LF-33.2,1%,1/16W,CHIA
     1 H_CPU0_PMSYNC_PCH_R @S9S_MB_2U_LIB.S9S_MB_2U(SCH_1):H_CPU0_PMSYNC_PCH_R    I78 @S9S_MB_2U_LIB.S9S_MB_2U(SCH_1):PAGE14
     2 H_CPU0_PMSYNC_PCH @S9S_MB_2U_LIB.S9S_MB_2U(SCH_1):H_CPU0_PMSYNC_PCH    I78 @S9S_MB_2U_LIB.S9S_MB_2U(SCH_1):PAGE14

 R11 Q_RES_0402LF-33.2,1%,1/16W,CHIA
     1 H_CPU0_PMDOWN_CPU1_R1 @S9S_MB_2U_LIB.S9S_MB_2U(SCH_1):H_CPU0_PMDOWN_CPU1_R1    I79 @S9S_MB_2U_LIB.S9S_MB_2U(SCH_1):PAGE14
     2 H_CPU0_PMDOWN_CPU1 @S9S_MB_2U_LIB.S9S_MB_2U(SCH_1):H_CPU0_PMDOWN_CPU1    I79 @S9S_MB_2U_LIB.S9S_MB_2U(SCH_1):PAGE14

 R12 Q_RES_0402LF-0,5%,1/16W,CHIP,CA
     1 SVID_DIO0_CPU0 @S9S_MB_2U_LIB.S9S_MB_2U(SCH_1):SVID_DIO0_CPU0    I59 @S9S_MB_2U_LIB.S9S_MB_2U(SCH_1):PAGE14
     2 SVID_DIO0_CPU0_R @S9S_MB_2U_LIB.S9S_MB_2U(SCH_1):SVID_DIO0_CPU0_R    I59 @S9S_MB_2U_LIB.S9S_MB_2U(SCH_1):PAGE14

 R13 Q_RES_0402LF-0,5%,1/16W,CHIP,CA
     1 SVID_CLK0_CPU0 @S9S_MB_2U_LIB.S9S_MB_2U(SCH_1):SVID_CLK0_CPU0    I60 @S9S_MB_2U_LIB.S9S_MB_2U(SCH_1):PAGE14
     2 SVID_CLK0_CPU0_R @S9S_MB_2U_LIB.S9S_MB_2U(SCH_1):SVID_CLK0_CPU0_R    I60 @S9S_MB_2U_LIB.S9S_MB_2U(SCH_1):PAGE14

 R14 Q_RES_0402LF-200,1%,1/16W,CHIPA
     1 SVID_ALERT0_CPU0_N @S9S_MB_2U_LIB.S9S_MB_2U(SCH_1):SVID_ALERT0_CPU0_N    I61 @S9S_MB_2U_LIB.S9S_MB_2U(SCH_1):PAGE14
     2 SVID_ALERT0_CPU0_R_N @S9S_MB_2U_LIB.S9S_MB_2U(SCH_1):SVID_ALERT0_CPU0_R_N    I61 @S9S_MB_2U_LIB.S9S_MB_2U(SCH_1):PAGE14

 R15 Q_RES_0402LF-0,5%,1/16W,CHIP,CA
     1 SVID_DIO1_CPU0 @S9S_MB_2U_LIB.S9S_MB_2U(SCH_1):SVID_DIO1_CPU0    I62 @S9S_MB_2U_LIB.S9S_MB_2U(SCH_1):PAGE14
     2 SVID_DIO1_CPU0_R @S9S_MB_2U_LIB.S9S_MB_2U(SCH_1):SVID_DIO1_CPU0_R    I62 @S9S_MB_2U_LIB.S9S_MB_2U(SCH_1):PAGE14

 R16 Q_RES_0402LF-0,5%,1/16W,CHIP,CA
     1 SVID_CLK1_CPU0 @S9S_MB_2U_LIB.S9S_MB_2U(SCH_1):SVID_CLK1_CPU0    I63 @S9S_MB_2U_LIB.S9S_MB_2U(SCH_1):PAGE14
     2 SVID_CLK1_CPU0_R @S9S_MB_2U_LIB.S9S_MB_2U(SCH_1):SVID_CLK1_CPU0_R    I63 @S9S_MB_2U_LIB.S9S_MB_2U(SCH_1):PAGE14

 R17 Q_RES_0402LF-200,1%,1/16W,CHIPA
     1 SVID_ALERT1_CPU0_N @S9S_MB_2U_LIB.S9S_MB_2U(SCH_1):SVID_ALERT1_CPU0_N    I64 @S9S_MB_2U_LIB.S9S_MB_2U(SCH_1):PAGE14
     2 SVID_ALERT1_CPU0_R_N @S9S_MB_2U_LIB.S9S_MB_2U(SCH_1):SVID_ALERT1_CPU0_R_N    I64 @S9S_MB_2U_LIB.S9S_MB_2U(SCH_1):PAGE14

 R18 Q_RES_0402LF-499,1%,1/16W,CHIPA
     1 PVNN_TERM_CPU0 @S9S_MB_2U_LIB.S9S_MB_2U(SCH_1):PVNN_TERM_CPU0    I35 @S9S_MB_2U_LIB.S9S_MB_2U(SCH_1):PAGE16
     2 DBP_CPU_MBP0_GTL_N @S9S_MB_2U_LIB.S9S_MB_2U(SCH_1):DBP_CPU_MBP0_GTL_N    I35 @S9S_MB_2U_LIB.S9S_MB_2U(SCH_1):PAGE16

 R19 Q_RES_0402LF-499,1%,1/16W,CHIPA
     1 PVNN_TERM_CPU0 @S9S_MB_2U_LIB.S9S_MB_2U(SCH_1):PVNN_TERM_CPU0    I36 @S9S_MB_2U_LIB.S9S_MB_2U(SCH_1):PAGE16
     2 DBP_CPU_MBP1_GTL_N @S9S_MB_2U_LIB.S9S_MB_2U(SCH_1):DBP_CPU_MBP1_GTL_N    I36 @S9S_MB_2U_LIB.S9S_MB_2U(SCH_1):PAGE16

 R20 Q_RES_0402LF-0,5%,1/16W,CHIP,CA
     1 DBP_CPU_MBP0_GTL_N @S9S_MB_2U_LIB.S9S_MB_2U(SCH_1):DBP_CPU_MBP0_GTL_N    I31 @S9S_MB_2U_LIB.S9S_MB_2U(SCH_1):PAGE16
     2 FM_PCH_TRIGGER0_N @S9S_MB_2U_LIB.S9S_MB_2U(SCH_1):FM_PCH_TRIGGER0_N    I31 @S9S_MB_2U_LIB.S9S_MB_2U(SCH_1):PAGE16

 R21 Q_RES_0402LF-0,5%,1/16W,CHIP,CA
     1 DBP_CPU_MBP1_GTL_N @S9S_MB_2U_LIB.S9S_MB_2U(SCH_1):DBP_CPU_MBP1_GTL_N    I32 @S9S_MB_2U_LIB.S9S_MB_2U(SCH_1):PAGE16
     2 FM_PCH_TRIGGER1_N @S9S_MB_2U_LIB.S9S_MB_2U(SCH_1):FM_PCH_TRIGGER1_N    I32 @S9S_MB_2U_LIB.S9S_MB_2U(SCH_1):PAGE16

 R22 Q_RES_0402LF-100,1%,1/16W,CHIPA
     1 DBP_CPU0_MBP0_GTL_R_N @S9S_MB_2U_LIB.S9S_MB_2U(SCH_1):DBP_CPU0_MBP0_GTL_R_N    I19 @S9S_MB_2U_LIB.S9S_MB_2U(SCH_1):PAGE16
     2 DBP_CPU_MBP0_GTL_N @S9S_MB_2U_LIB.S9S_MB_2U(SCH_1):DBP_CPU_MBP0_GTL_N    I19 @S9S_MB_2U_LIB.S9S_MB_2U(SCH_1):PAGE16

 R23 Q_RES_0402LF-100,1%,1/16W,CHIPA
     1 DBP_CPU0_MBP1_GTL_R_N @S9S_MB_2U_LIB.S9S_MB_2U(SCH_1):DBP_CPU0_MBP1_GTL_R_N    I20 @S9S_MB_2U_LIB.S9S_MB_2U(SCH_1):PAGE16
     2 DBP_CPU_MBP1_GTL_N @S9S_MB_2U_LIB.S9S_MB_2U(SCH_1):DBP_CPU_MBP1_GTL_N    I20 @S9S_MB_2U_LIB.S9S_MB_2U(SCH_1):PAGE16

 R24 Q_RES_0402LF-10,1%,1/16W,CHIP,A
     1 DBP_CPU0_HOOK8_MBP2_GTL_QS_R_N @S9S_MB_2U_LIB.S9S_MB_2U(SCH_1):DBP_CPU0_HOOK8_MBP2_GTL_QS_R_N    I25 @S9S_MB_2U_LIB.S9S_MB_2U(SCH_1):PAGE16
     2 DBP_CPU_HOOK8_MBP2_GTL_QS_N @S9S_MB_2U_LIB.S9S_MB_2U(SCH_1):DBP_CPU_HOOK8_MBP2_GTL_QS_N    I25 @S9S_MB_2U_LIB.S9S_MB_2U(SCH_1):PAGE16

 R25 Q_RES_0402LF-10,1%,1/16W,CHIP,A
     1 DBP_CPU0_HOOK9_MBP3_GTL_QS_R_N @S9S_MB_2U_LIB.S9S_MB_2U(SCH_1):DBP_CPU0_HOOK9_MBP3_GTL_QS_R_N    I26 @S9S_MB_2U_LIB.S9S_MB_2U(SCH_1):PAGE16
     2 DBP_CPU_HOOK9_MBP3_GTL_QS_N @S9S_MB_2U_LIB.S9S_MB_2U(SCH_1):DBP_CPU_HOOK9_MBP3_GTL_QS_N    I26 @S9S_MB_2U_LIB.S9S_MB_2U(SCH_1):PAGE16

 R26 Q_RES_0402LF-10K,1%,1/16W,CHIPA
     1 PD_CHA_CPU0_DIMM1_SAA @S9S_MB_2U_LIB.S9S_MB_2U(SCH_1):PD_CHA_CPU0_DIMM1_SAA   I196 @S9S_MB_2U_LIB.S9S_MB_2U(SCH_1):PAGE82
     2    GND @S9S_MB_2U_LIB.S9S_MB_2U(SCH_1):GND   I196 @S9S_MB_2U_LIB.S9S_MB_2U(SCH_1):PAGE82

 R27 Q_RES_0402LF-15.4K,1%,1/16W,CHA
     1 PD_CHA_CPU0_DIMM2_SAA @S9S_MB_2U_LIB.S9S_MB_2U(SCH_1):PD_CHA_CPU0_DIMM2_SAA    I10 @S9S_MB_2U_LIB.S9S_MB_2U(SCH_1):PAGE83
     2    GND @S9S_MB_2U_LIB.S9S_MB_2U(SCH_1):GND    I10 @S9S_MB_2U_LIB.S9S_MB_2U(SCH_1):PAGE83

 R28 Q_RES_0402LF-23.2K,1%,1/16W,CHA
     1 PD_CHB_CPU0_DIMM1_SAA @S9S_MB_2U_LIB.S9S_MB_2U(SCH_1):PD_CHB_CPU0_DIMM1_SAA    I10 @S9S_MB_2U_LIB.S9S_MB_2U(SCH_1):PAGE84
     2    GND @S9S_MB_2U_LIB.S9S_MB_2U(SCH_1):GND    I10 @S9S_MB_2U_LIB.S9S_MB_2U(SCH_1):PAGE84

 R29 Q_RES_0402LF-35.7K,1%,1/16W,CHA
     1 PD_CHB_CPU0_DIMM2_SAA @S9S_MB_2U_LIB.S9S_MB_2U(SCH_1):PD_CHB_CPU0_DIMM2_SAA     I1 @S9S_MB_2U_LIB.S9S_MB_2U(SCH_1):PAGE85
     2    GND @S9S_MB_2U_LIB.S9S_MB_2U(SCH_1):GND     I1 @S9S_MB_2U_LIB.S9S_MB_2U(SCH_1):PAGE85

 R30 Q_RES_0402LF-54.9K,1%,1/16W,CHA
     1 PD_CHC_CPU0_DIMM1_SAA @S9S_MB_2U_LIB.S9S_MB_2U(SCH_1):PD_CHC_CPU0_DIMM1_SAA     I3 @S9S_MB_2U_LIB.S9S_MB_2U(SCH_1):PAGE86
     2    GND @S9S_MB_2U_LIB.S9S_MB_2U(SCH_1):GND     I3 @S9S_MB_2U_LIB.S9S_MB_2U(SCH_1):PAGE86

 R31 Q_RES_0402LF-84.5K,1%,1/16W,CHA
     1 PD_CHC_CPU0_DIMM2_SAA @S9S_MB_2U_LIB.S9S_MB_2U(SCH_1):PD_CHC_CPU0_DIMM2_SAA    I45 @S9S_MB_2U_LIB.S9S_MB_2U(SCH_1):PAGE87
     2    GND @S9S_MB_2U_LIB.S9S_MB_2U(SCH_1):GND    I45 @S9S_MB_2U_LIB.S9S_MB_2U(SCH_1):PAGE87

 R32 Q_RES_0402LF-127K,1%,1/16W,CHIA
     1 PD_CHD_CPU0_DIMM1_SAA @S9S_MB_2U_LIB.S9S_MB_2U(SCH_1):PD_CHD_CPU0_DIMM1_SAA     I2 @S9S_MB_2U_LIB.S9S_MB_2U(SCH_1):PAGE88
     2    GND @S9S_MB_2U_LIB.S9S_MB_2U(SCH_1):GND     I2 @S9S_MB_2U_LIB.S9S_MB_2U(SCH_1):PAGE88

 R33 Q_RES_0402LF-196K,1%,1/16W,CHIA
     1 PD_CHD_CPU0_DIMM2_SAA @S9S_MB_2U_LIB.S9S_MB_2U(SCH_1):PD_CHD_CPU0_DIMM2_SAA     I2 @S9S_MB_2U_LIB.S9S_MB_2U(SCH_1):PAGE89
     2    GND @S9S_MB_2U_LIB.S9S_MB_2U(SCH_1):GND     I2 @S9S_MB_2U_LIB.S9S_MB_2U(SCH_1):PAGE89

 R34 Q_RES_0402LF-10K,1%,1/16W,CHIPA
     1 PD_CHE_CPU0_DIMM1_SAA @S9S_MB_2U_LIB.S9S_MB_2U(SCH_1):PD_CHE_CPU0_DIMM1_SAA    I11 @S9S_MB_2U_LIB.S9S_MB_2U(SCH_1):PAGE90
     2    GND @S9S_MB_2U_LIB.S9S_MB_2U(SCH_1):GND    I11 @S9S_MB_2U_LIB.S9S_MB_2U(SCH_1):PAGE90

 R35 Q_RES_0402LF-15.4K,1%,1/16W,CHA
     1 PD_CHE_CPU0_DIMM2_SAA @S9S_MB_2U_LIB.S9S_MB_2U(SCH_1):PD_CHE_CPU0_DIMM2_SAA     I2 @S9S_MB_2U_LIB.S9S_MB_2U(SCH_1):PAGE91
     2    GND @S9S_MB_2U_LIB.S9S_MB_2U(SCH_1):GND     I2 @S9S_MB_2U_LIB.S9S_MB_2U(SCH_1):PAGE91

 R36 Q_RES_0402LF-23.2K,1%,1/16W,CHA
     1 PD_CHF_CPU0_DIMM1_SAA @S9S_MB_2U_LIB.S9S_MB_2U(SCH_1):PD_CHF_CPU0_DIMM1_SAA     I2 @S9S_MB_2U_LIB.S9S_MB_2U(SCH_1):PAGE92
     2    GND @S9S_MB_2U_LIB.S9S_MB_2U(SCH_1):GND     I2 @S9S_MB_2U_LIB.S9S_MB_2U(SCH_1):PAGE92

 R37 Q_RES_0402LF-35.7K,1%,1/16W,CHA
     1 PD_CHF_CPU0_DIMM2_SAA @S9S_MB_2U_LIB.S9S_MB_2U(SCH_1):PD_CHF_CPU0_DIMM2_SAA     I2 @S9S_MB_2U_LIB.S9S_MB_2U(SCH_1):PAGE93
     2    GND @S9S_MB_2U_LIB.S9S_MB_2U(SCH_1):GND     I2 @S9S_MB_2U_LIB.S9S_MB_2U(SCH_1):PAGE93

 R38 Q_RES_0402LF-54.9K,1%,1/16W,CHA
     1 PD_CHG_CPU0_DIMM1_SAA @S9S_MB_2U_LIB.S9S_MB_2U(SCH_1):PD_CHG_CPU0_DIMM1_SAA    I10 @S9S_MB_2U_LIB.S9S_MB_2U(SCH_1):PAGE94
     2    GND @S9S_MB_2U_LIB.S9S_MB_2U(SCH_1):GND    I10 @S9S_MB_2U_LIB.S9S_MB_2U(SCH_1):PAGE94

 R39 Q_RES_0402LF-84.5K,1%,1/16W,CHA
     1 PD_CHG_CPU0_DIMM2_SAA @S9S_MB_2U_LIB.S9S_MB_2U(SCH_1):PD_CHG_CPU0_DIMM2_SAA    I46 @S9S_MB_2U_LIB.S9S_MB_2U(SCH_1):PAGE95
     2    GND @S9S_MB_2U_LIB.S9S_MB_2U(SCH_1):GND    I46 @S9S_MB_2U_LIB.S9S_MB_2U(SCH_1):PAGE95

 R40 Q_RES_0402LF-127K,1%,1/16W,CHIA
     1 PD_CHH_CPU0_DIMM1_SAA @S9S_MB_2U_LIB.S9S_MB_2U(SCH_1):PD_CHH_CPU0_DIMM1_SAA    I47 @S9S_MB_2U_LIB.S9S_MB_2U(SCH_1):PAGE96
     2    GND @S9S_MB_2U_LIB.S9S_MB_2U(SCH_1):GND    I47 @S9S_MB_2U_LIB.S9S_MB_2U(SCH_1):PAGE96

 R41 Q_RES_0402LF-196K,1%,1/16W,CHIA
     1 PD_CHH_CPU0_DIMM2_SAA @S9S_MB_2U_LIB.S9S_MB_2U(SCH_1):PD_CHH_CPU0_DIMM2_SAA     I5 @S9S_MB_2U_LIB.S9S_MB_2U(SCH_1):PAGE97
     2    GND @S9S_MB_2U_LIB.S9S_MB_2U(SCH_1):GND     I5 @S9S_MB_2U_LIB.S9S_MB_2U(SCH_1):PAGE97

 R42 Q_RES_0402LF-10K,1%,1/16W,CHIPA
     1 PD_CHA_CPU1_DIMM1_SAA @S9S_MB_2U_LIB.S9S_MB_2U(SCH_1):PD_CHA_CPU1_DIMM1_SAA    I11 @S9S_MB_2U_LIB.S9S_MB_2U(SCH_1):PAGE98
     2    GND @S9S_MB_2U_LIB.S9S_MB_2U(SCH_1):GND    I11 @S9S_MB_2U_LIB.S9S_MB_2U(SCH_1):PAGE98

 R43 Q_RES_0402LF-15.4K,1%,1/16W,CHA
     1 PD_CHA_CPU1_DIMM2_SAA @S9S_MB_2U_LIB.S9S_MB_2U(SCH_1):PD_CHA_CPU1_DIMM2_SAA     I2 @S9S_MB_2U_LIB.S9S_MB_2U(SCH_1):PAGE99
     2    GND @S9S_MB_2U_LIB.S9S_MB_2U(SCH_1):GND     I2 @S9S_MB_2U_LIB.S9S_MB_2U(SCH_1):PAGE99

 R44 Q_RES_0402LF-23.2K,1%,1/16W,CHA
     1 PD_CHB_CPU1_DIMM1_SAA @S9S_MB_2U_LIB.S9S_MB_2U(SCH_1):PD_CHB_CPU1_DIMM1_SAA     I3 @S9S_MB_2U_LIB.S9S_MB_2U(SCH_1):PAGE100
     2    GND @S9S_MB_2U_LIB.S9S_MB_2U(SCH_1):GND     I3 @S9S_MB_2U_LIB.S9S_MB_2U(SCH_1):PAGE100

 R45 Q_RES_0402LF-35.7K,1%,1/16W,CHA
     1 PD_CHB_CPU1_DIMM2_SAA @S9S_MB_2U_LIB.S9S_MB_2U(SCH_1):PD_CHB_CPU1_DIMM2_SAA    I46 @S9S_MB_2U_LIB.S9S_MB_2U(SCH_1):PAGE101
     2    GND @S9S_MB_2U_LIB.S9S_MB_2U(SCH_1):GND    I46 @S9S_MB_2U_LIB.S9S_MB_2U(SCH_1):PAGE101

 R46 Q_RES_0402LF-54.9K,1%,1/16W,CHA
     1 PD_CHC_CPU1_DIMM1_SAA @S9S_MB_2U_LIB.S9S_MB_2U(SCH_1):PD_CHC_CPU1_DIMM1_SAA     I2 @S9S_MB_2U_LIB.S9S_MB_2U(SCH_1):PAGE102
     2    GND @S9S_MB_2U_LIB.S9S_MB_2U(SCH_1):GND     I2 @S9S_MB_2U_LIB.S9S_MB_2U(SCH_1):PAGE102

 R47 Q_RES_0402LF-84.5K,1%,1/16W,CHA
     1 PD_CHC_CPU1_DIMM2_SAA @S9S_MB_2U_LIB.S9S_MB_2U(SCH_1):PD_CHC_CPU1_DIMM2_SAA     I2 @S9S_MB_2U_LIB.S9S_MB_2U(SCH_1):PAGE103
     2    GND @S9S_MB_2U_LIB.S9S_MB_2U(SCH_1):GND     I2 @S9S_MB_2U_LIB.S9S_MB_2U(SCH_1):PAGE103

 R48 Q_RES_0402LF-127K,1%,1/16W,CHIA
     1 PD_CHD_CPU1_DIMM1_SAA @S9S_MB_2U_LIB.S9S_MB_2U(SCH_1):PD_CHD_CPU1_DIMM1_SAA     I2 @S9S_MB_2U_LIB.S9S_MB_2U(SCH_1):PAGE104
     2    GND @S9S_MB_2U_LIB.S9S_MB_2U(SCH_1):GND     I2 @S9S_MB_2U_LIB.S9S_MB_2U(SCH_1):PAGE104

 R49 Q_RES_0402LF-499,1%,1/16W,CHIPA
     1 PVNN_TERM_CPU1 @S9S_MB_2U_LIB.S9S_MB_2U(SCH_1):PVNN_TERM_CPU1    I34 @S9S_MB_2U_LIB.S9S_MB_2U(SCH_1):PAGE47
     2 DBP_CPU_MBP0_GTL_N @S9S_MB_2U_LIB.S9S_MB_2U(SCH_1):DBP_CPU_MBP0_GTL_N    I34 @S9S_MB_2U_LIB.S9S_MB_2U(SCH_1):PAGE47

 R50 Q_RES_0402LF-499,1%,1/16W,CHIPA
     1 PVNN_TERM_CPU1 @S9S_MB_2U_LIB.S9S_MB_2U(SCH_1):PVNN_TERM_CPU1    I35 @S9S_MB_2U_LIB.S9S_MB_2U(SCH_1):PAGE47
     2 DBP_CPU_MBP1_GTL_N @S9S_MB_2U_LIB.S9S_MB_2U(SCH_1):DBP_CPU_MBP1_GTL_N    I35 @S9S_MB_2U_LIB.S9S_MB_2U(SCH_1):PAGE47

 R51 Q_RES_0402LF-100,1%,1/16W,CHIPA
     1 DBP_CPU1_MBP0_GTL_R_N @S9S_MB_2U_LIB.S9S_MB_2U(SCH_1):DBP_CPU1_MBP0_GTL_R_N    I24 @S9S_MB_2U_LIB.S9S_MB_2U(SCH_1):PAGE47
     2 DBP_CPU_MBP0_GTL_N @S9S_MB_2U_LIB.S9S_MB_2U(SCH_1):DBP_CPU_MBP0_GTL_N    I24 @S9S_MB_2U_LIB.S9S_MB_2U(SCH_1):PAGE47

 R52 Q_RES_0402LF-100,1%,1/16W,CHIPA
     1 DBP_CPU1_MBP1_GTL_R_N @S9S_MB_2U_LIB.S9S_MB_2U(SCH_1):DBP_CPU1_MBP1_GTL_R_N    I25 @S9S_MB_2U_LIB.S9S_MB_2U(SCH_1):PAGE47
     2 DBP_CPU_MBP1_GTL_N @S9S_MB_2U_LIB.S9S_MB_2U(SCH_1):DBP_CPU_MBP1_GTL_N    I25 @S9S_MB_2U_LIB.S9S_MB_2U(SCH_1):PAGE47

 R53 Q_RES_0402LF-10,1%,1/16W,CHIP,A
     1 DBP_CPU1_HOOK8_MBP2_GTL_QS_R_N @S9S_MB_2U_LIB.S9S_MB_2U(SCH_1):DBP_CPU1_HOOK8_MBP2_GTL_QS_R_N    I23 @S9S_MB_2U_LIB.S9S_MB_2U(SCH_1):PAGE47
     2 DBP_CPU_HOOK8_MBP2_GTL_QS_N @S9S_MB_2U_LIB.S9S_MB_2U(SCH_1):DBP_CPU_HOOK8_MBP2_GTL_QS_N    I23 @S9S_MB_2U_LIB.S9S_MB_2U(SCH_1):PAGE47

 R54 Q_RES_0402LF-10,1%,1/16W,CHIP,A
     1 DBP_CPU1_HOOK9_MBP3_GTL_QS_R_N @S9S_MB_2U_LIB.S9S_MB_2U(SCH_1):DBP_CPU1_HOOK9_MBP3_GTL_QS_R_N    I22 @S9S_MB_2U_LIB.S9S_MB_2U(SCH_1):PAGE47
     2 DBP_CPU_HOOK9_MBP3_GTL_QS_N @S9S_MB_2U_LIB.S9S_MB_2U(SCH_1):DBP_CPU_HOOK9_MBP3_GTL_QS_N    I22 @S9S_MB_2U_LIB.S9S_MB_2U(SCH_1):PAGE47

 R55 Q_RES_0402LF-0,5%,1/16W,CHIP,CA
     1 SVID_DIO0_CPU1 @S9S_MB_2U_LIB.S9S_MB_2U(SCH_1):SVID_DIO0_CPU1    I54 @S9S_MB_2U_LIB.S9S_MB_2U(SCH_1):PAGE45
     2 SVID_DIO0_CPU1_R @S9S_MB_2U_LIB.S9S_MB_2U(SCH_1):SVID_DIO0_CPU1_R    I54 @S9S_MB_2U_LIB.S9S_MB_2U(SCH_1):PAGE45

 R56 Q_RES_0402LF-0,5%,1/16W,CHIP,CA
     1 SVID_CLK0_CPU1 @S9S_MB_2U_LIB.S9S_MB_2U(SCH_1):SVID_CLK0_CPU1    I55 @S9S_MB_2U_LIB.S9S_MB_2U(SCH_1):PAGE45
     2 SVID_CLK0_CPU1_R @S9S_MB_2U_LIB.S9S_MB_2U(SCH_1):SVID_CLK0_CPU1_R    I55 @S9S_MB_2U_LIB.S9S_MB_2U(SCH_1):PAGE45

 R57 Q_RES_0402LF-200,1%,1/16W,CHIPA
     1 SVID_ALERT0_CPU1_N @S9S_MB_2U_LIB.S9S_MB_2U(SCH_1):SVID_ALERT0_CPU1_N    I56 @S9S_MB_2U_LIB.S9S_MB_2U(SCH_1):PAGE45
     2 SVID_ALERT0_CPU1_R_N @S9S_MB_2U_LIB.S9S_MB_2U(SCH_1):SVID_ALERT0_CPU1_R_N    I56 @S9S_MB_2U_LIB.S9S_MB_2U(SCH_1):PAGE45

 R58 Q_RES_0402LF-0,5%,1/16W,CHIP,CA
     1 SVID_DIO1_CPU1 @S9S_MB_2U_LIB.S9S_MB_2U(SCH_1):SVID_DIO1_CPU1    I51 @S9S_MB_2U_LIB.S9S_MB_2U(SCH_1):PAGE45
     2 SVID_DIO1_CPU1_R @S9S_MB_2U_LIB.S9S_MB_2U(SCH_1):SVID_DIO1_CPU1_R    I51 @S9S_MB_2U_LIB.S9S_MB_2U(SCH_1):PAGE45

 R59 Q_RES_0402LF-0,5%,1/16W,CHIP,CA
     1 SVID_CLK1_CPU1 @S9S_MB_2U_LIB.S9S_MB_2U(SCH_1):SVID_CLK1_CPU1    I52 @S9S_MB_2U_LIB.S9S_MB_2U(SCH_1):PAGE45
     2 SVID_CLK1_CPU1_R @S9S_MB_2U_LIB.S9S_MB_2U(SCH_1):SVID_CLK1_CPU1_R    I52 @S9S_MB_2U_LIB.S9S_MB_2U(SCH_1):PAGE45

 R60 Q_RES_0402LF-200,1%,1/16W,CHIPA
     1 SVID_ALERT1_CPU1_N @S9S_MB_2U_LIB.S9S_MB_2U(SCH_1):SVID_ALERT1_CPU1_N    I53 @S9S_MB_2U_LIB.S9S_MB_2U(SCH_1):PAGE45
     2 SVID_ALERT1_CPU1_R_N @S9S_MB_2U_LIB.S9S_MB_2U(SCH_1):SVID_ALERT1_CPU1_R_N    I53 @S9S_MB_2U_LIB.S9S_MB_2U(SCH_1):PAGE45

 R61 Q_RES_0402LF-10,1%,1/16W,CHIP,A
     1 H_CPU_PRDY_QS_GTL_N @S9S_MB_2U_LIB.S9S_MB_2U(SCH_1):H_CPU_PRDY_QS_GTL_N    I16 @S9S_MB_2U_LIB.S9S_MB_2U(SCH_1):PAGE44
     2 H_CPU1_PRDY_QS_GTL_R_N @S9S_MB_2U_LIB.S9S_MB_2U(SCH_1):H_CPU1_PRDY_QS_GTL_R_N    I16 @S9S_MB_2U_LIB.S9S_MB_2U(SCH_1):PAGE44

 R62 Q_RES_0402LF-100,1%,1/16W,CHIPA
     1 H_CPU_PREQ_QS_GTL_N @S9S_MB_2U_LIB.S9S_MB_2U(SCH_1):H_CPU_PREQ_QS_GTL_N    I11 @S9S_MB_2U_LIB.S9S_MB_2U(SCH_1):PAGE44
     2 H_CPU1_PREQ_QS_GTL_R_N @S9S_MB_2U_LIB.S9S_MB_2U(SCH_1):H_CPU1_PREQ_QS_GTL_R_N    I11 @S9S_MB_2U_LIB.S9S_MB_2U(SCH_1):PAGE44

 R63 Q_RES_0402LF-33.2,1%,1/16W,CHIA
     1 PECI_CPU_GTL @S9S_MB_2U_LIB.S9S_MB_2U(SCH_1):PECI_CPU_GTL    I10 @S9S_MB_2U_LIB.S9S_MB_2U(SCH_1):PAGE44
     2 PECI_CPU1_GTL_R @S9S_MB_2U_LIB.S9S_MB_2U(SCH_1):PECI_CPU1_GTL_R    I10 @S9S_MB_2U_LIB.S9S_MB_2U(SCH_1):PAGE44

 R64 Q_RES_0402LF-200,1%,1/16W,CHIPA
     1 JTAG_MUX_CPU1_GTL_TDI @S9S_MB_2U_LIB.S9S_MB_2U(SCH_1):JTAG_MUX_CPU1_GTL_TDI     I9 @S9S_MB_2U_LIB.S9S_MB_2U(SCH_1):PAGE44
     2 JTAG_DBP_CPU1_GTL_R_TDI @S9S_MB_2U_LIB.S9S_MB_2U(SCH_1):JTAG_DBP_CPU1_GTL_R_TDI     I9 @S9S_MB_2U_LIB.S9S_MB_2U(SCH_1):PAGE44

 R65 Q_RES_0402LF-100,1%,1/16W,CHIPA
     1 JTAG_DBP_CPU_GTL_TCK @S9S_MB_2U_LIB.S9S_MB_2U(SCH_1):JTAG_DBP_CPU_GTL_TCK     I8 @S9S_MB_2U_LIB.S9S_MB_2U(SCH_1):PAGE44
     2 JTAG_DBP_CPU1_GTL_R_TCK @S9S_MB_2U_LIB.S9S_MB_2U(SCH_1):JTAG_DBP_CPU1_GTL_R_TCK     I8 @S9S_MB_2U_LIB.S9S_MB_2U(SCH_1):PAGE44

 R66 Q_RES_0402LF-100,1%,1/16W,CHIPA
     1 JTAG_DBP_CPU_QS_GTL_TMS @S9S_MB_2U_LIB.S9S_MB_2U(SCH_1):JTAG_DBP_CPU_QS_GTL_TMS     I7 @S9S_MB_2U_LIB.S9S_MB_2U(SCH_1):PAGE44
     2 JTAG_DBP_CPU1_QS_GTL_R_TMS @S9S_MB_2U_LIB.S9S_MB_2U(SCH_1):JTAG_DBP_CPU1_QS_GTL_R_TMS     I7 @S9S_MB_2U_LIB.S9S_MB_2U(SCH_1):PAGE44

 R67 Q_RES_0402LF-33.2,1%,1/16W,CHIA
     1 PWRGD_PLT_AUX_CPU0_LVT3_R @S9S_MB_2U_LIB.S9S_MB_2U(SCH_1):PWRGD_PLT_AUX_CPU0_LVT3_R    I12 @S9S_MB_2U_LIB.S9S_MB_2U(SCH_1):PAGE43
     2 PWRGD_PLT_AUX_CPU0_LVT3 @S9S_MB_2U_LIB.S9S_MB_2U(SCH_1):PWRGD_PLT_AUX_CPU0_LVT3    I12 @S9S_MB_2U_LIB.S9S_MB_2U(SCH_1):PAGE43

 R68 Q_RES_0402LF-33.2,1%,1/16W,CHIA
     1 PWRGD_PLT_AUX_CPU1_LVT3_R @S9S_MB_2U_LIB.S9S_MB_2U(SCH_1):PWRGD_PLT_AUX_CPU1_LVT3_R    I13 @S9S_MB_2U_LIB.S9S_MB_2U(SCH_1):PAGE43
     2 PWRGD_PLT_AUX_CPU1_LVT3 @S9S_MB_2U_LIB.S9S_MB_2U(SCH_1):PWRGD_PLT_AUX_CPU1_LVT3    I13 @S9S_MB_2U_LIB.S9S_MB_2U(SCH_1):PAGE43

 R69 Q_RES_0402LF-10K,1%,1/16W,CHIPA
     1 PWRGD_PLT_AUX_CPU0_LVT3 @S9S_MB_2U_LIB.S9S_MB_2U(SCH_1):PWRGD_PLT_AUX_CPU0_LVT3    I16 @S9S_MB_2U_LIB.S9S_MB_2U(SCH_1):PAGE43
     2    GND @S9S_MB_2U_LIB.S9S_MB_2U(SCH_1):GND    I16 @S9S_MB_2U_LIB.S9S_MB_2U(SCH_1):PAGE43

 R70 Q_RES_0402LF-10K,1%,1/16W,CHIPA
     1 PWRGD_PLT_AUX_CPU1_LVT3 @S9S_MB_2U_LIB.S9S_MB_2U(SCH_1):PWRGD_PLT_AUX_CPU1_LVT3    I17 @S9S_MB_2U_LIB.S9S_MB_2U(SCH_1):PAGE43
     2    GND @S9S_MB_2U_LIB.S9S_MB_2U(SCH_1):GND    I17 @S9S_MB_2U_LIB.S9S_MB_2U(SCH_1):PAGE43

 R71 Q_RES_0402LF-10K,1%,1/16W,CHIPA
     1 P3V3_AUX @S9S_MB_2U_LIB.S9S_MB_2U(SCH_1):P3V3_AUX    I60 @S9S_MB_2U_LIB.S9S_MB_2U(SCH_1):PAGE192
     2 FM_ME_BT_DONE @S9S_MB_2U_LIB.S9S_MB_2U(SCH_1):FM_ME_BT_DONE    I60 @S9S_MB_2U_LIB.S9S_MB_2U(SCH_1):PAGE192

 R72 Q_RES_0402LF-196K,1%,1/16W,CHIA
     1 PD_CHH_CPU1_DIMM2_SAA @S9S_MB_2U_LIB.S9S_MB_2U(SCH_1):PD_CHH_CPU1_DIMM2_SAA     I2 @S9S_MB_2U_LIB.S9S_MB_2U(SCH_1):PAGE113
     2    GND @S9S_MB_2U_LIB.S9S_MB_2U(SCH_1):GND     I2 @S9S_MB_2U_LIB.S9S_MB_2U(SCH_1):PAGE113

 R73 Q_RES_0402LF-127K,1%,1/16W,CHIA
     1 PD_CHH_CPU1_DIMM1_SAA @S9S_MB_2U_LIB.S9S_MB_2U(SCH_1):PD_CHH_CPU1_DIMM1_SAA     I3 @S9S_MB_2U_LIB.S9S_MB_2U(SCH_1):PAGE112
     2    GND @S9S_MB_2U_LIB.S9S_MB_2U(SCH_1):GND     I3 @S9S_MB_2U_LIB.S9S_MB_2U(SCH_1):PAGE112

 R74 Q_RES_0402LF-84.5K,1%,1/16W,CHA
     1 PD_CHG_CPU1_DIMM2_SAA @S9S_MB_2U_LIB.S9S_MB_2U(SCH_1):PD_CHG_CPU1_DIMM2_SAA     I5 @S9S_MB_2U_LIB.S9S_MB_2U(SCH_1):PAGE111
     2    GND @S9S_MB_2U_LIB.S9S_MB_2U(SCH_1):GND     I5 @S9S_MB_2U_LIB.S9S_MB_2U(SCH_1):PAGE111

 R75 Q_RES_0402LF-54.9K,1%,1/16W,CHA
     1 PD_CHG_CPU1_DIMM1_SAA @S9S_MB_2U_LIB.S9S_MB_2U(SCH_1):PD_CHG_CPU1_DIMM1_SAA    I47 @S9S_MB_2U_LIB.S9S_MB_2U(SCH_1):PAGE110
     2    GND @S9S_MB_2U_LIB.S9S_MB_2U(SCH_1):GND    I47 @S9S_MB_2U_LIB.S9S_MB_2U(SCH_1):PAGE110

 R76 Q_RES_0402LF-35.7K,1%,1/16W,CHA
     1 PD_CHF_CPU1_DIMM2_SAA @S9S_MB_2U_LIB.S9S_MB_2U(SCH_1):PD_CHF_CPU1_DIMM2_SAA    I46 @S9S_MB_2U_LIB.S9S_MB_2U(SCH_1):PAGE109
     2    GND @S9S_MB_2U_LIB.S9S_MB_2U(SCH_1):GND    I46 @S9S_MB_2U_LIB.S9S_MB_2U(SCH_1):PAGE109

 R77 Q_RES_0402LF-23.2K,1%,1/16W,CHA
     1 PD_CHF_CPU1_DIMM1_SAA @S9S_MB_2U_LIB.S9S_MB_2U(SCH_1):PD_CHF_CPU1_DIMM1_SAA    I10 @S9S_MB_2U_LIB.S9S_MB_2U(SCH_1):PAGE108
     2    GND @S9S_MB_2U_LIB.S9S_MB_2U(SCH_1):GND    I10 @S9S_MB_2U_LIB.S9S_MB_2U(SCH_1):PAGE108

 R78 Q_RES_0402LF-15.4K,1%,1/16W,CHA
     1 PD_CHE_CPU1_DIMM2_SAA @S9S_MB_2U_LIB.S9S_MB_2U(SCH_1):PD_CHE_CPU1_DIMM2_SAA     I2 @S9S_MB_2U_LIB.S9S_MB_2U(SCH_1):PAGE107
     2    GND @S9S_MB_2U_LIB.S9S_MB_2U(SCH_1):GND     I2 @S9S_MB_2U_LIB.S9S_MB_2U(SCH_1):PAGE107

 R79 Q_RES_0402LF-10K,1%,1/16W,CHIPA
     1 PD_CHE_CPU1_DIMM1_SAA @S9S_MB_2U_LIB.S9S_MB_2U(SCH_1):PD_CHE_CPU1_DIMM1_SAA     I2 @S9S_MB_2U_LIB.S9S_MB_2U(SCH_1):PAGE106
     2    GND @S9S_MB_2U_LIB.S9S_MB_2U(SCH_1):GND     I2 @S9S_MB_2U_LIB.S9S_MB_2U(SCH_1):PAGE106

 R80 Q_RES_0402LF-196K,1%,1/16W,CHIA
     1 PD_CHD_CPU1_DIMM2_SAA @S9S_MB_2U_LIB.S9S_MB_2U(SCH_1):PD_CHD_CPU1_DIMM2_SAA     I2 @S9S_MB_2U_LIB.S9S_MB_2U(SCH_1):PAGE105
     2    GND @S9S_MB_2U_LIB.S9S_MB_2U(SCH_1):GND     I2 @S9S_MB_2U_LIB.S9S_MB_2U(SCH_1):PAGE105

 R87 Q_RES_0402LF-1K,1%,1/16W,EMPTYA
     1 P3V3_AUX @S9S_MB_2U_LIB.S9S_MB_2U(SCH_1):P3V3_AUX    I43 @S9S_MB_2U_LIB.S9S_MB_2U(SCH_1):PAGE217
     2 FM_SPD_REMOTE_EN @S9S_MB_2U_LIB.S9S_MB_2U(SCH_1):FM_SPD_REMOTE_EN    I43 @S9S_MB_2U_LIB.S9S_MB_2U(SCH_1):PAGE217

 R90 Q_RES_0402LF-240,1%,1/16W,EMPTA
     1 PVNN_TERM_CPU1 @S9S_MB_2U_LIB.S9S_MB_2U(SCH_1):PVNN_TERM_CPU1   I135 @S9S_MB_2U_LIB.S9S_MB_2U(SCH_1):PAGE126
     2 PU_CPU1_UPI0_AC_COUPLING @S9S_MB_2U_LIB.S9S_MB_2U(SCH_1):PU_CPU1_UPI0_AC_COUPLING   I135 @S9S_MB_2U_LIB.S9S_MB_2U(SCH_1):PAGE126

 R91 Q_RES_0402LF-240,1%,1/16W,EMPTA
     1 PVNN_TERM_CPU1 @S9S_MB_2U_LIB.S9S_MB_2U(SCH_1):PVNN_TERM_CPU1   I136 @S9S_MB_2U_LIB.S9S_MB_2U(SCH_1):PAGE126
     2 PU_CPU1_UPI1_AC_COUPLING @S9S_MB_2U_LIB.S9S_MB_2U(SCH_1):PU_CPU1_UPI1_AC_COUPLING   I136 @S9S_MB_2U_LIB.S9S_MB_2U(SCH_1):PAGE126

 R92 Q_RES_0402LF-240,1%,1/16W,EMPTA
     1 PVNN_TERM_CPU1 @S9S_MB_2U_LIB.S9S_MB_2U(SCH_1):PVNN_TERM_CPU1   I140 @S9S_MB_2U_LIB.S9S_MB_2U(SCH_1):PAGE126
     2 PU_CPU1_UPI2_AC_COUPLING @S9S_MB_2U_LIB.S9S_MB_2U(SCH_1):PU_CPU1_UPI2_AC_COUPLING   I140 @S9S_MB_2U_LIB.S9S_MB_2U(SCH_1):PAGE126

 R93 Q_RES_0402LF-240,1%,1/16W,EMPTA
     1 PVNN_TERM_CPU1 @S9S_MB_2U_LIB.S9S_MB_2U(SCH_1):PVNN_TERM_CPU1   I141 @S9S_MB_2U_LIB.S9S_MB_2U(SCH_1):PAGE126
     2 PU_CPU1_UPI3_AC_COUPLING @S9S_MB_2U_LIB.S9S_MB_2U(SCH_1):PU_CPU1_UPI3_AC_COUPLING   I141 @S9S_MB_2U_LIB.S9S_MB_2U(SCH_1):PAGE126

 R94 Q_RES_0402LF-240,1%,1/16W,EMPTA
     1 PVNN_TERM_CPU0 @S9S_MB_2U_LIB.S9S_MB_2U(SCH_1):PVNN_TERM_CPU0    I25 @S9S_MB_2U_LIB.S9S_MB_2U(SCH_1):PAGE126
     2 PU_CPU0_UPI0_AC_COUPLING @S9S_MB_2U_LIB.S9S_MB_2U(SCH_1):PU_CPU0_UPI0_AC_COUPLING    I25 @S9S_MB_2U_LIB.S9S_MB_2U(SCH_1):PAGE126

 R95 Q_RES_0402LF-240,1%,1/16W,EMPTA
     1 PVNN_TERM_CPU0 @S9S_MB_2U_LIB.S9S_MB_2U(SCH_1):PVNN_TERM_CPU0    I23 @S9S_MB_2U_LIB.S9S_MB_2U(SCH_1):PAGE126
     2 PU_CPU0_UPI1_AC_COUPLING @S9S_MB_2U_LIB.S9S_MB_2U(SCH_1):PU_CPU0_UPI1_AC_COUPLING    I23 @S9S_MB_2U_LIB.S9S_MB_2U(SCH_1):PAGE126

 R96 Q_RES_0402LF-240,1%,1/16W,EMPTA
     1 PVNN_TERM_CPU0 @S9S_MB_2U_LIB.S9S_MB_2U(SCH_1):PVNN_TERM_CPU0    I22 @S9S_MB_2U_LIB.S9S_MB_2U(SCH_1):PAGE126
     2 PU_CPU0_UPI2_AC_COUPLING @S9S_MB_2U_LIB.S9S_MB_2U(SCH_1):PU_CPU0_UPI2_AC_COUPLING    I22 @S9S_MB_2U_LIB.S9S_MB_2U(SCH_1):PAGE126

 R97 Q_RES_0402LF-240,1%,1/16W,EMPTA
     1 PVNN_TERM_CPU0 @S9S_MB_2U_LIB.S9S_MB_2U(SCH_1):PVNN_TERM_CPU0   I114 @S9S_MB_2U_LIB.S9S_MB_2U(SCH_1):PAGE126
     2 PU_CPU0_UPI3_AC_COUPLING @S9S_MB_2U_LIB.S9S_MB_2U(SCH_1):PU_CPU0_UPI3_AC_COUPLING   I114 @S9S_MB_2U_LIB.S9S_MB_2U(SCH_1):PAGE126

R106 Q_RES_0402LF-2K,1%,1/16W,CHIP,A
     1    GND @S9S_MB_2U_LIB.S9S_MB_2U(SCH_1):GND   I304 @S9S_MB_2U_LIB.S9S_MB_2U(SCH_1):PAGE195
     2 FM_PLD_CLKS_DEV_EN @S9S_MB_2U_LIB.S9S_MB_2U(SCH_1):FM_PLD_CLKS_DEV_EN   I304 @S9S_MB_2U_LIB.S9S_MB_2U(SCH_1):PAGE195

R107 Q_RES_0402LF-33.2,1%,1/16W,CHIA
     1 SMB_HOST_3V3AUX_SCL_R @S9S_MB_2U_LIB.S9S_MB_2U(SCH_1):SMB_HOST_3V3AUX_SCL_R    I43 @S9S_MB_2U_LIB.S9S_MB_2U(SCH_1):PAGE228
     2 SMB_HOST_CLK_BUF_3V3AUX_SCL @S9S_MB_2U_LIB.S9S_MB_2U(SCH_1):SMB_HOST_CLK_BUF_3V3AUX_SCL    I43 @S9S_MB_2U_LIB.S9S_MB_2U(SCH_1):PAGE228

R108 Q_RES_0402LF-33.2,1%,1/16W,CHIA
     1 SMB_HOST_3V3AUX_SDA_R @S9S_MB_2U_LIB.S9S_MB_2U(SCH_1):SMB_HOST_3V3AUX_SDA_R    I42 @S9S_MB_2U_LIB.S9S_MB_2U(SCH_1):PAGE228
     2 SMB_HOST_CLK_BUF_3V3AUX_SDA @S9S_MB_2U_LIB.S9S_MB_2U(SCH_1):SMB_HOST_CLK_BUF_3V3AUX_SDA    I42 @S9S_MB_2U_LIB.S9S_MB_2U(SCH_1):PAGE228

R109 Q_RES_0402LF-33.2,1%,1/16W,CHIA
     1 FM_PLD_CLK_25M_R_EN @S9S_MB_2U_LIB.S9S_MB_2U(SCH_1):FM_PLD_CLK_25M_R_EN    I44 @S9S_MB_2U_LIB.S9S_MB_2U(SCH_1):PAGE212
     2 FM_PLD_CLK_25M_EN @S9S_MB_2U_LIB.S9S_MB_2U(SCH_1):FM_PLD_CLK_25M_EN    I44 @S9S_MB_2U_LIB.S9S_MB_2U(SCH_1):PAGE212

R110 Q_RES_0402LF-33.2,1%,1/16W,CHIA
     1 FM_PLD_CLKS_DEV_R_EN @S9S_MB_2U_LIB.S9S_MB_2U(SCH_1):FM_PLD_CLKS_DEV_R_EN    I17 @S9S_MB_2U_LIB.S9S_MB_2U(SCH_1):PAGE212
     2 FM_PLD_CLKS_DEV_EN @S9S_MB_2U_LIB.S9S_MB_2U(SCH_1):FM_PLD_CLKS_DEV_EN    I17 @S9S_MB_2U_LIB.S9S_MB_2U(SCH_1):PAGE212

R111 Q_RES_0402LF-10K,1%,1/16W,CHIPA
     1   P3V3 @S9S_MB_2U_LIB.S9S_MB_2U(SCH_1):P3V3    I24 @S9S_MB_2U_LIB.S9S_MB_2U(SCH_1):PAGE212
     2 FM_PLD_CLKS_OE_R_N @S9S_MB_2U_LIB.S9S_MB_2U(SCH_1):FM_PLD_CLKS_OE_R_N    I24 @S9S_MB_2U_LIB.S9S_MB_2U(SCH_1):PAGE212

R113 Q_RES_0402LF-33.2,1%,1/16W,CHIA
     1 FM_PLD_CLKS_OE_R_N @S9S_MB_2U_LIB.S9S_MB_2U(SCH_1):FM_PLD_CLKS_OE_R_N    I27 @S9S_MB_2U_LIB.S9S_MB_2U(SCH_1):PAGE212
     2 FM_DB2000_OE_N @S9S_MB_2U_LIB.S9S_MB_2U(SCH_1):FM_DB2000_OE_N    I27 @S9S_MB_2U_LIB.S9S_MB_2U(SCH_1):PAGE212

R120 Q_RES_0603LF-10M,1%,1/10W,CHIPA
     1 XTAL_PCH_RTC2_R @S9S_MB_2U_LIB.S9S_MB_2U(SCH_1):XTAL_PCH_RTC2_R    I74 @S9S_MB_2U_LIB.S9S_MB_2U(SCH_1):PAGE171
     2 XTAL_PCH_RTC1 @S9S_MB_2U_LIB.S9S_MB_2U(SCH_1):XTAL_PCH_RTC1    I74 @S9S_MB_2U_LIB.S9S_MB_2U(SCH_1):PAGE171

R122 Q_RES_0402LF-0,5%,1/16W,CHIP,CA
     1 PWRGD_DRAMPWRGD_CPU1_AB_R_LVC1 @S9S_MB_2U_LIB.S9S_MB_2U(SCH_1):PWRGD_DRAMPWRGD_CPU1_AB_R_LVC1    I17 @S9S_MB_2U_LIB.S9S_MB_2U(SCH_1):PAGE125
     2 PWRGD_DRAMPWRGD_CPU1_AB_LVC1_R2 @S9S_MB_2U_LIB.S9S_MB_2U(SCH_1):PWRGD_DRAMPWRGD_CPU1_AB_LVC1_R2    I17 @S9S_MB_2U_LIB.S9S_MB_2U(SCH_1):PAGE125

R124 Q_RES_0402LF-0,5%,1/16W,CHIP,CA
     1 PWRGD_DRAMPWRGD_CPU1_CD_R_LVC1 @S9S_MB_2U_LIB.S9S_MB_2U(SCH_1):PWRGD_DRAMPWRGD_CPU1_CD_R_LVC1    I15 @S9S_MB_2U_LIB.S9S_MB_2U(SCH_1):PAGE125
     2 PWRGD_DRAMPWRGD_CPU1_CD_LVC1_R2 @S9S_MB_2U_LIB.S9S_MB_2U(SCH_1):PWRGD_DRAMPWRGD_CPU1_CD_LVC1_R2    I15 @S9S_MB_2U_LIB.S9S_MB_2U(SCH_1):PAGE125

R126 Q_RES_0402LF-0,5%,1/16W,CHIP,CA
     1 PWRGD_DRAMPWRGD_CPU1_EF_R_LVC1 @S9S_MB_2U_LIB.S9S_MB_2U(SCH_1):PWRGD_DRAMPWRGD_CPU1_EF_R_LVC1    I13 @S9S_MB_2U_LIB.S9S_MB_2U(SCH_1):PAGE125
     2 PWRGD_DRAMPWRGD_CPU1_EF_LVC1_R2 @S9S_MB_2U_LIB.S9S_MB_2U(SCH_1):PWRGD_DRAMPWRGD_CPU1_EF_LVC1_R2    I13 @S9S_MB_2U_LIB.S9S_MB_2U(SCH_1):PAGE125

R128 Q_RES_0402LF-0,5%,1/16W,CHIP,CA
     1 PWRGD_DRAMPWRGD_CPU1_GH_R_LVC1 @S9S_MB_2U_LIB.S9S_MB_2U(SCH_1):PWRGD_DRAMPWRGD_CPU1_GH_R_LVC1     I7 @S9S_MB_2U_LIB.S9S_MB_2U(SCH_1):PAGE125
     2 PWRGD_DRAMPWRGD_CPU1_GH_LVC1_R2 @S9S_MB_2U_LIB.S9S_MB_2U(SCH_1):PWRGD_DRAMPWRGD_CPU1_GH_LVC1_R2     I7 @S9S_MB_2U_LIB.S9S_MB_2U(SCH_1):PAGE125

R130 Q_RES_0402LF-0,5%,1/16W,CHIP,CA
     1 PWRGD_CPU1_LVC1_R @S9S_MB_2U_LIB.S9S_MB_2U(SCH_1):PWRGD_CPU1_LVC1_R     I5 @S9S_MB_2U_LIB.S9S_MB_2U(SCH_1):PAGE125
     2 PWRGD_CPU1_BUF_R @S9S_MB_2U_LIB.S9S_MB_2U(SCH_1):PWRGD_CPU1_BUF_R     I5 @S9S_MB_2U_LIB.S9S_MB_2U(SCH_1):PAGE125

R132 Q_RES_0402LF-0,5%,1/16W,CHIP,CA
     1 RST_CPU1_LVC1_R_N @S9S_MB_2U_LIB.S9S_MB_2U(SCH_1):RST_CPU1_LVC1_R_N     I3 @S9S_MB_2U_LIB.S9S_MB_2U(SCH_1):PAGE125
     2 RST_CPU1_BUF_R_N @S9S_MB_2U_LIB.S9S_MB_2U(SCH_1):RST_CPU1_BUF_R_N     I3 @S9S_MB_2U_LIB.S9S_MB_2U(SCH_1):PAGE125

R135 Q_RES_0402LF-100,1%,1/16W,CHIPA
     1 PWRGD_DRAMPWRGD_CPU1_AB_LVC1_R2 @S9S_MB_2U_LIB.S9S_MB_2U(SCH_1):PWRGD_DRAMPWRGD_CPU1_AB_LVC1_R2    I62 @S9S_MB_2U_LIB.S9S_MB_2U(SCH_1):PAGE125
     2 PVCCD_HV_CPU1 @S9S_MB_2U_LIB.S9S_MB_2U(SCH_1):PVCCD_HV_CPU1    I62 @S9S_MB_2U_LIB.S9S_MB_2U(SCH_1):PAGE125

R137 Q_RES_0402LF-100,1%,1/16W,CHIPA
     1 PWRGD_DRAMPWRGD_CPU1_CD_LVC1_R2 @S9S_MB_2U_LIB.S9S_MB_2U(SCH_1):PWRGD_DRAMPWRGD_CPU1_CD_LVC1_R2    I60 @S9S_MB_2U_LIB.S9S_MB_2U(SCH_1):PAGE125
     2 PVCCD_HV_CPU1 @S9S_MB_2U_LIB.S9S_MB_2U(SCH_1):PVCCD_HV_CPU1    I60 @S9S_MB_2U_LIB.S9S_MB_2U(SCH_1):PAGE125

R139 Q_RES_0402LF-10K,1%,1/16W,EMPTA
     1 FM_BMC_PWRBTN_N @S9S_MB_2U_LIB.S9S_MB_2U(SCH_1):FM_BMC_PWRBTN_N    I40 @S9S_MB_2U_LIB.S9S_MB_2U(SCH_1):PAGE209
     2 P3V3_AUX @S9S_MB_2U_LIB.S9S_MB_2U(SCH_1):P3V3_AUX    I40 @S9S_MB_2U_LIB.S9S_MB_2U(SCH_1):PAGE209

R142 Q_RES_0402LF-0,5%,1/16W,CHIP,CA
     1 PVNN_TERM_CPU0 @S9S_MB_2U_LIB.S9S_MB_2U(SCH_1):PVNN_TERM_CPU0    I84 @S9S_MB_2U_LIB.S9S_MB_2U(SCH_1):PAGE227
     2 PVCCIO_PECI_BMC @S9S_MB_2U_LIB.S9S_MB_2U(SCH_1):PVCCIO_PECI_BMC    I84 @S9S_MB_2U_LIB.S9S_MB_2U(SCH_1):PAGE227

R143 Q_RES_0402LF-49.9,1%,1/16W,CHIA
     1 PECI_PCH @S9S_MB_2U_LIB.S9S_MB_2U(SCH_1):PECI_PCH    I47 @S9S_MB_2U_LIB.S9S_MB_2U(SCH_1):PAGE185
     2 PECI_PCH_R @S9S_MB_2U_LIB.S9S_MB_2U(SCH_1):PECI_PCH_R    I47 @S9S_MB_2U_LIB.S9S_MB_2U(SCH_1):PAGE185

R144 Q_RES_0402LF-0,5%,1/16W,CHIP,CA
     1 PECI_BMC @S9S_MB_2U_LIB.S9S_MB_2U(SCH_1):PECI_BMC    I51 @S9S_MB_2U_LIB.S9S_MB_2U(SCH_1):PAGE185
     2 PECI_BMC_R @S9S_MB_2U_LIB.S9S_MB_2U(SCH_1):PECI_BMC_R    I51 @S9S_MB_2U_LIB.S9S_MB_2U(SCH_1):PAGE185

R145 Q_RES_0402LF-4.75K,1%,1/16W,EMA
     1 PVNN_TERM_CPU0 @S9S_MB_2U_LIB.S9S_MB_2U(SCH_1):PVNN_TERM_CPU0    I26 @S9S_MB_2U_LIB.S9S_MB_2U(SCH_1):PAGE185
     2 PECI_PCH_R @S9S_MB_2U_LIB.S9S_MB_2U(SCH_1):PECI_PCH_R    I26 @S9S_MB_2U_LIB.S9S_MB_2U(SCH_1):PAGE185

R146 Q_RES_0402LF-4.75K,1%,1/16W,EMA
     1 PVNN_TERM_CPU0 @S9S_MB_2U_LIB.S9S_MB_2U(SCH_1):PVNN_TERM_CPU0    I30 @S9S_MB_2U_LIB.S9S_MB_2U(SCH_1):PAGE185
     2 PECI_BMC_R @S9S_MB_2U_LIB.S9S_MB_2U(SCH_1):PECI_BMC_R    I30 @S9S_MB_2U_LIB.S9S_MB_2U(SCH_1):PAGE185

R147 Q_RES_0402LF-10K,1%,1/16W,CHIPA
     1 PECI_PCH_R @S9S_MB_2U_LIB.S9S_MB_2U(SCH_1):PECI_PCH_R    I50 @S9S_MB_2U_LIB.S9S_MB_2U(SCH_1):PAGE185
     2    GND @S9S_MB_2U_LIB.S9S_MB_2U(SCH_1):GND    I50 @S9S_MB_2U_LIB.S9S_MB_2U(SCH_1):PAGE185

R148 Q_RES_0402LF-10K,1%,1/16W,EMPTA
     1 PECI_BMC_R @S9S_MB_2U_LIB.S9S_MB_2U(SCH_1):PECI_BMC_R    I49 @S9S_MB_2U_LIB.S9S_MB_2U(SCH_1):PAGE185
     2    GND @S9S_MB_2U_LIB.S9S_MB_2U(SCH_1):GND    I49 @S9S_MB_2U_LIB.S9S_MB_2U(SCH_1):PAGE185

R149 Q_RES_0402LF-0,5%,1/16W,CHIP,CA
     1 PECI_PCH_R @S9S_MB_2U_LIB.S9S_MB_2U(SCH_1):PECI_PCH_R    I24 @S9S_MB_2U_LIB.S9S_MB_2U(SCH_1):PAGE185
     2 PECI_PCH_B1 @S9S_MB_2U_LIB.S9S_MB_2U(SCH_1):PECI_PCH_B1    I24 @S9S_MB_2U_LIB.S9S_MB_2U(SCH_1):PAGE185

R151 Q_RES_0402LF-100,1%,1/16W,CHIPA
     1 PWRGD_DRAMPWRGD_CPU1_EF_LVC1_R2 @S9S_MB_2U_LIB.S9S_MB_2U(SCH_1):PWRGD_DRAMPWRGD_CPU1_EF_LVC1_R2    I58 @S9S_MB_2U_LIB.S9S_MB_2U(SCH_1):PAGE125
     2 PVCCD_HV_CPU1 @S9S_MB_2U_LIB.S9S_MB_2U(SCH_1):PVCCD_HV_CPU1    I58 @S9S_MB_2U_LIB.S9S_MB_2U(SCH_1):PAGE125

R153 Q_RES_0402LF-100,1%,1/16W,CHIPA
     1 PWRGD_DRAMPWRGD_CPU1_GH_LVC1_R2 @S9S_MB_2U_LIB.S9S_MB_2U(SCH_1):PWRGD_DRAMPWRGD_CPU1_GH_LVC1_R2    I56 @S9S_MB_2U_LIB.S9S_MB_2U(SCH_1):PAGE125
     2 PVCCD_HV_CPU1 @S9S_MB_2U_LIB.S9S_MB_2U(SCH_1):PVCCD_HV_CPU1    I56 @S9S_MB_2U_LIB.S9S_MB_2U(SCH_1):PAGE125

R155 Q_RES_0402LF-100,1%,1/16W,CHIPA
     1 PWRGD_CPU1_BUF_R @S9S_MB_2U_LIB.S9S_MB_2U(SCH_1):PWRGD_CPU1_BUF_R    I26 @S9S_MB_2U_LIB.S9S_MB_2U(SCH_1):PAGE125
     2 PVNN_TERM_CPU1 @S9S_MB_2U_LIB.S9S_MB_2U(SCH_1):PVNN_TERM_CPU1    I26 @S9S_MB_2U_LIB.S9S_MB_2U(SCH_1):PAGE125

R156 Q_RES_0402LF-100,1%,1/16W,CHIPA
     1 PWRGD_CPU1_BUF_R @S9S_MB_2U_LIB.S9S_MB_2U(SCH_1):PWRGD_CPU1_BUF_R    I64 @S9S_MB_2U_LIB.S9S_MB_2U(SCH_1):PAGE125
     2 PWRGD_CPU1_LVC1 @S9S_MB_2U_LIB.S9S_MB_2U(SCH_1):PWRGD_CPU1_LVC1    I64 @S9S_MB_2U_LIB.S9S_MB_2U(SCH_1):PAGE125

R157 Q_RES_0402LF-100,1%,1/16W,CHIPA
     1 RST_CPU1_BUF_R_N @S9S_MB_2U_LIB.S9S_MB_2U(SCH_1):RST_CPU1_BUF_R_N    I24 @S9S_MB_2U_LIB.S9S_MB_2U(SCH_1):PAGE125
     2 PVNN_TERM_CPU1 @S9S_MB_2U_LIB.S9S_MB_2U(SCH_1):PVNN_TERM_CPU1    I24 @S9S_MB_2U_LIB.S9S_MB_2U(SCH_1):PAGE125

R158 Q_RES_0402LF-100,1%,1/16W,CHIPA
     1 RST_CPU1_BUF_R_N @S9S_MB_2U_LIB.S9S_MB_2U(SCH_1):RST_CPU1_BUF_R_N    I65 @S9S_MB_2U_LIB.S9S_MB_2U(SCH_1):PAGE125
     2 RST_CPU1_LVC1_N @S9S_MB_2U_LIB.S9S_MB_2U(SCH_1):RST_CPU1_LVC1_N    I65 @S9S_MB_2U_LIB.S9S_MB_2U(SCH_1):PAGE125

R160 Q_RES_0402LF-0,5%,1/16W,CHIP,CA
     1 PWRGD_DRAMPWRGD_CPU0_AB_R_LVC1 @S9S_MB_2U_LIB.S9S_MB_2U(SCH_1):PWRGD_DRAMPWRGD_CPU0_AB_R_LVC1    I17 @S9S_MB_2U_LIB.S9S_MB_2U(SCH_1):PAGE124
     2 PWRGD_DRAMPWRGD_CPU0_AB_LVC1_R2 @S9S_MB_2U_LIB.S9S_MB_2U(SCH_1):PWRGD_DRAMPWRGD_CPU0_AB_LVC1_R2    I17 @S9S_MB_2U_LIB.S9S_MB_2U(SCH_1):PAGE124

R162 Q_RES_0402LF-0,5%,1/16W,CHIP,CA
     1 PWRGD_DRAMPWRGD_CPU0_CD_R_LVC1 @S9S_MB_2U_LIB.S9S_MB_2U(SCH_1):PWRGD_DRAMPWRGD_CPU0_CD_R_LVC1    I19 @S9S_MB_2U_LIB.S9S_MB_2U(SCH_1):PAGE124
     2 PWRGD_DRAMPWRGD_CPU0_CD_LVC1_R2 @S9S_MB_2U_LIB.S9S_MB_2U(SCH_1):PWRGD_DRAMPWRGD_CPU0_CD_LVC1_R2    I19 @S9S_MB_2U_LIB.S9S_MB_2U(SCH_1):PAGE124

R164 Q_RES_0402LF-0,5%,1/16W,CHIP,CA
     1 PWRGD_DRAMPWRGD_CPU0_EF_R_LVC1 @S9S_MB_2U_LIB.S9S_MB_2U(SCH_1):PWRGD_DRAMPWRGD_CPU0_EF_R_LVC1    I26 @S9S_MB_2U_LIB.S9S_MB_2U(SCH_1):PAGE124
     2 PWRGD_DRAMPWRGD_CPU0_EF_LVC1_R2 @S9S_MB_2U_LIB.S9S_MB_2U(SCH_1):PWRGD_DRAMPWRGD_CPU0_EF_LVC1_R2    I26 @S9S_MB_2U_LIB.S9S_MB_2U(SCH_1):PAGE124

R166 Q_RES_0402LF-0,5%,1/16W,CHIP,CA
     1 PWRGD_DRAMPWRGD_CPU0_GH_R_LVC1 @S9S_MB_2U_LIB.S9S_MB_2U(SCH_1):PWRGD_DRAMPWRGD_CPU0_GH_R_LVC1    I33 @S9S_MB_2U_LIB.S9S_MB_2U(SCH_1):PAGE124
     2 PWRGD_DRAMPWRGD_CPU0_GH_LVC1_R2 @S9S_MB_2U_LIB.S9S_MB_2U(SCH_1):PWRGD_DRAMPWRGD_CPU0_GH_LVC1_R2    I33 @S9S_MB_2U_LIB.S9S_MB_2U(SCH_1):PAGE124

R168 Q_RES_0402LF-0,5%,1/16W,CHIP,CA
     1 PWRGD_CPU0_LVC1_R @S9S_MB_2U_LIB.S9S_MB_2U(SCH_1):PWRGD_CPU0_LVC1_R    I43 @S9S_MB_2U_LIB.S9S_MB_2U(SCH_1):PAGE124
     2 PWRGD_CPU0_BUF_R @S9S_MB_2U_LIB.S9S_MB_2U(SCH_1):PWRGD_CPU0_BUF_R    I43 @S9S_MB_2U_LIB.S9S_MB_2U(SCH_1):PAGE124

R171 Q_RES_0402LF-0,5%,1/16W,CHIP,CA
     1 RST_CPU0_LVC1_R_N @S9S_MB_2U_LIB.S9S_MB_2U(SCH_1):RST_CPU0_LVC1_R_N    I52 @S9S_MB_2U_LIB.S9S_MB_2U(SCH_1):PAGE124
     2 RST_CPU0_BUF_R_N @S9S_MB_2U_LIB.S9S_MB_2U(SCH_1):RST_CPU0_BUF_R_N    I52 @S9S_MB_2U_LIB.S9S_MB_2U(SCH_1):PAGE124

R175 Q_RES_0402LF-100,1%,1/16W,CHIPA
     1 PWRGD_DRAMPWRGD_CPU0_AB_LVC1_R2 @S9S_MB_2U_LIB.S9S_MB_2U(SCH_1):PWRGD_DRAMPWRGD_CPU0_AB_LVC1_R2    I76 @S9S_MB_2U_LIB.S9S_MB_2U(SCH_1):PAGE124
     2 PVCCD_HV_CPU0 @S9S_MB_2U_LIB.S9S_MB_2U(SCH_1):PVCCD_HV_CPU0    I76 @S9S_MB_2U_LIB.S9S_MB_2U(SCH_1):PAGE124

R177 Q_RES_0402LF-100,1%,1/16W,CHIPA
     1 PWRGD_DRAMPWRGD_CPU0_CD_LVC1_R2 @S9S_MB_2U_LIB.S9S_MB_2U(SCH_1):PWRGD_DRAMPWRGD_CPU0_CD_LVC1_R2    I72 @S9S_MB_2U_LIB.S9S_MB_2U(SCH_1):PAGE124
     2 PVCCD_HV_CPU0 @S9S_MB_2U_LIB.S9S_MB_2U(SCH_1):PVCCD_HV_CPU0    I72 @S9S_MB_2U_LIB.S9S_MB_2U(SCH_1):PAGE124

R179 Q_RES_0402LF-100,1%,1/16W,CHIPA
     1 PWRGD_DRAMPWRGD_CPU0_EF_LVC1_R2 @S9S_MB_2U_LIB.S9S_MB_2U(SCH_1):PWRGD_DRAMPWRGD_CPU0_EF_LVC1_R2    I70 @S9S_MB_2U_LIB.S9S_MB_2U(SCH_1):PAGE124
     2 PVCCD_HV_CPU0 @S9S_MB_2U_LIB.S9S_MB_2U(SCH_1):PVCCD_HV_CPU0    I70 @S9S_MB_2U_LIB.S9S_MB_2U(SCH_1):PAGE124

R181 Q_RES_0402LF-100,1%,1/16W,CHIPA
     1 PWRGD_DRAMPWRGD_CPU0_GH_LVC1_R2 @S9S_MB_2U_LIB.S9S_MB_2U(SCH_1):PWRGD_DRAMPWRGD_CPU0_GH_LVC1_R2    I68 @S9S_MB_2U_LIB.S9S_MB_2U(SCH_1):PAGE124
     2 PVCCD_HV_CPU0 @S9S_MB_2U_LIB.S9S_MB_2U(SCH_1):PVCCD_HV_CPU0    I68 @S9S_MB_2U_LIB.S9S_MB_2U(SCH_1):PAGE124

R183 Q_RES_0402LF-100,1%,1/16W,CHIPA
     1 PWRGD_CPU0_BUF_R @S9S_MB_2U_LIB.S9S_MB_2U(SCH_1):PWRGD_CPU0_BUF_R    I62 @S9S_MB_2U_LIB.S9S_MB_2U(SCH_1):PAGE124
     2 PVNN_TERM_CPU0 @S9S_MB_2U_LIB.S9S_MB_2U(SCH_1):PVNN_TERM_CPU0    I62 @S9S_MB_2U_LIB.S9S_MB_2U(SCH_1):PAGE124

R184 Q_RES_0402LF-100,1%,1/16W,CHIPA
     1 PWRGD_CPU0_BUF_R @S9S_MB_2U_LIB.S9S_MB_2U(SCH_1):PWRGD_CPU0_BUF_R    I77 @S9S_MB_2U_LIB.S9S_MB_2U(SCH_1):PAGE124
     2 PWRGD_CPU0_LVC1 @S9S_MB_2U_LIB.S9S_MB_2U(SCH_1):PWRGD_CPU0_LVC1    I77 @S9S_MB_2U_LIB.S9S_MB_2U(SCH_1):PAGE124

R185 Q_RES_0402LF-100,1%,1/16W,CHIPA
     1 RST_CPU0_BUF_R_N @S9S_MB_2U_LIB.S9S_MB_2U(SCH_1):RST_CPU0_BUF_R_N    I60 @S9S_MB_2U_LIB.S9S_MB_2U(SCH_1):PAGE124
     2 PVNN_TERM_CPU0 @S9S_MB_2U_LIB.S9S_MB_2U(SCH_1):PVNN_TERM_CPU0    I60 @S9S_MB_2U_LIB.S9S_MB_2U(SCH_1):PAGE124

R186 Q_RES_0402LF-100,1%,1/16W,CHIPA
     1 RST_CPU0_BUF_R_N @S9S_MB_2U_LIB.S9S_MB_2U(SCH_1):RST_CPU0_BUF_R_N    I78 @S9S_MB_2U_LIB.S9S_MB_2U(SCH_1):PAGE124
     2 RST_CPU0_LVC1_N @S9S_MB_2U_LIB.S9S_MB_2U(SCH_1):RST_CPU0_LVC1_N    I78 @S9S_MB_2U_LIB.S9S_MB_2U(SCH_1):PAGE124

R188 Q_RES_0402LF-0,5%,1/16W,CHIP,CA
     1 H_CPU_NMI_LVC1_R_N @S9S_MB_2U_LIB.S9S_MB_2U(SCH_1):H_CPU_NMI_LVC1_R_N     I4 @S9S_MB_2U_LIB.S9S_MB_2U(SCH_1):PAGE123
     2 H_CPU_NMI_LVC1_N @S9S_MB_2U_LIB.S9S_MB_2U(SCH_1):H_CPU_NMI_LVC1_N     I4 @S9S_MB_2U_LIB.S9S_MB_2U(SCH_1):PAGE123

R195 Q_RES_0402LF-49.9,1%,1/16W,CHIA
     1 H_CPU_NMI_LVC1_N @S9S_MB_2U_LIB.S9S_MB_2U(SCH_1):H_CPU_NMI_LVC1_N     I6 @S9S_MB_2U_LIB.S9S_MB_2U(SCH_1):PAGE123
     2 H_CPU0_NMI_LVC1_N @S9S_MB_2U_LIB.S9S_MB_2U(SCH_1):H_CPU0_NMI_LVC1_N     I6 @S9S_MB_2U_LIB.S9S_MB_2U(SCH_1):PAGE123

R196 Q_RES_0402LF-49.9,1%,1/16W,CHIA
     1 H_CPU_NMI_LVC1_N @S9S_MB_2U_LIB.S9S_MB_2U(SCH_1):H_CPU_NMI_LVC1_N     I5 @S9S_MB_2U_LIB.S9S_MB_2U(SCH_1):PAGE123
     2 H_CPU1_NMI_LVC1_N @S9S_MB_2U_LIB.S9S_MB_2U(SCH_1):H_CPU1_NMI_LVC1_N     I5 @S9S_MB_2U_LIB.S9S_MB_2U(SCH_1):PAGE123

R197 Q_RES_0402LF-301,1%,1/16W,CHIPA
     1 PVNN_TERM_CPU0 @S9S_MB_2U_LIB.S9S_MB_2U(SCH_1):PVNN_TERM_CPU0    I27 @S9S_MB_2U_LIB.S9S_MB_2U(SCH_1):PAGE123
     2 H_CPU0_NMI_LVC1_N @S9S_MB_2U_LIB.S9S_MB_2U(SCH_1):H_CPU0_NMI_LVC1_N    I27 @S9S_MB_2U_LIB.S9S_MB_2U(SCH_1):PAGE123

R198 Q_RES_0402LF-301,1%,1/16W,CHIPA
     1 PVNN_TERM_CPU1 @S9S_MB_2U_LIB.S9S_MB_2U(SCH_1):PVNN_TERM_CPU1    I23 @S9S_MB_2U_LIB.S9S_MB_2U(SCH_1):PAGE123
     2 H_CPU1_NMI_LVC1_N @S9S_MB_2U_LIB.S9S_MB_2U(SCH_1):H_CPU1_NMI_LVC1_N    I23 @S9S_MB_2U_LIB.S9S_MB_2U(SCH_1):PAGE123

R200 Q_RES_0402LF-100,1%,1/16W,CHIPA
     1 PVNN_TERM_CPU0 @S9S_MB_2U_LIB.S9S_MB_2U(SCH_1):PVNN_TERM_CPU0    I19 @S9S_MB_2U_LIB.S9S_MB_2U(SCH_1):PAGE123
     2 H_CPU0_MEMTRIP_LVC1_R_N @S9S_MB_2U_LIB.S9S_MB_2U(SCH_1):H_CPU0_MEMTRIP_LVC1_R_N    I19 @S9S_MB_2U_LIB.S9S_MB_2U(SCH_1):PAGE123

R202 Q_RES_0402LF-100,1%,1/16W,CHIPA
     1 PVNN_TERM_CPU1 @S9S_MB_2U_LIB.S9S_MB_2U(SCH_1):PVNN_TERM_CPU1     I7 @S9S_MB_2U_LIB.S9S_MB_2U(SCH_1):PAGE123
     2 H_CPU1_MEMTRIP_LVC1_R_N @S9S_MB_2U_LIB.S9S_MB_2U(SCH_1):H_CPU1_MEMTRIP_LVC1_R_N     I7 @S9S_MB_2U_LIB.S9S_MB_2U(SCH_1):PAGE123

R203 Q_RES_0402LF-1.5K,1%,1/16W,CHIA
     1 H_CPU0_MEMHOT_OUT_LVC1_R_N @S9S_MB_2U_LIB.S9S_MB_2U(SCH_1):H_CPU0_MEMHOT_OUT_LVC1_R_N     I9 @S9S_MB_2U_LIB.S9S_MB_2U(SCH_1):PAGE122
     2 H_CPU0_MEMHOT_OUT_VT_R_N @S9S_MB_2U_LIB.S9S_MB_2U(SCH_1):H_CPU0_MEMHOT_OUT_VT_R_N     I9 @S9S_MB_2U_LIB.S9S_MB_2U(SCH_1):PAGE122

R204 Q_RES_0402LF-1.5K,1%,1/16W,CHIA
     1 H_CPU1_MEMHOT_OUT_LVC1_R_N @S9S_MB_2U_LIB.S9S_MB_2U(SCH_1):H_CPU1_MEMHOT_OUT_LVC1_R_N     I6 @S9S_MB_2U_LIB.S9S_MB_2U(SCH_1):PAGE122
     2 H_CPU1_MEMHOT_OUT_VT_R_N @S9S_MB_2U_LIB.S9S_MB_2U(SCH_1):H_CPU1_MEMHOT_OUT_VT_R_N     I6 @S9S_MB_2U_LIB.S9S_MB_2U(SCH_1):PAGE122

R205 Q_RES_0402LF-1.5K,1%,1/16W,CHIA
     1 H_CPU0_MEMTRIP_LVC1_R_N @S9S_MB_2U_LIB.S9S_MB_2U(SCH_1):H_CPU0_MEMTRIP_LVC1_R_N    I10 @S9S_MB_2U_LIB.S9S_MB_2U(SCH_1):PAGE123
     2 H_CPU0_MEMTRIP_OUT_VT_R_N @S9S_MB_2U_LIB.S9S_MB_2U(SCH_1):H_CPU0_MEMTRIP_OUT_VT_R_N    I10 @S9S_MB_2U_LIB.S9S_MB_2U(SCH_1):PAGE123

R206 Q_RES_0402LF-1.5K,1%,1/16W,CHIA
     1 H_CPU1_MEMTRIP_LVC1_R_N @S9S_MB_2U_LIB.S9S_MB_2U(SCH_1):H_CPU1_MEMTRIP_LVC1_R_N     I8 @S9S_MB_2U_LIB.S9S_MB_2U(SCH_1):PAGE123
     2 H_CPU1_MEMTRIP_OUT_VT_R_N @S9S_MB_2U_LIB.S9S_MB_2U(SCH_1):H_CPU1_MEMTRIP_OUT_VT_R_N     I8 @S9S_MB_2U_LIB.S9S_MB_2U(SCH_1):PAGE123

R208 Q_RES_0402LF-0,5%,1/16W,CHIP,CA
     1 H_CPU0_MEMHOT_IN_LVC1_R_N @S9S_MB_2U_LIB.S9S_MB_2U(SCH_1):H_CPU0_MEMHOT_IN_LVC1_R_N    I16 @S9S_MB_2U_LIB.S9S_MB_2U(SCH_1):PAGE122
     2 H_CPU0_MEMHOT_IN_LVC1_R1_N @S9S_MB_2U_LIB.S9S_MB_2U(SCH_1):H_CPU0_MEMHOT_IN_LVC1_R1_N    I16 @S9S_MB_2U_LIB.S9S_MB_2U(SCH_1):PAGE122

R210 Q_RES_0402LF-0,5%,1/16W,CHIP,CA
     1 H_CPU1_MEMHOT_IN_LVC1_R_N @S9S_MB_2U_LIB.S9S_MB_2U(SCH_1):H_CPU1_MEMHOT_IN_LVC1_R_N    I15 @S9S_MB_2U_LIB.S9S_MB_2U(SCH_1):PAGE122
     2 H_CPU1_MEMHOT_IN_LVC1_R1_N @S9S_MB_2U_LIB.S9S_MB_2U(SCH_1):H_CPU1_MEMHOT_IN_LVC1_R1_N    I15 @S9S_MB_2U_LIB.S9S_MB_2U(SCH_1):PAGE122

R219 Q_RES_0402LF-100,1%,1/16W,CHIPA
     1 PVNN_TERM_CPU0 @S9S_MB_2U_LIB.S9S_MB_2U(SCH_1):PVNN_TERM_CPU0    I37 @S9S_MB_2U_LIB.S9S_MB_2U(SCH_1):PAGE122
     2 H_CPU0_MEMHOT_IN_LVC1_R1_N @S9S_MB_2U_LIB.S9S_MB_2U(SCH_1):H_CPU0_MEMHOT_IN_LVC1_R1_N    I37 @S9S_MB_2U_LIB.S9S_MB_2U(SCH_1):PAGE122

R220 Q_RES_0402LF-100,1%,1/16W,CHIPA
     1 PVNN_TERM_CPU1 @S9S_MB_2U_LIB.S9S_MB_2U(SCH_1):PVNN_TERM_CPU1    I29 @S9S_MB_2U_LIB.S9S_MB_2U(SCH_1):PAGE122
     2 H_CPU1_MEMHOT_IN_LVC1_R1_N @S9S_MB_2U_LIB.S9S_MB_2U(SCH_1):H_CPU1_MEMHOT_IN_LVC1_R1_N    I29 @S9S_MB_2U_LIB.S9S_MB_2U(SCH_1):PAGE122

R223 Q_RES_0402LF-1K,1%,1/16W,CHIP,A
     1 P3V3_AUX @S9S_MB_2U_LIB.S9S_MB_2U(SCH_1):P3V3_AUX    I85 @S9S_MB_2U_LIB.S9S_MB_2U(SCH_1):PAGE282
     2 IRQ_PVCCD_CPU1_VRHOT_LVC3_N @S9S_MB_2U_LIB.S9S_MB_2U(SCH_1):IRQ_PVCCD_CPU1_VRHOT_LVC3_N    I85 @S9S_MB_2U_LIB.S9S_MB_2U(SCH_1):PAGE282

R237 Q_RES_0402LF-1.5K,1%,1/16W,CHIA
     1 H_CPU0_THERMTRIP_LVC1_R_N @S9S_MB_2U_LIB.S9S_MB_2U(SCH_1):H_CPU0_THERMTRIP_LVC1_R_N    I15 @S9S_MB_2U_LIB.S9S_MB_2U(SCH_1):PAGE121
     2 H_CPU0_THERMTRIP_VT_R_N @S9S_MB_2U_LIB.S9S_MB_2U(SCH_1):H_CPU0_THERMTRIP_VT_R_N    I15 @S9S_MB_2U_LIB.S9S_MB_2U(SCH_1):PAGE121

R238 Q_RES_0402LF-1.5K,1%,1/16W,CHIA
     1 H_CPU1_THERMTRIP_LVC1_R_N @S9S_MB_2U_LIB.S9S_MB_2U(SCH_1):H_CPU1_THERMTRIP_LVC1_R_N     I6 @S9S_MB_2U_LIB.S9S_MB_2U(SCH_1):PAGE121
     2 H_CPU1_THERMTRIP_VT_R_N @S9S_MB_2U_LIB.S9S_MB_2U(SCH_1):H_CPU1_THERMTRIP_VT_R_N     I6 @S9S_MB_2U_LIB.S9S_MB_2U(SCH_1):PAGE121

R239 Q_RES_0402LF-0,5%,1/16W,CHIP,CA
     1 H_CPU0_PROCHOT_LVC1_R_N @S9S_MB_2U_LIB.S9S_MB_2U(SCH_1):H_CPU0_PROCHOT_LVC1_R_N     I7 @S9S_MB_2U_LIB.S9S_MB_2U(SCH_1):PAGE121
     2 H_CPU0_PROCHOT_LVC1_N @S9S_MB_2U_LIB.S9S_MB_2U(SCH_1):H_CPU0_PROCHOT_LVC1_N     I7 @S9S_MB_2U_LIB.S9S_MB_2U(SCH_1):PAGE121

R240 Q_RES_0402LF-0,5%,1/16W,CHIP,CA
     1 H_CPU1_PROCHOT_LVC1_R_N @S9S_MB_2U_LIB.S9S_MB_2U(SCH_1):H_CPU1_PROCHOT_LVC1_R_N     I5 @S9S_MB_2U_LIB.S9S_MB_2U(SCH_1):PAGE121
     2 H_CPU1_PROCHOT_LVC1_N @S9S_MB_2U_LIB.S9S_MB_2U(SCH_1):H_CPU1_PROCHOT_LVC1_N     I5 @S9S_MB_2U_LIB.S9S_MB_2U(SCH_1):PAGE121

R241 Q_RES_0402LF-4.75K,1%,1/16W,CHA
     1   P3V3 @S9S_MB_2U_LIB.S9S_MB_2U(SCH_1):P3V3    I33 @S9S_MB_2U_LIB.S9S_MB_2U(SCH_1):PAGE121
     2 H_CPU0_THERMTRIP_VT_N @S9S_MB_2U_LIB.S9S_MB_2U(SCH_1):H_CPU0_THERMTRIP_VT_N    I33 @S9S_MB_2U_LIB.S9S_MB_2U(SCH_1):PAGE121

R242 Q_RES_0402LF-4.75K,1%,1/16W,CHA
     1   P3V3 @S9S_MB_2U_LIB.S9S_MB_2U(SCH_1):P3V3    I26 @S9S_MB_2U_LIB.S9S_MB_2U(SCH_1):PAGE121
     2 H_CPU1_THERMTRIP_VT_N @S9S_MB_2U_LIB.S9S_MB_2U(SCH_1):H_CPU1_THERMTRIP_VT_N    I26 @S9S_MB_2U_LIB.S9S_MB_2U(SCH_1):PAGE121

R243 Q_RES_0402LF-100,1%,1/16W,CHIPA
     1 PVNN_TERM_CPU0 @S9S_MB_2U_LIB.S9S_MB_2U(SCH_1):PVNN_TERM_CPU0    I23 @S9S_MB_2U_LIB.S9S_MB_2U(SCH_1):PAGE121
     2 H_CPU0_PROCHOT_LVC1_N @S9S_MB_2U_LIB.S9S_MB_2U(SCH_1):H_CPU0_PROCHOT_LVC1_N    I23 @S9S_MB_2U_LIB.S9S_MB_2U(SCH_1):PAGE121

R244 Q_RES_0402LF-100,1%,1/16W,CHIPA
     1 PVNN_TERM_CPU1 @S9S_MB_2U_LIB.S9S_MB_2U(SCH_1):PVNN_TERM_CPU1    I19 @S9S_MB_2U_LIB.S9S_MB_2U(SCH_1):PAGE121
     2 H_CPU1_PROCHOT_LVC1_N @S9S_MB_2U_LIB.S9S_MB_2U(SCH_1):H_CPU1_PROCHOT_LVC1_N    I19 @S9S_MB_2U_LIB.S9S_MB_2U(SCH_1):PAGE121

R249 Q_RES_0402LF-240,1%,1/16W,EMPTA
     1 PVNN_TERM_CPU0 @S9S_MB_2U_LIB.S9S_MB_2U(SCH_1):PVNN_TERM_CPU0    I27 @S9S_MB_2U_LIB.S9S_MB_2U(SCH_1):PAGE120
     2 FM_S3M_CPU0_LVC1_GPIO_0 @S9S_MB_2U_LIB.S9S_MB_2U(SCH_1):FM_S3M_CPU0_LVC1_GPIO_0    I27 @S9S_MB_2U_LIB.S9S_MB_2U(SCH_1):PAGE120

R250 Q_RES_0402LF-240,1%,1/16W,EMPTA
     1 PVNN_TERM_CPU0 @S9S_MB_2U_LIB.S9S_MB_2U(SCH_1):PVNN_TERM_CPU0    I29 @S9S_MB_2U_LIB.S9S_MB_2U(SCH_1):PAGE120
     2 FM_S3M_CPU0_LVC1_GPIO_1 @S9S_MB_2U_LIB.S9S_MB_2U(SCH_1):FM_S3M_CPU0_LVC1_GPIO_1    I29 @S9S_MB_2U_LIB.S9S_MB_2U(SCH_1):PAGE120

R251 Q_RES_0402LF-240,1%,1/16W,EMPTA
     1 PVNN_TERM_CPU0 @S9S_MB_2U_LIB.S9S_MB_2U(SCH_1):PVNN_TERM_CPU0    I28 @S9S_MB_2U_LIB.S9S_MB_2U(SCH_1):PAGE120
     2 FM_S3M_CPU0_LVC1_GPIO_4 @S9S_MB_2U_LIB.S9S_MB_2U(SCH_1):FM_S3M_CPU0_LVC1_GPIO_4    I28 @S9S_MB_2U_LIB.S9S_MB_2U(SCH_1):PAGE120

R252 Q_RES_0402LF-240,1%,1/16W,CHIPA
     1 PVNN_TERM_CPU0 @S9S_MB_2U_LIB.S9S_MB_2U(SCH_1):PVNN_TERM_CPU0    I30 @S9S_MB_2U_LIB.S9S_MB_2U(SCH_1):PAGE120
     2 PUD_PCH_BOOT_MODE_CPU0 @S9S_MB_2U_LIB.S9S_MB_2U(SCH_1):PUD_PCH_BOOT_MODE_CPU0    I30 @S9S_MB_2U_LIB.S9S_MB_2U(SCH_1):PAGE120

R253 Q_RES_0402LF-240,1%,1/16W,CHIPA
     1 PVNN_TERM_CPU0 @S9S_MB_2U_LIB.S9S_MB_2U(SCH_1):PVNN_TERM_CPU0    I31 @S9S_MB_2U_LIB.S9S_MB_2U(SCH_1):PAGE120
     2 FM_S3M_CPU0_LVC1_GPIO_2 @S9S_MB_2U_LIB.S9S_MB_2U(SCH_1):FM_S3M_CPU0_LVC1_GPIO_2    I31 @S9S_MB_2U_LIB.S9S_MB_2U(SCH_1):PAGE120

R254 Q_RES_0402LF-240,1%,1/16W,CHIPA
     1 PVNN_TERM_CPU0 @S9S_MB_2U_LIB.S9S_MB_2U(SCH_1):PVNN_TERM_CPU0    I32 @S9S_MB_2U_LIB.S9S_MB_2U(SCH_1):PAGE120
     2 FM_S3M_CPU0_LVC1_GPIO_3 @S9S_MB_2U_LIB.S9S_MB_2U(SCH_1):FM_S3M_CPU0_LVC1_GPIO_3    I32 @S9S_MB_2U_LIB.S9S_MB_2U(SCH_1):PAGE120

R255 Q_RES_0402LF-240,1%,1/16W,EMPTA
     1 PVNN_TERM_CPU1 @S9S_MB_2U_LIB.S9S_MB_2U(SCH_1):PVNN_TERM_CPU1    I42 @S9S_MB_2U_LIB.S9S_MB_2U(SCH_1):PAGE120
     2 FM_S3M_CPU1_LVC1_GPIO_0 @S9S_MB_2U_LIB.S9S_MB_2U(SCH_1):FM_S3M_CPU1_LVC1_GPIO_0    I42 @S9S_MB_2U_LIB.S9S_MB_2U(SCH_1):PAGE120

R256 Q_RES_0402LF-240,1%,1/16W,EMPTA
     1 PVNN_TERM_CPU1 @S9S_MB_2U_LIB.S9S_MB_2U(SCH_1):PVNN_TERM_CPU1    I48 @S9S_MB_2U_LIB.S9S_MB_2U(SCH_1):PAGE120
     2 FM_S3M_CPU1_LVC1_GPIO_1 @S9S_MB_2U_LIB.S9S_MB_2U(SCH_1):FM_S3M_CPU1_LVC1_GPIO_1    I48 @S9S_MB_2U_LIB.S9S_MB_2U(SCH_1):PAGE120

R257 Q_RES_0402LF-240,1%,1/16W,EMPTA
     1 PVNN_TERM_CPU1 @S9S_MB_2U_LIB.S9S_MB_2U(SCH_1):PVNN_TERM_CPU1    I43 @S9S_MB_2U_LIB.S9S_MB_2U(SCH_1):PAGE120
     2 FM_S3M_CPU1_LVC1_GPIO_4 @S9S_MB_2U_LIB.S9S_MB_2U(SCH_1):FM_S3M_CPU1_LVC1_GPIO_4    I43 @S9S_MB_2U_LIB.S9S_MB_2U(SCH_1):PAGE120

R258 Q_RES_0402LF-240,1%,1/16W,CHIPA
     1 PVNN_TERM_CPU1 @S9S_MB_2U_LIB.S9S_MB_2U(SCH_1):PVNN_TERM_CPU1    I44 @S9S_MB_2U_LIB.S9S_MB_2U(SCH_1):PAGE120
     2 PUD_PCH_BOOT_MODE_CPU1 @S9S_MB_2U_LIB.S9S_MB_2U(SCH_1):PUD_PCH_BOOT_MODE_CPU1    I44 @S9S_MB_2U_LIB.S9S_MB_2U(SCH_1):PAGE120

R259 Q_RES_0402LF-240,1%,1/16W,CHIPA
     1 PVNN_TERM_CPU1 @S9S_MB_2U_LIB.S9S_MB_2U(SCH_1):PVNN_TERM_CPU1    I45 @S9S_MB_2U_LIB.S9S_MB_2U(SCH_1):PAGE120
     2 FM_S3M_CPU1_LVC1_GPIO_2 @S9S_MB_2U_LIB.S9S_MB_2U(SCH_1):FM_S3M_CPU1_LVC1_GPIO_2    I45 @S9S_MB_2U_LIB.S9S_MB_2U(SCH_1):PAGE120

R260 Q_RES_0402LF-240,1%,1/16W,CHIPA
     1 PVNN_TERM_CPU1 @S9S_MB_2U_LIB.S9S_MB_2U(SCH_1):PVNN_TERM_CPU1    I46 @S9S_MB_2U_LIB.S9S_MB_2U(SCH_1):PAGE120
     2 FM_S3M_CPU1_LVC1_GPIO_3 @S9S_MB_2U_LIB.S9S_MB_2U(SCH_1):FM_S3M_CPU1_LVC1_GPIO_3    I46 @S9S_MB_2U_LIB.S9S_MB_2U(SCH_1):PAGE120

R261 Q_RES_0402LF-240,1%,1/16W,EMPTA
     1 PVNN_TERM_CPU1 @S9S_MB_2U_LIB.S9S_MB_2U(SCH_1):PVNN_TERM_CPU1   I101 @S9S_MB_2U_LIB.S9S_MB_2U(SCH_1):PAGE119
     2 PU_CPU1_TXT_AGENT @S9S_MB_2U_LIB.S9S_MB_2U(SCH_1):PU_CPU1_TXT_AGENT   I101 @S9S_MB_2U_LIB.S9S_MB_2U(SCH_1):PAGE119

R262 Q_RES_0402LF-240,1%,1/16W,EMPTA
     1 PVNN_TERM_CPU1 @S9S_MB_2U_LIB.S9S_MB_2U(SCH_1):PVNN_TERM_CPU1   I100 @S9S_MB_2U_LIB.S9S_MB_2U(SCH_1):PAGE119
     2 PU_CPU1_SAFE_MODE_BOOT @S9S_MB_2U_LIB.S9S_MB_2U(SCH_1):PU_CPU1_SAFE_MODE_BOOT   I100 @S9S_MB_2U_LIB.S9S_MB_2U(SCH_1):PAGE119

R263 Q_RES_0402LF-240,1%,1/16W,EMPTA
     1 PVNN_TERM_CPU1 @S9S_MB_2U_LIB.S9S_MB_2U(SCH_1):PVNN_TERM_CPU1   I125 @S9S_MB_2U_LIB.S9S_MB_2U(SCH_1):PAGE119
     2 PU_CPU1_FRMAGENT @S9S_MB_2U_LIB.S9S_MB_2U(SCH_1):PU_CPU1_FRMAGENT   I125 @S9S_MB_2U_LIB.S9S_MB_2U(SCH_1):PAGE119

R264 Q_RES_0402LF-240,1%,1/16W,EMPTA
     1 PVNN_TERM_CPU1 @S9S_MB_2U_LIB.S9S_MB_2U(SCH_1):PVNN_TERM_CPU1    I98 @S9S_MB_2U_LIB.S9S_MB_2U(SCH_1):PAGE119
     2 H_CPU1_BMCINIT_LVC1 @S9S_MB_2U_LIB.S9S_MB_2U(SCH_1):H_CPU1_BMCINIT_LVC1    I98 @S9S_MB_2U_LIB.S9S_MB_2U(SCH_1):PAGE119

R265 Q_RES_0402LF-240,1%,1/16W,CHIPA
     1 PVNN_TERM_CPU1 @S9S_MB_2U_LIB.S9S_MB_2U(SCH_1):PVNN_TERM_CPU1    I97 @S9S_MB_2U_LIB.S9S_MB_2U(SCH_1):PAGE119
     2 PU_CPU1_SOCKET_ID0 @S9S_MB_2U_LIB.S9S_MB_2U(SCH_1):PU_CPU1_SOCKET_ID0    I97 @S9S_MB_2U_LIB.S9S_MB_2U(SCH_1):PAGE119

R266 Q_RES_0402LF-240,1%,1/16W,EMPTA
     1 PVNN_TERM_CPU1 @S9S_MB_2U_LIB.S9S_MB_2U(SCH_1):PVNN_TERM_CPU1    I96 @S9S_MB_2U_LIB.S9S_MB_2U(SCH_1):PAGE119
     2 PU_CPU1_SOCKET_ID1 @S9S_MB_2U_LIB.S9S_MB_2U(SCH_1):PU_CPU1_SOCKET_ID1    I96 @S9S_MB_2U_LIB.S9S_MB_2U(SCH_1):PAGE119

R267 Q_RES_0402LF-240,1%,1/16W,EMPTA
     1 PVNN_TERM_CPU1 @S9S_MB_2U_LIB.S9S_MB_2U(SCH_1):PVNN_TERM_CPU1    I95 @S9S_MB_2U_LIB.S9S_MB_2U(SCH_1):PAGE119
     2 PU_CPU1_SOCKET_ID2 @S9S_MB_2U_LIB.S9S_MB_2U(SCH_1):PU_CPU1_SOCKET_ID2    I95 @S9S_MB_2U_LIB.S9S_MB_2U(SCH_1):PAGE119

R268 Q_RES_0402LF-240,1%,1/16W,EMPTA
     1 PVNN_TERM_CPU1 @S9S_MB_2U_LIB.S9S_MB_2U(SCH_1):PVNN_TERM_CPU1    I94 @S9S_MB_2U_LIB.S9S_MB_2U(SCH_1):PAGE119
     2 PU_CPU1_LEGACY_SKT @S9S_MB_2U_LIB.S9S_MB_2U(SCH_1):PU_CPU1_LEGACY_SKT    I94 @S9S_MB_2U_LIB.S9S_MB_2U(SCH_1):PAGE119

R269 Q_RES_0402LF-33.2,1%,1/16W,CHIA
     1 FM_ADR_MODE1 @S9S_MB_2U_LIB.S9S_MB_2U(SCH_1):FM_ADR_MODE1    I91 @S9S_MB_2U_LIB.S9S_MB_2U(SCH_1):PAGE212
     2 FM_ADR_MODE1_R @S9S_MB_2U_LIB.S9S_MB_2U(SCH_1):FM_ADR_MODE1_R    I91 @S9S_MB_2U_LIB.S9S_MB_2U(SCH_1):PAGE212

R270 Q_RES_0402LF-10K,1%,1/16W,CHIPA
     1 P3V3_AUX @S9S_MB_2U_LIB.S9S_MB_2U(SCH_1):P3V3_AUX    I93 @S9S_MB_2U_LIB.S9S_MB_2U(SCH_1):PAGE119
     2 FM_CPU1_PKGID0 @S9S_MB_2U_LIB.S9S_MB_2U(SCH_1):FM_CPU1_PKGID0    I93 @S9S_MB_2U_LIB.S9S_MB_2U(SCH_1):PAGE119

R271 Q_RES_0402LF-10K,1%,1/16W,CHIPA
     1 P3V3_AUX @S9S_MB_2U_LIB.S9S_MB_2U(SCH_1):P3V3_AUX    I92 @S9S_MB_2U_LIB.S9S_MB_2U(SCH_1):PAGE119
     2 FM_CPU1_PKGID1 @S9S_MB_2U_LIB.S9S_MB_2U(SCH_1):FM_CPU1_PKGID1    I92 @S9S_MB_2U_LIB.S9S_MB_2U(SCH_1):PAGE119

R272 Q_RES_0402LF-10K,1%,1/16W,CHIPA
     1 P3V3_AUX @S9S_MB_2U_LIB.S9S_MB_2U(SCH_1):P3V3_AUX    I90 @S9S_MB_2U_LIB.S9S_MB_2U(SCH_1):PAGE119
     2 FM_CPU1_PKGID2 @S9S_MB_2U_LIB.S9S_MB_2U(SCH_1):FM_CPU1_PKGID2    I90 @S9S_MB_2U_LIB.S9S_MB_2U(SCH_1):PAGE119

R273 Q_RES_0402LF-10K,1%,1/16W,CHIPA
     1 P3V3_AUX @S9S_MB_2U_LIB.S9S_MB_2U(SCH_1):P3V3_AUX    I89 @S9S_MB_2U_LIB.S9S_MB_2U(SCH_1):PAGE119
     2 FM_CPU1_PROC_ID0 @S9S_MB_2U_LIB.S9S_MB_2U(SCH_1):FM_CPU1_PROC_ID0    I89 @S9S_MB_2U_LIB.S9S_MB_2U(SCH_1):PAGE119

R274 Q_RES_0402LF-10K,1%,1/16W,CHIPA
     1 P3V3_AUX @S9S_MB_2U_LIB.S9S_MB_2U(SCH_1):P3V3_AUX    I88 @S9S_MB_2U_LIB.S9S_MB_2U(SCH_1):PAGE119
     2 FM_CPU1_PROC_ID1 @S9S_MB_2U_LIB.S9S_MB_2U(SCH_1):FM_CPU1_PROC_ID1    I88 @S9S_MB_2U_LIB.S9S_MB_2U(SCH_1):PAGE119

R275 Q_RES_0402LF-240,1%,1/16W,CHIPA
     1 PVNN_TERM_CPU0 @S9S_MB_2U_LIB.S9S_MB_2U(SCH_1):PVNN_TERM_CPU0    I68 @S9S_MB_2U_LIB.S9S_MB_2U(SCH_1):PAGE119
     2 PU_CPU0_TXT_AGENT @S9S_MB_2U_LIB.S9S_MB_2U(SCH_1):PU_CPU0_TXT_AGENT    I68 @S9S_MB_2U_LIB.S9S_MB_2U(SCH_1):PAGE119

R276 Q_RES_0402LF-240,1%,1/16W,EMPTA
     1 PVNN_TERM_CPU0 @S9S_MB_2U_LIB.S9S_MB_2U(SCH_1):PVNN_TERM_CPU0    I66 @S9S_MB_2U_LIB.S9S_MB_2U(SCH_1):PAGE119
     2 PU_CPU0_SAFE_MODE_BOOT @S9S_MB_2U_LIB.S9S_MB_2U(SCH_1):PU_CPU0_SAFE_MODE_BOOT    I66 @S9S_MB_2U_LIB.S9S_MB_2U(SCH_1):PAGE119

R277 Q_RES_0402LF-240,1%,1/16W,CHIPA
     1 PVNN_TERM_CPU0 @S9S_MB_2U_LIB.S9S_MB_2U(SCH_1):PVNN_TERM_CPU0    I62 @S9S_MB_2U_LIB.S9S_MB_2U(SCH_1):PAGE119
     2 PU_CPU0_FRMAGENT @S9S_MB_2U_LIB.S9S_MB_2U(SCH_1):PU_CPU0_FRMAGENT    I62 @S9S_MB_2U_LIB.S9S_MB_2U(SCH_1):PAGE119

R278 Q_RES_0402LF-240,1%,1/16W,EMPTA
     1 PVNN_TERM_CPU0 @S9S_MB_2U_LIB.S9S_MB_2U(SCH_1):PVNN_TERM_CPU0    I61 @S9S_MB_2U_LIB.S9S_MB_2U(SCH_1):PAGE119
     2 H_CPU0_BMCINIT_LVC1 @S9S_MB_2U_LIB.S9S_MB_2U(SCH_1):H_CPU0_BMCINIT_LVC1    I61 @S9S_MB_2U_LIB.S9S_MB_2U(SCH_1):PAGE119

R279 Q_RES_0402LF-240,1%,1/16W,EMPTA
     1 PVNN_TERM_CPU0 @S9S_MB_2U_LIB.S9S_MB_2U(SCH_1):PVNN_TERM_CPU0    I54 @S9S_MB_2U_LIB.S9S_MB_2U(SCH_1):PAGE119
     2 PU_CPU0_SOCKET_ID0 @S9S_MB_2U_LIB.S9S_MB_2U(SCH_1):PU_CPU0_SOCKET_ID0    I54 @S9S_MB_2U_LIB.S9S_MB_2U(SCH_1):PAGE119

R280 Q_RES_0402LF-240,1%,1/16W,EMPTA
     1 PVNN_TERM_CPU0 @S9S_MB_2U_LIB.S9S_MB_2U(SCH_1):PVNN_TERM_CPU0    I57 @S9S_MB_2U_LIB.S9S_MB_2U(SCH_1):PAGE119
     2 PU_CPU0_SOCKET_ID1 @S9S_MB_2U_LIB.S9S_MB_2U(SCH_1):PU_CPU0_SOCKET_ID1    I57 @S9S_MB_2U_LIB.S9S_MB_2U(SCH_1):PAGE119

R281 Q_RES_0402LF-240,1%,1/16W,EMPTA
     1 PVNN_TERM_CPU0 @S9S_MB_2U_LIB.S9S_MB_2U(SCH_1):PVNN_TERM_CPU0    I58 @S9S_MB_2U_LIB.S9S_MB_2U(SCH_1):PAGE119
     2 PU_CPU0_SOCKET_ID2 @S9S_MB_2U_LIB.S9S_MB_2U(SCH_1):PU_CPU0_SOCKET_ID2    I58 @S9S_MB_2U_LIB.S9S_MB_2U(SCH_1):PAGE119

R282 Q_RES_0402LF-240,1%,1/16W,CHIPA
     1 PVNN_TERM_CPU0 @S9S_MB_2U_LIB.S9S_MB_2U(SCH_1):PVNN_TERM_CPU0    I53 @S9S_MB_2U_LIB.S9S_MB_2U(SCH_1):PAGE119
     2 PU_CPU0_LEGACY_SKT @S9S_MB_2U_LIB.S9S_MB_2U(SCH_1):PU_CPU0_LEGACY_SKT    I53 @S9S_MB_2U_LIB.S9S_MB_2U(SCH_1):PAGE119

R283 Q_RES_0402LF-10K,1%,1/16W,CHIPA
     1 P3V3_AUX @S9S_MB_2U_LIB.S9S_MB_2U(SCH_1):P3V3_AUX   I147 @S9S_MB_2U_LIB.S9S_MB_2U(SCH_1):PAGE119
     2 FM_CPU0_PKGID0 @S9S_MB_2U_LIB.S9S_MB_2U(SCH_1):FM_CPU0_PKGID0   I147 @S9S_MB_2U_LIB.S9S_MB_2U(SCH_1):PAGE119

R284 Q_RES_0402LF-10K,1%,1/16W,CHIPA
     1 P3V3_AUX @S9S_MB_2U_LIB.S9S_MB_2U(SCH_1):P3V3_AUX   I148 @S9S_MB_2U_LIB.S9S_MB_2U(SCH_1):PAGE119
     2 FM_CPU0_PKGID1 @S9S_MB_2U_LIB.S9S_MB_2U(SCH_1):FM_CPU0_PKGID1   I148 @S9S_MB_2U_LIB.S9S_MB_2U(SCH_1):PAGE119

R285 Q_RES_0402LF-10K,1%,1/16W,CHIPA
     1 P3V3_AUX @S9S_MB_2U_LIB.S9S_MB_2U(SCH_1):P3V3_AUX   I150 @S9S_MB_2U_LIB.S9S_MB_2U(SCH_1):PAGE119
     2 FM_CPU0_PKGID2 @S9S_MB_2U_LIB.S9S_MB_2U(SCH_1):FM_CPU0_PKGID2   I150 @S9S_MB_2U_LIB.S9S_MB_2U(SCH_1):PAGE119

R286 Q_RES_0402LF-10K,1%,1/16W,CHIPA
     1 P3V3_AUX @S9S_MB_2U_LIB.S9S_MB_2U(SCH_1):P3V3_AUX   I151 @S9S_MB_2U_LIB.S9S_MB_2U(SCH_1):PAGE119
     2 FM_CPU0_PROC_ID0 @S9S_MB_2U_LIB.S9S_MB_2U(SCH_1):FM_CPU0_PROC_ID0   I151 @S9S_MB_2U_LIB.S9S_MB_2U(SCH_1):PAGE119

R287 Q_RES_0402LF-10K,1%,1/16W,CHIPA
     1 P3V3_AUX @S9S_MB_2U_LIB.S9S_MB_2U(SCH_1):P3V3_AUX   I152 @S9S_MB_2U_LIB.S9S_MB_2U(SCH_1):PAGE119
     2 FM_CPU0_PROC_ID1 @S9S_MB_2U_LIB.S9S_MB_2U(SCH_1):FM_CPU0_PROC_ID1   I152 @S9S_MB_2U_LIB.S9S_MB_2U(SCH_1):PAGE119

R288 Q_RES_0402LF-240,1%,1/16W,EMPTA
     1 PVNN_TERM_CPU0 @S9S_MB_2U_LIB.S9S_MB_2U(SCH_1):PVNN_TERM_CPU0   I224 @S9S_MB_2U_LIB.S9S_MB_2U(SCH_1):PAGE119
     2 PD_CPU1_TXT_PLTEN @S9S_MB_2U_LIB.S9S_MB_2U(SCH_1):PD_CPU1_TXT_PLTEN   I224 @S9S_MB_2U_LIB.S9S_MB_2U(SCH_1):PAGE119

R289 Q_RES_0402LF-240,1%,1/16W,EMPTA
     1 PD_CPU1_TXT_PLTEN @S9S_MB_2U_LIB.S9S_MB_2U(SCH_1):PD_CPU1_TXT_PLTEN   I225 @S9S_MB_2U_LIB.S9S_MB_2U(SCH_1):PAGE119
     2    GND @S9S_MB_2U_LIB.S9S_MB_2U(SCH_1):GND   I225 @S9S_MB_2U_LIB.S9S_MB_2U(SCH_1):PAGE119

R290 Q_RES_0402LF-240,1%,1/16W,CHIPA
     1    GND @S9S_MB_2U_LIB.S9S_MB_2U(SCH_1):GND   I135 @S9S_MB_2U_LIB.S9S_MB_2U(SCH_1):PAGE119
     2 PD_CPU1_DMIMODE_OVERRIDE @S9S_MB_2U_LIB.S9S_MB_2U(SCH_1):PD_CPU1_DMIMODE_OVERRIDE   I135 @S9S_MB_2U_LIB.S9S_MB_2U(SCH_1):PAGE119

R291 Q_RES_0402LF-240,1%,1/16W,EMPTA
     1    GND @S9S_MB_2U_LIB.S9S_MB_2U(SCH_1):GND   I116 @S9S_MB_2U_LIB.S9S_MB_2U(SCH_1):PAGE119
     2 PD_CPU1_ENH_MCECC_DIS @S9S_MB_2U_LIB.S9S_MB_2U(SCH_1):PD_CPU1_ENH_MCECC_DIS   I116 @S9S_MB_2U_LIB.S9S_MB_2U(SCH_1):PAGE119

R292 Q_RES_0402LF-240,1%,1/16W,EMPTA
     1 PVNN_TERM_CPU0 @S9S_MB_2U_LIB.S9S_MB_2U(SCH_1):PVNN_TERM_CPU0   I196 @S9S_MB_2U_LIB.S9S_MB_2U(SCH_1):PAGE119
     2 PD_CPU0_TXT_PLTEN @S9S_MB_2U_LIB.S9S_MB_2U(SCH_1):PD_CPU0_TXT_PLTEN   I196 @S9S_MB_2U_LIB.S9S_MB_2U(SCH_1):PAGE119

R293 Q_RES_0402LF-240,1%,1/16W,EMPTA
     1 PD_CPU0_TXT_PLTEN @S9S_MB_2U_LIB.S9S_MB_2U(SCH_1):PD_CPU0_TXT_PLTEN   I211 @S9S_MB_2U_LIB.S9S_MB_2U(SCH_1):PAGE119
     2    GND @S9S_MB_2U_LIB.S9S_MB_2U(SCH_1):GND   I211 @S9S_MB_2U_LIB.S9S_MB_2U(SCH_1):PAGE119

R294 Q_RES_0402LF-240,1%,1/16W,EMPTA
     1    GND @S9S_MB_2U_LIB.S9S_MB_2U(SCH_1):GND    I71 @S9S_MB_2U_LIB.S9S_MB_2U(SCH_1):PAGE119
     2 PD_CPU0_DMIMODE_OVERRIDE @S9S_MB_2U_LIB.S9S_MB_2U(SCH_1):PD_CPU0_DMIMODE_OVERRIDE    I71 @S9S_MB_2U_LIB.S9S_MB_2U(SCH_1):PAGE119

R295 Q_RES_0402LF-240,1%,1/16W,EMPTA
     1    GND @S9S_MB_2U_LIB.S9S_MB_2U(SCH_1):GND    I72 @S9S_MB_2U_LIB.S9S_MB_2U(SCH_1):PAGE119
     2 PD_CPU0_ENH_MCECC_DIS @S9S_MB_2U_LIB.S9S_MB_2U(SCH_1):PD_CPU0_ENH_MCECC_DIS    I72 @S9S_MB_2U_LIB.S9S_MB_2U(SCH_1):PAGE119

R296 Q_RES_0402LF-301,1%,1/16W,CHIPA
     1 PVNN_TERM_CPU0 @S9S_MB_2U_LIB.S9S_MB_2U(SCH_1):PVNN_TERM_CPU0    I65 @S9S_MB_2U_LIB.S9S_MB_2U(SCH_1):PAGE118
     2 H_CPU_CATERR_LVC1_R_N @S9S_MB_2U_LIB.S9S_MB_2U(SCH_1):H_CPU_CATERR_LVC1_R_N    I65 @S9S_MB_2U_LIB.S9S_MB_2U(SCH_1):PAGE118

R297 Q_RES_0402LF-0,5%,1/16W,CHIP,CA
     1 H_CPU0_CATERR_LVC1_R_N @S9S_MB_2U_LIB.S9S_MB_2U(SCH_1):H_CPU0_CATERR_LVC1_R_N    I23 @S9S_MB_2U_LIB.S9S_MB_2U(SCH_1):PAGE118
     2 H_CPU_CATERR_LVC1_R_N @S9S_MB_2U_LIB.S9S_MB_2U(SCH_1):H_CPU_CATERR_LVC1_R_N    I23 @S9S_MB_2U_LIB.S9S_MB_2U(SCH_1):PAGE118

R298 Q_RES_0402LF-301,1%,1/16W,CHIPA
     1 PVNN_TERM_CPU1 @S9S_MB_2U_LIB.S9S_MB_2U(SCH_1):PVNN_TERM_CPU1    I67 @S9S_MB_2U_LIB.S9S_MB_2U(SCH_1):PAGE118
     2 H_CPU_CATERR_LVC1_R_N @S9S_MB_2U_LIB.S9S_MB_2U(SCH_1):H_CPU_CATERR_LVC1_R_N    I67 @S9S_MB_2U_LIB.S9S_MB_2U(SCH_1):PAGE118

R299 Q_RES_0402LF-0,5%,1/16W,CHIP,CA
     1 H_CPU1_CATERR_LVC1_R_N @S9S_MB_2U_LIB.S9S_MB_2U(SCH_1):H_CPU1_CATERR_LVC1_R_N    I63 @S9S_MB_2U_LIB.S9S_MB_2U(SCH_1):PAGE118
     2 H_CPU_CATERR_LVC1_R_N @S9S_MB_2U_LIB.S9S_MB_2U(SCH_1):H_CPU_CATERR_LVC1_R_N    I63 @S9S_MB_2U_LIB.S9S_MB_2U(SCH_1):PAGE118

R301 Q_RES_0402LF-301,1%,1/16W,CHIPA
     1 PVNN_TERM_CPU0 @S9S_MB_2U_LIB.S9S_MB_2U(SCH_1):PVNN_TERM_CPU0    I73 @S9S_MB_2U_LIB.S9S_MB_2U(SCH_1):PAGE118
     2 H_CPU_RMCA_LVC1_R_N @S9S_MB_2U_LIB.S9S_MB_2U(SCH_1):H_CPU_RMCA_LVC1_R_N    I73 @S9S_MB_2U_LIB.S9S_MB_2U(SCH_1):PAGE118

R302 Q_RES_0402LF-0,5%,1/16W,CHIP,CA
     1 H_CPU0_RMCA_LVC1_R_N @S9S_MB_2U_LIB.S9S_MB_2U(SCH_1):H_CPU0_RMCA_LVC1_R_N   I101 @S9S_MB_2U_LIB.S9S_MB_2U(SCH_1):PAGE118
     2 H_CPU_RMCA_LVC1_R_N @S9S_MB_2U_LIB.S9S_MB_2U(SCH_1):H_CPU_RMCA_LVC1_R_N   I101 @S9S_MB_2U_LIB.S9S_MB_2U(SCH_1):PAGE118

R303 Q_RES_0402LF-301,1%,1/16W,CHIPA
     1 PVNN_TERM_CPU1 @S9S_MB_2U_LIB.S9S_MB_2U(SCH_1):PVNN_TERM_CPU1    I76 @S9S_MB_2U_LIB.S9S_MB_2U(SCH_1):PAGE118
     2 H_CPU_RMCA_LVC1_R_N @S9S_MB_2U_LIB.S9S_MB_2U(SCH_1):H_CPU_RMCA_LVC1_R_N    I76 @S9S_MB_2U_LIB.S9S_MB_2U(SCH_1):PAGE118

R304 Q_RES_0402LF-0,5%,1/16W,CHIP,CA
     1 H_CPU1_RMCA_LVC1_R_N @S9S_MB_2U_LIB.S9S_MB_2U(SCH_1):H_CPU1_RMCA_LVC1_R_N   I102 @S9S_MB_2U_LIB.S9S_MB_2U(SCH_1):PAGE118
     2 H_CPU_RMCA_LVC1_R_N @S9S_MB_2U_LIB.S9S_MB_2U(SCH_1):H_CPU_RMCA_LVC1_R_N   I102 @S9S_MB_2U_LIB.S9S_MB_2U(SCH_1):PAGE118

R307 Q_RES_0402LF-1K,1%,1/16W,CHIP,A
     1 P3V3_AUX @S9S_MB_2U_LIB.S9S_MB_2U(SCH_1):P3V3_AUX    I61 @S9S_MB_2U_LIB.S9S_MB_2U(SCH_1):PAGE270
     2 PWRGD_PVCCIN_CPU1_R @S9S_MB_2U_LIB.S9S_MB_2U(SCH_1):PWRGD_PVCCIN_CPU1_R    I61 @S9S_MB_2U_LIB.S9S_MB_2U(SCH_1):PAGE270

R308 Q_RES_0402LF-0,5%,1/16W,CHIP,CA
     1 PWRGD_PVCCIN_CPU1 @S9S_MB_2U_LIB.S9S_MB_2U(SCH_1):PWRGD_PVCCIN_CPU1    I60 @S9S_MB_2U_LIB.S9S_MB_2U(SCH_1):PAGE270
     2 PWRGD_PVCCIN_CPU1_R @S9S_MB_2U_LIB.S9S_MB_2U(SCH_1):PWRGD_PVCCIN_CPU1_R    I60 @S9S_MB_2U_LIB.S9S_MB_2U(SCH_1):PAGE270

R309 Q_RES_0402LF-0,5%,1/16W,CHIP,CA
     1 FM_PVCCIN_CPU1_EN @S9S_MB_2U_LIB.S9S_MB_2U(SCH_1):FM_PVCCIN_CPU1_EN    I59 @S9S_MB_2U_LIB.S9S_MB_2U(SCH_1):PAGE270
     2 PVCCIN_CPU1_EN_R @S9S_MB_2U_LIB.S9S_MB_2U(SCH_1):PVCCIN_CPU1_EN_R    I59 @S9S_MB_2U_LIB.S9S_MB_2U(SCH_1):PAGE270

R310 Q_RES_0402LF-150,1%,1/16W,CHIPA
     1 SVID_CLK0_CPU1_R @S9S_MB_2U_LIB.S9S_MB_2U(SCH_1):SVID_CLK0_CPU1_R    I58 @S9S_MB_2U_LIB.S9S_MB_2U(SCH_1):PAGE270
     2 SVID_CLK_PVCCIN_CPU1_R @S9S_MB_2U_LIB.S9S_MB_2U(SCH_1):SVID_CLK_PVCCIN_CPU1_R    I58 @S9S_MB_2U_LIB.S9S_MB_2U(SCH_1):PAGE270

R311 Q_RES_0402LF-0,5%,1/16W,CHIP,CA
     1 SVID_DIO0_CPU1_R @S9S_MB_2U_LIB.S9S_MB_2U(SCH_1):SVID_DIO0_CPU1_R    I56 @S9S_MB_2U_LIB.S9S_MB_2U(SCH_1):PAGE270
     2 SVID_DIO_PVCCIN_CPU1_R @S9S_MB_2U_LIB.S9S_MB_2U(SCH_1):SVID_DIO_PVCCIN_CPU1_R    I56 @S9S_MB_2U_LIB.S9S_MB_2U(SCH_1):PAGE270

R312 Q_RES_0402LF-0,5%,1/16W,CHIP,CA
     1 SVID_ALERT0_CPU1_R_N @S9S_MB_2U_LIB.S9S_MB_2U(SCH_1):SVID_ALERT0_CPU1_R_N    I57 @S9S_MB_2U_LIB.S9S_MB_2U(SCH_1):PAGE270
     2 SVID_ALERT_PVCCIN_CPU1_R @S9S_MB_2U_LIB.S9S_MB_2U(SCH_1):SVID_ALERT_PVCCIN_CPU1_R    I57 @S9S_MB_2U_LIB.S9S_MB_2U(SCH_1):PAGE270

R315 Q_RES_0402LF-33.2,1%,1/16W,CHIA
     1 PWRGD_CPUPWRGD_GTL @S9S_MB_2U_LIB.S9S_MB_2U(SCH_1):PWRGD_CPUPWRGD_GTL    I92 @S9S_MB_2U_LIB.S9S_MB_2U(SCH_1):PAGE118
     2 PWRGD_CPUPWRGD_LVC1_R @S9S_MB_2U_LIB.S9S_MB_2U(SCH_1):PWRGD_CPUPWRGD_LVC1_R    I92 @S9S_MB_2U_LIB.S9S_MB_2U(SCH_1):PAGE118

R318 Q_RES_0402LF-10K,1%,1/16W,CHIPA
     1 FM_SPD_REMOTE_EN @S9S_MB_2U_LIB.S9S_MB_2U(SCH_1):FM_SPD_REMOTE_EN    I42 @S9S_MB_2U_LIB.S9S_MB_2U(SCH_1):PAGE217
     2    GND @S9S_MB_2U_LIB.S9S_MB_2U(SCH_1):GND    I42 @S9S_MB_2U_LIB.S9S_MB_2U(SCH_1):PAGE217

R319 Q_RES_0402LF-10K,1%,1/16W,CHIPA
     1 P3V3_AUX @S9S_MB_2U_LIB.S9S_MB_2U(SCH_1):P3V3_AUX     I8 @S9S_MB_2U_LIB.S9S_MB_2U(SCH_1):PAGE80
     2 PU_S3M_CPU0_CPLD_STATUS @S9S_MB_2U_LIB.S9S_MB_2U(SCH_1):PU_S3M_CPU0_CPLD_STATUS     I8 @S9S_MB_2U_LIB.S9S_MB_2U(SCH_1):PAGE80

R320 Q_RES_0402LF-10K,1%,1/16W,CHIPA
     1 P3V3_AUX @S9S_MB_2U_LIB.S9S_MB_2U(SCH_1):P3V3_AUX     I7 @S9S_MB_2U_LIB.S9S_MB_2U(SCH_1):PAGE80
     2 PU_S3M_CPU0_CPLD_CONFD @S9S_MB_2U_LIB.S9S_MB_2U(SCH_1):PU_S3M_CPU0_CPLD_CONFD     I7 @S9S_MB_2U_LIB.S9S_MB_2U(SCH_1):PAGE80

R321 Q_RES_0402LF-10K,1%,1/16W,CHIPA
     1 P3V3_AUX @S9S_MB_2U_LIB.S9S_MB_2U(SCH_1):P3V3_AUX     I2 @S9S_MB_2U_LIB.S9S_MB_2U(SCH_1):PAGE80
     2 FM_S3M_CPU0_CPLD_CONFIG_N @S9S_MB_2U_LIB.S9S_MB_2U(SCH_1):FM_S3M_CPU0_CPLD_CONFIG_N     I2 @S9S_MB_2U_LIB.S9S_MB_2U(SCH_1):PAGE80

R322 Q_RES_0402LF-33.2,1%,1/16W,CHIA
     1 H_CPU0_PMSYNC_CPU1_R @S9S_MB_2U_LIB.S9S_MB_2U(SCH_1):H_CPU0_PMSYNC_CPU1_R    I90 @S9S_MB_2U_LIB.S9S_MB_2U(SCH_1):PAGE14
     2 H_CPU0_PMSYNC_CPU1_R1 @S9S_MB_2U_LIB.S9S_MB_2U(SCH_1):H_CPU0_PMSYNC_CPU1_R1    I90 @S9S_MB_2U_LIB.S9S_MB_2U(SCH_1):PAGE14

R323 Q_RES_1206LF-0,,1/2W,EMPTY,CS0A
     1 PVCCINFAON_CPU0 @S9S_MB_2U_LIB.S9S_MB_2U(SCH_1):PVCCINFAON_CPU0    I13 @S9S_MB_2U_LIB.S9S_MB_2U(SCH_1):PAGE80
     2 PVNN_TERM_CPU0 @S9S_MB_2U_LIB.S9S_MB_2U(SCH_1):PVNN_TERM_CPU0    I13 @S9S_MB_2U_LIB.S9S_MB_2U(SCH_1):PAGE80

R324 Q_RES_1206LF-0,,1/2W,CHIP,CS00A
     1 PVNN_MAIN_CPU0 @S9S_MB_2U_LIB.S9S_MB_2U(SCH_1):PVNN_MAIN_CPU0    I12 @S9S_MB_2U_LIB.S9S_MB_2U(SCH_1):PAGE80
     2 PVNN_TERM_CPU0 @S9S_MB_2U_LIB.S9S_MB_2U(SCH_1):PVNN_TERM_CPU0    I12 @S9S_MB_2U_LIB.S9S_MB_2U(SCH_1):PAGE80

R325 Q_RES_0402LF-10K,1%,1/16W,CHIPA
     1 P3V3_AUX @S9S_MB_2U_LIB.S9S_MB_2U(SCH_1):P3V3_AUX    I27 @S9S_MB_2U_LIB.S9S_MB_2U(SCH_1):PAGE80
     2 PU_S3M_CPU1_CPLD_STATUS @S9S_MB_2U_LIB.S9S_MB_2U(SCH_1):PU_S3M_CPU1_CPLD_STATUS    I27 @S9S_MB_2U_LIB.S9S_MB_2U(SCH_1):PAGE80

R326 Q_RES_0402LF-10K,1%,1/16W,CHIPA
     1 P3V3_AUX @S9S_MB_2U_LIB.S9S_MB_2U(SCH_1):P3V3_AUX    I26 @S9S_MB_2U_LIB.S9S_MB_2U(SCH_1):PAGE80
     2 PU_S3M_CPU1_CPLD_CONFD @S9S_MB_2U_LIB.S9S_MB_2U(SCH_1):PU_S3M_CPU1_CPLD_CONFD    I26 @S9S_MB_2U_LIB.S9S_MB_2U(SCH_1):PAGE80

R327 Q_RES_0402LF-10K,1%,1/16W,CHIPA
     1 P3V3_AUX @S9S_MB_2U_LIB.S9S_MB_2U(SCH_1):P3V3_AUX    I25 @S9S_MB_2U_LIB.S9S_MB_2U(SCH_1):PAGE80
     2 FM_S3M_CPU1_CPLD_CONFIG_N @S9S_MB_2U_LIB.S9S_MB_2U(SCH_1):FM_S3M_CPU1_CPLD_CONFIG_N    I25 @S9S_MB_2U_LIB.S9S_MB_2U(SCH_1):PAGE80

R328 Q_RES_0402LF-100,1%,1/16W,CHIPA
     1 SVID_DIO0_CPU0_R @S9S_MB_2U_LIB.S9S_MB_2U(SCH_1):SVID_DIO0_CPU0_R    I93 @S9S_MB_2U_LIB.S9S_MB_2U(SCH_1):PAGE14
     2 PVNN_TERM_CPU0 @S9S_MB_2U_LIB.S9S_MB_2U(SCH_1):PVNN_TERM_CPU0    I93 @S9S_MB_2U_LIB.S9S_MB_2U(SCH_1):PAGE14

R329 Q_RES_1206LF-0,,1/2W,EMPTY,CS0A
     1 PVCCINFAON_CPU1 @S9S_MB_2U_LIB.S9S_MB_2U(SCH_1):PVCCINFAON_CPU1    I35 @S9S_MB_2U_LIB.S9S_MB_2U(SCH_1):PAGE80
     2 PVNN_TERM_CPU1 @S9S_MB_2U_LIB.S9S_MB_2U(SCH_1):PVNN_TERM_CPU1    I35 @S9S_MB_2U_LIB.S9S_MB_2U(SCH_1):PAGE80

R330 Q_RES_1206LF-0,,1/2W,CHIP,CS00A
     1 PVNN_MAIN_CPU1 @S9S_MB_2U_LIB.S9S_MB_2U(SCH_1):PVNN_MAIN_CPU1    I34 @S9S_MB_2U_LIB.S9S_MB_2U(SCH_1):PAGE80
     2 PVNN_TERM_CPU1 @S9S_MB_2U_LIB.S9S_MB_2U(SCH_1):PVNN_TERM_CPU1    I34 @S9S_MB_2U_LIB.S9S_MB_2U(SCH_1):PAGE80

R331 Q_RES_0402LF-1K,1%,1/16W,EMPTYA
     1 P3V3_AUX @S9S_MB_2U_LIB.S9S_MB_2U(SCH_1):P3V3_AUX    I20 @S9S_MB_2U_LIB.S9S_MB_2U(SCH_1):PAGE127
     2 PD_PIROM_CPU0_ADDR2 @S9S_MB_2U_LIB.S9S_MB_2U(SCH_1):PD_PIROM_CPU0_ADDR2    I20 @S9S_MB_2U_LIB.S9S_MB_2U(SCH_1):PAGE127

R332 Q_RES_0402LF-10K,1%,1/16W,CHIPA
     1 PD_PIROM_CPU0_ADDR2 @S9S_MB_2U_LIB.S9S_MB_2U(SCH_1):PD_PIROM_CPU0_ADDR2    I21 @S9S_MB_2U_LIB.S9S_MB_2U(SCH_1):PAGE127
     2    GND @S9S_MB_2U_LIB.S9S_MB_2U(SCH_1):GND    I21 @S9S_MB_2U_LIB.S9S_MB_2U(SCH_1):PAGE127

R333 Q_RES_0402LF-1K,1%,1/16W,EMPTYA
     1 P3V3_AUX @S9S_MB_2U_LIB.S9S_MB_2U(SCH_1):P3V3_AUX     I6 @S9S_MB_2U_LIB.S9S_MB_2U(SCH_1):PAGE127
     2 PD_PIROM_CPU0_ADDR1 @S9S_MB_2U_LIB.S9S_MB_2U(SCH_1):PD_PIROM_CPU0_ADDR1     I6 @S9S_MB_2U_LIB.S9S_MB_2U(SCH_1):PAGE127

R334 Q_RES_0402LF-10K,1%,1/16W,CHIPA
     1 PD_PIROM_CPU0_ADDR1 @S9S_MB_2U_LIB.S9S_MB_2U(SCH_1):PD_PIROM_CPU0_ADDR1     I1 @S9S_MB_2U_LIB.S9S_MB_2U(SCH_1):PAGE127
     2    GND @S9S_MB_2U_LIB.S9S_MB_2U(SCH_1):GND     I1 @S9S_MB_2U_LIB.S9S_MB_2U(SCH_1):PAGE127

R335 Q_RES_0402LF-1K,1%,1/16W,EMPTYA
     1 P3V3_AUX @S9S_MB_2U_LIB.S9S_MB_2U(SCH_1):P3V3_AUX     I5 @S9S_MB_2U_LIB.S9S_MB_2U(SCH_1):PAGE127
     2 PD_PIROM_CPU0_ADDR0 @S9S_MB_2U_LIB.S9S_MB_2U(SCH_1):PD_PIROM_CPU0_ADDR0     I5 @S9S_MB_2U_LIB.S9S_MB_2U(SCH_1):PAGE127

R336 Q_RES_0402LF-0,5%,1/16W,CHIP,CA
     1 H_CPU0_ERR0_LVC1_R_N @S9S_MB_2U_LIB.S9S_MB_2U(SCH_1):H_CPU0_ERR0_LVC1_R_N   I159 @S9S_MB_2U_LIB.S9S_MB_2U(SCH_1):PAGE322
     2 H_CPU_ERR0_LVC1_R_N @S9S_MB_2U_LIB.S9S_MB_2U(SCH_1):H_CPU_ERR0_LVC1_R_N   I159 @S9S_MB_2U_LIB.S9S_MB_2U(SCH_1):PAGE322

R337 Q_RES_0402LF-0,5%,1/16W,CHIP,CA
     1 H_CPU1_ERR0_LVC1_R_N @S9S_MB_2U_LIB.S9S_MB_2U(SCH_1):H_CPU1_ERR0_LVC1_R_N   I160 @S9S_MB_2U_LIB.S9S_MB_2U(SCH_1):PAGE322
     2 H_CPU_ERR0_LVC1_R_N @S9S_MB_2U_LIB.S9S_MB_2U(SCH_1):H_CPU_ERR0_LVC1_R_N   I160 @S9S_MB_2U_LIB.S9S_MB_2U(SCH_1):PAGE322

R338 Q_RES_0402LF-0,5%,1/16W,CHIP,CA
     1 H_CPU_ERR0_LVC1_R_N @S9S_MB_2U_LIB.S9S_MB_2U(SCH_1):H_CPU_ERR0_LVC1_R_N   I173 @S9S_MB_2U_LIB.S9S_MB_2U(SCH_1):PAGE322
     2 H_CPU_ERR0_LVC1_N @S9S_MB_2U_LIB.S9S_MB_2U(SCH_1):H_CPU_ERR0_LVC1_N   I173 @S9S_MB_2U_LIB.S9S_MB_2U(SCH_1):PAGE322

R340 Q_RES_0402LF-0,5%,1/16W,CHIP,CA
     1 H_CPU0_ERR1_LVC1_R_N @S9S_MB_2U_LIB.S9S_MB_2U(SCH_1):H_CPU0_ERR1_LVC1_R_N   I164 @S9S_MB_2U_LIB.S9S_MB_2U(SCH_1):PAGE322
     2 H_CPU_ERR1_LVC1_R_N @S9S_MB_2U_LIB.S9S_MB_2U(SCH_1):H_CPU_ERR1_LVC1_R_N   I164 @S9S_MB_2U_LIB.S9S_MB_2U(SCH_1):PAGE322

R341 Q_RES_0402LF-0,5%,1/16W,CHIP,CA
     1 H_CPU1_ERR1_LVC1_R_N @S9S_MB_2U_LIB.S9S_MB_2U(SCH_1):H_CPU1_ERR1_LVC1_R_N   I163 @S9S_MB_2U_LIB.S9S_MB_2U(SCH_1):PAGE322
     2 H_CPU_ERR1_LVC1_R_N @S9S_MB_2U_LIB.S9S_MB_2U(SCH_1):H_CPU_ERR1_LVC1_R_N   I163 @S9S_MB_2U_LIB.S9S_MB_2U(SCH_1):PAGE322

R342 Q_RES_0402LF-0,5%,1/16W,CHIP,CA
     1 H_CPU_ERR1_LVC1_R_N @S9S_MB_2U_LIB.S9S_MB_2U(SCH_1):H_CPU_ERR1_LVC1_R_N   I172 @S9S_MB_2U_LIB.S9S_MB_2U(SCH_1):PAGE322
     2 H_CPU_ERR1_LVC1_N @S9S_MB_2U_LIB.S9S_MB_2U(SCH_1):H_CPU_ERR1_LVC1_N   I172 @S9S_MB_2U_LIB.S9S_MB_2U(SCH_1):PAGE322

R344 Q_RES_0402LF-0,5%,1/16W,CHIP,CA
     1 H_CPU0_ERR2_LVC1_R_N @S9S_MB_2U_LIB.S9S_MB_2U(SCH_1):H_CPU0_ERR2_LVC1_R_N   I157 @S9S_MB_2U_LIB.S9S_MB_2U(SCH_1):PAGE322
     2 H_CPU_ERR2_LVC1_R_N @S9S_MB_2U_LIB.S9S_MB_2U(SCH_1):H_CPU_ERR2_LVC1_R_N   I157 @S9S_MB_2U_LIB.S9S_MB_2U(SCH_1):PAGE322

R345 Q_RES_0402LF-0,5%,1/16W,CHIP,CA
     1 H_CPU1_ERR2_LVC1_R_N @S9S_MB_2U_LIB.S9S_MB_2U(SCH_1):H_CPU1_ERR2_LVC1_R_N   I158 @S9S_MB_2U_LIB.S9S_MB_2U(SCH_1):PAGE322
     2 H_CPU_ERR2_LVC1_R_N @S9S_MB_2U_LIB.S9S_MB_2U(SCH_1):H_CPU_ERR2_LVC1_R_N   I158 @S9S_MB_2U_LIB.S9S_MB_2U(SCH_1):PAGE322

R346 Q_RES_0402LF-0,5%,1/16W,CHIP,CA
     1 H_CPU_ERR2_LVC1_R_N @S9S_MB_2U_LIB.S9S_MB_2U(SCH_1):H_CPU_ERR2_LVC1_R_N   I171 @S9S_MB_2U_LIB.S9S_MB_2U(SCH_1):PAGE322
     2 H_CPU_ERR2_LVC1_N @S9S_MB_2U_LIB.S9S_MB_2U(SCH_1):H_CPU_ERR2_LVC1_N   I171 @S9S_MB_2U_LIB.S9S_MB_2U(SCH_1):PAGE322

R361 Q_RES_0402LF-1K,1%,1/16W,CHIP,A
     1 P3V3_AUX @S9S_MB_2U_LIB.S9S_MB_2U(SCH_1):P3V3_AUX    I46 @S9S_MB_2U_LIB.S9S_MB_2U(SCH_1):PAGE264
     2 PWRGD_PVCCD_HV_CPU0_R @S9S_MB_2U_LIB.S9S_MB_2U(SCH_1):PWRGD_PVCCD_HV_CPU0_R    I46 @S9S_MB_2U_LIB.S9S_MB_2U(SCH_1):PAGE264

R362 Q_RES_0402LF-0,5%,1/16W,CHIP,CA
     1 PWRGD_PVCCD_HV_CPU0 @S9S_MB_2U_LIB.S9S_MB_2U(SCH_1):PWRGD_PVCCD_HV_CPU0    I44 @S9S_MB_2U_LIB.S9S_MB_2U(SCH_1):PAGE264
     2 PWRGD_PVCCD_HV_CPU0_R @S9S_MB_2U_LIB.S9S_MB_2U(SCH_1):PWRGD_PVCCD_HV_CPU0_R    I44 @S9S_MB_2U_LIB.S9S_MB_2U(SCH_1):PAGE264

R363 Q_RES_0402LF-0,5%,1/16W,CHIP,CA
     1 FM_PVCCD_HV_CPU0_EN @S9S_MB_2U_LIB.S9S_MB_2U(SCH_1):FM_PVCCD_HV_CPU0_EN    I45 @S9S_MB_2U_LIB.S9S_MB_2U(SCH_1):PAGE264
     2 PVCCD_HV_CPU0_EN_R @S9S_MB_2U_LIB.S9S_MB_2U(SCH_1):PVCCD_HV_CPU0_EN_R    I45 @S9S_MB_2U_LIB.S9S_MB_2U(SCH_1):PAGE264

R365 Q_RES_0402LF-0,5%,1/16W,CHIP,CA
     1 FM_CPU_RMCA_CATERR_LVT3_R_N @S9S_MB_2U_LIB.S9S_MB_2U(SCH_1):FM_CPU_RMCA_CATERR_LVT3_R_N   I273 @S9S_MB_2U_LIB.S9S_MB_2U(SCH_1):PAGE207
     2 CPU_RMCA_CATERR_LVT3_N @S9S_MB_2U_LIB.S9S_MB_2U(SCH_1):CPU_RMCA_CATERR_LVT3_N   I273 @S9S_MB_2U_LIB.S9S_MB_2U(SCH_1):PAGE207

R366 Q_RES_0402LF-249,1%,1/16W,CHIPA
     1 P3V3_AUX @S9S_MB_2U_LIB.S9S_MB_2U(SCH_1):P3V3_AUX   I280 @S9S_MB_2U_LIB.S9S_MB_2U(SCH_1):PAGE207
     2 LED_CPU_RMCA_CATERR @S9S_MB_2U_LIB.S9S_MB_2U(SCH_1):LED_CPU_RMCA_CATERR   I280 @S9S_MB_2U_LIB.S9S_MB_2U(SCH_1):PAGE207

R367 Q_RES_0402LF-1K,1%,1/16W,EMPTYA
     1 P3V3_AUX @S9S_MB_2U_LIB.S9S_MB_2U(SCH_1):P3V3_AUX    I11 @S9S_MB_2U_LIB.S9S_MB_2U(SCH_1):PAGE186
     2 FM_PCH_SPKR @S9S_MB_2U_LIB.S9S_MB_2U(SCH_1):FM_PCH_SPKR    I11 @S9S_MB_2U_LIB.S9S_MB_2U(SCH_1):PAGE186

R369 Q_RES_0402LF-1K,1%,1/16W,CHIP,A
     1 P3V3_AUX @S9S_MB_2U_LIB.S9S_MB_2U(SCH_1):P3V3_AUX    I16 @S9S_MB_2U_LIB.S9S_MB_2U(SCH_1):PAGE186
     2 FM_ADR_ACK @S9S_MB_2U_LIB.S9S_MB_2U(SCH_1):FM_ADR_ACK    I16 @S9S_MB_2U_LIB.S9S_MB_2U(SCH_1):PAGE186

R371 Q_RES_0402LF-1K,1%,1/16W,EMPTYA
     1 P3V3_AUX @S9S_MB_2U_LIB.S9S_MB_2U(SCH_1):P3V3_AUX    I45 @S9S_MB_2U_LIB.S9S_MB_2U(SCH_1):PAGE186
     2 FM_PCH_BOOT_BIOS_STRAP @S9S_MB_2U_LIB.S9S_MB_2U(SCH_1):FM_PCH_BOOT_BIOS_STRAP    I45 @S9S_MB_2U_LIB.S9S_MB_2U(SCH_1):PAGE186

R372 Q_RES_0402LF-10K,1%,1/16W,CHIPA
     1 FM_PCH_BOOT_BIOS_STRAP @S9S_MB_2U_LIB.S9S_MB_2U(SCH_1):FM_PCH_BOOT_BIOS_STRAP    I46 @S9S_MB_2U_LIB.S9S_MB_2U(SCH_1):PAGE186
     2    GND @S9S_MB_2U_LIB.S9S_MB_2U(SCH_1):GND    I46 @S9S_MB_2U_LIB.S9S_MB_2U(SCH_1):PAGE186

R374 Q_RES_0402LF-1K,1%,1/16W,EMPTYA
     1 P3V3_AUX @S9S_MB_2U_LIB.S9S_MB_2U(SCH_1):P3V3_AUX    I60 @S9S_MB_2U_LIB.S9S_MB_2U(SCH_1):PAGE186
     2 FM_SPI_3V3_1V8_VOLTAGE @S9S_MB_2U_LIB.S9S_MB_2U(SCH_1):FM_SPI_3V3_1V8_VOLTAGE    I60 @S9S_MB_2U_LIB.S9S_MB_2U(SCH_1):PAGE186

R375 Q_RES_0402LF-10K,1%,1/16W,CHIPA
     1 FM_SPI_3V3_1V8_VOLTAGE @S9S_MB_2U_LIB.S9S_MB_2U(SCH_1):FM_SPI_3V3_1V8_VOLTAGE    I61 @S9S_MB_2U_LIB.S9S_MB_2U(SCH_1):PAGE186
     2    GND @S9S_MB_2U_LIB.S9S_MB_2U(SCH_1):GND    I61 @S9S_MB_2U_LIB.S9S_MB_2U(SCH_1):PAGE186

R378 Q_RES_0402LF-1K,1%,1/16W,EMPTYA
     1 P3V3_AUX @S9S_MB_2U_LIB.S9S_MB_2U(SCH_1):P3V3_AUX    I77 @S9S_MB_2U_LIB.S9S_MB_2U(SCH_1):PAGE186
     2 FM_ADR_MODE1 @S9S_MB_2U_LIB.S9S_MB_2U(SCH_1):FM_ADR_MODE1    I77 @S9S_MB_2U_LIB.S9S_MB_2U(SCH_1):PAGE186

R379 Q_RES_0402LF-1K,1%,1/16W,CHIP,A
     1 FM_ADR_MODE1 @S9S_MB_2U_LIB.S9S_MB_2U(SCH_1):FM_ADR_MODE1    I76 @S9S_MB_2U_LIB.S9S_MB_2U(SCH_1):PAGE186
     2    GND @S9S_MB_2U_LIB.S9S_MB_2U(SCH_1):GND    I76 @S9S_MB_2U_LIB.S9S_MB_2U(SCH_1):PAGE186

R380 Q_RES_0402LF-1K,1%,1/16W,EMPTYA
     1 P3V3_AUX @S9S_MB_2U_LIB.S9S_MB_2U(SCH_1):P3V3_AUX    I78 @S9S_MB_2U_LIB.S9S_MB_2U(SCH_1):PAGE186
     2 FM_FLASH_SECURITY_STRAP @S9S_MB_2U_LIB.S9S_MB_2U(SCH_1):FM_FLASH_SECURITY_STRAP    I78 @S9S_MB_2U_LIB.S9S_MB_2U(SCH_1):PAGE186

R381 Q_RES_0402LF-10K,1%,1/16W,CHIPA
     1 FM_FLASH_SECURITY_STRAP @S9S_MB_2U_LIB.S9S_MB_2U(SCH_1):FM_FLASH_SECURITY_STRAP    I81 @S9S_MB_2U_LIB.S9S_MB_2U(SCH_1):PAGE186
     2    GND @S9S_MB_2U_LIB.S9S_MB_2U(SCH_1):GND    I81 @S9S_MB_2U_LIB.S9S_MB_2U(SCH_1):PAGE186

R401 Q_RES_0402LF-10K,1%,1/16W,EMPTA
     1 P3V3_AUX @S9S_MB_2U_LIB.S9S_MB_2U(SCH_1):P3V3_AUX    I69 @S9S_MB_2U_LIB.S9S_MB_2U(SCH_1):PAGE192
     2 IRQ_TPM_SPI_N @S9S_MB_2U_LIB.S9S_MB_2U(SCH_1):IRQ_TPM_SPI_N    I69 @S9S_MB_2U_LIB.S9S_MB_2U(SCH_1):PAGE192

R409 Q_RES_0402LF-4.7K,1%,1/16W,EMPA
     1 P3V3_OCP_SFF @S9S_MB_2U_LIB.S9S_MB_2U(SCH_1):P3V3_OCP_SFF     I5 @S9S_MB_2U_LIB.S9S_MB_2U(SCH_1):PAGE150
     2 OCP_SFF_ID0 @S9S_MB_2U_LIB.S9S_MB_2U(SCH_1):OCP_SFF_ID0     I5 @S9S_MB_2U_LIB.S9S_MB_2U(SCH_1):PAGE150

R410 Q_RES_0402LF-4.7K,1%,1/16W,CHIA
     1 OCP_SFF_ID0 @S9S_MB_2U_LIB.S9S_MB_2U(SCH_1):OCP_SFF_ID0     I2 @S9S_MB_2U_LIB.S9S_MB_2U(SCH_1):PAGE150
     2    GND @S9S_MB_2U_LIB.S9S_MB_2U(SCH_1):GND     I2 @S9S_MB_2U_LIB.S9S_MB_2U(SCH_1):PAGE150

R413 Q_RES_0402LF-100K,1%,1/16W,CHIA
     1    GND @S9S_MB_2U_LIB.S9S_MB_2U(SCH_1):GND    I43 @S9S_MB_2U_LIB.S9S_MB_2U(SCH_1):PAGE146
     2 FM_OCP_V3_2_PWR_GOOD @S9S_MB_2U_LIB.S9S_MB_2U(SCH_1):FM_OCP_V3_2_PWR_GOOD    I43 @S9S_MB_2U_LIB.S9S_MB_2U(SCH_1):PAGE146

R414 Q_RES_0402LF-4.7K,1%,1/16W,EMPA
     1 P3V3_OCP_SFF @S9S_MB_2U_LIB.S9S_MB_2U(SCH_1):P3V3_OCP_SFF     I6 @S9S_MB_2U_LIB.S9S_MB_2U(SCH_1):PAGE150
     2 OCP_SFF_ID1 @S9S_MB_2U_LIB.S9S_MB_2U(SCH_1):OCP_SFF_ID1     I6 @S9S_MB_2U_LIB.S9S_MB_2U(SCH_1):PAGE150

R415 Q_RES_0402LF-4.7K,1%,1/16W,CHIA
     1 OCP_SFF_ID1 @S9S_MB_2U_LIB.S9S_MB_2U(SCH_1):OCP_SFF_ID1     I4 @S9S_MB_2U_LIB.S9S_MB_2U(SCH_1):PAGE150
     2    GND @S9S_MB_2U_LIB.S9S_MB_2U(SCH_1):GND     I4 @S9S_MB_2U_LIB.S9S_MB_2U(SCH_1):PAGE150

R416 Q_RES_0402LF-0,5%,1/16W,CHIP,CA
     1 OCP_SFF_ISO_BIF0_EN @S9S_MB_2U_LIB.S9S_MB_2U(SCH_1):OCP_SFF_ISO_BIF0_EN    I54 @S9S_MB_2U_LIB.S9S_MB_2U(SCH_1):PAGE150
     2 OCP_SFF_BIF0_R_N @S9S_MB_2U_LIB.S9S_MB_2U(SCH_1):OCP_SFF_BIF0_R_N    I54 @S9S_MB_2U_LIB.S9S_MB_2U(SCH_1):PAGE150

R417 Q_RES_0402LF-0,5%,1/16W,CHIP,CA
     1 OCP_SFF_ISO_BIF1_EN @S9S_MB_2U_LIB.S9S_MB_2U(SCH_1):OCP_SFF_ISO_BIF1_EN    I53 @S9S_MB_2U_LIB.S9S_MB_2U(SCH_1):PAGE150
     2 OCP_SFF_BIF1_R_N @S9S_MB_2U_LIB.S9S_MB_2U(SCH_1):OCP_SFF_BIF1_R_N    I53 @S9S_MB_2U_LIB.S9S_MB_2U(SCH_1):PAGE150

R418 Q_RES_0402LF-0,5%,1/16W,CHIP,CA
     1 OCP_SFF_ISO_BIF2_EN @S9S_MB_2U_LIB.S9S_MB_2U(SCH_1):OCP_SFF_ISO_BIF2_EN    I52 @S9S_MB_2U_LIB.S9S_MB_2U(SCH_1):PAGE150
     2 OCP_SFF_BIF2_R_N @S9S_MB_2U_LIB.S9S_MB_2U(SCH_1):OCP_SFF_BIF2_R_N    I52 @S9S_MB_2U_LIB.S9S_MB_2U(SCH_1):PAGE150

R419 Q_RES_0402LF-33.2,1%,1/16W,CHIA
     1 RST_OCP_V3_1_BUF_N @S9S_MB_2U_LIB.S9S_MB_2U(SCH_1):RST_OCP_V3_1_BUF_N     I6 @S9S_MB_2U_LIB.S9S_MB_2U(SCH_1):PAGE152
     2 RST_PERST0_OCP_SFF_N @S9S_MB_2U_LIB.S9S_MB_2U(SCH_1):RST_PERST0_OCP_SFF_N     I6 @S9S_MB_2U_LIB.S9S_MB_2U(SCH_1):PAGE152

R420 Q_RES_0402LF-1K,1%,1/16W,CHIP,A
     1 SGPIO_OCP_SFF_LD_N @S9S_MB_2U_LIB.S9S_MB_2U(SCH_1):SGPIO_OCP_SFF_LD_N   I218 @S9S_MB_2U_LIB.S9S_MB_2U(SCH_1):PAGE150
     2 P3V3_OCP_SFF @S9S_MB_2U_LIB.S9S_MB_2U(SCH_1):P3V3_OCP_SFF   I218 @S9S_MB_2U_LIB.S9S_MB_2U(SCH_1):PAGE150

R421 Q_RES_0402LF-10K,1%,1/16W,CHIPA
     1 SGPIO_OCP_SFF_DATAIN @S9S_MB_2U_LIB.S9S_MB_2U(SCH_1):SGPIO_OCP_SFF_DATAIN   I217 @S9S_MB_2U_LIB.S9S_MB_2U(SCH_1):PAGE150
     2 P3V3_OCP_SFF @S9S_MB_2U_LIB.S9S_MB_2U(SCH_1):P3V3_OCP_SFF   I217 @S9S_MB_2U_LIB.S9S_MB_2U(SCH_1):PAGE150

R422 Q_RES_0402LF-10K,1%,1/16W,CHIPA
     1 SGPIO_OCP_SFF_DATAOUT @S9S_MB_2U_LIB.S9S_MB_2U(SCH_1):SGPIO_OCP_SFF_DATAOUT   I215 @S9S_MB_2U_LIB.S9S_MB_2U(SCH_1):PAGE150
     2    GND @S9S_MB_2U_LIB.S9S_MB_2U(SCH_1):GND   I215 @S9S_MB_2U_LIB.S9S_MB_2U(SCH_1):PAGE150

R423 Q_RES_0402LF-1K,1%,1/16W,CHIP,A
     1 SGPIO_OCP_SFF_CLK @S9S_MB_2U_LIB.S9S_MB_2U(SCH_1):SGPIO_OCP_SFF_CLK   I212 @S9S_MB_2U_LIB.S9S_MB_2U(SCH_1):PAGE150
     2 P3V3_OCP_SFF @S9S_MB_2U_LIB.S9S_MB_2U(SCH_1):P3V3_OCP_SFF   I212 @S9S_MB_2U_LIB.S9S_MB_2U(SCH_1):PAGE150

R424 Q_RES_0402LF-33.2,1%,1/16W,CHIA
     1 SMB_OCP_SFF_3V3AUX_BUF_R_SCL @S9S_MB_2U_LIB.S9S_MB_2U(SCH_1):SMB_OCP_SFF_3V3AUX_BUF_R_SCL   I151 @S9S_MB_2U_LIB.S9S_MB_2U(SCH_1):PAGE150
     2 SMB_OCP_SFF_3V3AUX_BUF_SCL @S9S_MB_2U_LIB.S9S_MB_2U(SCH_1):SMB_OCP_SFF_3V3AUX_BUF_SCL   I151 @S9S_MB_2U_LIB.S9S_MB_2U(SCH_1):PAGE150

R425 Q_RES_0402LF-200,1%,1/16W,CHIPA
     1 SMB_OCP_SFF_3V3AUX_BUF_R_SDA @S9S_MB_2U_LIB.S9S_MB_2U(SCH_1):SMB_OCP_SFF_3V3AUX_BUF_R_SDA   I220 @S9S_MB_2U_LIB.S9S_MB_2U(SCH_1):PAGE150
     2 SMB_OCP_SFF_3V3AUX_BUF_SDA @S9S_MB_2U_LIB.S9S_MB_2U(SCH_1):SMB_OCP_SFF_3V3AUX_BUF_SDA   I220 @S9S_MB_2U_LIB.S9S_MB_2U(SCH_1):PAGE150

R429 Q_RES_0402LF-0,5%,1/16W,CHIP,CA
     1 OCP_SFF_MAIN_PWR_EN @S9S_MB_2U_LIB.S9S_MB_2U(SCH_1):OCP_SFF_MAIN_PWR_EN    I58 @S9S_MB_2U_LIB.S9S_MB_2U(SCH_1):PAGE150
     2 OCP_SFF_MAIN_PWR_EN_R @S9S_MB_2U_LIB.S9S_MB_2U(SCH_1):OCP_SFF_MAIN_PWR_EN_R    I58 @S9S_MB_2U_LIB.S9S_MB_2U(SCH_1):PAGE150

R435 Q_RES_0402LF-33.2,1%,1/16W,CHIA
     1 RST_OCP_V3_1_BUF_N @S9S_MB_2U_LIB.S9S_MB_2U(SCH_1):RST_OCP_V3_1_BUF_N     I8 @S9S_MB_2U_LIB.S9S_MB_2U(SCH_1):PAGE152
     2 RST_PERST1_OCP_SFF_N @S9S_MB_2U_LIB.S9S_MB_2U(SCH_1):RST_PERST1_OCP_SFF_N     I8 @S9S_MB_2U_LIB.S9S_MB_2U(SCH_1):PAGE152

R442 Q_RES_0603LF-1,1%,1/10W,CHIP,CA
     1 P3V3_AUX_CLK_GEN_VDDXTAL_CK440 @S9S_MB_2U_LIB.S9S_MB_2U(SCH_1):P3V3_AUX_CLK_GEN_VDDXTAL_CK440    I36 @S9S_MB_2U_LIB.S9S_MB_2U(SCH_1):PAGE199
     2 P3V3_AUX_CLK_GEN_VDDA25M_CK440 @S9S_MB_2U_LIB.S9S_MB_2U(SCH_1):P3V3_AUX_CLK_GEN_VDDA25M_CK440    I36 @S9S_MB_2U_LIB.S9S_MB_2U(SCH_1):PAGE199

R444 Q_RES_0402LF-0,5%,1/16W,CHIP,CA
     1 OCP_SFF_USB2_3_DN @S9S_MB_2U_LIB.S9S_MB_2U(SCH_1):OCP_SFF_USB2_3_DN   I118 @S9S_MB_2U_LIB.S9S_MB_2U(SCH_1):PAGE150
     2 USB2_3_DN @S9S_MB_2U_LIB.S9S_MB_2U(SCH_1):USB2_3_DN   I118 @S9S_MB_2U_LIB.S9S_MB_2U(SCH_1):PAGE150

R445 Q_RES_0402LF-0,5%,1/16W,CHIP,CA
     1 OCP_SFF_USB2_3_DP @S9S_MB_2U_LIB.S9S_MB_2U(SCH_1):OCP_SFF_USB2_3_DP   I119 @S9S_MB_2U_LIB.S9S_MB_2U(SCH_1):PAGE150
     2 USB2_3_DP @S9S_MB_2U_LIB.S9S_MB_2U(SCH_1):USB2_3_DP   I119 @S9S_MB_2U_LIB.S9S_MB_2U(SCH_1):PAGE150

R447 Q_RES_0603LF-1,1%,1/10W,CHIP,CA
     1 P3V3_AUX_CLK_GEN_VDDMXCK_CK440 @S9S_MB_2U_LIB.S9S_MB_2U(SCH_1):P3V3_AUX_CLK_GEN_VDDMXCK_CK440    I55 @S9S_MB_2U_LIB.S9S_MB_2U(SCH_1):PAGE199
     2 P3V3_AUX_CLK_GEN_VDDPT_CK440 @S9S_MB_2U_LIB.S9S_MB_2U(SCH_1):P3V3_AUX_CLK_GEN_VDDPT_CK440    I55 @S9S_MB_2U_LIB.S9S_MB_2U(SCH_1):PAGE199

R448 Q_RES_0402LF-0,5%,1/16W,EMPTY,A
     1 SMB_S3M_CPU0_3V3AUX_SCL @S9S_MB_2U_LIB.S9S_MB_2U(SCH_1):SMB_S3M_CPU0_3V3AUX_SCL    I13 @S9S_MB_2U_LIB.S9S_MB_2U(SCH_1):PAGE224
     2 SMB_S3M_CPU1_3V3AUX_SCL @S9S_MB_2U_LIB.S9S_MB_2U(SCH_1):SMB_S3M_CPU1_3V3AUX_SCL    I13 @S9S_MB_2U_LIB.S9S_MB_2U(SCH_1):PAGE224

R453 Q_RES_0402LF-10K,1%,1/16W,CHIPA
     1 P3V3_AUX @S9S_MB_2U_LIB.S9S_MB_2U(SCH_1):P3V3_AUX    I77 @S9S_MB_2U_LIB.S9S_MB_2U(SCH_1):PAGE174
     2 PU_LAN_WAKE_N @S9S_MB_2U_LIB.S9S_MB_2U(SCH_1):PU_LAN_WAKE_N    I77 @S9S_MB_2U_LIB.S9S_MB_2U(SCH_1):PAGE174

R456 Q_RES_0402LF-10K,1%,1/16W,CHIPA
     1 P3V3_AUX @S9S_MB_2U_LIB.S9S_MB_2U(SCH_1):P3V3_AUX    I66 @S9S_MB_2U_LIB.S9S_MB_2U(SCH_1):PAGE192
     2 PU_PCH_PMCALERT_N @S9S_MB_2U_LIB.S9S_MB_2U(SCH_1):PU_PCH_PMCALERT_N    I66 @S9S_MB_2U_LIB.S9S_MB_2U(SCH_1):PAGE192

R474 Q_RES_0402LF-33.2,1%,1/16W,CHIA
     1 FM_PCHHOT_N @S9S_MB_2U_LIB.S9S_MB_2U(SCH_1):FM_PCHHOT_N   I213 @S9S_MB_2U_LIB.S9S_MB_2U(SCH_1):PAGE175
     2 FM_PCHHOT_R_N @S9S_MB_2U_LIB.S9S_MB_2U(SCH_1):FM_PCHHOT_R_N   I213 @S9S_MB_2U_LIB.S9S_MB_2U(SCH_1):PAGE175

R477 Q_RES_0402LF-60.4,1%,1/16W,CHIA
     1 PD_PCH_XCLK_BIASREF @S9S_MB_2U_LIB.S9S_MB_2U(SCH_1):PD_PCH_XCLK_BIASREF    I69 @S9S_MB_2U_LIB.S9S_MB_2U(SCH_1):PAGE171
     2    GND @S9S_MB_2U_LIB.S9S_MB_2U(SCH_1):GND    I69 @S9S_MB_2U_LIB.S9S_MB_2U(SCH_1):PAGE171

R478 Q_RES_0402LF-4.7K,1%,1/16W,CHIA
     1 P3V3_AUX @S9S_MB_2U_LIB.S9S_MB_2U(SCH_1):P3V3_AUX   I176 @S9S_MB_2U_LIB.S9S_MB_2U(SCH_1):PAGE182
     2 PCIE_M2_SSD0_PRSNT_N @S9S_MB_2U_LIB.S9S_MB_2U(SCH_1):PCIE_M2_SSD0_PRSNT_N   I176 @S9S_MB_2U_LIB.S9S_MB_2U(SCH_1):PAGE182

R480 Q_RES_0402LF-0,5%,1/16W,CHIP,CA
     1 JTAG_DBP_TMS @S9S_MB_2U_LIB.S9S_MB_2U(SCH_1):JTAG_DBP_TMS    I59 @S9S_MB_2U_LIB.S9S_MB_2U(SCH_1):PAGE226
     2 JTAG_DBP_FB_TMS @S9S_MB_2U_LIB.S9S_MB_2U(SCH_1):JTAG_DBP_FB_TMS    I59 @S9S_MB_2U_LIB.S9S_MB_2U(SCH_1):PAGE226

R481 Q_RES_0402LF-0,5%,1/16W,CHIP,CA
     1 JTAG_DBP_TDI @S9S_MB_2U_LIB.S9S_MB_2U(SCH_1):JTAG_DBP_TDI    I58 @S9S_MB_2U_LIB.S9S_MB_2U(SCH_1):PAGE226
     2 JTAG_DBP_FB_TDI @S9S_MB_2U_LIB.S9S_MB_2U(SCH_1):JTAG_DBP_FB_TDI    I58 @S9S_MB_2U_LIB.S9S_MB_2U(SCH_1):PAGE226

R482 Q_RES_0402LF-0,5%,1/16W,CHIP,CA
     1 JTAG_DBP_PREQ_N @S9S_MB_2U_LIB.S9S_MB_2U(SCH_1):JTAG_DBP_PREQ_N    I57 @S9S_MB_2U_LIB.S9S_MB_2U(SCH_1):PAGE226
     2 JTAG_DBP_PREQ_R_N @S9S_MB_2U_LIB.S9S_MB_2U(SCH_1):JTAG_DBP_PREQ_R_N    I57 @S9S_MB_2U_LIB.S9S_MB_2U(SCH_1):PAGE226

R483 Q_RES_0402LF-0,5%,1/16W,CHIP,CA
     1 JTAG_BMC_DBP_TDO_R @S9S_MB_2U_LIB.S9S_MB_2U(SCH_1):JTAG_BMC_DBP_TDO_R    I37 @S9S_MB_2U_LIB.S9S_MB_2U(SCH_1):PAGE226
     2 JTAG_BMC_DBP_TDO @S9S_MB_2U_LIB.S9S_MB_2U(SCH_1):JTAG_BMC_DBP_TDO    I37 @S9S_MB_2U_LIB.S9S_MB_2U(SCH_1):PAGE226

R486 Q_RES_0402LF-0,5%,1/16W,CHIP,CA
     1 M2_SSD0_CLKREQ_EN_N @S9S_MB_2U_LIB.S9S_MB_2U(SCH_1):M2_SSD0_CLKREQ_EN_N   I162 @S9S_MB_2U_LIB.S9S_MB_2U(SCH_1):PAGE182
     2 M2_SSD0_CLKREQ_EN_N_BUF @S9S_MB_2U_LIB.S9S_MB_2U(SCH_1):M2_SSD0_CLKREQ_EN_N_BUF   I162 @S9S_MB_2U_LIB.S9S_MB_2U(SCH_1):PAGE182

R487 Q_RES_0402LF-1K,1%,1/16W,CHIP,A
     1 P3V3_AUX @S9S_MB_2U_LIB.S9S_MB_2U(SCH_1):P3V3_AUX   I173 @S9S_MB_2U_LIB.S9S_MB_2U(SCH_1):PAGE182
     2 M2_SSD0_CLKREQ_EN_N_BUF @S9S_MB_2U_LIB.S9S_MB_2U(SCH_1):M2_SSD0_CLKREQ_EN_N_BUF   I173 @S9S_MB_2U_LIB.S9S_MB_2U(SCH_1):PAGE182

R491 Q_RES_0402LF-4.7K,1%,1/16W,EMPA
     1 M2_SSD0_CLKREQ_EN_N @S9S_MB_2U_LIB.S9S_MB_2U(SCH_1):M2_SSD0_CLKREQ_EN_N   I164 @S9S_MB_2U_LIB.S9S_MB_2U(SCH_1):PAGE182
     2    GND @S9S_MB_2U_LIB.S9S_MB_2U(SCH_1):GND   I164 @S9S_MB_2U_LIB.S9S_MB_2U(SCH_1):PAGE182

R494 Q_RES_0402LF-1K,1%,1/16W,CHIP,A
     1 P3V3_AUX @S9S_MB_2U_LIB.S9S_MB_2U(SCH_1):P3V3_AUX    I98 @S9S_MB_2U_LIB.S9S_MB_2U(SCH_1):PAGE174
     2 IRQ_LVC3_WAKE_N @S9S_MB_2U_LIB.S9S_MB_2U(SCH_1):IRQ_LVC3_WAKE_N    I98 @S9S_MB_2U_LIB.S9S_MB_2U(SCH_1):PAGE174

R495 Q_RES_0402LF-100,1%,1/16W,CHIPA
     1 PCH_PCIEUP_RCOMPP @S9S_MB_2U_LIB.S9S_MB_2U(SCH_1):PCH_PCIEUP_RCOMPP     I1 @S9S_MB_2U_LIB.S9S_MB_2U(SCH_1):PAGE173
     2 PCH_PCIEUP_RCOMPN @S9S_MB_2U_LIB.S9S_MB_2U(SCH_1):PCH_PCIEUP_RCOMPN     I1 @S9S_MB_2U_LIB.S9S_MB_2U(SCH_1):PAGE173

R496 Q_RES_0402LF-113,1%,1/16W,CHIPA
     1 PD_PCH_USB2_COMP @S9S_MB_2U_LIB.S9S_MB_2U(SCH_1):PD_PCH_USB2_COMP    I10 @S9S_MB_2U_LIB.S9S_MB_2U(SCH_1):PAGE172
     2    GND @S9S_MB_2U_LIB.S9S_MB_2U(SCH_1):GND    I10 @S9S_MB_2U_LIB.S9S_MB_2U(SCH_1):PAGE172

R497 Q_RES_0402LF-200,1%,1/16W,CHIPA
     1 PD_RCOMP_1P8_3P3 @S9S_MB_2U_LIB.S9S_MB_2U(SCH_1):PD_RCOMP_1P8_3P3     I2 @S9S_MB_2U_LIB.S9S_MB_2U(SCH_1):PAGE179
     2    GND @S9S_MB_2U_LIB.S9S_MB_2U(SCH_1):GND     I2 @S9S_MB_2U_LIB.S9S_MB_2U(SCH_1):PAGE179

R498 Q_RES_0402LF-10K,1%,1/16W,CHIPA
     1 P3V3_AUX @S9S_MB_2U_LIB.S9S_MB_2U(SCH_1):P3V3_AUX    I24 @S9S_MB_2U_LIB.S9S_MB_2U(SCH_1):PAGE177
     2 FM_PCH_PRSNT_N @S9S_MB_2U_LIB.S9S_MB_2U(SCH_1):FM_PCH_PRSNT_N    I24 @S9S_MB_2U_LIB.S9S_MB_2U(SCH_1):PAGE177

R499 Q_RES_0402LF-33.2,1%,1/16W,CHIA
     1 SPI_PCH_CLK @S9S_MB_2U_LIB.S9S_MB_2U(SCH_1):SPI_PCH_CLK   I106 @S9S_MB_2U_LIB.S9S_MB_2U(SCH_1):PAGE177
     2 SPI_SYS_CLK @S9S_MB_2U_LIB.S9S_MB_2U(SCH_1):SPI_SYS_CLK   I106 @S9S_MB_2U_LIB.S9S_MB_2U(SCH_1):PAGE177

R501 Q_RES_0402LF-33.2,1%,1/16W,CHIA
     1 SPI_PCH_CS0_R_N @S9S_MB_2U_LIB.S9S_MB_2U(SCH_1):SPI_PCH_CS0_R_N   I100 @S9S_MB_2U_LIB.S9S_MB_2U(SCH_1):PAGE177
     2 SPI_SYS_CS0_N @S9S_MB_2U_LIB.S9S_MB_2U(SCH_1):SPI_SYS_CS0_N   I100 @S9S_MB_2U_LIB.S9S_MB_2U(SCH_1):PAGE177

R502 Q_RES_0402LF-20K,1%,1/16W,CHIPA
     1 P3V3_AUX @S9S_MB_2U_LIB.S9S_MB_2U(SCH_1):P3V3_AUX    I68 @S9S_MB_2U_LIB.S9S_MB_2U(SCH_1):PAGE186
     2 FM_PCH_CONSENT_STRAP_N @S9S_MB_2U_LIB.S9S_MB_2U(SCH_1):FM_PCH_CONSENT_STRAP_N    I68 @S9S_MB_2U_LIB.S9S_MB_2U(SCH_1):PAGE186

R506 Q_RES_0402LF-0,5%,1/16W,CHIP,CA
     1 IRQ_SMI_ACTIVE_BMC_N @S9S_MB_2U_LIB.S9S_MB_2U(SCH_1):IRQ_SMI_ACTIVE_BMC_N    I18 @S9S_MB_2U_LIB.S9S_MB_2U(SCH_1):PAGE227
     2 IRQ0_A57 @S9S_MB_2U_LIB.S9S_MB_2U(SCH_1):IRQ0_A57    I18 @S9S_MB_2U_LIB.S9S_MB_2U(SCH_1):PAGE227

R515 Q_RES_0402LF-10K,1%,1/16W,CHIPA
     1 PD_PIROM_CPU0_ADDR0 @S9S_MB_2U_LIB.S9S_MB_2U(SCH_1):PD_PIROM_CPU0_ADDR0     I7 @S9S_MB_2U_LIB.S9S_MB_2U(SCH_1):PAGE127
     2    GND @S9S_MB_2U_LIB.S9S_MB_2U(SCH_1):GND     I7 @S9S_MB_2U_LIB.S9S_MB_2U(SCH_1):PAGE127

R519 Q_RES_0603LF-1,1%,1/10W,CHIP,CA
     1 P3V3_AUX_CLK_GEN_VDD_CK440 @S9S_MB_2U_LIB.S9S_MB_2U(SCH_1):P3V3_AUX_CLK_GEN_VDD_CK440     I7 @S9S_MB_2U_LIB.S9S_MB_2U(SCH_1):PAGE199
     2 P3V3_AUX_CLK_GEN_VDDA100M_CK440 @S9S_MB_2U_LIB.S9S_MB_2U(SCH_1):P3V3_AUX_CLK_GEN_VDDA100M_CK440     I7 @S9S_MB_2U_LIB.S9S_MB_2U(SCH_1):PAGE199

R536 Q_RES_0402LF-10K,1%,1/16W,EMPTA
     1 P3V3_AUX @S9S_MB_2U_LIB.S9S_MB_2U(SCH_1):P3V3_AUX     I3 @S9S_MB_2U_LIB.S9S_MB_2U(SCH_1):PAGE219
     2 PCA9548_PCIE3_ADDR2 @S9S_MB_2U_LIB.S9S_MB_2U(SCH_1):PCA9548_PCIE3_ADDR2     I3 @S9S_MB_2U_LIB.S9S_MB_2U(SCH_1):PAGE219

R537 Q_RES_0402LF-1K,1%,1/16W,CHIP,A
     1 PCA9548_PCIE3_ADDR2 @S9S_MB_2U_LIB.S9S_MB_2U(SCH_1):PCA9548_PCIE3_ADDR2     I2 @S9S_MB_2U_LIB.S9S_MB_2U(SCH_1):PAGE219
     2    GND @S9S_MB_2U_LIB.S9S_MB_2U(SCH_1):GND     I2 @S9S_MB_2U_LIB.S9S_MB_2U(SCH_1):PAGE219

R538 Q_RES_0402LF-10K,1%,1/16W,EMPTA
     1 P3V3_AUX @S9S_MB_2U_LIB.S9S_MB_2U(SCH_1):P3V3_AUX     I9 @S9S_MB_2U_LIB.S9S_MB_2U(SCH_1):PAGE219
     2 PCA9548_PCIE3_ADDR1 @S9S_MB_2U_LIB.S9S_MB_2U(SCH_1):PCA9548_PCIE3_ADDR1     I9 @S9S_MB_2U_LIB.S9S_MB_2U(SCH_1):PAGE219

R539 Q_RES_0402LF-1K,1%,1/16W,CHIP,A
     1 PCA9548_PCIE3_ADDR1 @S9S_MB_2U_LIB.S9S_MB_2U(SCH_1):PCA9548_PCIE3_ADDR1     I6 @S9S_MB_2U_LIB.S9S_MB_2U(SCH_1):PAGE219
     2    GND @S9S_MB_2U_LIB.S9S_MB_2U(SCH_1):GND     I6 @S9S_MB_2U_LIB.S9S_MB_2U(SCH_1):PAGE219

R540 Q_RES_0402LF-10K,1%,1/16W,EMPTA
     1 P3V3_AUX @S9S_MB_2U_LIB.S9S_MB_2U(SCH_1):P3V3_AUX    I10 @S9S_MB_2U_LIB.S9S_MB_2U(SCH_1):PAGE219
     2 PCA9548_PCIE3_ADDR0 @S9S_MB_2U_LIB.S9S_MB_2U(SCH_1):PCA9548_PCIE3_ADDR0    I10 @S9S_MB_2U_LIB.S9S_MB_2U(SCH_1):PAGE219

R548 Q_RES_0402LF-49.9,1%,1/16W,CHIA
     1 SVID_ALERT0_CPU0_R_N @S9S_MB_2U_LIB.S9S_MB_2U(SCH_1):SVID_ALERT0_CPU0_R_N    I94 @S9S_MB_2U_LIB.S9S_MB_2U(SCH_1):PAGE14
     2 PVNN_TERM_CPU0 @S9S_MB_2U_LIB.S9S_MB_2U(SCH_1):PVNN_TERM_CPU0    I94 @S9S_MB_2U_LIB.S9S_MB_2U(SCH_1):PAGE14

R553 Q_RES_0402LF-0,5%,1/16W,CHIP,CA
     1 CLK_100M_CK440_PCH_EXTCLK_R_DP @S9S_MB_2U_LIB.S9S_MB_2U(SCH_1):CLK_100M_CK440_PCH_EXTCLK_R_DP    I58 @S9S_MB_2U_LIB.S9S_MB_2U(SCH_1):PAGE198
     2 CLK_100M_CK440_PCH_EXTCLK_DP @S9S_MB_2U_LIB.S9S_MB_2U(SCH_1):CLK_100M_CK440_PCH_EXTCLK_DP    I58 @S9S_MB_2U_LIB.S9S_MB_2U(SCH_1):PAGE198

R554 Q_RES_0402LF-0,5%,1/16W,CHIP,CA
     1 CLK_100M_CK440_PCH_EXTCLK_R_DN @S9S_MB_2U_LIB.S9S_MB_2U(SCH_1):CLK_100M_CK440_PCH_EXTCLK_R_DN    I57 @S9S_MB_2U_LIB.S9S_MB_2U(SCH_1):PAGE198
     2 CLK_100M_CK440_PCH_EXTCLK_DN @S9S_MB_2U_LIB.S9S_MB_2U(SCH_1):CLK_100M_CK440_PCH_EXTCLK_DN    I57 @S9S_MB_2U_LIB.S9S_MB_2U(SCH_1):PAGE198

R555 Q_RES_0402LF-100,1%,1/16W,CHIPA
     1 SVID_DIO1_CPU0_R @S9S_MB_2U_LIB.S9S_MB_2U(SCH_1):SVID_DIO1_CPU0_R    I98 @S9S_MB_2U_LIB.S9S_MB_2U(SCH_1):PAGE14
     2 PVNN_TERM_CPU0 @S9S_MB_2U_LIB.S9S_MB_2U(SCH_1):PVNN_TERM_CPU0    I98 @S9S_MB_2U_LIB.S9S_MB_2U(SCH_1):PAGE14

R556 Q_RES_0402LF-49.9,1%,1/16W,CHIA
     1 SVID_ALERT1_CPU0_R_N @S9S_MB_2U_LIB.S9S_MB_2U(SCH_1):SVID_ALERT1_CPU0_R_N   I100 @S9S_MB_2U_LIB.S9S_MB_2U(SCH_1):PAGE14
     2 PVNN_TERM_CPU0 @S9S_MB_2U_LIB.S9S_MB_2U(SCH_1):PVNN_TERM_CPU0   I100 @S9S_MB_2U_LIB.S9S_MB_2U(SCH_1):PAGE14

R557 Q_RES_0402LF-100,1%,1/16W,CHIPA
     1 SVID_DIO0_CPU1_R @S9S_MB_2U_LIB.S9S_MB_2U(SCH_1):SVID_DIO0_CPU1_R    I74 @S9S_MB_2U_LIB.S9S_MB_2U(SCH_1):PAGE45
     2 PVNN_TERM_CPU1 @S9S_MB_2U_LIB.S9S_MB_2U(SCH_1):PVNN_TERM_CPU1    I74 @S9S_MB_2U_LIB.S9S_MB_2U(SCH_1):PAGE45

R558 Q_RES_0402LF-49.9,1%,1/16W,CHIA
     1 SVID_ALERT0_CPU1_R_N @S9S_MB_2U_LIB.S9S_MB_2U(SCH_1):SVID_ALERT0_CPU1_R_N    I73 @S9S_MB_2U_LIB.S9S_MB_2U(SCH_1):PAGE45
     2 PVNN_TERM_CPU1 @S9S_MB_2U_LIB.S9S_MB_2U(SCH_1):PVNN_TERM_CPU1    I73 @S9S_MB_2U_LIB.S9S_MB_2U(SCH_1):PAGE45

R559 Q_RES_0402LF-100,1%,1/16W,CHIPA
     1 SVID_DIO1_CPU1_R @S9S_MB_2U_LIB.S9S_MB_2U(SCH_1):SVID_DIO1_CPU1_R    I69 @S9S_MB_2U_LIB.S9S_MB_2U(SCH_1):PAGE45
     2 PVNN_TERM_CPU1 @S9S_MB_2U_LIB.S9S_MB_2U(SCH_1):PVNN_TERM_CPU1    I69 @S9S_MB_2U_LIB.S9S_MB_2U(SCH_1):PAGE45

R560 Q_RES_0402LF-49.9,1%,1/16W,CHIA
     1 SVID_ALERT1_CPU1_R_N @S9S_MB_2U_LIB.S9S_MB_2U(SCH_1):SVID_ALERT1_CPU1_R_N    I70 @S9S_MB_2U_LIB.S9S_MB_2U(SCH_1):PAGE45
     2 PVNN_TERM_CPU1 @S9S_MB_2U_LIB.S9S_MB_2U(SCH_1):PVNN_TERM_CPU1    I70 @S9S_MB_2U_LIB.S9S_MB_2U(SCH_1):PAGE45

R563 Q_RES_0402LF-22,1%,1/16W,CHIP,A
     1 CLK_100M_OCP_SFF_0_R_DP @S9S_MB_2U_LIB.S9S_MB_2U(SCH_1):CLK_100M_OCP_SFF_0_R_DP    I48 @S9S_MB_2U_LIB.S9S_MB_2U(SCH_1):PAGE198
     2 CLK_100M_OCP_SFF_0_DP @S9S_MB_2U_LIB.S9S_MB_2U(SCH_1):CLK_100M_OCP_SFF_0_DP    I48 @S9S_MB_2U_LIB.S9S_MB_2U(SCH_1):PAGE198

R564 Q_RES_0402LF-22,1%,1/16W,CHIP,A
     1 CLK_100M_OCP_SFF_0_R_DN @S9S_MB_2U_LIB.S9S_MB_2U(SCH_1):CLK_100M_OCP_SFF_0_R_DN    I47 @S9S_MB_2U_LIB.S9S_MB_2U(SCH_1):PAGE198
     2 CLK_100M_OCP_SFF_0_DN @S9S_MB_2U_LIB.S9S_MB_2U(SCH_1):CLK_100M_OCP_SFF_0_DN    I47 @S9S_MB_2U_LIB.S9S_MB_2U(SCH_1):PAGE198

R565 Q_RES_0402LF-22,1%,1/16W,CHIP,A
     1 CLK_100M_OCP_SFF_1_R_DP @S9S_MB_2U_LIB.S9S_MB_2U(SCH_1):CLK_100M_OCP_SFF_1_R_DP    I46 @S9S_MB_2U_LIB.S9S_MB_2U(SCH_1):PAGE198
     2 CLK_100M_OCP_SFF_1_DP @S9S_MB_2U_LIB.S9S_MB_2U(SCH_1):CLK_100M_OCP_SFF_1_DP    I46 @S9S_MB_2U_LIB.S9S_MB_2U(SCH_1):PAGE198

R566 Q_RES_0402LF-22,1%,1/16W,CHIP,A
     1 CLK_100M_OCP_SFF_1_R_DN @S9S_MB_2U_LIB.S9S_MB_2U(SCH_1):CLK_100M_OCP_SFF_1_R_DN    I45 @S9S_MB_2U_LIB.S9S_MB_2U(SCH_1):PAGE198
     2 CLK_100M_OCP_SFF_1_DN @S9S_MB_2U_LIB.S9S_MB_2U(SCH_1):CLK_100M_OCP_SFF_1_DN    I45 @S9S_MB_2U_LIB.S9S_MB_2U(SCH_1):PAGE198

R567 Q_RES_0402LF-4.7K,1%,1/16W,EMPA
     1   P3V3 @S9S_MB_2U_LIB.S9S_MB_2U(SCH_1):P3V3   I179 @S9S_MB_2U_LIB.S9S_MB_2U(SCH_1):PAGE195
     2 PD_DB2000_SMB_SA1 @S9S_MB_2U_LIB.S9S_MB_2U(SCH_1):PD_DB2000_SMB_SA1   I179 @S9S_MB_2U_LIB.S9S_MB_2U(SCH_1):PAGE195

R568 Q_RES_0402LF-4.7K,1%,1/16W,CHIA
     1 PD_DB2000_SMB_SA1 @S9S_MB_2U_LIB.S9S_MB_2U(SCH_1):PD_DB2000_SMB_SA1   I178 @S9S_MB_2U_LIB.S9S_MB_2U(SCH_1):PAGE195
     2    GND @S9S_MB_2U_LIB.S9S_MB_2U(SCH_1):GND   I178 @S9S_MB_2U_LIB.S9S_MB_2U(SCH_1):PAGE195

R569 Q_RES_0402LF-4.7K,1%,1/16W,EMPA
     1   P3V3 @S9S_MB_2U_LIB.S9S_MB_2U(SCH_1):P3V3   I185 @S9S_MB_2U_LIB.S9S_MB_2U(SCH_1):PAGE195
     2 PD_DB2000_SMB_SA0 @S9S_MB_2U_LIB.S9S_MB_2U(SCH_1):PD_DB2000_SMB_SA0   I185 @S9S_MB_2U_LIB.S9S_MB_2U(SCH_1):PAGE195

R570 Q_RES_0402LF-4.7K,1%,1/16W,CHIA
     1 PD_DB2000_SMB_SA0 @S9S_MB_2U_LIB.S9S_MB_2U(SCH_1):PD_DB2000_SMB_SA0   I187 @S9S_MB_2U_LIB.S9S_MB_2U(SCH_1):PAGE195
     2    GND @S9S_MB_2U_LIB.S9S_MB_2U(SCH_1):GND   I187 @S9S_MB_2U_LIB.S9S_MB_2U(SCH_1):PAGE195

R571 Q_RES_0603LF-2.2,1%,1/10W,CHIPA
     1 P3V3_DB2000_FB_VDD @S9S_MB_2U_LIB.S9S_MB_2U(SCH_1):P3V3_DB2000_FB_VDD   I163 @S9S_MB_2U_LIB.S9S_MB_2U(SCH_1):PAGE195
     2 P3V3_DB2000_VDDR @S9S_MB_2U_LIB.S9S_MB_2U(SCH_1):P3V3_DB2000_VDDR   I163 @S9S_MB_2U_LIB.S9S_MB_2U(SCH_1):PAGE195

R572 Q_RES_0603LF-2.2,1%,1/10W,CHIPA
     1 P3V3_DB2000_FB_VDD @S9S_MB_2U_LIB.S9S_MB_2U(SCH_1):P3V3_DB2000_FB_VDD   I162 @S9S_MB_2U_LIB.S9S_MB_2U(SCH_1):PAGE195
     2 P3V3_DB2000_VDDA @S9S_MB_2U_LIB.S9S_MB_2U(SCH_1):P3V3_DB2000_VDDA   I162 @S9S_MB_2U_LIB.S9S_MB_2U(SCH_1):PAGE195

R573 Q_RES_0402LF-4.7K,1%,1/16W,EMPA
     1   P3V3 @S9S_MB_2U_LIB.S9S_MB_2U(SCH_1):P3V3   I194 @S9S_MB_2U_LIB.S9S_MB_2U(SCH_1):PAGE195
     2 FM_DB2000_VSBEN @S9S_MB_2U_LIB.S9S_MB_2U(SCH_1):FM_DB2000_VSBEN   I194 @S9S_MB_2U_LIB.S9S_MB_2U(SCH_1):PAGE195

R574 Q_RES_0402LF-4.7K,1%,1/16W,CHIA
     1 FM_DB2000_VSBEN @S9S_MB_2U_LIB.S9S_MB_2U(SCH_1):FM_DB2000_VSBEN   I197 @S9S_MB_2U_LIB.S9S_MB_2U(SCH_1):PAGE195
     2    GND @S9S_MB_2U_LIB.S9S_MB_2U(SCH_1):GND   I197 @S9S_MB_2U_LIB.S9S_MB_2U(SCH_1):PAGE195

R575 Q_RES_0402LF-49.9,1%,1/16W,CHIA
     1 FM_PLD_CLKS_DEV_EN @S9S_MB_2U_LIB.S9S_MB_2U(SCH_1):FM_PLD_CLKS_DEV_EN   I199 @S9S_MB_2U_LIB.S9S_MB_2U(SCH_1):PAGE195
     2 FM_DB2000_DEV_EN @S9S_MB_2U_LIB.S9S_MB_2U(SCH_1):FM_DB2000_DEV_EN   I199 @S9S_MB_2U_LIB.S9S_MB_2U(SCH_1):PAGE195

R576 Q_RES_0402LF-49.9,1%,1/16W,CHIA
     1 FM_DB2000_OE_N @S9S_MB_2U_LIB.S9S_MB_2U(SCH_1):FM_DB2000_OE_N   I156 @S9S_MB_2U_LIB.S9S_MB_2U(SCH_1):PAGE195
     2 FM_DB2000_1_OE_N @S9S_MB_2U_LIB.S9S_MB_2U(SCH_1):FM_DB2000_1_OE_N   I156 @S9S_MB_2U_LIB.S9S_MB_2U(SCH_1):PAGE195

R577 Q_RES_0402LF-33.2,1%,1/16W,CHIA
     1 SMB_HOST_3V3AUX_SCL_R4 @S9S_MB_2U_LIB.S9S_MB_2U(SCH_1):SMB_HOST_3V3AUX_SCL_R4   I303 @S9S_MB_2U_LIB.S9S_MB_2U(SCH_1):PAGE228
     2 SMB_HOST_3V3AUX_SCL_R @S9S_MB_2U_LIB.S9S_MB_2U(SCH_1):SMB_HOST_3V3AUX_SCL_R   I303 @S9S_MB_2U_LIB.S9S_MB_2U(SCH_1):PAGE228

R578 Q_RES_0402LF-33.2,1%,1/16W,CHIA
     1 SMB_HOST_3V3AUX_SDA_R4 @S9S_MB_2U_LIB.S9S_MB_2U(SCH_1):SMB_HOST_3V3AUX_SDA_R4   I304 @S9S_MB_2U_LIB.S9S_MB_2U(SCH_1):PAGE228
     2 SMB_HOST_3V3AUX_SDA_R @S9S_MB_2U_LIB.S9S_MB_2U(SCH_1):SMB_HOST_3V3AUX_SDA_R   I304 @S9S_MB_2U_LIB.S9S_MB_2U(SCH_1):PAGE228

R579 Q_RES_0402LF-33.2,1%,1/16W,CHIA
     1 SMB_HOST_3V3AUX_SCL_R5 @S9S_MB_2U_LIB.S9S_MB_2U(SCH_1):SMB_HOST_3V3AUX_SCL_R5    I38 @S9S_MB_2U_LIB.S9S_MB_2U(SCH_1):PAGE228
     2 SMB_HOST_BMC_3V3AUX_SCL @S9S_MB_2U_LIB.S9S_MB_2U(SCH_1):SMB_HOST_BMC_3V3AUX_SCL    I38 @S9S_MB_2U_LIB.S9S_MB_2U(SCH_1):PAGE228

R580 Q_RES_0402LF-33.2,1%,1/16W,CHIA
     1 SMB_HOST_3V3AUX_SDA_R5 @S9S_MB_2U_LIB.S9S_MB_2U(SCH_1):SMB_HOST_3V3AUX_SDA_R5    I39 @S9S_MB_2U_LIB.S9S_MB_2U(SCH_1):PAGE228
     2 SMB_HOST_BMC_3V3AUX_SDA @S9S_MB_2U_LIB.S9S_MB_2U(SCH_1):SMB_HOST_BMC_3V3AUX_SDA    I39 @S9S_MB_2U_LIB.S9S_MB_2U(SCH_1):PAGE228

R581 Q_RES_0402LF-33.2,1%,1/16W,CHIA
     1 SMB_SML0_3V3AUX_SCL @S9S_MB_2U_LIB.S9S_MB_2U(SCH_1):SMB_SML0_3V3AUX_SCL    I44 @S9S_MB_2U_LIB.S9S_MB_2U(SCH_1):PAGE228
     2 SMB_SML0_3V3AUX_PCH_SCL @S9S_MB_2U_LIB.S9S_MB_2U(SCH_1):SMB_SML0_3V3AUX_PCH_SCL    I44 @S9S_MB_2U_LIB.S9S_MB_2U(SCH_1):PAGE228

R582 Q_RES_0402LF-33.2,1%,1/16W,CHIA
     1 SMB_SML0_3V3AUX_SDA @S9S_MB_2U_LIB.S9S_MB_2U(SCH_1):SMB_SML0_3V3AUX_SDA    I45 @S9S_MB_2U_LIB.S9S_MB_2U(SCH_1):PAGE228
     2 SMB_SML0_3V3AUX_PCH_SDA @S9S_MB_2U_LIB.S9S_MB_2U(SCH_1):SMB_SML0_3V3AUX_PCH_SDA    I45 @S9S_MB_2U_LIB.S9S_MB_2U(SCH_1):PAGE228

R587 Q_RES_0402LF-1K,1%,1/16W,CHIP,A
     1 PCA9548_PCIE3_ADDR0 @S9S_MB_2U_LIB.S9S_MB_2U(SCH_1):PCA9548_PCIE3_ADDR0     I8 @S9S_MB_2U_LIB.S9S_MB_2U(SCH_1):PAGE219
     2    GND @S9S_MB_2U_LIB.S9S_MB_2U(SCH_1):GND     I8 @S9S_MB_2U_LIB.S9S_MB_2U(SCH_1):PAGE219

R588 Q_RES_0402LF-33.2,1%,1/16W,CHIA
     1 SMB_PCIE0_3V3AUX_SCL @S9S_MB_2U_LIB.S9S_MB_2U(SCH_1):SMB_PCIE0_3V3AUX_SCL    I65 @S9S_MB_2U_LIB.S9S_MB_2U(SCH_1):PAGE219
     2 SMB_PCIE0_3V3AUX_SCL_R @S9S_MB_2U_LIB.S9S_MB_2U(SCH_1):SMB_PCIE0_3V3AUX_SCL_R    I65 @S9S_MB_2U_LIB.S9S_MB_2U(SCH_1):PAGE219

R589 Q_RES_0402LF-33.2,1%,1/16W,CHIA
     1 SMB_PCIE0_3V3AUX_SDA @S9S_MB_2U_LIB.S9S_MB_2U(SCH_1):SMB_PCIE0_3V3AUX_SDA    I66 @S9S_MB_2U_LIB.S9S_MB_2U(SCH_1):PAGE219
     2 SMB_PCIE0_3V3AUX_SDA_R @S9S_MB_2U_LIB.S9S_MB_2U(SCH_1):SMB_PCIE0_3V3AUX_SDA_R    I66 @S9S_MB_2U_LIB.S9S_MB_2U(SCH_1):PAGE219

R592 Q_RES_0402LF-2.2K,5%,1/16W,EMPA
     1 SMB_FAN_3V3AUX_SCL @S9S_MB_2U_LIB.S9S_MB_2U(SCH_1):SMB_FAN_3V3AUX_SCL   I173 @S9S_MB_2U_LIB.S9S_MB_2U(SCH_1):PAGE228
     2 P3V3_AUX @S9S_MB_2U_LIB.S9S_MB_2U(SCH_1):P3V3_AUX   I173 @S9S_MB_2U_LIB.S9S_MB_2U(SCH_1):PAGE228

R593 Q_RES_0402LF-0,5%,1/16W,CHIP,CA
     1 I3C_SPD_DDRABCD_CPU0_BMC_R_SCL @S9S_MB_2U_LIB.S9S_MB_2U(SCH_1):I3C_SPD_DDRABCD_CPU0_BMC_R_SCL   I311 @S9S_MB_2U_LIB.S9S_MB_2U(SCH_1):PAGE228
     2 I3C_SPD_DDRABCD_CPU0_BMC_SCL @S9S_MB_2U_LIB.S9S_MB_2U(SCH_1):I3C_SPD_DDRABCD_CPU0_BMC_SCL   I311 @S9S_MB_2U_LIB.S9S_MB_2U(SCH_1):PAGE228

R594 Q_RES_0402LF-0,5%,1/16W,CHIP,CA
     1 I3C_SPD_DDRABCD_CPU0_BMC_R_SDA @S9S_MB_2U_LIB.S9S_MB_2U(SCH_1):I3C_SPD_DDRABCD_CPU0_BMC_R_SDA   I312 @S9S_MB_2U_LIB.S9S_MB_2U(SCH_1):PAGE228
     2 I3C_SPD_DDRABCD_CPU0_BMC_SDA @S9S_MB_2U_LIB.S9S_MB_2U(SCH_1):I3C_SPD_DDRABCD_CPU0_BMC_SDA   I312 @S9S_MB_2U_LIB.S9S_MB_2U(SCH_1):PAGE228

R595 Q_RES_0402LF-0,5%,1/16W,CHIP,CA
     1 I3C_SPD_DDREFGH_CPU0_BMC_R_SCL @S9S_MB_2U_LIB.S9S_MB_2U(SCH_1):I3C_SPD_DDREFGH_CPU0_BMC_R_SCL   I314 @S9S_MB_2U_LIB.S9S_MB_2U(SCH_1):PAGE228
     2 I3C_SPD_DDREFGH_CPU0_BMC_SCL @S9S_MB_2U_LIB.S9S_MB_2U(SCH_1):I3C_SPD_DDREFGH_CPU0_BMC_SCL   I314 @S9S_MB_2U_LIB.S9S_MB_2U(SCH_1):PAGE228

R596 Q_RES_0402LF-0,5%,1/16W,CHIP,CA
     1 I3C_SPD_DDREFGH_CPU0_BMC_R_SDA @S9S_MB_2U_LIB.S9S_MB_2U(SCH_1):I3C_SPD_DDREFGH_CPU0_BMC_R_SDA   I313 @S9S_MB_2U_LIB.S9S_MB_2U(SCH_1):PAGE228
     2 I3C_SPD_DDREFGH_CPU0_BMC_SDA @S9S_MB_2U_LIB.S9S_MB_2U(SCH_1):I3C_SPD_DDREFGH_CPU0_BMC_SDA   I313 @S9S_MB_2U_LIB.S9S_MB_2U(SCH_1):PAGE228

R597 Q_RES_0402LF-0,5%,1/16W,CHIP,CA
     1 I3C_SPD_DDRABCD_CPU1_BMC_R_SCL @S9S_MB_2U_LIB.S9S_MB_2U(SCH_1):I3C_SPD_DDRABCD_CPU1_BMC_R_SCL   I316 @S9S_MB_2U_LIB.S9S_MB_2U(SCH_1):PAGE228
     2 I3C_SPD_DDRABCD_CPU1_BMC_SCL @S9S_MB_2U_LIB.S9S_MB_2U(SCH_1):I3C_SPD_DDRABCD_CPU1_BMC_SCL   I316 @S9S_MB_2U_LIB.S9S_MB_2U(SCH_1):PAGE228

R598 Q_RES_0402LF-0,5%,1/16W,CHIP,CA
     1 I3C_SPD_DDRABCD_CPU1_BMC_R_SDA @S9S_MB_2U_LIB.S9S_MB_2U(SCH_1):I3C_SPD_DDRABCD_CPU1_BMC_R_SDA   I315 @S9S_MB_2U_LIB.S9S_MB_2U(SCH_1):PAGE228
     2 I3C_SPD_DDRABCD_CPU1_BMC_SDA @S9S_MB_2U_LIB.S9S_MB_2U(SCH_1):I3C_SPD_DDRABCD_CPU1_BMC_SDA   I315 @S9S_MB_2U_LIB.S9S_MB_2U(SCH_1):PAGE228

R599 Q_RES_0402LF-0,5%,1/16W,CHIP,CA
     1 I3C_SPD_DDREFGH_CPU1_BMC_R_SCL @S9S_MB_2U_LIB.S9S_MB_2U(SCH_1):I3C_SPD_DDREFGH_CPU1_BMC_R_SCL   I317 @S9S_MB_2U_LIB.S9S_MB_2U(SCH_1):PAGE228
     2 I3C_SPD_DDREFGH_CPU1_BMC_SCL @S9S_MB_2U_LIB.S9S_MB_2U(SCH_1):I3C_SPD_DDREFGH_CPU1_BMC_SCL   I317 @S9S_MB_2U_LIB.S9S_MB_2U(SCH_1):PAGE228

R600 Q_RES_0402LF-0,5%,1/16W,CHIP,CA
     1 I3C_SPD_DDREFGH_CPU1_BMC_R_SDA @S9S_MB_2U_LIB.S9S_MB_2U(SCH_1):I3C_SPD_DDREFGH_CPU1_BMC_R_SDA   I318 @S9S_MB_2U_LIB.S9S_MB_2U(SCH_1):PAGE228
     2 I3C_SPD_DDREFGH_CPU1_BMC_SDA @S9S_MB_2U_LIB.S9S_MB_2U(SCH_1):I3C_SPD_DDREFGH_CPU1_BMC_SDA   I318 @S9S_MB_2U_LIB.S9S_MB_2U(SCH_1):PAGE228

R601 Q_RES_0402LF-2.2K,5%,1/16W,EMPA
     1 SMB_FAN_3V3AUX_SDA @S9S_MB_2U_LIB.S9S_MB_2U(SCH_1):SMB_FAN_3V3AUX_SDA   I172 @S9S_MB_2U_LIB.S9S_MB_2U(SCH_1):PAGE228
     2 P3V3_AUX @S9S_MB_2U_LIB.S9S_MB_2U(SCH_1):P3V3_AUX   I172 @S9S_MB_2U_LIB.S9S_MB_2U(SCH_1):PAGE228

R607 Q_RES_0402LF-1K,1%,1/16W,EMPTYA
     1 P3V3_AUX @S9S_MB_2U_LIB.S9S_MB_2U(SCH_1):P3V3_AUX    I21 @S9S_MB_2U_LIB.S9S_MB_2U(SCH_1):PAGE187
     2 FM_ESPI_FLASH_MODE @S9S_MB_2U_LIB.S9S_MB_2U(SCH_1):FM_ESPI_FLASH_MODE    I21 @S9S_MB_2U_LIB.S9S_MB_2U(SCH_1):PAGE187

R608 Q_RES_0402LF-10K,1%,1/16W,CHIPA
     1 FM_ESPI_FLASH_MODE @S9S_MB_2U_LIB.S9S_MB_2U(SCH_1):FM_ESPI_FLASH_MODE    I36 @S9S_MB_2U_LIB.S9S_MB_2U(SCH_1):PAGE187
     2    GND @S9S_MB_2U_LIB.S9S_MB_2U(SCH_1):GND    I36 @S9S_MB_2U_LIB.S9S_MB_2U(SCH_1):PAGE187

R609 Q_RES_0402LF-1K,1%,1/16W,EMPTYA
     1 P3V3_AUX @S9S_MB_2U_LIB.S9S_MB_2U(SCH_1):P3V3_AUX    I39 @S9S_MB_2U_LIB.S9S_MB_2U(SCH_1):PAGE187
     2 FM_ESPI_CS_SWIZZLE @S9S_MB_2U_LIB.S9S_MB_2U(SCH_1):FM_ESPI_CS_SWIZZLE    I39 @S9S_MB_2U_LIB.S9S_MB_2U(SCH_1):PAGE187

R610 Q_RES_0402LF-10K,1%,1/16W,CHIPA
     1 FM_ESPI_CS_SWIZZLE @S9S_MB_2U_LIB.S9S_MB_2U(SCH_1):FM_ESPI_CS_SWIZZLE    I40 @S9S_MB_2U_LIB.S9S_MB_2U(SCH_1):PAGE187
     2    GND @S9S_MB_2U_LIB.S9S_MB_2U(SCH_1):GND    I40 @S9S_MB_2U_LIB.S9S_MB_2U(SCH_1):PAGE187

R611 Q_RES_0402LF-1K,1%,1/16W,CHIP,A
     1 P3V3_AUX @S9S_MB_2U_LIB.S9S_MB_2U(SCH_1):P3V3_AUX    I43 @S9S_MB_2U_LIB.S9S_MB_2U(SCH_1):PAGE187
     2 FM_PCH_EXTERNALCLKMODE @S9S_MB_2U_LIB.S9S_MB_2U(SCH_1):FM_PCH_EXTERNALCLKMODE    I43 @S9S_MB_2U_LIB.S9S_MB_2U(SCH_1):PAGE187

R612 Q_RES_0402LF-10K,1%,1/16W,EMPTA
     1 FM_PCH_EXTERNALCLKMODE @S9S_MB_2U_LIB.S9S_MB_2U(SCH_1):FM_PCH_EXTERNALCLKMODE    I44 @S9S_MB_2U_LIB.S9S_MB_2U(SCH_1):PAGE187
     2    GND @S9S_MB_2U_LIB.S9S_MB_2U(SCH_1):GND    I44 @S9S_MB_2U_LIB.S9S_MB_2U(SCH_1):PAGE187

R613 Q_RES_0402LF-10K,1%,1/16W,CHIPA
     1 P3V3_AUX @S9S_MB_2U_LIB.S9S_MB_2U(SCH_1):P3V3_AUX    I18 @S9S_MB_2U_LIB.S9S_MB_2U(SCH_1):PAGE187
     2 FM_JTAG_ODT_DISABLE @S9S_MB_2U_LIB.S9S_MB_2U(SCH_1):FM_JTAG_ODT_DISABLE    I18 @S9S_MB_2U_LIB.S9S_MB_2U(SCH_1):PAGE187

R614 Q_RES_0402LF-1K,1%,1/16W,EMPTYA
     1 FM_JTAG_ODT_DISABLE @S9S_MB_2U_LIB.S9S_MB_2U(SCH_1):FM_JTAG_ODT_DISABLE    I23 @S9S_MB_2U_LIB.S9S_MB_2U(SCH_1):PAGE187
     2    GND @S9S_MB_2U_LIB.S9S_MB_2U(SCH_1):GND    I23 @S9S_MB_2U_LIB.S9S_MB_2U(SCH_1):PAGE187

R615 Q_RES_0402LF-1K,1%,1/16W,CHIP,A
     1 P3V3_AUX @S9S_MB_2U_LIB.S9S_MB_2U(SCH_1):P3V3_AUX    I51 @S9S_MB_2U_LIB.S9S_MB_2U(SCH_1):PAGE187
     2 FM_PCH_VISA_DEFAULT @S9S_MB_2U_LIB.S9S_MB_2U(SCH_1):FM_PCH_VISA_DEFAULT    I51 @S9S_MB_2U_LIB.S9S_MB_2U(SCH_1):PAGE187

R617 Q_RES_0402LF-1K,1%,1/16W,EMPTYA
     1 P3V3_AUX @S9S_MB_2U_LIB.S9S_MB_2U(SCH_1):P3V3_AUX    I54 @S9S_MB_2U_LIB.S9S_MB_2U(SCH_1):PAGE187
     2 FM_PCH_IO_EXPANDER @S9S_MB_2U_LIB.S9S_MB_2U(SCH_1):FM_PCH_IO_EXPANDER    I54 @S9S_MB_2U_LIB.S9S_MB_2U(SCH_1):PAGE187

R618 Q_RES_0402LF-10K,1%,1/16W,CHIPA
     1 FM_PCH_IO_EXPANDER @S9S_MB_2U_LIB.S9S_MB_2U(SCH_1):FM_PCH_IO_EXPANDER    I53 @S9S_MB_2U_LIB.S9S_MB_2U(SCH_1):PAGE187
     2    GND @S9S_MB_2U_LIB.S9S_MB_2U(SCH_1):GND    I53 @S9S_MB_2U_LIB.S9S_MB_2U(SCH_1):PAGE187

R619 Q_RES_0402LF-10K,1%,1/16W,CHIPA
     1 P3V3_AUX @S9S_MB_2U_LIB.S9S_MB_2U(SCH_1):P3V3_AUX    I48 @S9S_MB_2U_LIB.S9S_MB_2U(SCH_1):PAGE187
     2 FM_LT_KEY_DOWNGRADE_N @S9S_MB_2U_LIB.S9S_MB_2U(SCH_1):FM_LT_KEY_DOWNGRADE_N    I48 @S9S_MB_2U_LIB.S9S_MB_2U(SCH_1):PAGE187

R621 Q_RES_0402LF-1K,1%,1/16W,EMPTYA
     1 P3V3_AUX @S9S_MB_2U_LIB.S9S_MB_2U(SCH_1):P3V3_AUX    I55 @S9S_MB_2U_LIB.S9S_MB_2U(SCH_1):PAGE187
     2 FM_PCH_SKIP_RTC_CLOCK @S9S_MB_2U_LIB.S9S_MB_2U(SCH_1):FM_PCH_SKIP_RTC_CLOCK    I55 @S9S_MB_2U_LIB.S9S_MB_2U(SCH_1):PAGE187

R622 Q_RES_0402LF-1K,1%,1/16W,CHIP,A
     1 FM_PCH_SKIP_RTC_CLOCK @S9S_MB_2U_LIB.S9S_MB_2U(SCH_1):FM_PCH_SKIP_RTC_CLOCK    I56 @S9S_MB_2U_LIB.S9S_MB_2U(SCH_1):PAGE187
     2    GND @S9S_MB_2U_LIB.S9S_MB_2U(SCH_1):GND    I56 @S9S_MB_2U_LIB.S9S_MB_2U(SCH_1):PAGE187

R623 Q_RES_0402LF-1K,1%,1/16W,EMPTYA
     1 P3V3_AUX @S9S_MB_2U_LIB.S9S_MB_2U(SCH_1):P3V3_AUX    I13 @S9S_MB_2U_LIB.S9S_MB_2U(SCH_1):PAGE187
     2 FM_PCH_XTALSEL @S9S_MB_2U_LIB.S9S_MB_2U(SCH_1):FM_PCH_XTALSEL    I13 @S9S_MB_2U_LIB.S9S_MB_2U(SCH_1):PAGE187

R624 Q_RES_0402LF-10K,1%,1/16W,CHIPA
     1 FM_PCH_XTALSEL @S9S_MB_2U_LIB.S9S_MB_2U(SCH_1):FM_PCH_XTALSEL    I14 @S9S_MB_2U_LIB.S9S_MB_2U(SCH_1):PAGE187
     2    GND @S9S_MB_2U_LIB.S9S_MB_2U(SCH_1):GND    I14 @S9S_MB_2U_LIB.S9S_MB_2U(SCH_1):PAGE187

R625 Q_RES_0402LF-1K,1%,1/16W,EMPTYA
     1 P3V3_AUX @S9S_MB_2U_LIB.S9S_MB_2U(SCH_1):P3V3_AUX    I24 @S9S_MB_2U_LIB.S9S_MB_2U(SCH_1):PAGE127
     2 PD_PIROM_CPU1_ADDR2 @S9S_MB_2U_LIB.S9S_MB_2U(SCH_1):PD_PIROM_CPU1_ADDR2    I24 @S9S_MB_2U_LIB.S9S_MB_2U(SCH_1):PAGE127

R626 Q_RES_0402LF-10K,1%,1/16W,CHIPA
     1 PD_PIROM_CPU1_ADDR2 @S9S_MB_2U_LIB.S9S_MB_2U(SCH_1):PD_PIROM_CPU1_ADDR2    I26 @S9S_MB_2U_LIB.S9S_MB_2U(SCH_1):PAGE127
     2    GND @S9S_MB_2U_LIB.S9S_MB_2U(SCH_1):GND    I26 @S9S_MB_2U_LIB.S9S_MB_2U(SCH_1):PAGE127

R627 Q_RES_0402LF-1K,1%,1/16W,EMPTYA
     1 P3V3_AUX @S9S_MB_2U_LIB.S9S_MB_2U(SCH_1):P3V3_AUX    I14 @S9S_MB_2U_LIB.S9S_MB_2U(SCH_1):PAGE127
     2 PD_PIROM_CPU1_ADDR1 @S9S_MB_2U_LIB.S9S_MB_2U(SCH_1):PD_PIROM_CPU1_ADDR1    I14 @S9S_MB_2U_LIB.S9S_MB_2U(SCH_1):PAGE127

R628 Q_RES_0402LF-10K,1%,1/16W,CHIPA
     1 PD_PIROM_CPU1_ADDR1 @S9S_MB_2U_LIB.S9S_MB_2U(SCH_1):PD_PIROM_CPU1_ADDR1    I17 @S9S_MB_2U_LIB.S9S_MB_2U(SCH_1):PAGE127
     2    GND @S9S_MB_2U_LIB.S9S_MB_2U(SCH_1):GND    I17 @S9S_MB_2U_LIB.S9S_MB_2U(SCH_1):PAGE127

R629 Q_RES_0402LF-1K,1%,1/16W,CHIP,A
     1 P3V3_AUX @S9S_MB_2U_LIB.S9S_MB_2U(SCH_1):P3V3_AUX    I13 @S9S_MB_2U_LIB.S9S_MB_2U(SCH_1):PAGE127
     2 PU_PIROM_CPU1_ADDR0 @S9S_MB_2U_LIB.S9S_MB_2U(SCH_1):PU_PIROM_CPU1_ADDR0    I13 @S9S_MB_2U_LIB.S9S_MB_2U(SCH_1):PAGE127

R630 Q_RES_0402LF-10K,1%,1/16W,EMPTA
     1 PU_PIROM_CPU1_ADDR0 @S9S_MB_2U_LIB.S9S_MB_2U(SCH_1):PU_PIROM_CPU1_ADDR0    I15 @S9S_MB_2U_LIB.S9S_MB_2U(SCH_1):PAGE127
     2    GND @S9S_MB_2U_LIB.S9S_MB_2U(SCH_1):GND    I15 @S9S_MB_2U_LIB.S9S_MB_2U(SCH_1):PAGE127

R635 Q_RES_0402LF-10K,1%,1/16W,CHIPA
     1 PU_OC3_USB_N @S9S_MB_2U_LIB.S9S_MB_2U(SCH_1):PU_OC3_USB_N   I234 @S9S_MB_2U_LIB.S9S_MB_2U(SCH_1):PAGE175
     2 P3V3_AUX @S9S_MB_2U_LIB.S9S_MB_2U(SCH_1):P3V3_AUX   I234 @S9S_MB_2U_LIB.S9S_MB_2U(SCH_1):PAGE175

R650 Q_RES_0402LF-1K,1%,1/16W,CHIP,A
     1 P3V3_AUX @S9S_MB_2U_LIB.S9S_MB_2U(SCH_1):P3V3_AUX    I32 @S9S_MB_2U_LIB.S9S_MB_2U(SCH_1):PAGE127
     2 PU_PIROM_CPU0_SM_WP @S9S_MB_2U_LIB.S9S_MB_2U(SCH_1):PU_PIROM_CPU0_SM_WP    I32 @S9S_MB_2U_LIB.S9S_MB_2U(SCH_1):PAGE127

R651 Q_RES_0402LF-2.2K,5%,1/16W,CHIA
     1 P3V3_AUX @S9S_MB_2U_LIB.S9S_MB_2U(SCH_1):P3V3_AUX    I22 @S9S_MB_2U_LIB.S9S_MB_2U(SCH_1):PAGE219
     2 SMB_FRU_3V3AUX_SCL @S9S_MB_2U_LIB.S9S_MB_2U(SCH_1):SMB_FRU_3V3AUX_SCL    I22 @S9S_MB_2U_LIB.S9S_MB_2U(SCH_1):PAGE219

R652 Q_RES_0402LF-2.2K,5%,1/16W,CHIA
     1 P3V3_AUX @S9S_MB_2U_LIB.S9S_MB_2U(SCH_1):P3V3_AUX    I23 @S9S_MB_2U_LIB.S9S_MB_2U(SCH_1):PAGE219
     2 SMB_FRU_3V3AUX_SDA @S9S_MB_2U_LIB.S9S_MB_2U(SCH_1):SMB_FRU_3V3AUX_SDA    I23 @S9S_MB_2U_LIB.S9S_MB_2U(SCH_1):PAGE219

R661 Q_RES_0402LF-1K,1%,1/16W,CHIP,A
     1 PD_I3C_SPD_DDR_CPU1_OE_N @S9S_MB_2U_LIB.S9S_MB_2U(SCH_1):PD_I3C_SPD_DDR_CPU1_OE_N     I4 @S9S_MB_2U_LIB.S9S_MB_2U(SCH_1):PAGE218
     2    GND @S9S_MB_2U_LIB.S9S_MB_2U(SCH_1):GND     I4 @S9S_MB_2U_LIB.S9S_MB_2U(SCH_1):PAGE218

R662 Q_RES_0402LF-499,1%,1/16W,CHIPA
     1 PVNN_TERM_CPU1 @S9S_MB_2U_LIB.S9S_MB_2U(SCH_1):PVNN_TERM_CPU1    I17 @S9S_MB_2U_LIB.S9S_MB_2U(SCH_1):PAGE218
     2 I3C_SPD_DDRABCD_CPU1_SCL @S9S_MB_2U_LIB.S9S_MB_2U(SCH_1):I3C_SPD_DDRABCD_CPU1_SCL    I17 @S9S_MB_2U_LIB.S9S_MB_2U(SCH_1):PAGE218

R663 Q_RES_0402LF-499,1%,1/16W,CHIPA
     1 PVNN_TERM_CPU1 @S9S_MB_2U_LIB.S9S_MB_2U(SCH_1):PVNN_TERM_CPU1    I18 @S9S_MB_2U_LIB.S9S_MB_2U(SCH_1):PAGE218
     2 I3C_SPD_DDRABCD_CPU1_SDA @S9S_MB_2U_LIB.S9S_MB_2U(SCH_1):I3C_SPD_DDRABCD_CPU1_SDA    I18 @S9S_MB_2U_LIB.S9S_MB_2U(SCH_1):PAGE218

R664 Q_RES_0402LF-499,1%,1/16W,CHIPA
     1 PVNN_TERM_CPU1 @S9S_MB_2U_LIB.S9S_MB_2U(SCH_1):PVNN_TERM_CPU1    I28 @S9S_MB_2U_LIB.S9S_MB_2U(SCH_1):PAGE218
     2 I3C_SPD_DDREFGH_CPU1_SCL @S9S_MB_2U_LIB.S9S_MB_2U(SCH_1):I3C_SPD_DDREFGH_CPU1_SCL    I28 @S9S_MB_2U_LIB.S9S_MB_2U(SCH_1):PAGE218

R665 Q_RES_0402LF-0,5%,1/16W,EMPTY,A
     1 I3C_SPD_DDRABCD_CPU1_R_SCL @S9S_MB_2U_LIB.S9S_MB_2U(SCH_1):I3C_SPD_DDRABCD_CPU1_R_SCL    I23 @S9S_MB_2U_LIB.S9S_MB_2U(SCH_1):PAGE218
     2 I3C_SPD_DDRABCD_CPU1_LVC1_R_SCL @S9S_MB_2U_LIB.S9S_MB_2U(SCH_1):I3C_SPD_DDRABCD_CPU1_LVC1_R_SCL    I23 @S9S_MB_2U_LIB.S9S_MB_2U(SCH_1):PAGE218

R666 Q_RES_0402LF-0,5%,1/16W,EMPTY,A
     1 I3C_SPD_DDRABCD_CPU1_R_SDA @S9S_MB_2U_LIB.S9S_MB_2U(SCH_1):I3C_SPD_DDRABCD_CPU1_R_SDA    I22 @S9S_MB_2U_LIB.S9S_MB_2U(SCH_1):PAGE218
     2 I3C_SPD_DDRABCD_CPU1_LVC1_R_SDA @S9S_MB_2U_LIB.S9S_MB_2U(SCH_1):I3C_SPD_DDRABCD_CPU1_LVC1_R_SDA    I22 @S9S_MB_2U_LIB.S9S_MB_2U(SCH_1):PAGE218

R667 Q_RES_0402LF-0,5%,1/16W,EMPTY,A
     1 I3C_SPD_DDREFGH_CPU1_R_SCL @S9S_MB_2U_LIB.S9S_MB_2U(SCH_1):I3C_SPD_DDREFGH_CPU1_R_SCL    I21 @S9S_MB_2U_LIB.S9S_MB_2U(SCH_1):PAGE218
     2 I3C_SPD_DDREFGH_CPU1_LVC1_R_SCL @S9S_MB_2U_LIB.S9S_MB_2U(SCH_1):I3C_SPD_DDREFGH_CPU1_LVC1_R_SCL    I21 @S9S_MB_2U_LIB.S9S_MB_2U(SCH_1):PAGE218

R668 Q_RES_0402LF-0,5%,1/16W,EMPTY,A
     1 I3C_SPD_DDREFGH_CPU1_R_SDA @S9S_MB_2U_LIB.S9S_MB_2U(SCH_1):I3C_SPD_DDREFGH_CPU1_R_SDA    I20 @S9S_MB_2U_LIB.S9S_MB_2U(SCH_1):PAGE218
     2 I3C_SPD_DDREFGH_CPU1_LVC1_R_SDA @S9S_MB_2U_LIB.S9S_MB_2U(SCH_1):I3C_SPD_DDREFGH_CPU1_LVC1_R_SDA    I20 @S9S_MB_2U_LIB.S9S_MB_2U(SCH_1):PAGE218

R669 Q_RES_0402LF-499,1%,1/16W,CHIPA
     1 PVNN_TERM_CPU1 @S9S_MB_2U_LIB.S9S_MB_2U(SCH_1):PVNN_TERM_CPU1    I29 @S9S_MB_2U_LIB.S9S_MB_2U(SCH_1):PAGE218
     2 I3C_SPD_DDREFGH_CPU1_SDA @S9S_MB_2U_LIB.S9S_MB_2U(SCH_1):I3C_SPD_DDREFGH_CPU1_SDA    I29 @S9S_MB_2U_LIB.S9S_MB_2U(SCH_1):PAGE218

R670 Q_RES_0402LF-0,5%,1/16W,CHIP,CA
     1 I3C_SPD_DDRABCD_CPU1_SCL @S9S_MB_2U_LIB.S9S_MB_2U(SCH_1):I3C_SPD_DDRABCD_CPU1_SCL    I32 @S9S_MB_2U_LIB.S9S_MB_2U(SCH_1):PAGE218
     2 I3C_SPD_DDRABCD_CPU1_R_SCL @S9S_MB_2U_LIB.S9S_MB_2U(SCH_1):I3C_SPD_DDRABCD_CPU1_R_SCL    I32 @S9S_MB_2U_LIB.S9S_MB_2U(SCH_1):PAGE218

R671 Q_RES_0402LF-33.2,1%,1/16W,CHIA
     1 I3C_SPD_DDRABCD_CPU1_SDA @S9S_MB_2U_LIB.S9S_MB_2U(SCH_1):I3C_SPD_DDRABCD_CPU1_SDA    I33 @S9S_MB_2U_LIB.S9S_MB_2U(SCH_1):PAGE218
     2 I3C_SPD_DDRABCD_CPU1_R_SDA @S9S_MB_2U_LIB.S9S_MB_2U(SCH_1):I3C_SPD_DDRABCD_CPU1_R_SDA    I33 @S9S_MB_2U_LIB.S9S_MB_2U(SCH_1):PAGE218

R672 Q_RES_0402LF-0,5%,1/16W,CHIP,CA
     1 I3C_SPD_DDREFGH_CPU1_SCL @S9S_MB_2U_LIB.S9S_MB_2U(SCH_1):I3C_SPD_DDREFGH_CPU1_SCL    I30 @S9S_MB_2U_LIB.S9S_MB_2U(SCH_1):PAGE218
     2 I3C_SPD_DDREFGH_CPU1_R_SCL @S9S_MB_2U_LIB.S9S_MB_2U(SCH_1):I3C_SPD_DDREFGH_CPU1_R_SCL    I30 @S9S_MB_2U_LIB.S9S_MB_2U(SCH_1):PAGE218

R673 Q_RES_0402LF-33.2,1%,1/16W,CHIA
     1 I3C_SPD_DDREFGH_CPU1_SDA @S9S_MB_2U_LIB.S9S_MB_2U(SCH_1):I3C_SPD_DDREFGH_CPU1_SDA    I31 @S9S_MB_2U_LIB.S9S_MB_2U(SCH_1):PAGE218
     2 I3C_SPD_DDREFGH_CPU1_R_SDA @S9S_MB_2U_LIB.S9S_MB_2U(SCH_1):I3C_SPD_DDREFGH_CPU1_R_SDA    I31 @S9S_MB_2U_LIB.S9S_MB_2U(SCH_1):PAGE218

R674 Q_RES_0402LF-0,5%,1/16W,CHIP,CA
     1 I3C_SPD_DDRABCD_CPU1_LVC1_R_SCL @S9S_MB_2U_LIB.S9S_MB_2U(SCH_1):I3C_SPD_DDRABCD_CPU1_LVC1_R_SCL    I37 @S9S_MB_2U_LIB.S9S_MB_2U(SCH_1):PAGE218
     2 I3C_SPD_DDRABCD_CPU1_LVC1_SCL @S9S_MB_2U_LIB.S9S_MB_2U(SCH_1):I3C_SPD_DDRABCD_CPU1_LVC1_SCL    I37 @S9S_MB_2U_LIB.S9S_MB_2U(SCH_1):PAGE218

R675 Q_RES_0402LF-33.2,1%,1/16W,CHIA
     1 I3C_SPD_DDRABCD_CPU1_LVC1_R_SDA @S9S_MB_2U_LIB.S9S_MB_2U(SCH_1):I3C_SPD_DDRABCD_CPU1_LVC1_R_SDA    I36 @S9S_MB_2U_LIB.S9S_MB_2U(SCH_1):PAGE218
     2 I3C_SPD_DDRABCD_CPU1_LVC1_SDA @S9S_MB_2U_LIB.S9S_MB_2U(SCH_1):I3C_SPD_DDRABCD_CPU1_LVC1_SDA    I36 @S9S_MB_2U_LIB.S9S_MB_2U(SCH_1):PAGE218

R676 Q_RES_0402LF-0,5%,1/16W,CHIP,CA
     1 I3C_SPD_DDREFGH_CPU1_LVC1_R_SCL @S9S_MB_2U_LIB.S9S_MB_2U(SCH_1):I3C_SPD_DDREFGH_CPU1_LVC1_R_SCL    I35 @S9S_MB_2U_LIB.S9S_MB_2U(SCH_1):PAGE218
     2 I3C_SPD_DDREFGH_CPU1_LVC1_SCL @S9S_MB_2U_LIB.S9S_MB_2U(SCH_1):I3C_SPD_DDREFGH_CPU1_LVC1_SCL    I35 @S9S_MB_2U_LIB.S9S_MB_2U(SCH_1):PAGE218

R677 Q_RES_0402LF-33.2,1%,1/16W,CHIA
     1 I3C_SPD_DDREFGH_CPU1_LVC1_R_SDA @S9S_MB_2U_LIB.S9S_MB_2U(SCH_1):I3C_SPD_DDREFGH_CPU1_LVC1_R_SDA    I34 @S9S_MB_2U_LIB.S9S_MB_2U(SCH_1):PAGE218
     2 I3C_SPD_DDREFGH_CPU1_LVC1_SDA @S9S_MB_2U_LIB.S9S_MB_2U(SCH_1):I3C_SPD_DDREFGH_CPU1_LVC1_SDA    I34 @S9S_MB_2U_LIB.S9S_MB_2U(SCH_1):PAGE218

R678 Q_RES_0402LF-1K,1%,1/16W,CHIP,A
     1 PD_I3C_SPD_DDR_CPU0_OE_N @S9S_MB_2U_LIB.S9S_MB_2U(SCH_1):PD_I3C_SPD_DDR_CPU0_OE_N    I13 @S9S_MB_2U_LIB.S9S_MB_2U(SCH_1):PAGE217
     2    GND @S9S_MB_2U_LIB.S9S_MB_2U(SCH_1):GND    I13 @S9S_MB_2U_LIB.S9S_MB_2U(SCH_1):PAGE217

R679 Q_RES_0402LF-499,1%,1/16W,CHIPA
     1 PVNN_TERM_CPU0 @S9S_MB_2U_LIB.S9S_MB_2U(SCH_1):PVNN_TERM_CPU0    I29 @S9S_MB_2U_LIB.S9S_MB_2U(SCH_1):PAGE217
     2 I3C_SPD_DDRABCD_CPU0_SCL @S9S_MB_2U_LIB.S9S_MB_2U(SCH_1):I3C_SPD_DDRABCD_CPU0_SCL    I29 @S9S_MB_2U_LIB.S9S_MB_2U(SCH_1):PAGE217

R680 Q_RES_0402LF-499,1%,1/16W,CHIPA
     1 PVNN_TERM_CPU0 @S9S_MB_2U_LIB.S9S_MB_2U(SCH_1):PVNN_TERM_CPU0    I30 @S9S_MB_2U_LIB.S9S_MB_2U(SCH_1):PAGE217
     2 I3C_SPD_DDRABCD_CPU0_SDA @S9S_MB_2U_LIB.S9S_MB_2U(SCH_1):I3C_SPD_DDRABCD_CPU0_SDA    I30 @S9S_MB_2U_LIB.S9S_MB_2U(SCH_1):PAGE217

R681 Q_RES_0402LF-499,1%,1/16W,CHIPA
     1 PVNN_TERM_CPU0 @S9S_MB_2U_LIB.S9S_MB_2U(SCH_1):PVNN_TERM_CPU0    I32 @S9S_MB_2U_LIB.S9S_MB_2U(SCH_1):PAGE217
     2 I3C_SPD_DDREFGH_CPU0_SCL @S9S_MB_2U_LIB.S9S_MB_2U(SCH_1):I3C_SPD_DDREFGH_CPU0_SCL    I32 @S9S_MB_2U_LIB.S9S_MB_2U(SCH_1):PAGE217

R682 Q_RES_0402LF-0,5%,1/16W,EMPTY,A
     1 I3C_SPD_DDRABCD_CPU0_R_SCL @S9S_MB_2U_LIB.S9S_MB_2U(SCH_1):I3C_SPD_DDRABCD_CPU0_R_SCL    I20 @S9S_MB_2U_LIB.S9S_MB_2U(SCH_1):PAGE217
     2 I3C_SPD_DDRABCD_CPU0_LVC1_R_SCL @S9S_MB_2U_LIB.S9S_MB_2U(SCH_1):I3C_SPD_DDRABCD_CPU0_LVC1_R_SCL    I20 @S9S_MB_2U_LIB.S9S_MB_2U(SCH_1):PAGE217

R683 Q_RES_0402LF-0,5%,1/16W,EMPTY,A
     1 I3C_SPD_DDRABCD_CPU0_R_SDA @S9S_MB_2U_LIB.S9S_MB_2U(SCH_1):I3C_SPD_DDRABCD_CPU0_R_SDA    I18 @S9S_MB_2U_LIB.S9S_MB_2U(SCH_1):PAGE217
     2 I3C_SPD_DDRABCD_CPU0_LVC1_R_SDA @S9S_MB_2U_LIB.S9S_MB_2U(SCH_1):I3C_SPD_DDRABCD_CPU0_LVC1_R_SDA    I18 @S9S_MB_2U_LIB.S9S_MB_2U(SCH_1):PAGE217

R684 Q_RES_0402LF-0,5%,1/16W,EMPTY,A
     1 I3C_SPD_DDREFGH_CPU0_R_SCL @S9S_MB_2U_LIB.S9S_MB_2U(SCH_1):I3C_SPD_DDREFGH_CPU0_R_SCL    I17 @S9S_MB_2U_LIB.S9S_MB_2U(SCH_1):PAGE217
     2 I3C_SPD_DDREFGH_CPU0_LVC1_R_SCL @S9S_MB_2U_LIB.S9S_MB_2U(SCH_1):I3C_SPD_DDREFGH_CPU0_LVC1_R_SCL    I17 @S9S_MB_2U_LIB.S9S_MB_2U(SCH_1):PAGE217

R685 Q_RES_0402LF-0,5%,1/16W,EMPTY,A
     1 I3C_SPD_DDREFGH_CPU0_R_SDA @S9S_MB_2U_LIB.S9S_MB_2U(SCH_1):I3C_SPD_DDREFGH_CPU0_R_SDA    I16 @S9S_MB_2U_LIB.S9S_MB_2U(SCH_1):PAGE217
     2 I3C_SPD_DDREFGH_CPU0_LVC1_R_SDA @S9S_MB_2U_LIB.S9S_MB_2U(SCH_1):I3C_SPD_DDREFGH_CPU0_LVC1_R_SDA    I16 @S9S_MB_2U_LIB.S9S_MB_2U(SCH_1):PAGE217

R686 Q_RES_0402LF-499,1%,1/16W,CHIPA
     1 PVNN_TERM_CPU0 @S9S_MB_2U_LIB.S9S_MB_2U(SCH_1):PVNN_TERM_CPU0    I33 @S9S_MB_2U_LIB.S9S_MB_2U(SCH_1):PAGE217
     2 I3C_SPD_DDREFGH_CPU0_SDA @S9S_MB_2U_LIB.S9S_MB_2U(SCH_1):I3C_SPD_DDREFGH_CPU0_SDA    I33 @S9S_MB_2U_LIB.S9S_MB_2U(SCH_1):PAGE217

R687 Q_RES_0402LF-0,5%,1/16W,CHIP,CA
     1 I3C_SPD_DDRABCD_CPU0_SCL @S9S_MB_2U_LIB.S9S_MB_2U(SCH_1):I3C_SPD_DDRABCD_CPU0_SCL    I34 @S9S_MB_2U_LIB.S9S_MB_2U(SCH_1):PAGE217
     2 I3C_SPD_DDRABCD_CPU0_R_SCL @S9S_MB_2U_LIB.S9S_MB_2U(SCH_1):I3C_SPD_DDRABCD_CPU0_R_SCL    I34 @S9S_MB_2U_LIB.S9S_MB_2U(SCH_1):PAGE217

R688 Q_RES_0402LF-33.2,1%,1/16W,CHIA
     1 I3C_SPD_DDRABCD_CPU0_SDA @S9S_MB_2U_LIB.S9S_MB_2U(SCH_1):I3C_SPD_DDRABCD_CPU0_SDA    I35 @S9S_MB_2U_LIB.S9S_MB_2U(SCH_1):PAGE217
     2 I3C_SPD_DDRABCD_CPU0_R_SDA @S9S_MB_2U_LIB.S9S_MB_2U(SCH_1):I3C_SPD_DDRABCD_CPU0_R_SDA    I35 @S9S_MB_2U_LIB.S9S_MB_2U(SCH_1):PAGE217

R689 Q_RES_0402LF-0,5%,1/16W,CHIP,CA
     1 I3C_SPD_DDREFGH_CPU0_SCL @S9S_MB_2U_LIB.S9S_MB_2U(SCH_1):I3C_SPD_DDREFGH_CPU0_SCL    I25 @S9S_MB_2U_LIB.S9S_MB_2U(SCH_1):PAGE217
     2 I3C_SPD_DDREFGH_CPU0_R_SCL @S9S_MB_2U_LIB.S9S_MB_2U(SCH_1):I3C_SPD_DDREFGH_CPU0_R_SCL    I25 @S9S_MB_2U_LIB.S9S_MB_2U(SCH_1):PAGE217

R690 Q_RES_0402LF-33.2,1%,1/16W,CHIA
     1 I3C_SPD_DDREFGH_CPU0_SDA @S9S_MB_2U_LIB.S9S_MB_2U(SCH_1):I3C_SPD_DDREFGH_CPU0_SDA    I26 @S9S_MB_2U_LIB.S9S_MB_2U(SCH_1):PAGE217
     2 I3C_SPD_DDREFGH_CPU0_R_SDA @S9S_MB_2U_LIB.S9S_MB_2U(SCH_1):I3C_SPD_DDREFGH_CPU0_R_SDA    I26 @S9S_MB_2U_LIB.S9S_MB_2U(SCH_1):PAGE217

R691 Q_RES_0402LF-0,5%,1/16W,CHIP,CA
     1 I3C_SPD_DDRABCD_CPU0_LVC1_R_SCL @S9S_MB_2U_LIB.S9S_MB_2U(SCH_1):I3C_SPD_DDRABCD_CPU0_LVC1_R_SCL    I39 @S9S_MB_2U_LIB.S9S_MB_2U(SCH_1):PAGE217
     2 I3C_SPD_DDRABCD_CPU0_LVC1_SCL @S9S_MB_2U_LIB.S9S_MB_2U(SCH_1):I3C_SPD_DDRABCD_CPU0_LVC1_SCL    I39 @S9S_MB_2U_LIB.S9S_MB_2U(SCH_1):PAGE217

R692 Q_RES_0402LF-33.2,1%,1/16W,CHIA
     1 I3C_SPD_DDRABCD_CPU0_LVC1_R_SDA @S9S_MB_2U_LIB.S9S_MB_2U(SCH_1):I3C_SPD_DDRABCD_CPU0_LVC1_R_SDA    I40 @S9S_MB_2U_LIB.S9S_MB_2U(SCH_1):PAGE217
     2 I3C_SPD_DDRABCD_CPU0_LVC1_SDA @S9S_MB_2U_LIB.S9S_MB_2U(SCH_1):I3C_SPD_DDRABCD_CPU0_LVC1_SDA    I40 @S9S_MB_2U_LIB.S9S_MB_2U(SCH_1):PAGE217

R693 Q_RES_0402LF-0,5%,1/16W,CHIP,CA
     1 I3C_SPD_DDREFGH_CPU0_LVC1_R_SCL @S9S_MB_2U_LIB.S9S_MB_2U(SCH_1):I3C_SPD_DDREFGH_CPU0_LVC1_R_SCL    I38 @S9S_MB_2U_LIB.S9S_MB_2U(SCH_1):PAGE217
     2 I3C_SPD_DDREFGH_CPU0_LVC1_SCL @S9S_MB_2U_LIB.S9S_MB_2U(SCH_1):I3C_SPD_DDREFGH_CPU0_LVC1_SCL    I38 @S9S_MB_2U_LIB.S9S_MB_2U(SCH_1):PAGE217

R694 Q_RES_0402LF-33.2,1%,1/16W,CHIA
     1 I3C_SPD_DDREFGH_CPU0_LVC1_R_SDA @S9S_MB_2U_LIB.S9S_MB_2U(SCH_1):I3C_SPD_DDREFGH_CPU0_LVC1_R_SDA    I37 @S9S_MB_2U_LIB.S9S_MB_2U(SCH_1):PAGE217
     2 I3C_SPD_DDREFGH_CPU0_LVC1_SDA @S9S_MB_2U_LIB.S9S_MB_2U(SCH_1):I3C_SPD_DDREFGH_CPU0_LVC1_SDA    I37 @S9S_MB_2U_LIB.S9S_MB_2U(SCH_1):PAGE217

R696 Q_RES_0402LF-4.75K,1%,1/16W,CHA
     1 P3V3_AUX @S9S_MB_2U_LIB.S9S_MB_2U(SCH_1):P3V3_AUX    I63 @S9S_MB_2U_LIB.S9S_MB_2U(SCH_1):PAGE174
     2 RST_PCH_RSTBTN_R_N @S9S_MB_2U_LIB.S9S_MB_2U(SCH_1):RST_PCH_RSTBTN_R_N    I63 @S9S_MB_2U_LIB.S9S_MB_2U(SCH_1):PAGE174

R697 Q_RES_0402LF-33.2,1%,1/16W,CHIA
     1 FM_BMC_RSTBTN_OUT_N @S9S_MB_2U_LIB.S9S_MB_2U(SCH_1):FM_BMC_RSTBTN_OUT_N    I66 @S9S_MB_2U_LIB.S9S_MB_2U(SCH_1):PAGE174
     2 RST_PCH_RSTBTN_R_N @S9S_MB_2U_LIB.S9S_MB_2U(SCH_1):RST_PCH_RSTBTN_R_N    I66 @S9S_MB_2U_LIB.S9S_MB_2U(SCH_1):PAGE174

R698 Q_RES_0402LF-49.9,1%,1/16W,CHIA
     1 FM_ADR_TRIGGER_R_N @S9S_MB_2U_LIB.S9S_MB_2U(SCH_1):FM_ADR_TRIGGER_R_N    I32 @S9S_MB_2U_LIB.S9S_MB_2U(SCH_1):PAGE193
     2 FM_ADR_TRIGGER_N @S9S_MB_2U_LIB.S9S_MB_2U(SCH_1):FM_ADR_TRIGGER_N    I32 @S9S_MB_2U_LIB.S9S_MB_2U(SCH_1):PAGE193

R699 Q_RES_0402LF-33.2,1%,1/16W,CHIA
     1 FM_PCH_CRASHLOG_TRIG_R_N @S9S_MB_2U_LIB.S9S_MB_2U(SCH_1):FM_PCH_CRASHLOG_TRIG_R_N   I102 @S9S_MB_2U_LIB.S9S_MB_2U(SCH_1):PAGE175
     2 FM_PCH_CRASHLOG_TRIG_N @S9S_MB_2U_LIB.S9S_MB_2U(SCH_1):FM_PCH_CRASHLOG_TRIG_N   I102 @S9S_MB_2U_LIB.S9S_MB_2U(SCH_1):PAGE175

R700 Q_RES_0402LF-0,5%,1/16W,CHIP,CA
     1 FM_ADR_ACK_R @S9S_MB_2U_LIB.S9S_MB_2U(SCH_1):FM_ADR_ACK_R   I169 @S9S_MB_2U_LIB.S9S_MB_2U(SCH_1):PAGE312
     2 FM_ADR_ACK @S9S_MB_2U_LIB.S9S_MB_2U(SCH_1):FM_ADR_ACK   I169 @S9S_MB_2U_LIB.S9S_MB_2U(SCH_1):PAGE312

R701 Q_RES_0402LF-10K,1%,1/16W,EMPTA
     1 RST_PLD_CPU1_DRAM_CD_N @S9S_MB_2U_LIB.S9S_MB_2U(SCH_1):RST_PLD_CPU1_DRAM_CD_N    I63 @S9S_MB_2U_LIB.S9S_MB_2U(SCH_1):PAGE130
     2    GND @S9S_MB_2U_LIB.S9S_MB_2U(SCH_1):GND    I63 @S9S_MB_2U_LIB.S9S_MB_2U(SCH_1):PAGE130

R702 Q_RES_0402LF-10K,1%,1/16W,EMPTA
     1 RST_PLD_CPU1_DRAM_GH_N @S9S_MB_2U_LIB.S9S_MB_2U(SCH_1):RST_PLD_CPU1_DRAM_GH_N    I76 @S9S_MB_2U_LIB.S9S_MB_2U(SCH_1):PAGE130
     2    GND @S9S_MB_2U_LIB.S9S_MB_2U(SCH_1):GND    I76 @S9S_MB_2U_LIB.S9S_MB_2U(SCH_1):PAGE130

R703 Q_RES_0402LF-10K,1%,1/16W,EMPTA
     1 RST_PLD_CPU1_DRAM_AB_N @S9S_MB_2U_LIB.S9S_MB_2U(SCH_1):RST_PLD_CPU1_DRAM_AB_N    I79 @S9S_MB_2U_LIB.S9S_MB_2U(SCH_1):PAGE130
     2    GND @S9S_MB_2U_LIB.S9S_MB_2U(SCH_1):GND    I79 @S9S_MB_2U_LIB.S9S_MB_2U(SCH_1):PAGE130

R704 Q_RES_0402LF-10K,1%,1/16W,EMPTA
     1 RST_PLD_CPU1_DRAM_EF_N @S9S_MB_2U_LIB.S9S_MB_2U(SCH_1):RST_PLD_CPU1_DRAM_EF_N    I75 @S9S_MB_2U_LIB.S9S_MB_2U(SCH_1):PAGE130
     2    GND @S9S_MB_2U_LIB.S9S_MB_2U(SCH_1):GND    I75 @S9S_MB_2U_LIB.S9S_MB_2U(SCH_1):PAGE130

R705 Q_RES_0402LF-10K,1%,1/16W,EMPTA
     1 RST_PLD_CPU0_DRAM_GH_N @S9S_MB_2U_LIB.S9S_MB_2U(SCH_1):RST_PLD_CPU0_DRAM_GH_N   I112 @S9S_MB_2U_LIB.S9S_MB_2U(SCH_1):PAGE129
     2    GND @S9S_MB_2U_LIB.S9S_MB_2U(SCH_1):GND   I112 @S9S_MB_2U_LIB.S9S_MB_2U(SCH_1):PAGE129

R706 Q_RES_0402LF-10K,1%,1/16W,EMPTA
     1 RST_PLD_CPU0_DRAM_AB_N @S9S_MB_2U_LIB.S9S_MB_2U(SCH_1):RST_PLD_CPU0_DRAM_AB_N   I103 @S9S_MB_2U_LIB.S9S_MB_2U(SCH_1):PAGE129
     2    GND @S9S_MB_2U_LIB.S9S_MB_2U(SCH_1):GND   I103 @S9S_MB_2U_LIB.S9S_MB_2U(SCH_1):PAGE129

R707 Q_RES_0402LF-10K,1%,1/16W,EMPTA
     1 RST_PLD_CPU0_DRAM_CD_N @S9S_MB_2U_LIB.S9S_MB_2U(SCH_1):RST_PLD_CPU0_DRAM_CD_N   I106 @S9S_MB_2U_LIB.S9S_MB_2U(SCH_1):PAGE129
     2    GND @S9S_MB_2U_LIB.S9S_MB_2U(SCH_1):GND   I106 @S9S_MB_2U_LIB.S9S_MB_2U(SCH_1):PAGE129

R708 Q_RES_0402LF-10K,1%,1/16W,EMPTA
     1 RST_PLD_CPU0_DRAM_EF_N @S9S_MB_2U_LIB.S9S_MB_2U(SCH_1):RST_PLD_CPU0_DRAM_EF_N   I109 @S9S_MB_2U_LIB.S9S_MB_2U(SCH_1):PAGE129
     2    GND @S9S_MB_2U_LIB.S9S_MB_2U(SCH_1):GND   I109 @S9S_MB_2U_LIB.S9S_MB_2U(SCH_1):PAGE129

R710 Q_RES_0402LF-1K,1%,1/16W,CHIP,A
     1 PD_MB_FRU_WP @S9S_MB_2U_LIB.S9S_MB_2U(SCH_1):PD_MB_FRU_WP    I57 @S9S_MB_2U_LIB.S9S_MB_2U(SCH_1):PAGE231
     2    GND @S9S_MB_2U_LIB.S9S_MB_2U(SCH_1):GND    I57 @S9S_MB_2U_LIB.S9S_MB_2U(SCH_1):PAGE231

R713 Q_RES_0402LF-10K,1%,1/16W,EMPTA
     1 P3V3_AUX @S9S_MB_2U_LIB.S9S_MB_2U(SCH_1):P3V3_AUX    I47 @S9S_MB_2U_LIB.S9S_MB_2U(SCH_1):PAGE231
     2 MB_FRU_ADDR2 @S9S_MB_2U_LIB.S9S_MB_2U(SCH_1):MB_FRU_ADDR2    I47 @S9S_MB_2U_LIB.S9S_MB_2U(SCH_1):PAGE231

R714 Q_RES_0402LF-1K,1%,1/16W,CHIP,A
     1 MB_FRU_ADDR2 @S9S_MB_2U_LIB.S9S_MB_2U(SCH_1):MB_FRU_ADDR2    I52 @S9S_MB_2U_LIB.S9S_MB_2U(SCH_1):PAGE231
     2    GND @S9S_MB_2U_LIB.S9S_MB_2U(SCH_1):GND    I52 @S9S_MB_2U_LIB.S9S_MB_2U(SCH_1):PAGE231

R717 Q_RES_0402LF-10K,1%,1/16W,EMPTA
     1 P3V3_AUX @S9S_MB_2U_LIB.S9S_MB_2U(SCH_1):P3V3_AUX    I45 @S9S_MB_2U_LIB.S9S_MB_2U(SCH_1):PAGE231
     2 MB_FRU_ADDR1 @S9S_MB_2U_LIB.S9S_MB_2U(SCH_1):MB_FRU_ADDR1    I45 @S9S_MB_2U_LIB.S9S_MB_2U(SCH_1):PAGE231

R718 Q_RES_0402LF-1K,1%,1/16W,CHIP,A
     1 MB_FRU_ADDR1 @S9S_MB_2U_LIB.S9S_MB_2U(SCH_1):MB_FRU_ADDR1    I50 @S9S_MB_2U_LIB.S9S_MB_2U(SCH_1):PAGE231
     2    GND @S9S_MB_2U_LIB.S9S_MB_2U(SCH_1):GND    I50 @S9S_MB_2U_LIB.S9S_MB_2U(SCH_1):PAGE231

R721 Q_RES_0402LF-10K,1%,1/16W,CHIPA
     1 P3V3_AUX @S9S_MB_2U_LIB.S9S_MB_2U(SCH_1):P3V3_AUX    I62 @S9S_MB_2U_LIB.S9S_MB_2U(SCH_1):PAGE231
     2 MB_FRU_ADDR0 @S9S_MB_2U_LIB.S9S_MB_2U(SCH_1):MB_FRU_ADDR0    I62 @S9S_MB_2U_LIB.S9S_MB_2U(SCH_1):PAGE231

R722 Q_RES_0402LF-1K,1%,1/16W,EMPTYA
     1 MB_FRU_ADDR0 @S9S_MB_2U_LIB.S9S_MB_2U(SCH_1):MB_FRU_ADDR0    I61 @S9S_MB_2U_LIB.S9S_MB_2U(SCH_1):PAGE231
     2    GND @S9S_MB_2U_LIB.S9S_MB_2U(SCH_1):GND    I61 @S9S_MB_2U_LIB.S9S_MB_2U(SCH_1):PAGE231

R727 Q_RES_0402LF-10K,1%,1/16W,CHIPA
     1 PU_OC4_USB_N @S9S_MB_2U_LIB.S9S_MB_2U(SCH_1):PU_OC4_USB_N   I236 @S9S_MB_2U_LIB.S9S_MB_2U(SCH_1):PAGE175
     2 P3V3_AUX @S9S_MB_2U_LIB.S9S_MB_2U(SCH_1):P3V3_AUX   I236 @S9S_MB_2U_LIB.S9S_MB_2U(SCH_1):PAGE175

R734 Q_RES_0402LF-4.75K,1%,1/16W,CHA
     1 CLK_CK440_SMB_ADDR1 @S9S_MB_2U_LIB.S9S_MB_2U(SCH_1):CLK_CK440_SMB_ADDR1   I283 @S9S_MB_2U_LIB.S9S_MB_2U(SCH_1):PAGE197
     2    GND @S9S_MB_2U_LIB.S9S_MB_2U(SCH_1):GND   I283 @S9S_MB_2U_LIB.S9S_MB_2U(SCH_1):PAGE197

R735 Q_RES_0402LF-10K,1%,1/16W,CHIPA
     1 P3V3_AUX @S9S_MB_2U_LIB.S9S_MB_2U(SCH_1):P3V3_AUX    I13 @S9S_MB_2U_LIB.S9S_MB_2U(SCH_1):PAGE209
     2 FM_DIMM_12V_CPS_SX_N @S9S_MB_2U_LIB.S9S_MB_2U(SCH_1):FM_DIMM_12V_CPS_SX_N    I13 @S9S_MB_2U_LIB.S9S_MB_2U(SCH_1):PAGE209

R736 Q_RES_0402LF-1K,1%,1/16W,EMPTYA
     1 FM_DIMM_12V_CPS_SX_N @S9S_MB_2U_LIB.S9S_MB_2U(SCH_1):FM_DIMM_12V_CPS_SX_N    I11 @S9S_MB_2U_LIB.S9S_MB_2U(SCH_1):PAGE209
     2    GND @S9S_MB_2U_LIB.S9S_MB_2U(SCH_1):GND    I11 @S9S_MB_2U_LIB.S9S_MB_2U(SCH_1):PAGE209

R737 Q_RES_0402LF-0,5%,1/16W,CHIP,CA
     1 FM_CPU1_SKTOCC_LVT3_N @S9S_MB_2U_LIB.S9S_MB_2U(SCH_1):FM_CPU1_SKTOCC_LVT3_N   I106 @S9S_MB_2U_LIB.S9S_MB_2U(SCH_1):PAGE135
     2 FM_CPU1_SKTOCC_N @S9S_MB_2U_LIB.S9S_MB_2U(SCH_1):FM_CPU1_SKTOCC_N   I106 @S9S_MB_2U_LIB.S9S_MB_2U(SCH_1):PAGE135

R738 Q_RES_0402LF-0,5%,1/16W,CHIP,CA
     1 FM_CPU0_SKTOCC_LVT3_N @S9S_MB_2U_LIB.S9S_MB_2U(SCH_1):FM_CPU0_SKTOCC_LVT3_N   I110 @S9S_MB_2U_LIB.S9S_MB_2U(SCH_1):PAGE135
     2 FM_CPU0_SKTOCC_N @S9S_MB_2U_LIB.S9S_MB_2U(SCH_1):FM_CPU0_SKTOCC_N   I110 @S9S_MB_2U_LIB.S9S_MB_2U(SCH_1):PAGE135

R739 Q_RES_0402LF-10K,1%,1/16W,CHIPA
     1 P3V3_AUX @S9S_MB_2U_LIB.S9S_MB_2U(SCH_1):P3V3_AUX   I109 @S9S_MB_2U_LIB.S9S_MB_2U(SCH_1):PAGE135
     2 FM_CPU1_SKTOCC_N @S9S_MB_2U_LIB.S9S_MB_2U(SCH_1):FM_CPU1_SKTOCC_N   I109 @S9S_MB_2U_LIB.S9S_MB_2U(SCH_1):PAGE135

R740 Q_RES_0402LF-10K,1%,1/16W,CHIPA
     1 P3V3_AUX @S9S_MB_2U_LIB.S9S_MB_2U(SCH_1):P3V3_AUX   I107 @S9S_MB_2U_LIB.S9S_MB_2U(SCH_1):PAGE135
     2 FM_CPU0_SKTOCC_N @S9S_MB_2U_LIB.S9S_MB_2U(SCH_1):FM_CPU0_SKTOCC_N   I107 @S9S_MB_2U_LIB.S9S_MB_2U(SCH_1):PAGE135

R741 Q_RES_0402LF-150,1%,1/16W,CHIPA
     1 PVNN_TERM_CPU0 @S9S_MB_2U_LIB.S9S_MB_2U(SCH_1):PVNN_TERM_CPU0    I66 @S9S_MB_2U_LIB.S9S_MB_2U(SCH_1):PAGE135
     2 JTAG_MUX_CPU0_GTL_TDI @S9S_MB_2U_LIB.S9S_MB_2U(SCH_1):JTAG_MUX_CPU0_GTL_TDI    I66 @S9S_MB_2U_LIB.S9S_MB_2U(SCH_1):PAGE135

R742 Q_RES_0402LF-75,1%,1/16W,CHIP,A
     1 PVNN_TERM_CPU1 @S9S_MB_2U_LIB.S9S_MB_2U(SCH_1):PVNN_TERM_CPU1    I78 @S9S_MB_2U_LIB.S9S_MB_2U(SCH_1):PAGE135
     2 JTAG_CPU1_MUX_GTL_TDO @S9S_MB_2U_LIB.S9S_MB_2U(SCH_1):JTAG_CPU1_MUX_GTL_TDO    I78 @S9S_MB_2U_LIB.S9S_MB_2U(SCH_1):PAGE135

R743 Q_RES_0402LF-150,1%,1/16W,CHIPA
     1 PVNN_TERM_CPU1 @S9S_MB_2U_LIB.S9S_MB_2U(SCH_1):PVNN_TERM_CPU1    I65 @S9S_MB_2U_LIB.S9S_MB_2U(SCH_1):PAGE135
     2 JTAG_MUX_CPU1_GTL_TDI @S9S_MB_2U_LIB.S9S_MB_2U(SCH_1):JTAG_MUX_CPU1_GTL_TDI    I65 @S9S_MB_2U_LIB.S9S_MB_2U(SCH_1):PAGE135

R744 Q_RES_0402LF-75,1%,1/16W,CHIP,A
     1 PVNN_TERM_CPU0 @S9S_MB_2U_LIB.S9S_MB_2U(SCH_1):PVNN_TERM_CPU0    I77 @S9S_MB_2U_LIB.S9S_MB_2U(SCH_1):PAGE135
     2 JTAG_CPU0_MUX_GTL_TDO @S9S_MB_2U_LIB.S9S_MB_2U(SCH_1):JTAG_CPU0_MUX_GTL_TDO    I77 @S9S_MB_2U_LIB.S9S_MB_2U(SCH_1):PAGE135

R745 Q_RES_0402LF-33.2,1%,1/16W,CHIA
     1 FM_CPU_EN @S9S_MB_2U_LIB.S9S_MB_2U(SCH_1):FM_CPU_EN    I97 @S9S_MB_2U_LIB.S9S_MB_2U(SCH_1):PAGE135
     2 FM_CPU_EN_R @S9S_MB_2U_LIB.S9S_MB_2U(SCH_1):FM_CPU_EN_R    I97 @S9S_MB_2U_LIB.S9S_MB_2U(SCH_1):PAGE135

R746 Q_RES_0402LF-0,5%,1/16W,CHIP,CA
     1 PD_74CB_A9 @S9S_MB_2U_LIB.S9S_MB_2U(SCH_1):PD_74CB_A9    I90 @S9S_MB_2U_LIB.S9S_MB_2U(SCH_1):PAGE134
     2    GND @S9S_MB_2U_LIB.S9S_MB_2U(SCH_1):GND    I90 @S9S_MB_2U_LIB.S9S_MB_2U(SCH_1):PAGE134

R747 Q_RES_0402LF-150,1%,1/16W,CHIPA
     1 P1V05_PCH_AUX @S9S_MB_2U_LIB.S9S_MB_2U(SCH_1):P1V05_PCH_AUX   I176 @S9S_MB_2U_LIB.S9S_MB_2U(SCH_1):PAGE134
     2 JTAG_DBP_TDO_PCH @S9S_MB_2U_LIB.S9S_MB_2U(SCH_1):JTAG_DBP_TDO_PCH   I176 @S9S_MB_2U_LIB.S9S_MB_2U(SCH_1):PAGE134

R748 Q_RES_0402LF-75,1%,1/16W,CHIP,A
     1 P1V05_PCH_AUX @S9S_MB_2U_LIB.S9S_MB_2U(SCH_1):P1V05_PCH_AUX   I180 @S9S_MB_2U_LIB.S9S_MB_2U(SCH_1):PAGE134
     2 JTAG_DBP_TDI_PCH @S9S_MB_2U_LIB.S9S_MB_2U(SCH_1):JTAG_DBP_TDI_PCH   I180 @S9S_MB_2U_LIB.S9S_MB_2U(SCH_1):PAGE134

R749 Q_RES_0402LF-75,1%,1/16W,CHIP,A
     1 P1V05_PCH_AUX @S9S_MB_2U_LIB.S9S_MB_2U(SCH_1):P1V05_PCH_AUX   I179 @S9S_MB_2U_LIB.S9S_MB_2U(SCH_1):PAGE134
     2 JTAG_DBP_TMS_PCH @S9S_MB_2U_LIB.S9S_MB_2U(SCH_1):JTAG_DBP_TMS_PCH   I179 @S9S_MB_2U_LIB.S9S_MB_2U(SCH_1):PAGE134

R750 Q_RES_0402LF-150,1%,1/16W,CHIPA
     1 P1V05_PCH_AUX @S9S_MB_2U_LIB.S9S_MB_2U(SCH_1):P1V05_PCH_AUX   I178 @S9S_MB_2U_LIB.S9S_MB_2U(SCH_1):PAGE134
     2 H_DBP_PREQ_N_PCH @S9S_MB_2U_LIB.S9S_MB_2U(SCH_1):H_DBP_PREQ_N_PCH   I178 @S9S_MB_2U_LIB.S9S_MB_2U(SCH_1):PAGE134

R751 Q_RES_0402LF-150,1%,1/16W,CHIPA
     1 P1V05_PCH_AUX @S9S_MB_2U_LIB.S9S_MB_2U(SCH_1):P1V05_PCH_AUX   I177 @S9S_MB_2U_LIB.S9S_MB_2U(SCH_1):PAGE134
     2 H_DBP_PRDY_N_PCH @S9S_MB_2U_LIB.S9S_MB_2U(SCH_1):H_DBP_PRDY_N_PCH   I177 @S9S_MB_2U_LIB.S9S_MB_2U(SCH_1):PAGE134

R752 Q_RES_0402LF-10,1%,1/16W,CHIP,A
     1 JTAG_DBP_TDO @S9S_MB_2U_LIB.S9S_MB_2U(SCH_1):JTAG_DBP_TDO   I127 @S9S_MB_2U_LIB.S9S_MB_2U(SCH_1):PAGE134
     2 JTAG_DBP_TDO_PCH @S9S_MB_2U_LIB.S9S_MB_2U(SCH_1):JTAG_DBP_TDO_PCH   I127 @S9S_MB_2U_LIB.S9S_MB_2U(SCH_1):PAGE134

R753 Q_RES_0402LF-10,1%,1/16W,CHIP,A
     1 JTAG_DBP_TDI @S9S_MB_2U_LIB.S9S_MB_2U(SCH_1):JTAG_DBP_TDI   I128 @S9S_MB_2U_LIB.S9S_MB_2U(SCH_1):PAGE134
     2 JTAG_DBP_TDI_PCH @S9S_MB_2U_LIB.S9S_MB_2U(SCH_1):JTAG_DBP_TDI_PCH   I128 @S9S_MB_2U_LIB.S9S_MB_2U(SCH_1):PAGE134

R754 Q_RES_0402LF-10,1%,1/16W,CHIP,A
     1 JTAG_DBP_TMS @S9S_MB_2U_LIB.S9S_MB_2U(SCH_1):JTAG_DBP_TMS   I126 @S9S_MB_2U_LIB.S9S_MB_2U(SCH_1):PAGE134
     2 JTAG_DBP_TMS_PCH @S9S_MB_2U_LIB.S9S_MB_2U(SCH_1):JTAG_DBP_TMS_PCH   I126 @S9S_MB_2U_LIB.S9S_MB_2U(SCH_1):PAGE134

R755 Q_RES_0402LF-10,1%,1/16W,CHIP,A
     1 JTAG_DBP_PREQ_N @S9S_MB_2U_LIB.S9S_MB_2U(SCH_1):JTAG_DBP_PREQ_N   I147 @S9S_MB_2U_LIB.S9S_MB_2U(SCH_1):PAGE134
     2 H_DBP_PREQ_N_PCH @S9S_MB_2U_LIB.S9S_MB_2U(SCH_1):H_DBP_PREQ_N_PCH   I147 @S9S_MB_2U_LIB.S9S_MB_2U(SCH_1):PAGE134

R756 Q_RES_0402LF-10,1%,1/16W,CHIP,A
     1 JTAG_DBP_PRDY_N @S9S_MB_2U_LIB.S9S_MB_2U(SCH_1):JTAG_DBP_PRDY_N   I148 @S9S_MB_2U_LIB.S9S_MB_2U(SCH_1):PAGE134
     2 H_DBP_PRDY_N_PCH @S9S_MB_2U_LIB.S9S_MB_2U(SCH_1):H_DBP_PRDY_N_PCH   I148 @S9S_MB_2U_LIB.S9S_MB_2U(SCH_1):PAGE134

R757 Q_RES_0402LF-120,1%,1/16W,CHIPA
     1 PVNN_TERM_CPU0 @S9S_MB_2U_LIB.S9S_MB_2U(SCH_1):PVNN_TERM_CPU0   I166 @S9S_MB_2U_LIB.S9S_MB_2U(SCH_1):PAGE134
     2 JTAG_DBP_CPU_QS_GTL_TMS @S9S_MB_2U_LIB.S9S_MB_2U(SCH_1):JTAG_DBP_CPU_QS_GTL_TMS   I166 @S9S_MB_2U_LIB.S9S_MB_2U(SCH_1):PAGE134

R758 Q_RES_0402LF-150,1%,1/16W,CHIPA
     1 PVNN_TERM_CPU0 @S9S_MB_2U_LIB.S9S_MB_2U(SCH_1):PVNN_TERM_CPU0   I168 @S9S_MB_2U_LIB.S9S_MB_2U(SCH_1):PAGE134
     2 H_CPU_PREQ_QS_GTL_N @S9S_MB_2U_LIB.S9S_MB_2U(SCH_1):H_CPU_PREQ_QS_GTL_N   I168 @S9S_MB_2U_LIB.S9S_MB_2U(SCH_1):PAGE134

R759 Q_RES_0402LF-150,1%,1/16W,CHIPA
     1 PVNN_TERM_CPU0 @S9S_MB_2U_LIB.S9S_MB_2U(SCH_1):PVNN_TERM_CPU0   I169 @S9S_MB_2U_LIB.S9S_MB_2U(SCH_1):PAGE134
     2 H_CPU_PRDY_QS_GTL_N @S9S_MB_2U_LIB.S9S_MB_2U(SCH_1):H_CPU_PRDY_QS_GTL_N   I169 @S9S_MB_2U_LIB.S9S_MB_2U(SCH_1):PAGE134

R760 Q_RES_0402LF-499,1%,1/16W,CHIPA
     1 PVNN_TERM_CPU0 @S9S_MB_2U_LIB.S9S_MB_2U(SCH_1):PVNN_TERM_CPU0   I174 @S9S_MB_2U_LIB.S9S_MB_2U(SCH_1):PAGE134
     2 DBP_CPU_HOOK8_MBP2_GTL_QS_N @S9S_MB_2U_LIB.S9S_MB_2U(SCH_1):DBP_CPU_HOOK8_MBP2_GTL_QS_N   I174 @S9S_MB_2U_LIB.S9S_MB_2U(SCH_1):PAGE134

R761 Q_RES_0402LF-499,1%,1/16W,CHIPA
     1 PVNN_TERM_CPU0 @S9S_MB_2U_LIB.S9S_MB_2U(SCH_1):PVNN_TERM_CPU0   I175 @S9S_MB_2U_LIB.S9S_MB_2U(SCH_1):PAGE134
     2 DBP_CPU_HOOK9_MBP3_GTL_QS_N @S9S_MB_2U_LIB.S9S_MB_2U(SCH_1):DBP_CPU_HOOK9_MBP3_GTL_QS_N   I175 @S9S_MB_2U_LIB.S9S_MB_2U(SCH_1):PAGE134

R762 Q_RES_0402LF-0,5%,1/16W,CHIP,CA
     1 JTAG_DBP_CPU_GTL_TCK @S9S_MB_2U_LIB.S9S_MB_2U(SCH_1):JTAG_DBP_CPU_GTL_TCK    I71 @S9S_MB_2U_LIB.S9S_MB_2U(SCH_1):PAGE133
     2 JTAG_DBP_CPU_GTL_TCK_R @S9S_MB_2U_LIB.S9S_MB_2U(SCH_1):JTAG_DBP_CPU_GTL_TCK_R    I71 @S9S_MB_2U_LIB.S9S_MB_2U(SCH_1):PAGE133

R763 Q_RES_0402LF-10,1%,1/16W,CHIP,A
     1 JTAG_DBP_TDI @S9S_MB_2U_LIB.S9S_MB_2U(SCH_1):JTAG_DBP_TDI    I70 @S9S_MB_2U_LIB.S9S_MB_2U(SCH_1):PAGE133
     2 JTAG_DBP_TDI_R @S9S_MB_2U_LIB.S9S_MB_2U(SCH_1):JTAG_DBP_TDI_R    I70 @S9S_MB_2U_LIB.S9S_MB_2U(SCH_1):PAGE133

R764 Q_RES_0402LF-0,5%,1/16W,CHIP,CA
     1 JTAG_DBP_PRDY_N @S9S_MB_2U_LIB.S9S_MB_2U(SCH_1):JTAG_DBP_PRDY_N    I83 @S9S_MB_2U_LIB.S9S_MB_2U(SCH_1):PAGE133
     2 JTAG_DBP_PRDY_R1_N @S9S_MB_2U_LIB.S9S_MB_2U(SCH_1):JTAG_DBP_PRDY_R1_N    I83 @S9S_MB_2U_LIB.S9S_MB_2U(SCH_1):PAGE133

R765 Q_RES_0402LF-0,5%,1/16W,CHIP,CA
     1 JTAG_DBP_TCK_PCH @S9S_MB_2U_LIB.S9S_MB_2U(SCH_1):JTAG_DBP_TCK_PCH    I74 @S9S_MB_2U_LIB.S9S_MB_2U(SCH_1):PAGE133
     2 JTAG_DBP_TCK_R_TCK @S9S_MB_2U_LIB.S9S_MB_2U(SCH_1):JTAG_DBP_TCK_R_TCK    I74 @S9S_MB_2U_LIB.S9S_MB_2U(SCH_1):PAGE133

R766 Q_RES_0402LF-1K,1%,1/16W,EMPTYA
     1 P3V3_AUX @S9S_MB_2U_LIB.S9S_MB_2U(SCH_1):P3V3_AUX   I111 @S9S_MB_2U_LIB.S9S_MB_2U(SCH_1):PAGE133
     2 JTAG_DBP_POWER_BTN_N @S9S_MB_2U_LIB.S9S_MB_2U(SCH_1):JTAG_DBP_POWER_BTN_N   I111 @S9S_MB_2U_LIB.S9S_MB_2U(SCH_1):PAGE133

R767 Q_RES_0402LF-1K,1%,1/16W,CHIP,A
     1 P3V3_AUX @S9S_MB_2U_LIB.S9S_MB_2U(SCH_1):P3V3_AUX   I113 @S9S_MB_2U_LIB.S9S_MB_2U(SCH_1):PAGE133
     2 JTAG_RST_DBP_RST_CO_N @S9S_MB_2U_LIB.S9S_MB_2U(SCH_1):JTAG_RST_DBP_RST_CO_N   I113 @S9S_MB_2U_LIB.S9S_MB_2U(SCH_1):PAGE133

R768 Q_RES_0402LF-1K,1%,1/16W,CHIP,A
     1 P3V3_AUX @S9S_MB_2U_LIB.S9S_MB_2U(SCH_1):P3V3_AUX   I112 @S9S_MB_2U_LIB.S9S_MB_2U(SCH_1):PAGE133
     2 JTAG_DBP_PRESENT_R_N @S9S_MB_2U_LIB.S9S_MB_2U(SCH_1):JTAG_DBP_PRESENT_R_N   I112 @S9S_MB_2U_LIB.S9S_MB_2U(SCH_1):PAGE133

R769 Q_RES_0402LF-10K,1%,1/16W,CHIPA
     1 PD_TRST_P3 @S9S_MB_2U_LIB.S9S_MB_2U(SCH_1):PD_TRST_P3   I102 @S9S_MB_2U_LIB.S9S_MB_2U(SCH_1):PAGE133
     2    GND @S9S_MB_2U_LIB.S9S_MB_2U(SCH_1):GND   I102 @S9S_MB_2U_LIB.S9S_MB_2U(SCH_1):PAGE133

R770 Q_RES_0402LF-10K,1%,1/16W,CHIPA
     1 PU_OC5_USB_N @S9S_MB_2U_LIB.S9S_MB_2U(SCH_1):PU_OC5_USB_N   I239 @S9S_MB_2U_LIB.S9S_MB_2U(SCH_1):PAGE175
     2 P3V3_AUX @S9S_MB_2U_LIB.S9S_MB_2U(SCH_1):P3V3_AUX   I239 @S9S_MB_2U_LIB.S9S_MB_2U(SCH_1):PAGE175

R771 Q_RES_0402LF-1K,1%,1/16W,CHIP,A
     1 JTAG_DBP_PCH_DEBUG_CONSENT_N @S9S_MB_2U_LIB.S9S_MB_2U(SCH_1):JTAG_DBP_PCH_DEBUG_CONSENT_N   I120 @S9S_MB_2U_LIB.S9S_MB_2U(SCH_1):PAGE133
     2 FM_PCH_CONSENT_STRAP_N @S9S_MB_2U_LIB.S9S_MB_2U(SCH_1):FM_PCH_CONSENT_STRAP_N   I120 @S9S_MB_2U_LIB.S9S_MB_2U(SCH_1):PAGE133

R772 Q_RES_0402LF-1K,1%,1/16W,CHIP,A
     1 JTAG_RST_DBP_RSMRST_N @S9S_MB_2U_LIB.S9S_MB_2U(SCH_1):JTAG_RST_DBP_RSMRST_N   I118 @S9S_MB_2U_LIB.S9S_MB_2U(SCH_1):PAGE133
     2 RST_RSMRST_PCH_N @S9S_MB_2U_LIB.S9S_MB_2U(SCH_1):RST_RSMRST_PCH_N   I118 @S9S_MB_2U_LIB.S9S_MB_2U(SCH_1):PAGE133

R773 Q_RES_0402LF-1K,1%,1/16W,CHIP,A
     1 JTAG_DBP_BOOT_HALT_N @S9S_MB_2U_LIB.S9S_MB_2U(SCH_1):JTAG_DBP_BOOT_HALT_N   I124 @S9S_MB_2U_LIB.S9S_MB_2U(SCH_1):PAGE133
     2 FM_ADR_MODE0 @S9S_MB_2U_LIB.S9S_MB_2U(SCH_1):FM_ADR_MODE0   I124 @S9S_MB_2U_LIB.S9S_MB_2U(SCH_1):PAGE133

R774 Q_RES_0402LF-75,1%,1/16W,CHIP,A
     1 JTAG_DBP_CPU_GTL_TCK @S9S_MB_2U_LIB.S9S_MB_2U(SCH_1):JTAG_DBP_CPU_GTL_TCK   I132 @S9S_MB_2U_LIB.S9S_MB_2U(SCH_1):PAGE133
     2    GND @S9S_MB_2U_LIB.S9S_MB_2U(SCH_1):GND   I132 @S9S_MB_2U_LIB.S9S_MB_2U(SCH_1):PAGE133

R775 Q_RES_0402LF-10,1%,1/16W,CHIP,A
     1 JTAG_DBP_TMS_R @S9S_MB_2U_LIB.S9S_MB_2U(SCH_1):JTAG_DBP_TMS_R     I5 @S9S_MB_2U_LIB.S9S_MB_2U(SCH_1):PAGE133
     2 JTAG_DBP_TMS @S9S_MB_2U_LIB.S9S_MB_2U(SCH_1):JTAG_DBP_TMS     I5 @S9S_MB_2U_LIB.S9S_MB_2U(SCH_1):PAGE133

R776 Q_RES_0402LF-100,1%,1/16W,CHIPA
     1 JTAG_DBP_TDO_R @S9S_MB_2U_LIB.S9S_MB_2U(SCH_1):JTAG_DBP_TDO_R     I7 @S9S_MB_2U_LIB.S9S_MB_2U(SCH_1):PAGE133
     2 JTAG_DBP_TDO @S9S_MB_2U_LIB.S9S_MB_2U(SCH_1):JTAG_DBP_TDO     I7 @S9S_MB_2U_LIB.S9S_MB_2U(SCH_1):PAGE133

R777 Q_RES_0402LF-10,1%,1/16W,CHIP,A
     1 JTAG_DBP_PREQ_N_R @S9S_MB_2U_LIB.S9S_MB_2U(SCH_1):JTAG_DBP_PREQ_N_R    I10 @S9S_MB_2U_LIB.S9S_MB_2U(SCH_1):PAGE133
     2 JTAG_DBP_PREQ_N @S9S_MB_2U_LIB.S9S_MB_2U(SCH_1):JTAG_DBP_PREQ_N    I10 @S9S_MB_2U_LIB.S9S_MB_2U(SCH_1):PAGE133

R778 Q_RES_0402LF-1K,1%,1/16W,CHIP,A
     1 P3V3_AUX @S9S_MB_2U_LIB.S9S_MB_2U(SCH_1):P3V3_AUX    I15 @S9S_MB_2U_LIB.S9S_MB_2U(SCH_1):PAGE133
     2 JTAG_DBP_BOOT_HALT_N @S9S_MB_2U_LIB.S9S_MB_2U(SCH_1):JTAG_DBP_BOOT_HALT_N    I15 @S9S_MB_2U_LIB.S9S_MB_2U(SCH_1):PAGE133

R779 Q_RES_0402LF-150,1%,1/16W,CHIPA
     1 PVNN_TERM_CPU0 @S9S_MB_2U_LIB.S9S_MB_2U(SCH_1):PVNN_TERM_CPU0    I95 @S9S_MB_2U_LIB.S9S_MB_2U(SCH_1):PAGE133
     2 FM_CPU_FBRK_DEBUG_N @S9S_MB_2U_LIB.S9S_MB_2U(SCH_1):FM_CPU_FBRK_DEBUG_N    I95 @S9S_MB_2U_LIB.S9S_MB_2U(SCH_1):PAGE133

R780 Q_RES_0402LF-49.9,1%,1/16W,CHIA
     1 FM_CPU_FBRK_DEBUG_N @S9S_MB_2U_LIB.S9S_MB_2U(SCH_1):FM_CPU_FBRK_DEBUG_N    I92 @S9S_MB_2U_LIB.S9S_MB_2U(SCH_1):PAGE133
     2 FM_CPU_FBRK_DEBUG_R_N @S9S_MB_2U_LIB.S9S_MB_2U(SCH_1):FM_CPU_FBRK_DEBUG_R_N    I92 @S9S_MB_2U_LIB.S9S_MB_2U(SCH_1):PAGE133

R803 Q_RES_0402LF-33.2,1%,1/16W,CHIA
     1 JTAG_PLD_TDI_R @S9S_MB_2U_LIB.S9S_MB_2U(SCH_1):JTAG_PLD_TDI_R    I19 @S9S_MB_2U_LIB.S9S_MB_2U(SCH_1):PAGE210
     2 JTAG_BMC_PLD_TDI @S9S_MB_2U_LIB.S9S_MB_2U(SCH_1):JTAG_BMC_PLD_TDI    I19 @S9S_MB_2U_LIB.S9S_MB_2U(SCH_1):PAGE210

R804 Q_RES_0402LF-33.2,1%,1/16W,CHIA
     1 JTAG_PLD_TDO_R @S9S_MB_2U_LIB.S9S_MB_2U(SCH_1):JTAG_PLD_TDO_R    I20 @S9S_MB_2U_LIB.S9S_MB_2U(SCH_1):PAGE210
     2 JTAG_BMC_PLD_TDO @S9S_MB_2U_LIB.S9S_MB_2U(SCH_1):JTAG_BMC_PLD_TDO    I20 @S9S_MB_2U_LIB.S9S_MB_2U(SCH_1):PAGE210

R805 Q_RES_0402LF-33.2,1%,1/16W,CHIA
     1 JTAG_PLD_TMS_R @S9S_MB_2U_LIB.S9S_MB_2U(SCH_1):JTAG_PLD_TMS_R    I25 @S9S_MB_2U_LIB.S9S_MB_2U(SCH_1):PAGE210
     2 JTAG_BMC_PLD_TMS @S9S_MB_2U_LIB.S9S_MB_2U(SCH_1):JTAG_BMC_PLD_TMS    I25 @S9S_MB_2U_LIB.S9S_MB_2U(SCH_1):PAGE210

R806 Q_RES_0402LF-33.2,1%,1/16W,CHIA
     1 JTAG_PLD_TCK_R @S9S_MB_2U_LIB.S9S_MB_2U(SCH_1):JTAG_PLD_TCK_R    I54 @S9S_MB_2U_LIB.S9S_MB_2U(SCH_1):PAGE210
     2 JTAG_BMC_PLD_TCK @S9S_MB_2U_LIB.S9S_MB_2U(SCH_1):JTAG_BMC_PLD_TCK    I54 @S9S_MB_2U_LIB.S9S_MB_2U(SCH_1):PAGE210

R815 Q_RES_0402LF-0,5%,1/16W,CHIP,CA
     1 RST_PLD_CPU1_DRAM_GH_N @S9S_MB_2U_LIB.S9S_MB_2U(SCH_1):RST_PLD_CPU1_DRAM_GH_N    I11 @S9S_MB_2U_LIB.S9S_MB_2U(SCH_1):PAGE130
     2 RST_M_GH_CPU1_FPGA_N @S9S_MB_2U_LIB.S9S_MB_2U(SCH_1):RST_M_GH_CPU1_FPGA_N    I11 @S9S_MB_2U_LIB.S9S_MB_2U(SCH_1):PAGE130

R816 Q_RES_0402LF-0,5%,1/16W,CHIP,CA
     1 RST_PLD_CPU1_DRAM_AB_N @S9S_MB_2U_LIB.S9S_MB_2U(SCH_1):RST_PLD_CPU1_DRAM_AB_N    I37 @S9S_MB_2U_LIB.S9S_MB_2U(SCH_1):PAGE130
     2 RST_M_AB_CPU1_FPGA_N @S9S_MB_2U_LIB.S9S_MB_2U(SCH_1):RST_M_AB_CPU1_FPGA_N    I37 @S9S_MB_2U_LIB.S9S_MB_2U(SCH_1):PAGE130

R817 Q_RES_0402LF-0,5%,1/16W,CHIP,CA
     1 RST_PLD_CPU1_DRAM_CD_N @S9S_MB_2U_LIB.S9S_MB_2U(SCH_1):RST_PLD_CPU1_DRAM_CD_N    I26 @S9S_MB_2U_LIB.S9S_MB_2U(SCH_1):PAGE130
     2 RST_M_CD_CPU1_FPGA_N @S9S_MB_2U_LIB.S9S_MB_2U(SCH_1):RST_M_CD_CPU1_FPGA_N    I26 @S9S_MB_2U_LIB.S9S_MB_2U(SCH_1):PAGE130

R818 Q_RES_0402LF-0,5%,1/16W,CHIP,CA
     1 RST_PLD_CPU1_DRAM_EF_N @S9S_MB_2U_LIB.S9S_MB_2U(SCH_1):RST_PLD_CPU1_DRAM_EF_N    I22 @S9S_MB_2U_LIB.S9S_MB_2U(SCH_1):PAGE130
     2 RST_M_EF_CPU1_FPGA_N @S9S_MB_2U_LIB.S9S_MB_2U(SCH_1):RST_M_EF_CPU1_FPGA_N    I22 @S9S_MB_2U_LIB.S9S_MB_2U(SCH_1):PAGE130

R819 Q_RES_0402LF-1K,1%,1/16W,CHIP,A
     1 PVCCD_HV_CPU1 @S9S_MB_2U_LIB.S9S_MB_2U(SCH_1):PVCCD_HV_CPU1    I90 @S9S_MB_2U_LIB.S9S_MB_2U(SCH_1):PAGE130
     2 RST_M_GH_CPU1_FPGA_N @S9S_MB_2U_LIB.S9S_MB_2U(SCH_1):RST_M_GH_CPU1_FPGA_N    I90 @S9S_MB_2U_LIB.S9S_MB_2U(SCH_1):PAGE130

R820 Q_RES_0402LF-1K,1%,1/16W,CHIP,A
     1 PVCCD_HV_CPU1 @S9S_MB_2U_LIB.S9S_MB_2U(SCH_1):PVCCD_HV_CPU1    I82 @S9S_MB_2U_LIB.S9S_MB_2U(SCH_1):PAGE130
     2 RST_M_AB_CPU1_FPGA_N @S9S_MB_2U_LIB.S9S_MB_2U(SCH_1):RST_M_AB_CPU1_FPGA_N    I82 @S9S_MB_2U_LIB.S9S_MB_2U(SCH_1):PAGE130

R821 Q_RES_0402LF-1K,1%,1/16W,CHIP,A
     1 PVCCD_HV_CPU1 @S9S_MB_2U_LIB.S9S_MB_2U(SCH_1):PVCCD_HV_CPU1    I84 @S9S_MB_2U_LIB.S9S_MB_2U(SCH_1):PAGE130
     2 RST_M_CD_CPU1_FPGA_N @S9S_MB_2U_LIB.S9S_MB_2U(SCH_1):RST_M_CD_CPU1_FPGA_N    I84 @S9S_MB_2U_LIB.S9S_MB_2U(SCH_1):PAGE130

R822 Q_RES_0402LF-1K,1%,1/16W,CHIP,A
     1 PVCCD_HV_CPU1 @S9S_MB_2U_LIB.S9S_MB_2U(SCH_1):PVCCD_HV_CPU1    I88 @S9S_MB_2U_LIB.S9S_MB_2U(SCH_1):PAGE130
     2 RST_M_EF_CPU1_FPGA_N @S9S_MB_2U_LIB.S9S_MB_2U(SCH_1):RST_M_EF_CPU1_FPGA_N    I88 @S9S_MB_2U_LIB.S9S_MB_2U(SCH_1):PAGE130

R835 Q_RES_0402LF-0,5%,1/16W,CHIP,CA
     1 RST_PLD_CPU0_DRAM_GH_N @S9S_MB_2U_LIB.S9S_MB_2U(SCH_1):RST_PLD_CPU0_DRAM_GH_N    I86 @S9S_MB_2U_LIB.S9S_MB_2U(SCH_1):PAGE129
     2 RST_M_GH_CPU0_FPGA_N @S9S_MB_2U_LIB.S9S_MB_2U(SCH_1):RST_M_GH_CPU0_FPGA_N    I86 @S9S_MB_2U_LIB.S9S_MB_2U(SCH_1):PAGE129

R836 Q_RES_0402LF-0,5%,1/16W,CHIP,CA
     1 RST_PLD_CPU0_DRAM_AB_N @S9S_MB_2U_LIB.S9S_MB_2U(SCH_1):RST_PLD_CPU0_DRAM_AB_N    I26 @S9S_MB_2U_LIB.S9S_MB_2U(SCH_1):PAGE129
     2 RST_M_AB_CPU0_FPGA_N @S9S_MB_2U_LIB.S9S_MB_2U(SCH_1):RST_M_AB_CPU0_FPGA_N    I26 @S9S_MB_2U_LIB.S9S_MB_2U(SCH_1):PAGE129

R837 Q_RES_0402LF-0,5%,1/16W,CHIP,CA
     1 RST_PLD_CPU0_DRAM_CD_N @S9S_MB_2U_LIB.S9S_MB_2U(SCH_1):RST_PLD_CPU0_DRAM_CD_N    I59 @S9S_MB_2U_LIB.S9S_MB_2U(SCH_1):PAGE129
     2 RST_M_CD_CPU0_FPGA_N @S9S_MB_2U_LIB.S9S_MB_2U(SCH_1):RST_M_CD_CPU0_FPGA_N    I59 @S9S_MB_2U_LIB.S9S_MB_2U(SCH_1):PAGE129

R838 Q_RES_0402LF-0,5%,1/16W,CHIP,CA
     1 RST_PLD_CPU0_DRAM_EF_N @S9S_MB_2U_LIB.S9S_MB_2U(SCH_1):RST_PLD_CPU0_DRAM_EF_N    I76 @S9S_MB_2U_LIB.S9S_MB_2U(SCH_1):PAGE129
     2 RST_M_EF_CPU0_FPGA_N @S9S_MB_2U_LIB.S9S_MB_2U(SCH_1):RST_M_EF_CPU0_FPGA_N    I76 @S9S_MB_2U_LIB.S9S_MB_2U(SCH_1):PAGE129

R839 Q_RES_0402LF-1K,1%,1/16W,CHIP,A
     1 PVCCD_HV_CPU0 @S9S_MB_2U_LIB.S9S_MB_2U(SCH_1):PVCCD_HV_CPU0   I125 @S9S_MB_2U_LIB.S9S_MB_2U(SCH_1):PAGE129
     2 RST_M_GH_CPU0_FPGA_N @S9S_MB_2U_LIB.S9S_MB_2U(SCH_1):RST_M_GH_CPU0_FPGA_N   I125 @S9S_MB_2U_LIB.S9S_MB_2U(SCH_1):PAGE129

R840 Q_RES_0402LF-1K,1%,1/16W,CHIP,A
     1 PVCCD_HV_CPU0 @S9S_MB_2U_LIB.S9S_MB_2U(SCH_1):PVCCD_HV_CPU0   I119 @S9S_MB_2U_LIB.S9S_MB_2U(SCH_1):PAGE129
     2 RST_M_AB_CPU0_FPGA_N @S9S_MB_2U_LIB.S9S_MB_2U(SCH_1):RST_M_AB_CPU0_FPGA_N   I119 @S9S_MB_2U_LIB.S9S_MB_2U(SCH_1):PAGE129

R841 Q_RES_0402LF-1K,1%,1/16W,CHIP,A
     1 PVCCD_HV_CPU0 @S9S_MB_2U_LIB.S9S_MB_2U(SCH_1):PVCCD_HV_CPU0   I121 @S9S_MB_2U_LIB.S9S_MB_2U(SCH_1):PAGE129
     2 RST_M_CD_CPU0_FPGA_N @S9S_MB_2U_LIB.S9S_MB_2U(SCH_1):RST_M_CD_CPU0_FPGA_N   I121 @S9S_MB_2U_LIB.S9S_MB_2U(SCH_1):PAGE129

R842 Q_RES_0402LF-1K,1%,1/16W,CHIP,A
     1 PVCCD_HV_CPU0 @S9S_MB_2U_LIB.S9S_MB_2U(SCH_1):PVCCD_HV_CPU0   I123 @S9S_MB_2U_LIB.S9S_MB_2U(SCH_1):PAGE129
     2 RST_M_EF_CPU0_FPGA_N @S9S_MB_2U_LIB.S9S_MB_2U(SCH_1):RST_M_EF_CPU0_FPGA_N   I123 @S9S_MB_2U_LIB.S9S_MB_2U(SCH_1):PAGE129

R851 Q_RES_0402LF-0,5%,1/16W,CHIP,CA
     1 RST_CPU0_DRAM_AB_N @S9S_MB_2U_LIB.S9S_MB_2U(SCH_1):RST_CPU0_DRAM_AB_N    I12 @S9S_MB_2U_LIB.S9S_MB_2U(SCH_1):PAGE128
     2 RST_CPU0_DRAM_AB_PLD_N @S9S_MB_2U_LIB.S9S_MB_2U(SCH_1):RST_CPU0_DRAM_AB_PLD_N    I12 @S9S_MB_2U_LIB.S9S_MB_2U(SCH_1):PAGE128

R852 Q_RES_0402LF-0,5%,1/16W,CHIP,CA
     1 RST_CPU0_DRAM_CD_N @S9S_MB_2U_LIB.S9S_MB_2U(SCH_1):RST_CPU0_DRAM_CD_N    I11 @S9S_MB_2U_LIB.S9S_MB_2U(SCH_1):PAGE128
     2 RST_CPU0_DRAM_CD_PLD_N @S9S_MB_2U_LIB.S9S_MB_2U(SCH_1):RST_CPU0_DRAM_CD_PLD_N    I11 @S9S_MB_2U_LIB.S9S_MB_2U(SCH_1):PAGE128

R853 Q_RES_0402LF-0,5%,1/16W,CHIP,CA
     1 RST_CPU0_DRAM_EF_N @S9S_MB_2U_LIB.S9S_MB_2U(SCH_1):RST_CPU0_DRAM_EF_N    I10 @S9S_MB_2U_LIB.S9S_MB_2U(SCH_1):PAGE128
     2 RST_CPU0_DRAM_EF_PLD_N @S9S_MB_2U_LIB.S9S_MB_2U(SCH_1):RST_CPU0_DRAM_EF_PLD_N    I10 @S9S_MB_2U_LIB.S9S_MB_2U(SCH_1):PAGE128

R854 Q_RES_0402LF-0,5%,1/16W,CHIP,CA
     1 RST_CPU0_DRAM_GH_N @S9S_MB_2U_LIB.S9S_MB_2U(SCH_1):RST_CPU0_DRAM_GH_N     I9 @S9S_MB_2U_LIB.S9S_MB_2U(SCH_1):PAGE128
     2 RST_CPU0_DRAM_GH_PLD_N @S9S_MB_2U_LIB.S9S_MB_2U(SCH_1):RST_CPU0_DRAM_GH_PLD_N     I9 @S9S_MB_2U_LIB.S9S_MB_2U(SCH_1):PAGE128

R859 Q_RES_0402LF-0,5%,1/16W,CHIP,CA
     1 RST_CPU1_DRAM_AB_N @S9S_MB_2U_LIB.S9S_MB_2U(SCH_1):RST_CPU1_DRAM_AB_N    I50 @S9S_MB_2U_LIB.S9S_MB_2U(SCH_1):PAGE128
     2 RST_CPU1_DRAM_AB_PLD_N @S9S_MB_2U_LIB.S9S_MB_2U(SCH_1):RST_CPU1_DRAM_AB_PLD_N    I50 @S9S_MB_2U_LIB.S9S_MB_2U(SCH_1):PAGE128

R860 Q_RES_0402LF-0,5%,1/16W,CHIP,CA
     1 RST_CPU1_DRAM_CD_N @S9S_MB_2U_LIB.S9S_MB_2U(SCH_1):RST_CPU1_DRAM_CD_N    I51 @S9S_MB_2U_LIB.S9S_MB_2U(SCH_1):PAGE128
     2 RST_CPU1_DRAM_CD_PLD_N @S9S_MB_2U_LIB.S9S_MB_2U(SCH_1):RST_CPU1_DRAM_CD_PLD_N    I51 @S9S_MB_2U_LIB.S9S_MB_2U(SCH_1):PAGE128

R861 Q_RES_0402LF-0,5%,1/16W,CHIP,CA
     1 RST_CPU1_DRAM_EF_N @S9S_MB_2U_LIB.S9S_MB_2U(SCH_1):RST_CPU1_DRAM_EF_N    I48 @S9S_MB_2U_LIB.S9S_MB_2U(SCH_1):PAGE128
     2 RST_CPU1_DRAM_EF_PLD_N @S9S_MB_2U_LIB.S9S_MB_2U(SCH_1):RST_CPU1_DRAM_EF_PLD_N    I48 @S9S_MB_2U_LIB.S9S_MB_2U(SCH_1):PAGE128

R880 Q_RES_0402LF-33.2,1%,1/16W,CHIA
     1 PWRGD_CHB_CPU0_DIMM2 @S9S_MB_2U_LIB.S9S_MB_2U(SCH_1):PWRGD_CHB_CPU0_DIMM2    I29 @S9S_MB_2U_LIB.S9S_MB_2U(SCH_1):PAGE114
     2 PWRGD_FAIL_CPU0_AB @S9S_MB_2U_LIB.S9S_MB_2U(SCH_1):PWRGD_FAIL_CPU0_AB    I29 @S9S_MB_2U_LIB.S9S_MB_2U(SCH_1):PAGE114

R884 Q_RES_0402LF-33.2,1%,1/16W,CHIA
     1 PWRGD_CHD_CPU0_DIMM2 @S9S_MB_2U_LIB.S9S_MB_2U(SCH_1):PWRGD_CHD_CPU0_DIMM2    I26 @S9S_MB_2U_LIB.S9S_MB_2U(SCH_1):PAGE114
     2 PWRGD_FAIL_CPU0_CD @S9S_MB_2U_LIB.S9S_MB_2U(SCH_1):PWRGD_FAIL_CPU0_CD    I26 @S9S_MB_2U_LIB.S9S_MB_2U(SCH_1):PAGE114

R885 Q_RES_0402LF-33.2,1%,1/16W,CHIA
     1 PWRGD_CHE_CPU0_DIMM1 @S9S_MB_2U_LIB.S9S_MB_2U(SCH_1):PWRGD_CHE_CPU0_DIMM1    I24 @S9S_MB_2U_LIB.S9S_MB_2U(SCH_1):PAGE114
     2 PWRGD_FAIL_CPU0_EF @S9S_MB_2U_LIB.S9S_MB_2U(SCH_1):PWRGD_FAIL_CPU0_EF    I24 @S9S_MB_2U_LIB.S9S_MB_2U(SCH_1):PAGE114

R886 Q_RES_0402LF-33.2,1%,1/16W,CHIA
     1 PWRGD_CHE_CPU0_DIMM2 @S9S_MB_2U_LIB.S9S_MB_2U(SCH_1):PWRGD_CHE_CPU0_DIMM2    I23 @S9S_MB_2U_LIB.S9S_MB_2U(SCH_1):PAGE114
     2 PWRGD_FAIL_CPU0_EF @S9S_MB_2U_LIB.S9S_MB_2U(SCH_1):PWRGD_FAIL_CPU0_EF    I23 @S9S_MB_2U_LIB.S9S_MB_2U(SCH_1):PAGE114

R889 Q_RES_0402LF-33.2,1%,1/16W,CHIA
     1 PWRGD_CHG_CPU0_DIMM1 @S9S_MB_2U_LIB.S9S_MB_2U(SCH_1):PWRGD_CHG_CPU0_DIMM1    I20 @S9S_MB_2U_LIB.S9S_MB_2U(SCH_1):PAGE114
     2 PWRGD_FAIL_CPU0_GH @S9S_MB_2U_LIB.S9S_MB_2U(SCH_1):PWRGD_FAIL_CPU0_GH    I20 @S9S_MB_2U_LIB.S9S_MB_2U(SCH_1):PAGE114

R890 Q_RES_0402LF-33.2,1%,1/16W,CHIA
     1 PWRGD_CHG_CPU0_DIMM2 @S9S_MB_2U_LIB.S9S_MB_2U(SCH_1):PWRGD_CHG_CPU0_DIMM2    I19 @S9S_MB_2U_LIB.S9S_MB_2U(SCH_1):PAGE114
     2 PWRGD_FAIL_CPU0_GH @S9S_MB_2U_LIB.S9S_MB_2U(SCH_1):PWRGD_FAIL_CPU0_GH    I19 @S9S_MB_2U_LIB.S9S_MB_2U(SCH_1):PAGE114

R893 Q_RES_0402LF-33.2,1%,1/16W,CHIA
     1 PWRGD_CHA_CPU1_DIMM1 @S9S_MB_2U_LIB.S9S_MB_2U(SCH_1):PWRGD_CHA_CPU1_DIMM1    I79 @S9S_MB_2U_LIB.S9S_MB_2U(SCH_1):PAGE114
     2 PWRGD_FAIL_CPU1_AB @S9S_MB_2U_LIB.S9S_MB_2U(SCH_1):PWRGD_FAIL_CPU1_AB    I79 @S9S_MB_2U_LIB.S9S_MB_2U(SCH_1):PAGE114

R894 Q_RES_0402LF-33.2,1%,1/16W,CHIA
     1 PWRGD_CHA_CPU1_DIMM2 @S9S_MB_2U_LIB.S9S_MB_2U(SCH_1):PWRGD_CHA_CPU1_DIMM2    I78 @S9S_MB_2U_LIB.S9S_MB_2U(SCH_1):PAGE114
     2 PWRGD_FAIL_CPU1_AB @S9S_MB_2U_LIB.S9S_MB_2U(SCH_1):PWRGD_FAIL_CPU1_AB    I78 @S9S_MB_2U_LIB.S9S_MB_2U(SCH_1):PAGE114

R895 Q_RES_0402LF-33.2,1%,1/16W,CHIA
     1 PWRGD_CHB_CPU1_DIMM1 @S9S_MB_2U_LIB.S9S_MB_2U(SCH_1):PWRGD_CHB_CPU1_DIMM1    I77 @S9S_MB_2U_LIB.S9S_MB_2U(SCH_1):PAGE114
     2 PWRGD_FAIL_CPU1_AB @S9S_MB_2U_LIB.S9S_MB_2U(SCH_1):PWRGD_FAIL_CPU1_AB    I77 @S9S_MB_2U_LIB.S9S_MB_2U(SCH_1):PAGE114

R896 Q_RES_0402LF-33.2,1%,1/16W,CHIA
     1 PWRGD_CHB_CPU1_DIMM2 @S9S_MB_2U_LIB.S9S_MB_2U(SCH_1):PWRGD_CHB_CPU1_DIMM2    I69 @S9S_MB_2U_LIB.S9S_MB_2U(SCH_1):PAGE114
     2 PWRGD_FAIL_CPU1_AB @S9S_MB_2U_LIB.S9S_MB_2U(SCH_1):PWRGD_FAIL_CPU1_AB    I69 @S9S_MB_2U_LIB.S9S_MB_2U(SCH_1):PAGE114

R897 Q_RES_0402LF-33.2,1%,1/16W,CHIA
     1 PWRGD_CHC_CPU1_DIMM1 @S9S_MB_2U_LIB.S9S_MB_2U(SCH_1):PWRGD_CHC_CPU1_DIMM1    I67 @S9S_MB_2U_LIB.S9S_MB_2U(SCH_1):PAGE114
     2 PWRGD_FAIL_CPU1_CD @S9S_MB_2U_LIB.S9S_MB_2U(SCH_1):PWRGD_FAIL_CPU1_CD    I67 @S9S_MB_2U_LIB.S9S_MB_2U(SCH_1):PAGE114

R898 Q_RES_0402LF-33.2,1%,1/16W,CHIA
     1 PWRGD_CHC_CPU1_DIMM2 @S9S_MB_2U_LIB.S9S_MB_2U(SCH_1):PWRGD_CHC_CPU1_DIMM2    I68 @S9S_MB_2U_LIB.S9S_MB_2U(SCH_1):PAGE114
     2 PWRGD_FAIL_CPU1_CD @S9S_MB_2U_LIB.S9S_MB_2U(SCH_1):PWRGD_FAIL_CPU1_CD    I68 @S9S_MB_2U_LIB.S9S_MB_2U(SCH_1):PAGE114

R899 Q_RES_0402LF-33.2,1%,1/16W,CHIA
     1 PWRGD_CHD_CPU1_DIMM1 @S9S_MB_2U_LIB.S9S_MB_2U(SCH_1):PWRGD_CHD_CPU1_DIMM1    I65 @S9S_MB_2U_LIB.S9S_MB_2U(SCH_1):PAGE114
     2 PWRGD_FAIL_CPU1_CD @S9S_MB_2U_LIB.S9S_MB_2U(SCH_1):PWRGD_FAIL_CPU1_CD    I65 @S9S_MB_2U_LIB.S9S_MB_2U(SCH_1):PAGE114

R900 Q_RES_0402LF-33.2,1%,1/16W,CHIA
     1 PWRGD_CHD_CPU1_DIMM2 @S9S_MB_2U_LIB.S9S_MB_2U(SCH_1):PWRGD_CHD_CPU1_DIMM2    I66 @S9S_MB_2U_LIB.S9S_MB_2U(SCH_1):PAGE114
     2 PWRGD_FAIL_CPU1_CD @S9S_MB_2U_LIB.S9S_MB_2U(SCH_1):PWRGD_FAIL_CPU1_CD    I66 @S9S_MB_2U_LIB.S9S_MB_2U(SCH_1):PAGE114

R901 Q_RES_0402LF-33.2,1%,1/16W,CHIA
     1 PWRGD_CHE_CPU1_DIMM1 @S9S_MB_2U_LIB.S9S_MB_2U(SCH_1):PWRGD_CHE_CPU1_DIMM1    I64 @S9S_MB_2U_LIB.S9S_MB_2U(SCH_1):PAGE114
     2 PWRGD_FAIL_CPU1_EF @S9S_MB_2U_LIB.S9S_MB_2U(SCH_1):PWRGD_FAIL_CPU1_EF    I64 @S9S_MB_2U_LIB.S9S_MB_2U(SCH_1):PAGE114

R902 Q_RES_0402LF-33.2,1%,1/16W,CHIA
     1 PWRGD_CHE_CPU1_DIMM2 @S9S_MB_2U_LIB.S9S_MB_2U(SCH_1):PWRGD_CHE_CPU1_DIMM2    I63 @S9S_MB_2U_LIB.S9S_MB_2U(SCH_1):PAGE114
     2 PWRGD_FAIL_CPU1_EF @S9S_MB_2U_LIB.S9S_MB_2U(SCH_1):PWRGD_FAIL_CPU1_EF    I63 @S9S_MB_2U_LIB.S9S_MB_2U(SCH_1):PAGE114

R903 Q_RES_0402LF-33.2,1%,1/16W,CHIA
     1 PWRGD_CHF_CPU1_DIMM1 @S9S_MB_2U_LIB.S9S_MB_2U(SCH_1):PWRGD_CHF_CPU1_DIMM1    I62 @S9S_MB_2U_LIB.S9S_MB_2U(SCH_1):PAGE114
     2 PWRGD_FAIL_CPU1_EF @S9S_MB_2U_LIB.S9S_MB_2U(SCH_1):PWRGD_FAIL_CPU1_EF    I62 @S9S_MB_2U_LIB.S9S_MB_2U(SCH_1):PAGE114

R905 Q_RES_0402LF-33.2,1%,1/16W,CHIA
     1 PWRGD_CHG_CPU1_DIMM1 @S9S_MB_2U_LIB.S9S_MB_2U(SCH_1):PWRGD_CHG_CPU1_DIMM1    I60 @S9S_MB_2U_LIB.S9S_MB_2U(SCH_1):PAGE114
     2 PWRGD_FAIL_CPU1_GH @S9S_MB_2U_LIB.S9S_MB_2U(SCH_1):PWRGD_FAIL_CPU1_GH    I60 @S9S_MB_2U_LIB.S9S_MB_2U(SCH_1):PAGE114

R906 Q_RES_0402LF-33.2,1%,1/16W,CHIA
     1 PWRGD_CHG_CPU1_DIMM2 @S9S_MB_2U_LIB.S9S_MB_2U(SCH_1):PWRGD_CHG_CPU1_DIMM2    I59 @S9S_MB_2U_LIB.S9S_MB_2U(SCH_1):PAGE114
     2 PWRGD_FAIL_CPU1_GH @S9S_MB_2U_LIB.S9S_MB_2U(SCH_1):PWRGD_FAIL_CPU1_GH    I59 @S9S_MB_2U_LIB.S9S_MB_2U(SCH_1):PAGE114

R907 Q_RES_0402LF-33.2,1%,1/16W,CHIA
     1 PWRGD_CHH_CPU1_DIMM1 @S9S_MB_2U_LIB.S9S_MB_2U(SCH_1):PWRGD_CHH_CPU1_DIMM1    I58 @S9S_MB_2U_LIB.S9S_MB_2U(SCH_1):PAGE114
     2 PWRGD_FAIL_CPU1_GH @S9S_MB_2U_LIB.S9S_MB_2U(SCH_1):PWRGD_FAIL_CPU1_GH    I58 @S9S_MB_2U_LIB.S9S_MB_2U(SCH_1):PAGE114

R908 Q_RES_0402LF-33.2,1%,1/16W,CHIA
     1 PWRGD_CHH_CPU1_DIMM2 @S9S_MB_2U_LIB.S9S_MB_2U(SCH_1):PWRGD_CHH_CPU1_DIMM2    I57 @S9S_MB_2U_LIB.S9S_MB_2U(SCH_1):PAGE114
     2 PWRGD_FAIL_CPU1_GH @S9S_MB_2U_LIB.S9S_MB_2U(SCH_1):PWRGD_FAIL_CPU1_GH    I57 @S9S_MB_2U_LIB.S9S_MB_2U(SCH_1):PAGE114

R909 Q_RES_0402LF-33.2,1%,1/16W,CHIA
     1 SMB_PEHPCPU0_GTL_SDA @S9S_MB_2U_LIB.S9S_MB_2U(SCH_1):SMB_PEHPCPU0_GTL_SDA   I102 @S9S_MB_2U_LIB.S9S_MB_2U(SCH_1):PAGE223
     2 SMB_PEHPCPU0_GTL_R_SDA @S9S_MB_2U_LIB.S9S_MB_2U(SCH_1):SMB_PEHPCPU0_GTL_R_SDA   I102 @S9S_MB_2U_LIB.S9S_MB_2U(SCH_1):PAGE223

R910 Q_RES_0402LF-240,1%,1/16W,CHIPA
     1 PVNN_TERM_CPU0 @S9S_MB_2U_LIB.S9S_MB_2U(SCH_1):PVNN_TERM_CPU0    I24 @S9S_MB_2U_LIB.S9S_MB_2U(SCH_1):PAGE223
     2 SMB_PEHPCPU0_GTL_R_SCL @S9S_MB_2U_LIB.S9S_MB_2U(SCH_1):SMB_PEHPCPU0_GTL_R_SCL    I24 @S9S_MB_2U_LIB.S9S_MB_2U(SCH_1):PAGE223

R911 Q_RES_0402LF-240,1%,1/16W,CHIPA
     1 PVNN_TERM_CPU0 @S9S_MB_2U_LIB.S9S_MB_2U(SCH_1):PVNN_TERM_CPU0    I22 @S9S_MB_2U_LIB.S9S_MB_2U(SCH_1):PAGE223
     2 SMB_PEHPCPU0_GTL_R_SDA @S9S_MB_2U_LIB.S9S_MB_2U(SCH_1):SMB_PEHPCPU0_GTL_R_SDA    I22 @S9S_MB_2U_LIB.S9S_MB_2U(SCH_1):PAGE223

R912 Q_RES_0402LF-4.75K,1%,1/16W,EMA
     1 P3V3_AUX @S9S_MB_2U_LIB.S9S_MB_2U(SCH_1):P3V3_AUX   I278 @S9S_MB_2U_LIB.S9S_MB_2U(SCH_1):PAGE197
     2 CLK_CK440_SMB_ADDR0 @S9S_MB_2U_LIB.S9S_MB_2U(SCH_1):CLK_CK440_SMB_ADDR0   I278 @S9S_MB_2U_LIB.S9S_MB_2U(SCH_1):PAGE197

R913 Q_RES_0402LF-10K,1%,1/16W,CHIPA
     1 PU_OC6_USB_N @S9S_MB_2U_LIB.S9S_MB_2U(SCH_1):PU_OC6_USB_N   I241 @S9S_MB_2U_LIB.S9S_MB_2U(SCH_1):PAGE175
     2 P3V3_AUX @S9S_MB_2U_LIB.S9S_MB_2U(SCH_1):P3V3_AUX   I241 @S9S_MB_2U_LIB.S9S_MB_2U(SCH_1):PAGE175

R915 Q_RES_0402LF-0,5%,1/16W,CHIP,CA
     1 SPI_PCH_IO0 @S9S_MB_2U_LIB.S9S_MB_2U(SCH_1):SPI_PCH_IO0   I118 @S9S_MB_2U_LIB.S9S_MB_2U(SCH_1):PAGE177
     2 SPI_SYS_MOSI @S9S_MB_2U_LIB.S9S_MB_2U(SCH_1):SPI_SYS_MOSI   I118 @S9S_MB_2U_LIB.S9S_MB_2U(SCH_1):PAGE177

R916 Q_RES_0402LF-0,5%,1/16W,CHIP,CA
     1 SPI_PCH_IO1 @S9S_MB_2U_LIB.S9S_MB_2U(SCH_1):SPI_PCH_IO1   I119 @S9S_MB_2U_LIB.S9S_MB_2U(SCH_1):PAGE177
     2 SPI_SYS_MISO @S9S_MB_2U_LIB.S9S_MB_2U(SCH_1):SPI_SYS_MISO   I119 @S9S_MB_2U_LIB.S9S_MB_2U(SCH_1):PAGE177

R917 Q_RES_0402LF-0,5%,1/16W,CHIP,CA
     1 SPI_PCH_IO3 @S9S_MB_2U_LIB.S9S_MB_2U(SCH_1):SPI_PCH_IO3   I121 @S9S_MB_2U_LIB.S9S_MB_2U(SCH_1):PAGE177
     2 SPI_SYS_HOLD_IO3 @S9S_MB_2U_LIB.S9S_MB_2U(SCH_1):SPI_SYS_HOLD_IO3   I121 @S9S_MB_2U_LIB.S9S_MB_2U(SCH_1):PAGE177

R918 Q_RES_0402LF-0,5%,1/16W,CHIP,CA
     1 SPI_PCH_IO2 @S9S_MB_2U_LIB.S9S_MB_2U(SCH_1):SPI_PCH_IO2   I120 @S9S_MB_2U_LIB.S9S_MB_2U(SCH_1):PAGE177
     2 SPI_SYS_WP_IO2 @S9S_MB_2U_LIB.S9S_MB_2U(SCH_1):SPI_SYS_WP_IO2   I120 @S9S_MB_2U_LIB.S9S_MB_2U(SCH_1):PAGE177

R919 Q_RES_0402LF-10K,1%,1/16W,CHIPA
     1 P3V3_AUX @S9S_MB_2U_LIB.S9S_MB_2U(SCH_1):P3V3_AUX    I75 @S9S_MB_2U_LIB.S9S_MB_2U(SCH_1):PAGE210
     2 JTAG_PLD_JTAGEN @S9S_MB_2U_LIB.S9S_MB_2U(SCH_1):JTAG_PLD_JTAGEN    I75 @S9S_MB_2U_LIB.S9S_MB_2U(SCH_1):PAGE210

R920 Q_RES_0402LF-1K,1%,1/16W,EMPTYA
     1 JTAG_PLD_JTAGEN @S9S_MB_2U_LIB.S9S_MB_2U(SCH_1):JTAG_PLD_JTAGEN    I76 @S9S_MB_2U_LIB.S9S_MB_2U(SCH_1):PAGE210
     2    GND @S9S_MB_2U_LIB.S9S_MB_2U(SCH_1):GND    I76 @S9S_MB_2U_LIB.S9S_MB_2U(SCH_1):PAGE210

R927 Q_RES_0402LF-10K,1%,1/16W,CHIPA
     1 P3V3_AUX @S9S_MB_2U_LIB.S9S_MB_2U(SCH_1):P3V3_AUX    I61 @S9S_MB_2U_LIB.S9S_MB_2U(SCH_1):PAGE210
     2 JTAG_BMC_PLD_TDI @S9S_MB_2U_LIB.S9S_MB_2U(SCH_1):JTAG_BMC_PLD_TDI    I61 @S9S_MB_2U_LIB.S9S_MB_2U(SCH_1):PAGE210

R928 Q_RES_0402LF-10K,1%,1/16W,CHIPA
     1 P3V3_AUX @S9S_MB_2U_LIB.S9S_MB_2U(SCH_1):P3V3_AUX    I60 @S9S_MB_2U_LIB.S9S_MB_2U(SCH_1):PAGE210
     2 JTAG_BMC_PLD_TDO @S9S_MB_2U_LIB.S9S_MB_2U(SCH_1):JTAG_BMC_PLD_TDO    I60 @S9S_MB_2U_LIB.S9S_MB_2U(SCH_1):PAGE210

R929 Q_RES_0402LF-10K,1%,1/16W,CHIPA
     1 P3V3_AUX @S9S_MB_2U_LIB.S9S_MB_2U(SCH_1):P3V3_AUX    I59 @S9S_MB_2U_LIB.S9S_MB_2U(SCH_1):PAGE210
     2 JTAG_BMC_PLD_TMS @S9S_MB_2U_LIB.S9S_MB_2U(SCH_1):JTAG_BMC_PLD_TMS    I59 @S9S_MB_2U_LIB.S9S_MB_2U(SCH_1):PAGE210

R930 Q_RES_0402LF-4.7K,1%,1/16W,CHIA
     1 JTAG_BMC_PLD_TCK @S9S_MB_2U_LIB.S9S_MB_2U(SCH_1):JTAG_BMC_PLD_TCK    I63 @S9S_MB_2U_LIB.S9S_MB_2U(SCH_1):PAGE210
     2    GND @S9S_MB_2U_LIB.S9S_MB_2U(SCH_1):GND    I63 @S9S_MB_2U_LIB.S9S_MB_2U(SCH_1):PAGE210

R932 Q_RES_0402LF-10K,1%,1/16W,CHIPA
     1 RST_CPU0_DRAM_AB_N @S9S_MB_2U_LIB.S9S_MB_2U(SCH_1):RST_CPU0_DRAM_AB_N    I80 @S9S_MB_2U_LIB.S9S_MB_2U(SCH_1):PAGE128
     2    GND @S9S_MB_2U_LIB.S9S_MB_2U(SCH_1):GND    I80 @S9S_MB_2U_LIB.S9S_MB_2U(SCH_1):PAGE128

R933 Q_RES_0402LF-10K,1%,1/16W,CHIPA
     1 RST_CPU1_DRAM_AB_N @S9S_MB_2U_LIB.S9S_MB_2U(SCH_1):RST_CPU1_DRAM_AB_N    I82 @S9S_MB_2U_LIB.S9S_MB_2U(SCH_1):PAGE128
     2    GND @S9S_MB_2U_LIB.S9S_MB_2U(SCH_1):GND    I82 @S9S_MB_2U_LIB.S9S_MB_2U(SCH_1):PAGE128

R934 Q_RES_0402LF-10K,1%,1/16W,CHIPA
     1 RST_CPU0_DRAM_CD_N @S9S_MB_2U_LIB.S9S_MB_2U(SCH_1):RST_CPU0_DRAM_CD_N    I79 @S9S_MB_2U_LIB.S9S_MB_2U(SCH_1):PAGE128
     2    GND @S9S_MB_2U_LIB.S9S_MB_2U(SCH_1):GND    I79 @S9S_MB_2U_LIB.S9S_MB_2U(SCH_1):PAGE128

R935 Q_RES_0402LF-10K,1%,1/16W,CHIPA
     1 RST_CPU1_DRAM_CD_N @S9S_MB_2U_LIB.S9S_MB_2U(SCH_1):RST_CPU1_DRAM_CD_N    I86 @S9S_MB_2U_LIB.S9S_MB_2U(SCH_1):PAGE128
     2    GND @S9S_MB_2U_LIB.S9S_MB_2U(SCH_1):GND    I86 @S9S_MB_2U_LIB.S9S_MB_2U(SCH_1):PAGE128

R936 Q_RES_0402LF-10K,1%,1/16W,CHIPA
     1 RST_CPU0_DRAM_EF_N @S9S_MB_2U_LIB.S9S_MB_2U(SCH_1):RST_CPU0_DRAM_EF_N    I78 @S9S_MB_2U_LIB.S9S_MB_2U(SCH_1):PAGE128
     2    GND @S9S_MB_2U_LIB.S9S_MB_2U(SCH_1):GND    I78 @S9S_MB_2U_LIB.S9S_MB_2U(SCH_1):PAGE128

R937 Q_RES_0402LF-10K,1%,1/16W,CHIPA
     1 RST_CPU1_DRAM_EF_N @S9S_MB_2U_LIB.S9S_MB_2U(SCH_1):RST_CPU1_DRAM_EF_N    I85 @S9S_MB_2U_LIB.S9S_MB_2U(SCH_1):PAGE128
     2    GND @S9S_MB_2U_LIB.S9S_MB_2U(SCH_1):GND    I85 @S9S_MB_2U_LIB.S9S_MB_2U(SCH_1):PAGE128

R938 Q_RES_0402LF-10K,1%,1/16W,CHIPA
     1 RST_CPU0_DRAM_GH_N @S9S_MB_2U_LIB.S9S_MB_2U(SCH_1):RST_CPU0_DRAM_GH_N    I77 @S9S_MB_2U_LIB.S9S_MB_2U(SCH_1):PAGE128
     2    GND @S9S_MB_2U_LIB.S9S_MB_2U(SCH_1):GND    I77 @S9S_MB_2U_LIB.S9S_MB_2U(SCH_1):PAGE128

R939 Q_RES_0402LF-10K,1%,1/16W,CHIPA
     1 RST_CPU1_DRAM_GH_N @S9S_MB_2U_LIB.S9S_MB_2U(SCH_1):RST_CPU1_DRAM_GH_N    I83 @S9S_MB_2U_LIB.S9S_MB_2U(SCH_1):PAGE128
     2    GND @S9S_MB_2U_LIB.S9S_MB_2U(SCH_1):GND    I83 @S9S_MB_2U_LIB.S9S_MB_2U(SCH_1):PAGE128

R940 Q_RES_0402LF-10K,1%,1/16W,CHIPA
     1 P3V3_AUX @S9S_MB_2U_LIB.S9S_MB_2U(SCH_1):P3V3_AUX    I48 @S9S_MB_2U_LIB.S9S_MB_2U(SCH_1):PAGE115
     2 PWRGD_FAIL_CPU0_AB_R1 @S9S_MB_2U_LIB.S9S_MB_2U(SCH_1):PWRGD_FAIL_CPU0_AB_R1    I48 @S9S_MB_2U_LIB.S9S_MB_2U(SCH_1):PAGE115

R941 Q_RES_0402LF-10K,1%,1/16W,CHIPA
     1 P3V3_AUX @S9S_MB_2U_LIB.S9S_MB_2U(SCH_1):P3V3_AUX    I45 @S9S_MB_2U_LIB.S9S_MB_2U(SCH_1):PAGE115
     2 PWRGD_FAIL_CPU0_CD_R1 @S9S_MB_2U_LIB.S9S_MB_2U(SCH_1):PWRGD_FAIL_CPU0_CD_R1    I45 @S9S_MB_2U_LIB.S9S_MB_2U(SCH_1):PAGE115

R942 Q_RES_0402LF-10K,1%,1/16W,CHIPA
     1 P3V3_AUX @S9S_MB_2U_LIB.S9S_MB_2U(SCH_1):P3V3_AUX    I40 @S9S_MB_2U_LIB.S9S_MB_2U(SCH_1):PAGE115
     2 PWRGD_FAIL_CPU0_EF_R1 @S9S_MB_2U_LIB.S9S_MB_2U(SCH_1):PWRGD_FAIL_CPU0_EF_R1    I40 @S9S_MB_2U_LIB.S9S_MB_2U(SCH_1):PAGE115

R943 Q_RES_0402LF-10K,1%,1/16W,CHIPA
     1 P3V3_AUX @S9S_MB_2U_LIB.S9S_MB_2U(SCH_1):P3V3_AUX    I37 @S9S_MB_2U_LIB.S9S_MB_2U(SCH_1):PAGE115
     2 PWRGD_FAIL_CPU0_GH_R1 @S9S_MB_2U_LIB.S9S_MB_2U(SCH_1):PWRGD_FAIL_CPU0_GH_R1    I37 @S9S_MB_2U_LIB.S9S_MB_2U(SCH_1):PAGE115

R944 Q_RES_0402LF-10K,1%,1/16W,CHIPA
     1 P3V3_AUX @S9S_MB_2U_LIB.S9S_MB_2U(SCH_1):P3V3_AUX    I19 @S9S_MB_2U_LIB.S9S_MB_2U(SCH_1):PAGE115
     2 PWRGD_FAIL_CPU1_AB_R1 @S9S_MB_2U_LIB.S9S_MB_2U(SCH_1):PWRGD_FAIL_CPU1_AB_R1    I19 @S9S_MB_2U_LIB.S9S_MB_2U(SCH_1):PAGE115

R945 Q_RES_0402LF-10K,1%,1/16W,CHIPA
     1 P3V3_AUX @S9S_MB_2U_LIB.S9S_MB_2U(SCH_1):P3V3_AUX    I16 @S9S_MB_2U_LIB.S9S_MB_2U(SCH_1):PAGE115
     2 PWRGD_FAIL_CPU1_CD_R1 @S9S_MB_2U_LIB.S9S_MB_2U(SCH_1):PWRGD_FAIL_CPU1_CD_R1    I16 @S9S_MB_2U_LIB.S9S_MB_2U(SCH_1):PAGE115

R946 Q_RES_0402LF-10K,1%,1/16W,CHIPA
     1 P3V3_AUX @S9S_MB_2U_LIB.S9S_MB_2U(SCH_1):P3V3_AUX    I14 @S9S_MB_2U_LIB.S9S_MB_2U(SCH_1):PAGE115
     2 PWRGD_FAIL_CPU1_EF_R1 @S9S_MB_2U_LIB.S9S_MB_2U(SCH_1):PWRGD_FAIL_CPU1_EF_R1    I14 @S9S_MB_2U_LIB.S9S_MB_2U(SCH_1):PAGE115

R947 Q_RES_0402LF-10K,1%,1/16W,CHIPA
     1 P3V3_AUX @S9S_MB_2U_LIB.S9S_MB_2U(SCH_1):P3V3_AUX    I11 @S9S_MB_2U_LIB.S9S_MB_2U(SCH_1):PAGE115
     2 PWRGD_FAIL_CPU1_GH_R1 @S9S_MB_2U_LIB.S9S_MB_2U(SCH_1):PWRGD_FAIL_CPU1_GH_R1    I11 @S9S_MB_2U_LIB.S9S_MB_2U(SCH_1):PAGE115

R953 Q_RES_0402LF-4.75K,1%,1/16W,CHA
     1 CLK_CK440_SMB_ADDR0 @S9S_MB_2U_LIB.S9S_MB_2U(SCH_1):CLK_CK440_SMB_ADDR0   I282 @S9S_MB_2U_LIB.S9S_MB_2U(SCH_1):PAGE197
     2    GND @S9S_MB_2U_LIB.S9S_MB_2U(SCH_1):GND   I282 @S9S_MB_2U_LIB.S9S_MB_2U(SCH_1):PAGE197

R960 Q_RES_0402LF-33.2,1%,1/16W,CHIA
     1 SMB_PEHPCPU0_GTL_SCL @S9S_MB_2U_LIB.S9S_MB_2U(SCH_1):SMB_PEHPCPU0_GTL_SCL   I101 @S9S_MB_2U_LIB.S9S_MB_2U(SCH_1):PAGE223
     2 SMB_PEHPCPU0_GTL_R_SCL @S9S_MB_2U_LIB.S9S_MB_2U(SCH_1):SMB_PEHPCPU0_GTL_R_SCL   I101 @S9S_MB_2U_LIB.S9S_MB_2U(SCH_1):PAGE223

R961 Q_RES_0402LF-33.2,1%,1/16W,CHIA
     1 SMB_PEHPCPU1_GTL_SCL @S9S_MB_2U_LIB.S9S_MB_2U(SCH_1):SMB_PEHPCPU1_GTL_SCL    I99 @S9S_MB_2U_LIB.S9S_MB_2U(SCH_1):PAGE223
     2 SMB_PEHPCPU1_GTL_R_SCL @S9S_MB_2U_LIB.S9S_MB_2U(SCH_1):SMB_PEHPCPU1_GTL_R_SCL    I99 @S9S_MB_2U_LIB.S9S_MB_2U(SCH_1):PAGE223

R962 Q_RES_0402LF-33.2,1%,1/16W,CHIA
     1 SMB_PEHPCPU1_GTL_SDA @S9S_MB_2U_LIB.S9S_MB_2U(SCH_1):SMB_PEHPCPU1_GTL_SDA   I100 @S9S_MB_2U_LIB.S9S_MB_2U(SCH_1):PAGE223
     2 SMB_PEHPCPU1_GTL_R_SDA @S9S_MB_2U_LIB.S9S_MB_2U(SCH_1):SMB_PEHPCPU1_GTL_R_SDA   I100 @S9S_MB_2U_LIB.S9S_MB_2U(SCH_1):PAGE223

R963 Q_RES_0402LF-240,1%,1/16W,CHIPA
     1 PVNN_TERM_CPU1 @S9S_MB_2U_LIB.S9S_MB_2U(SCH_1):PVNN_TERM_CPU1    I48 @S9S_MB_2U_LIB.S9S_MB_2U(SCH_1):PAGE223
     2 SMB_PEHPCPU1_GTL_R_SCL @S9S_MB_2U_LIB.S9S_MB_2U(SCH_1):SMB_PEHPCPU1_GTL_R_SCL    I48 @S9S_MB_2U_LIB.S9S_MB_2U(SCH_1):PAGE223

R964 Q_RES_0402LF-240,1%,1/16W,CHIPA
     1 PVNN_TERM_CPU1 @S9S_MB_2U_LIB.S9S_MB_2U(SCH_1):PVNN_TERM_CPU1    I46 @S9S_MB_2U_LIB.S9S_MB_2U(SCH_1):PAGE223
     2 SMB_PEHPCPU1_GTL_R_SDA @S9S_MB_2U_LIB.S9S_MB_2U(SCH_1):SMB_PEHPCPU1_GTL_R_SDA    I46 @S9S_MB_2U_LIB.S9S_MB_2U(SCH_1):PAGE223

R965 Q_RES_0402LF-1K,1%,1/16W,CHIP,A
     1 P3V3_AUX @S9S_MB_2U_LIB.S9S_MB_2U(SCH_1):P3V3_AUX    I93 @S9S_MB_2U_LIB.S9S_MB_2U(SCH_1):PAGE223
     2 SMB_PEHPCPU0_LVC3_SCL @S9S_MB_2U_LIB.S9S_MB_2U(SCH_1):SMB_PEHPCPU0_LVC3_SCL    I93 @S9S_MB_2U_LIB.S9S_MB_2U(SCH_1):PAGE223

R966 Q_RES_0402LF-1K,1%,1/16W,CHIP,A
     1 P3V3_AUX @S9S_MB_2U_LIB.S9S_MB_2U(SCH_1):P3V3_AUX    I82 @S9S_MB_2U_LIB.S9S_MB_2U(SCH_1):PAGE223
     2 SMB_PEHPCPU1_LVC3_SCL @S9S_MB_2U_LIB.S9S_MB_2U(SCH_1):SMB_PEHPCPU1_LVC3_SCL    I82 @S9S_MB_2U_LIB.S9S_MB_2U(SCH_1):PAGE223

R967 Q_RES_0402LF-1K,1%,1/16W,CHIP,A
     1 P3V3_AUX @S9S_MB_2U_LIB.S9S_MB_2U(SCH_1):P3V3_AUX    I94 @S9S_MB_2U_LIB.S9S_MB_2U(SCH_1):PAGE223
     2 SMB_PEHPCPU0_LVC3_SDA @S9S_MB_2U_LIB.S9S_MB_2U(SCH_1):SMB_PEHPCPU0_LVC3_SDA    I94 @S9S_MB_2U_LIB.S9S_MB_2U(SCH_1):PAGE223

R968 Q_RES_0402LF-1K,1%,1/16W,CHIP,A
     1 P3V3_AUX @S9S_MB_2U_LIB.S9S_MB_2U(SCH_1):P3V3_AUX    I81 @S9S_MB_2U_LIB.S9S_MB_2U(SCH_1):PAGE223
     2 SMB_PEHPCPU1_LVC3_SDA @S9S_MB_2U_LIB.S9S_MB_2U(SCH_1):SMB_PEHPCPU1_LVC3_SDA    I81 @S9S_MB_2U_LIB.S9S_MB_2U(SCH_1):PAGE223

R969 Q_RES_0402LF-240,1%,1/16W,CHIPA
     1 PVNN_TERM_CPU0 @S9S_MB_2U_LIB.S9S_MB_2U(SCH_1):PVNN_TERM_CPU0    I43 @S9S_MB_2U_LIB.S9S_MB_2U(SCH_1):PAGE224
     2 SMB_S3M_CPU0_R_SCL @S9S_MB_2U_LIB.S9S_MB_2U(SCH_1):SMB_S3M_CPU0_R_SCL    I43 @S9S_MB_2U_LIB.S9S_MB_2U(SCH_1):PAGE224

R970 Q_RES_0402LF-240,1%,1/16W,CHIPA
     1 PVNN_TERM_CPU1 @S9S_MB_2U_LIB.S9S_MB_2U(SCH_1):PVNN_TERM_CPU1    I50 @S9S_MB_2U_LIB.S9S_MB_2U(SCH_1):PAGE224
     2 SMB_S3M_CPU1_R_SCL @S9S_MB_2U_LIB.S9S_MB_2U(SCH_1):SMB_S3M_CPU1_R_SCL    I50 @S9S_MB_2U_LIB.S9S_MB_2U(SCH_1):PAGE224

R971 Q_RES_0402LF-240,1%,1/16W,CHIPA
     1 PVNN_TERM_CPU0 @S9S_MB_2U_LIB.S9S_MB_2U(SCH_1):PVNN_TERM_CPU0    I42 @S9S_MB_2U_LIB.S9S_MB_2U(SCH_1):PAGE224
     2 SMB_S3M_CPU0_R_SDA @S9S_MB_2U_LIB.S9S_MB_2U(SCH_1):SMB_S3M_CPU0_R_SDA    I42 @S9S_MB_2U_LIB.S9S_MB_2U(SCH_1):PAGE224

R972 Q_RES_0402LF-240,1%,1/16W,CHIPA
     1 PVNN_TERM_CPU1 @S9S_MB_2U_LIB.S9S_MB_2U(SCH_1):PVNN_TERM_CPU1    I49 @S9S_MB_2U_LIB.S9S_MB_2U(SCH_1):PAGE224
     2 SMB_S3M_CPU1_R_SDA @S9S_MB_2U_LIB.S9S_MB_2U(SCH_1):SMB_S3M_CPU1_R_SDA    I49 @S9S_MB_2U_LIB.S9S_MB_2U(SCH_1):PAGE224

R977 Q_RES_0402LF-560,1%,1/16W,CHIPA
     1 P3V3_AUX @S9S_MB_2U_LIB.S9S_MB_2U(SCH_1):P3V3_AUX     I8 @S9S_MB_2U_LIB.S9S_MB_2U(SCH_1):PAGE224
     2 SMB_S3M_CPU0_3V3AUX_SCL @S9S_MB_2U_LIB.S9S_MB_2U(SCH_1):SMB_S3M_CPU0_3V3AUX_SCL     I8 @S9S_MB_2U_LIB.S9S_MB_2U(SCH_1):PAGE224

R978 Q_RES_0402LF-560,1%,1/16W,CHIPA
     1 P3V3_AUX @S9S_MB_2U_LIB.S9S_MB_2U(SCH_1):P3V3_AUX    I16 @S9S_MB_2U_LIB.S9S_MB_2U(SCH_1):PAGE224
     2 SMB_S3M_CPU1_3V3AUX_SCL @S9S_MB_2U_LIB.S9S_MB_2U(SCH_1):SMB_S3M_CPU1_3V3AUX_SCL    I16 @S9S_MB_2U_LIB.S9S_MB_2U(SCH_1):PAGE224

R979 Q_RES_0402LF-560,1%,1/16W,CHIPA
     1 P3V3_AUX @S9S_MB_2U_LIB.S9S_MB_2U(SCH_1):P3V3_AUX     I6 @S9S_MB_2U_LIB.S9S_MB_2U(SCH_1):PAGE224
     2 SMB_S3M_CPU0_3V3AUX_SDA @S9S_MB_2U_LIB.S9S_MB_2U(SCH_1):SMB_S3M_CPU0_3V3AUX_SDA     I6 @S9S_MB_2U_LIB.S9S_MB_2U(SCH_1):PAGE224

R980 Q_RES_0402LF-560,1%,1/16W,CHIPA
     1 P3V3_AUX @S9S_MB_2U_LIB.S9S_MB_2U(SCH_1):P3V3_AUX    I14 @S9S_MB_2U_LIB.S9S_MB_2U(SCH_1):PAGE224
     2 SMB_S3M_CPU1_3V3AUX_SDA @S9S_MB_2U_LIB.S9S_MB_2U(SCH_1):SMB_S3M_CPU1_3V3AUX_SDA    I14 @S9S_MB_2U_LIB.S9S_MB_2U(SCH_1):PAGE224

R981 Q_RES_0402LF-33.2,1%,1/16W,CHIA
     1 FM_PVCCIN_CPU0_R_EN @S9S_MB_2U_LIB.S9S_MB_2U(SCH_1):FM_PVCCIN_CPU0_R_EN     I9 @S9S_MB_2U_LIB.S9S_MB_2U(SCH_1):PAGE211
     2 FM_PVCCIN_CPU0_EN @S9S_MB_2U_LIB.S9S_MB_2U(SCH_1):FM_PVCCIN_CPU0_EN     I9 @S9S_MB_2U_LIB.S9S_MB_2U(SCH_1):PAGE211

R982 Q_RES_0402LF-33.2,1%,1/16W,CHIA
     1 FM_PVCCFA_EHV_CPU0_R_EN @S9S_MB_2U_LIB.S9S_MB_2U(SCH_1):FM_PVCCFA_EHV_CPU0_R_EN    I10 @S9S_MB_2U_LIB.S9S_MB_2U(SCH_1):PAGE211
     2 FM_PVCCFA_EHV_CPU0_EN @S9S_MB_2U_LIB.S9S_MB_2U(SCH_1):FM_PVCCFA_EHV_CPU0_EN    I10 @S9S_MB_2U_LIB.S9S_MB_2U(SCH_1):PAGE211

R983 Q_RES_0402LF-33.2,1%,1/16W,CHIA
     1 FM_PVCCINFAON_CPU0_R_EN @S9S_MB_2U_LIB.S9S_MB_2U(SCH_1):FM_PVCCINFAON_CPU0_R_EN    I13 @S9S_MB_2U_LIB.S9S_MB_2U(SCH_1):PAGE211
     2 FM_PVCCINFAON_CPU0_EN @S9S_MB_2U_LIB.S9S_MB_2U(SCH_1):FM_PVCCINFAON_CPU0_EN    I13 @S9S_MB_2U_LIB.S9S_MB_2U(SCH_1):PAGE211

R984 Q_RES_0402LF-33.2,1%,1/16W,CHIA
     1 FM_PVCCFA_EHV_FIVRA_CPU0_R_EN @S9S_MB_2U_LIB.S9S_MB_2U(SCH_1):FM_PVCCFA_EHV_FIVRA_CPU0_R_EN    I15 @S9S_MB_2U_LIB.S9S_MB_2U(SCH_1):PAGE211
     2 FM_PVCCFA_EHV_FIVRA_CPU0_EN @S9S_MB_2U_LIB.S9S_MB_2U(SCH_1):FM_PVCCFA_EHV_FIVRA_CPU0_EN    I15 @S9S_MB_2U_LIB.S9S_MB_2U(SCH_1):PAGE211

R985 Q_RES_0402LF-33.2,1%,1/16W,CHIA
     1 FM_PVCCIN_CPU1_R_EN @S9S_MB_2U_LIB.S9S_MB_2U(SCH_1):FM_PVCCIN_CPU1_R_EN    I21 @S9S_MB_2U_LIB.S9S_MB_2U(SCH_1):PAGE211
     2 FM_PVCCIN_CPU1_EN @S9S_MB_2U_LIB.S9S_MB_2U(SCH_1):FM_PVCCIN_CPU1_EN    I21 @S9S_MB_2U_LIB.S9S_MB_2U(SCH_1):PAGE211

R986 Q_RES_0402LF-33.2,1%,1/16W,CHIA
     1 FM_PVCCFA_EHV_CPU1_R_EN @S9S_MB_2U_LIB.S9S_MB_2U(SCH_1):FM_PVCCFA_EHV_CPU1_R_EN    I25 @S9S_MB_2U_LIB.S9S_MB_2U(SCH_1):PAGE211
     2 FM_PVCCFA_EHV_CPU1_EN @S9S_MB_2U_LIB.S9S_MB_2U(SCH_1):FM_PVCCFA_EHV_CPU1_EN    I25 @S9S_MB_2U_LIB.S9S_MB_2U(SCH_1):PAGE211

R987 Q_RES_0402LF-33.2,1%,1/16W,CHIA
     1 FM_PVCCINFAON_CPU1_R_EN @S9S_MB_2U_LIB.S9S_MB_2U(SCH_1):FM_PVCCINFAON_CPU1_R_EN    I24 @S9S_MB_2U_LIB.S9S_MB_2U(SCH_1):PAGE211
     2 FM_PVCCINFAON_CPU1_EN @S9S_MB_2U_LIB.S9S_MB_2U(SCH_1):FM_PVCCINFAON_CPU1_EN    I24 @S9S_MB_2U_LIB.S9S_MB_2U(SCH_1):PAGE211

R988 Q_RES_0402LF-33.2,1%,1/16W,CHIA
     1 FM_PVCCFA_EHV_FIVRA_CPU1_R_EN @S9S_MB_2U_LIB.S9S_MB_2U(SCH_1):FM_PVCCFA_EHV_FIVRA_CPU1_R_EN    I23 @S9S_MB_2U_LIB.S9S_MB_2U(SCH_1):PAGE211
     2 FM_PVCCFA_EHV_FIVRA_CPU1_EN @S9S_MB_2U_LIB.S9S_MB_2U(SCH_1):FM_PVCCFA_EHV_FIVRA_CPU1_EN    I23 @S9S_MB_2U_LIB.S9S_MB_2U(SCH_1):PAGE211

R990 Q_RES_0402LF-2K,1%,1/16W,CHIP,A
     1 FM_PLD_CLK_25M_R_EN @S9S_MB_2U_LIB.S9S_MB_2U(SCH_1):FM_PLD_CLK_25M_R_EN    I18 @S9S_MB_2U_LIB.S9S_MB_2U(SCH_1):PAGE208
     2    GND @S9S_MB_2U_LIB.S9S_MB_2U(SCH_1):GND    I18 @S9S_MB_2U_LIB.S9S_MB_2U(SCH_1):PAGE208

R991 Q_RES_0402LF-2K,1%,1/16W,CHIP,A
     1 FM_AUX_SW_EN @S9S_MB_2U_LIB.S9S_MB_2U(SCH_1):FM_AUX_SW_EN    I20 @S9S_MB_2U_LIB.S9S_MB_2U(SCH_1):PAGE208
     2    GND @S9S_MB_2U_LIB.S9S_MB_2U(SCH_1):GND    I20 @S9S_MB_2U_LIB.S9S_MB_2U(SCH_1):PAGE208

R992 Q_RES_0402LF-2K,1%,1/16W,EMPTYA
     1 PWRGD_CPU0_LVC1_R @S9S_MB_2U_LIB.S9S_MB_2U(SCH_1):PWRGD_CPU0_LVC1_R    I21 @S9S_MB_2U_LIB.S9S_MB_2U(SCH_1):PAGE208
     2    GND @S9S_MB_2U_LIB.S9S_MB_2U(SCH_1):GND    I21 @S9S_MB_2U_LIB.S9S_MB_2U(SCH_1):PAGE208

R993 Q_RES_0402LF-33.2,1%,1/16W,CHIA
     1 SMB_S3M_CPU0_SCL @S9S_MB_2U_LIB.S9S_MB_2U(SCH_1):SMB_S3M_CPU0_SCL    I44 @S9S_MB_2U_LIB.S9S_MB_2U(SCH_1):PAGE224
     2 SMB_S3M_CPU0_R_SCL @S9S_MB_2U_LIB.S9S_MB_2U(SCH_1):SMB_S3M_CPU0_R_SCL    I44 @S9S_MB_2U_LIB.S9S_MB_2U(SCH_1):PAGE224

R994 Q_RES_0402LF-33.2,1%,1/16W,CHIA
     1 SMB_S3M_CPU0_SDA @S9S_MB_2U_LIB.S9S_MB_2U(SCH_1):SMB_S3M_CPU0_SDA   I142 @S9S_MB_2U_LIB.S9S_MB_2U(SCH_1):PAGE224
     2 SMB_S3M_CPU0_R_SDA @S9S_MB_2U_LIB.S9S_MB_2U(SCH_1):SMB_S3M_CPU0_R_SDA   I142 @S9S_MB_2U_LIB.S9S_MB_2U(SCH_1):PAGE224

R995 Q_RES_0402LF-33.2,1%,1/16W,CHIA
     1 SMB_S3M_CPU1_SCL @S9S_MB_2U_LIB.S9S_MB_2U(SCH_1):SMB_S3M_CPU1_SCL    I51 @S9S_MB_2U_LIB.S9S_MB_2U(SCH_1):PAGE224
     2 SMB_S3M_CPU1_R_SCL @S9S_MB_2U_LIB.S9S_MB_2U(SCH_1):SMB_S3M_CPU1_R_SCL    I51 @S9S_MB_2U_LIB.S9S_MB_2U(SCH_1):PAGE224

R996 Q_RES_0402LF-33.2,1%,1/16W,CHIA
     1 SMB_S3M_CPU1_SDA @S9S_MB_2U_LIB.S9S_MB_2U(SCH_1):SMB_S3M_CPU1_SDA   I143 @S9S_MB_2U_LIB.S9S_MB_2U(SCH_1):PAGE224
     2 SMB_S3M_CPU1_R_SDA @S9S_MB_2U_LIB.S9S_MB_2U(SCH_1):SMB_S3M_CPU1_R_SDA   I143 @S9S_MB_2U_LIB.S9S_MB_2U(SCH_1):PAGE224

R997 Q_RES_0402LF-10K,1%,1/16W,EMPTA
     1 PU_PIROM_CPU0_SM_WP @S9S_MB_2U_LIB.S9S_MB_2U(SCH_1):PU_PIROM_CPU0_SM_WP    I31 @S9S_MB_2U_LIB.S9S_MB_2U(SCH_1):PAGE127
     2    GND @S9S_MB_2U_LIB.S9S_MB_2U(SCH_1):GND    I31 @S9S_MB_2U_LIB.S9S_MB_2U(SCH_1):PAGE127

R998 Q_RES_0402LF-0,5%,1/16W,CHIP,CA
     1 FM_SMB_PEHPCPU0_PCIE_ALERT_N @S9S_MB_2U_LIB.S9S_MB_2U(SCH_1):FM_SMB_PEHPCPU0_PCIE_ALERT_N    I53 @S9S_MB_2U_LIB.S9S_MB_2U(SCH_1):PAGE223
     2 FM_SMB_PEHPCPU0_PCIE_ALERT_R_N @S9S_MB_2U_LIB.S9S_MB_2U(SCH_1):FM_SMB_PEHPCPU0_PCIE_ALERT_R_N    I53 @S9S_MB_2U_LIB.S9S_MB_2U(SCH_1):PAGE223

R999 Q_RES_0402LF-0,5%,1/16W,CHIP,CA
     1 FM_SMB_PEHPCPU1_PCIE_ALERT_N @S9S_MB_2U_LIB.S9S_MB_2U(SCH_1):FM_SMB_PEHPCPU1_PCIE_ALERT_N    I69 @S9S_MB_2U_LIB.S9S_MB_2U(SCH_1):PAGE223
     2 FM_SMB_PEHPCPU1_PCIE_ALERT_R_N @S9S_MB_2U_LIB.S9S_MB_2U(SCH_1):FM_SMB_PEHPCPU1_PCIE_ALERT_R_N    I69 @S9S_MB_2U_LIB.S9S_MB_2U(SCH_1):PAGE223

R1000 Q_RES_0402LF-4.7K,5%,1/16W,CHIA
     1   P3V3 @S9S_MB_2U_LIB.S9S_MB_2U(SCH_1):P3V3    I52 @S9S_MB_2U_LIB.S9S_MB_2U(SCH_1):PAGE223
     2 FM_SMB_PEHPCPU0_PCIE_ALERT_R_N @S9S_MB_2U_LIB.S9S_MB_2U(SCH_1):FM_SMB_PEHPCPU0_PCIE_ALERT_R_N    I52 @S9S_MB_2U_LIB.S9S_MB_2U(SCH_1):PAGE223

R1001 Q_RES_0402LF-4.7K,5%,1/16W,CHIA
     1   P3V3 @S9S_MB_2U_LIB.S9S_MB_2U(SCH_1):P3V3    I55 @S9S_MB_2U_LIB.S9S_MB_2U(SCH_1):PAGE223
     2 FM_SMB_PEHPCPU1_PCIE_ALERT_R_N @S9S_MB_2U_LIB.S9S_MB_2U(SCH_1):FM_SMB_PEHPCPU1_PCIE_ALERT_R_N    I55 @S9S_MB_2U_LIB.S9S_MB_2U(SCH_1):PAGE223

R1002 Q_RES_0402LF-4.7K,5%,1/16W,CHIA
     1   P3V3 @S9S_MB_2U_LIB.S9S_MB_2U(SCH_1):P3V3    I34 @S9S_MB_2U_LIB.S9S_MB_2U(SCH_1):PAGE223
     2 FM_SMB_CPU0_ALERT_R1 @S9S_MB_2U_LIB.S9S_MB_2U(SCH_1):FM_SMB_CPU0_ALERT_R1    I34 @S9S_MB_2U_LIB.S9S_MB_2U(SCH_1):PAGE223

R1003 Q_RES_0402LF-4.7K,5%,1/16W,CHIA
     1   P3V3 @S9S_MB_2U_LIB.S9S_MB_2U(SCH_1):P3V3    I38 @S9S_MB_2U_LIB.S9S_MB_2U(SCH_1):PAGE223
     2 FM_SMB_CPU1_ALERT_R1 @S9S_MB_2U_LIB.S9S_MB_2U(SCH_1):FM_SMB_CPU1_ALERT_R1    I38 @S9S_MB_2U_LIB.S9S_MB_2U(SCH_1):PAGE223

R1004 Q_RES_0402LF-1K,1%,1/16W,CHIP,A
     1 P3V3_AUX @S9S_MB_2U_LIB.S9S_MB_2U(SCH_1):P3V3_AUX    I35 @S9S_MB_2U_LIB.S9S_MB_2U(SCH_1):PAGE127
     2 PU_PIROM_CPU1_SM_WP @S9S_MB_2U_LIB.S9S_MB_2U(SCH_1):PU_PIROM_CPU1_SM_WP    I35 @S9S_MB_2U_LIB.S9S_MB_2U(SCH_1):PAGE127

R1005 Q_RES_0402LF-10K,1%,1/16W,EMPTA
     1 PU_PIROM_CPU1_SM_WP @S9S_MB_2U_LIB.S9S_MB_2U(SCH_1):PU_PIROM_CPU1_SM_WP    I36 @S9S_MB_2U_LIB.S9S_MB_2U(SCH_1):PAGE127
     2    GND @S9S_MB_2U_LIB.S9S_MB_2U(SCH_1):GND    I36 @S9S_MB_2U_LIB.S9S_MB_2U(SCH_1):PAGE127

R1006 Q_RES_0402LF-4.7K,5%,1/16W,CHIA
     1 PVNN_TERM_CPU0 @S9S_MB_2U_LIB.S9S_MB_2U(SCH_1):PVNN_TERM_CPU0     I8 @S9S_MB_2U_LIB.S9S_MB_2U(SCH_1):PAGE223
     2 FM_PEHPCPU0_ALERT_N @S9S_MB_2U_LIB.S9S_MB_2U(SCH_1):FM_PEHPCPU0_ALERT_N     I8 @S9S_MB_2U_LIB.S9S_MB_2U(SCH_1):PAGE223

R1007 Q_RES_0402LF-4.7K,5%,1/16W,CHIA
     1 PVNN_TERM_CPU1 @S9S_MB_2U_LIB.S9S_MB_2U(SCH_1):PVNN_TERM_CPU1    I12 @S9S_MB_2U_LIB.S9S_MB_2U(SCH_1):PAGE223
     2 FM_PEHPCPU1_ALERT_N @S9S_MB_2U_LIB.S9S_MB_2U(SCH_1):FM_PEHPCPU1_ALERT_N    I12 @S9S_MB_2U_LIB.S9S_MB_2U(SCH_1):PAGE223

R1008 Q_RES_0402LF-1K,1%,1/16W,EMPTYA
     1 PVNN_TERM_CPU1 @S9S_MB_2U_LIB.S9S_MB_2U(SCH_1):PVNN_TERM_CPU1   I139 @S9S_MB_2U_LIB.S9S_MB_2U(SCH_1):PAGE119
     2 PU_TAP_ODT_CPU1_EN @S9S_MB_2U_LIB.S9S_MB_2U(SCH_1):PU_TAP_ODT_CPU1_EN   I139 @S9S_MB_2U_LIB.S9S_MB_2U(SCH_1):PAGE119

R1009 Q_RES_0402LF-1K,1%,1/16W,EMPTYA
     1 PVNN_TERM_CPU0 @S9S_MB_2U_LIB.S9S_MB_2U(SCH_1):PVNN_TERM_CPU0   I136 @S9S_MB_2U_LIB.S9S_MB_2U(SCH_1):PAGE119
     2 PU_TAP_ODT_CPU0_EN @S9S_MB_2U_LIB.S9S_MB_2U(SCH_1):PU_TAP_ODT_CPU0_EN   I136 @S9S_MB_2U_LIB.S9S_MB_2U(SCH_1):PAGE119

R1010 Q_RES_0402LF-0,5%,1/16W,CHIP,CA
     1 CLK_25M_CK440_ISCLK_REF_DP @S9S_MB_2U_LIB.S9S_MB_2U(SCH_1):CLK_25M_CK440_ISCLK_REF_DP     I8 @S9S_MB_2U_LIB.S9S_MB_2U(SCH_1):PAGE198
     2 CLK_25M_PCH_REF_NS_DP @S9S_MB_2U_LIB.S9S_MB_2U(SCH_1):CLK_25M_PCH_REF_NS_DP     I8 @S9S_MB_2U_LIB.S9S_MB_2U(SCH_1):PAGE198

R1011 Q_RES_0402LF-0,5%,1/16W,CHIP,CA
     1 CLK_25M_CK440_ISCLK_REF_DN @S9S_MB_2U_LIB.S9S_MB_2U(SCH_1):CLK_25M_CK440_ISCLK_REF_DN     I7 @S9S_MB_2U_LIB.S9S_MB_2U(SCH_1):PAGE198
     2 CLK_25M_PCH_REF_NS_DN @S9S_MB_2U_LIB.S9S_MB_2U(SCH_1):CLK_25M_PCH_REF_NS_DN     I7 @S9S_MB_2U_LIB.S9S_MB_2U(SCH_1):PAGE198

R1012 Q_RES_0402LF-0,5%,1/16W,CHIP,CA
     1 CLK_25M_CK440_CPU0_DP @S9S_MB_2U_LIB.S9S_MB_2U(SCH_1):CLK_25M_CK440_CPU0_DP    I22 @S9S_MB_2U_LIB.S9S_MB_2U(SCH_1):PAGE198
     2 CLK_25M_CK440_CPU0_R_DP @S9S_MB_2U_LIB.S9S_MB_2U(SCH_1):CLK_25M_CK440_CPU0_R_DP    I22 @S9S_MB_2U_LIB.S9S_MB_2U(SCH_1):PAGE198

R1013 Q_RES_0402LF-0,5%,1/16W,EMPTY,A
     1 CLK_25M_PCH_CPU0_DP @S9S_MB_2U_LIB.S9S_MB_2U(SCH_1):CLK_25M_PCH_CPU0_DP    I21 @S9S_MB_2U_LIB.S9S_MB_2U(SCH_1):PAGE198
     2 CLK_25M_NSSC_CPU0_DP @S9S_MB_2U_LIB.S9S_MB_2U(SCH_1):CLK_25M_NSSC_CPU0_DP    I21 @S9S_MB_2U_LIB.S9S_MB_2U(SCH_1):PAGE198

R1014 Q_RES_0402LF-0,5%,1/16W,CHIP,CA
     1 CLK_25M_CK440_CPU0_DN @S9S_MB_2U_LIB.S9S_MB_2U(SCH_1):CLK_25M_CK440_CPU0_DN    I20 @S9S_MB_2U_LIB.S9S_MB_2U(SCH_1):PAGE198
     2 CLK_25M_CK440_CPU0_R_DN @S9S_MB_2U_LIB.S9S_MB_2U(SCH_1):CLK_25M_CK440_CPU0_R_DN    I20 @S9S_MB_2U_LIB.S9S_MB_2U(SCH_1):PAGE198

R1015 Q_RES_0402LF-0,5%,1/16W,EMPTY,A
     1 CLK_25M_PCH_CPU0_DN @S9S_MB_2U_LIB.S9S_MB_2U(SCH_1):CLK_25M_PCH_CPU0_DN    I19 @S9S_MB_2U_LIB.S9S_MB_2U(SCH_1):PAGE198
     2 CLK_25M_NSSC_CPU0_DN @S9S_MB_2U_LIB.S9S_MB_2U(SCH_1):CLK_25M_NSSC_CPU0_DN    I19 @S9S_MB_2U_LIB.S9S_MB_2U(SCH_1):PAGE198

R1016 Q_RES_0402LF-0,5%,1/16W,CHIP,CA
     1 CLK_25M_CK440_CPU1_DP @S9S_MB_2U_LIB.S9S_MB_2U(SCH_1):CLK_25M_CK440_CPU1_DP    I12 @S9S_MB_2U_LIB.S9S_MB_2U(SCH_1):PAGE198
     2 CLK_25M_CK440_CPU1_R_DP @S9S_MB_2U_LIB.S9S_MB_2U(SCH_1):CLK_25M_CK440_CPU1_R_DP    I12 @S9S_MB_2U_LIB.S9S_MB_2U(SCH_1):PAGE198

R1017 Q_RES_0402LF-0,5%,1/16W,EMPTY,A
     1 CLK_25M_PCH_CPU1_DP @S9S_MB_2U_LIB.S9S_MB_2U(SCH_1):CLK_25M_PCH_CPU1_DP    I11 @S9S_MB_2U_LIB.S9S_MB_2U(SCH_1):PAGE198
     2 CLK_25M_NSSC_CPU1_DP @S9S_MB_2U_LIB.S9S_MB_2U(SCH_1):CLK_25M_NSSC_CPU1_DP    I11 @S9S_MB_2U_LIB.S9S_MB_2U(SCH_1):PAGE198

R1018 Q_RES_0402LF-0,5%,1/16W,CHIP,CA
     1 CLK_25M_CK440_CPU1_DN @S9S_MB_2U_LIB.S9S_MB_2U(SCH_1):CLK_25M_CK440_CPU1_DN    I10 @S9S_MB_2U_LIB.S9S_MB_2U(SCH_1):PAGE198
     2 CLK_25M_CK440_CPU1_R_DN @S9S_MB_2U_LIB.S9S_MB_2U(SCH_1):CLK_25M_CK440_CPU1_R_DN    I10 @S9S_MB_2U_LIB.S9S_MB_2U(SCH_1):PAGE198

R1019 Q_RES_0402LF-0,5%,1/16W,EMPTY,A
     1 CLK_25M_PCH_CPU1_DN @S9S_MB_2U_LIB.S9S_MB_2U(SCH_1):CLK_25M_PCH_CPU1_DN     I9 @S9S_MB_2U_LIB.S9S_MB_2U(SCH_1):PAGE198
     2 CLK_25M_NSSC_CPU1_DN @S9S_MB_2U_LIB.S9S_MB_2U(SCH_1):CLK_25M_NSSC_CPU1_DN     I9 @S9S_MB_2U_LIB.S9S_MB_2U(SCH_1):PAGE198

R1020 Q_RES_0402LF-0,5%,1/16W,CHIP,CA
     1 CLK_25M_CK440_CPU0_R_DP @S9S_MB_2U_LIB.S9S_MB_2U(SCH_1):CLK_25M_CK440_CPU0_R_DP    I30 @S9S_MB_2U_LIB.S9S_MB_2U(SCH_1):PAGE198
     2 CLK_25M_NSSC_CPU0_DP @S9S_MB_2U_LIB.S9S_MB_2U(SCH_1):CLK_25M_NSSC_CPU0_DP    I30 @S9S_MB_2U_LIB.S9S_MB_2U(SCH_1):PAGE198

R1021 Q_RES_0402LF-0,5%,1/16W,CHIP,CA
     1 CLK_25M_CK440_CPU0_R_DN @S9S_MB_2U_LIB.S9S_MB_2U(SCH_1):CLK_25M_CK440_CPU0_R_DN    I29 @S9S_MB_2U_LIB.S9S_MB_2U(SCH_1):PAGE198
     2 CLK_25M_NSSC_CPU0_DN @S9S_MB_2U_LIB.S9S_MB_2U(SCH_1):CLK_25M_NSSC_CPU0_DN    I29 @S9S_MB_2U_LIB.S9S_MB_2U(SCH_1):PAGE198

R1022 Q_RES_0402LF-0,5%,1/16W,CHIP,CA
     1 CLK_25M_CK440_CPU1_R_DP @S9S_MB_2U_LIB.S9S_MB_2U(SCH_1):CLK_25M_CK440_CPU1_R_DP    I28 @S9S_MB_2U_LIB.S9S_MB_2U(SCH_1):PAGE198
     2 CLK_25M_NSSC_CPU1_DP @S9S_MB_2U_LIB.S9S_MB_2U(SCH_1):CLK_25M_NSSC_CPU1_DP    I28 @S9S_MB_2U_LIB.S9S_MB_2U(SCH_1):PAGE198

R1023 Q_RES_0402LF-0,5%,1/16W,CHIP,CA
     1 CLK_25M_CK440_CPU1_R_DN @S9S_MB_2U_LIB.S9S_MB_2U(SCH_1):CLK_25M_CK440_CPU1_R_DN    I27 @S9S_MB_2U_LIB.S9S_MB_2U(SCH_1):PAGE198
     2 CLK_25M_NSSC_CPU1_DN @S9S_MB_2U_LIB.S9S_MB_2U(SCH_1):CLK_25M_NSSC_CPU1_DN    I27 @S9S_MB_2U_LIB.S9S_MB_2U(SCH_1):PAGE198

R1024 Q_RES_0402LF-100,1%,1/16W,CHIPA
     1 JTAG_DBP_TCK_PCH @S9S_MB_2U_LIB.S9S_MB_2U(SCH_1):JTAG_DBP_TCK_PCH    I41 @S9S_MB_2U_LIB.S9S_MB_2U(SCH_1):PAGE174
     2    GND @S9S_MB_2U_LIB.S9S_MB_2U(SCH_1):GND    I41 @S9S_MB_2U_LIB.S9S_MB_2U(SCH_1):PAGE174

R1025 Q_RES_0402LF-75,1%,1/16W,EMPTYA
     1 JTAG_DBP_CPU_GTL_TCK @S9S_MB_2U_LIB.S9S_MB_2U(SCH_1):JTAG_DBP_CPU_GTL_TCK    I38 @S9S_MB_2U_LIB.S9S_MB_2U(SCH_1):PAGE174
     2    GND @S9S_MB_2U_LIB.S9S_MB_2U(SCH_1):GND    I38 @S9S_MB_2U_LIB.S9S_MB_2U(SCH_1):PAGE174

R1026 Q_RES_0402LF-1K,1%,1/16W,CHIP,A
     1 JTAG_DBP_PMODE @S9S_MB_2U_LIB.S9S_MB_2U(SCH_1):JTAG_DBP_PMODE    I37 @S9S_MB_2U_LIB.S9S_MB_2U(SCH_1):PAGE174
     2 P1V05_PCH_AUX @S9S_MB_2U_LIB.S9S_MB_2U(SCH_1):P1V05_PCH_AUX    I37 @S9S_MB_2U_LIB.S9S_MB_2U(SCH_1):PAGE174

R1044 Q_RES_0402LF-130,1%,1/16W,CHIPA
     1 LED_PWRGD_CPUPWRGD_GTL @S9S_MB_2U_LIB.S9S_MB_2U(SCH_1):LED_PWRGD_CPUPWRGD_GTL    I40 @S9S_MB_2U_LIB.S9S_MB_2U(SCH_1):PAGE241
     2 P3V3_AUX @S9S_MB_2U_LIB.S9S_MB_2U(SCH_1):P3V3_AUX    I40 @S9S_MB_2U_LIB.S9S_MB_2U(SCH_1):PAGE241

R1089 Q_RES_0402LF-2.2K,5%,1/16W,CHIA
     1 P3V3_AUX @S9S_MB_2U_LIB.S9S_MB_2U(SCH_1):P3V3_AUX    I21 @S9S_MB_2U_LIB.S9S_MB_2U(SCH_1):PAGE219
     2 SMB_SENSOR_M2_P0_3V3AUX_SCL @S9S_MB_2U_LIB.S9S_MB_2U(SCH_1):SMB_SENSOR_M2_P0_3V3AUX_SCL    I21 @S9S_MB_2U_LIB.S9S_MB_2U(SCH_1):PAGE219

R1090 Q_RES_0402LF-2.2K,5%,1/16W,CHIA
     1 P3V3_AUX @S9S_MB_2U_LIB.S9S_MB_2U(SCH_1):P3V3_AUX    I20 @S9S_MB_2U_LIB.S9S_MB_2U(SCH_1):PAGE219
     2 SMB_SENSOR_M2_P0_3V3AUX_SDA @S9S_MB_2U_LIB.S9S_MB_2U(SCH_1):SMB_SENSOR_M2_P0_3V3AUX_SDA    I20 @S9S_MB_2U_LIB.S9S_MB_2U(SCH_1):PAGE219

R1099 Q_RES_0402LF-10K,1%,1/16W,CHIPA
     1 P3V3_AUX @S9S_MB_2U_LIB.S9S_MB_2U(SCH_1):P3V3_AUX   I129 @S9S_MB_2U_LIB.S9S_MB_2U(SCH_1):PAGE313
     2 PU_CLK25M_OSC_FPGA_EN @S9S_MB_2U_LIB.S9S_MB_2U(SCH_1):PU_CLK25M_OSC_FPGA_EN   I129 @S9S_MB_2U_LIB.S9S_MB_2U(SCH_1):PAGE313

R1100 Q_RES_0402LF-33.2,1%,1/16W,CHIA
     1 CLK_25M_OSC_FPGA_R @S9S_MB_2U_LIB.S9S_MB_2U(SCH_1):CLK_25M_OSC_FPGA_R   I115 @S9S_MB_2U_LIB.S9S_MB_2U(SCH_1):PAGE313
     2 CLK_25M_OSC_MAIN_FPGA @S9S_MB_2U_LIB.S9S_MB_2U(SCH_1):CLK_25M_OSC_MAIN_FPGA   I115 @S9S_MB_2U_LIB.S9S_MB_2U(SCH_1):PAGE313

R1106 Q_RES_0402LF-10K,1%,1/16W,CHIPA
     1 P3V3_AUX @S9S_MB_2U_LIB.S9S_MB_2U(SCH_1):P3V3_AUX     I5 @S9S_MB_2U_LIB.S9S_MB_2U(SCH_1):PAGE312
     2 FM_PLD_REV_R_N @S9S_MB_2U_LIB.S9S_MB_2U(SCH_1):FM_PLD_REV_R_N     I5 @S9S_MB_2U_LIB.S9S_MB_2U(SCH_1):PAGE312

R1117 Q_RES_0402LF-6.19K,1%,1/16W,CHA
     1 MB0_P12V_STBY_PWRGD @S9S_MB_2U_LIB.S9S_MB_2U(SCH_1):MB0_P12V_STBY_PWRGD    I61 @S9S_MB_2U_LIB.S9S_MB_2U(SCH_1):PAGE303
     2 AGND_HSC @S9S_MB_2U_LIB.S9S_MB_2U(SCH_1):AGND_HSC    I61 @S9S_MB_2U_LIB.S9S_MB_2U(SCH_1):PAGE303

R1123 Q_RES_0402LF-1K,1%,1/16W,EMPTYA
     1 P3V3_AUX @S9S_MB_2U_LIB.S9S_MB_2U(SCH_1):P3V3_AUX   I142 @S9S_MB_2U_LIB.S9S_MB_2U(SCH_1):PAGE154
     2 PD_SMB_OCP1_HP_ADD2 @S9S_MB_2U_LIB.S9S_MB_2U(SCH_1):PD_SMB_OCP1_HP_ADD2   I142 @S9S_MB_2U_LIB.S9S_MB_2U(SCH_1):PAGE154

R1124 Q_RES_0402LF-1K,1%,1/16W,CHIP,A
     1 PD_SMB_OCP1_HP_ADD2 @S9S_MB_2U_LIB.S9S_MB_2U(SCH_1):PD_SMB_OCP1_HP_ADD2   I143 @S9S_MB_2U_LIB.S9S_MB_2U(SCH_1):PAGE154
     2    GND @S9S_MB_2U_LIB.S9S_MB_2U(SCH_1):GND   I143 @S9S_MB_2U_LIB.S9S_MB_2U(SCH_1):PAGE154

R1126 Q_RES_0402LF-1K,1%,1/16W,CHIP,A
     1 PD_SMB_OCP1_HP_ADD1 @S9S_MB_2U_LIB.S9S_MB_2U(SCH_1):PD_SMB_OCP1_HP_ADD1   I140 @S9S_MB_2U_LIB.S9S_MB_2U(SCH_1):PAGE154
     2    GND @S9S_MB_2U_LIB.S9S_MB_2U(SCH_1):GND   I140 @S9S_MB_2U_LIB.S9S_MB_2U(SCH_1):PAGE154

R1127 Q_RES_0402LF-1K,1%,1/16W,EMPTYA
     1 P3V3_AUX @S9S_MB_2U_LIB.S9S_MB_2U(SCH_1):P3V3_AUX   I133 @S9S_MB_2U_LIB.S9S_MB_2U(SCH_1):PAGE154
     2 PD_SMB_OCP1_HP_ADD0 @S9S_MB_2U_LIB.S9S_MB_2U(SCH_1):PD_SMB_OCP1_HP_ADD0   I133 @S9S_MB_2U_LIB.S9S_MB_2U(SCH_1):PAGE154

R1128 Q_RES_0402LF-1K,1%,1/16W,CHIP,A
     1 PD_SMB_OCP1_HP_ADD0 @S9S_MB_2U_LIB.S9S_MB_2U(SCH_1):PD_SMB_OCP1_HP_ADD0   I137 @S9S_MB_2U_LIB.S9S_MB_2U(SCH_1):PAGE154
     2    GND @S9S_MB_2U_LIB.S9S_MB_2U(SCH_1):GND   I137 @S9S_MB_2U_LIB.S9S_MB_2U(SCH_1):PAGE154

R1129 Q_RES_0402LF-1K,1%,1/16W,CHIP,A
     1 P3V3_AUX @S9S_MB_2U_LIB.S9S_MB_2U(SCH_1):P3V3_AUX   I172 @S9S_MB_2U_LIB.S9S_MB_2U(SCH_1):PAGE154
     2 HP_LVC3_OCP_V3_1_PRSNT2 @S9S_MB_2U_LIB.S9S_MB_2U(SCH_1):HP_LVC3_OCP_V3_1_PRSNT2   I172 @S9S_MB_2U_LIB.S9S_MB_2U(SCH_1):PAGE154

R1130 Q_RES_0402LF-33.2,1%,1/16W,CHIA
     1 SMB_PEHPCPU0_LVC3_SCL @S9S_MB_2U_LIB.S9S_MB_2U(SCH_1):SMB_PEHPCPU0_LVC3_SCL   I130 @S9S_MB_2U_LIB.S9S_MB_2U(SCH_1):PAGE154
     2 SMB_PEHPCPU0_LVC3_R_SCL @S9S_MB_2U_LIB.S9S_MB_2U(SCH_1):SMB_PEHPCPU0_LVC3_R_SCL   I130 @S9S_MB_2U_LIB.S9S_MB_2U(SCH_1):PAGE154

R1131 Q_RES_0402LF-33.2,1%,1/16W,CHIA
     1 SMB_PEHPCPU0_LVC3_SDA @S9S_MB_2U_LIB.S9S_MB_2U(SCH_1):SMB_PEHPCPU0_LVC3_SDA   I131 @S9S_MB_2U_LIB.S9S_MB_2U(SCH_1):PAGE154
     2 SMB_PEHPCPU0_LVC3_R_SDA @S9S_MB_2U_LIB.S9S_MB_2U(SCH_1):SMB_PEHPCPU0_LVC3_R_SDA   I131 @S9S_MB_2U_LIB.S9S_MB_2U(SCH_1):PAGE154

R1132 Q_RES_0402LF-1K,1%,1/16W,EMPTYA
     1 P3V3_AUX @S9S_MB_2U_LIB.S9S_MB_2U(SCH_1):P3V3_AUX    I95 @S9S_MB_2U_LIB.S9S_MB_2U(SCH_1):PAGE132
     2 HP_OCP_V3_2_RST_R @S9S_MB_2U_LIB.S9S_MB_2U(SCH_1):HP_OCP_V3_2_RST_R    I95 @S9S_MB_2U_LIB.S9S_MB_2U(SCH_1):PAGE132

R1138 Q_RES_0402LF-10K,1%,1/16W,CHIPA
     1 P3V3_AUX @S9S_MB_2U_LIB.S9S_MB_2U(SCH_1):P3V3_AUX    I61 @S9S_MB_2U_LIB.S9S_MB_2U(SCH_1):PAGE152
     2 CLK_50M_EN @S9S_MB_2U_LIB.S9S_MB_2U(SCH_1):CLK_50M_EN    I61 @S9S_MB_2U_LIB.S9S_MB_2U(SCH_1):PAGE152

R1139 Q_RES_0402LF-0,5%,1/16W,CHIP,CA
     1 CLK_50M_RMII @S9S_MB_2U_LIB.S9S_MB_2U(SCH_1):CLK_50M_RMII    I56 @S9S_MB_2U_LIB.S9S_MB_2U(SCH_1):PAGE152
     2 CLK_50M_RMII_R @S9S_MB_2U_LIB.S9S_MB_2U(SCH_1):CLK_50M_RMII_R    I56 @S9S_MB_2U_LIB.S9S_MB_2U(SCH_1):PAGE152

R1140 Q_RES_0402LF-27.4,1%,1/16W,CHIA
     1 CLK_50M_BMC_MAC_R @S9S_MB_2U_LIB.S9S_MB_2U(SCH_1):CLK_50M_BMC_MAC_R    I52 @S9S_MB_2U_LIB.S9S_MB_2U(SCH_1):PAGE152
     2 CLK_50M_RMII_BMC_OCP @S9S_MB_2U_LIB.S9S_MB_2U(SCH_1):CLK_50M_RMII_BMC_OCP    I52 @S9S_MB_2U_LIB.S9S_MB_2U(SCH_1):PAGE152

R1141 Q_RES_0402LF-27.4,1%,1/16W,CHIA
     1 CLK_50M_NCSI_OCP_1 @S9S_MB_2U_LIB.S9S_MB_2U(SCH_1):CLK_50M_NCSI_OCP_1    I53 @S9S_MB_2U_LIB.S9S_MB_2U(SCH_1):PAGE152
     2 CLK_50M_NCSI_OCP_SFF @S9S_MB_2U_LIB.S9S_MB_2U(SCH_1):CLK_50M_NCSI_OCP_SFF    I53 @S9S_MB_2U_LIB.S9S_MB_2U(SCH_1):PAGE152

R1147 Q_RES_0402LF-0,5%,1/16W,CHIP,CA
     1 HP_LVC3_OCP_V3_1_PRSNT2_N_R @S9S_MB_2U_LIB.S9S_MB_2U(SCH_1):HP_LVC3_OCP_V3_1_PRSNT2_N_R    I47 @S9S_MB_2U_LIB.S9S_MB_2U(SCH_1):PAGE153
     2 HP_LVC3_OCP_V3_1_ATTN_OUT_SW_N @S9S_MB_2U_LIB.S9S_MB_2U(SCH_1):HP_LVC3_OCP_V3_1_ATTN_OUT_SW_N    I47 @S9S_MB_2U_LIB.S9S_MB_2U(SCH_1):PAGE153

R1148 Q_RES_0402LF-0,5%,1/16W,CHIP,CA
     1 HP_LVC3_OCP_V3_1_PRSNT2_N_R @S9S_MB_2U_LIB.S9S_MB_2U(SCH_1):HP_LVC3_OCP_V3_1_PRSNT2_N_R    I46 @S9S_MB_2U_LIB.S9S_MB_2U(SCH_1):PAGE153
     2 HP_LVC3_OCP_V3_1_PRSNT2_N @S9S_MB_2U_LIB.S9S_MB_2U(SCH_1):HP_LVC3_OCP_V3_1_PRSNT2_N    I46 @S9S_MB_2U_LIB.S9S_MB_2U(SCH_1):PAGE153

R1149 Q_RES_0402LF-10K,1%,1/16W,CHIPA
     1 P3V3_AUX @S9S_MB_2U_LIB.S9S_MB_2U(SCH_1):P3V3_AUX    I50 @S9S_MB_2U_LIB.S9S_MB_2U(SCH_1):PAGE153
     2 HP_LVC3_OCP_V3_1_ATTN_OUT_SW_N @S9S_MB_2U_LIB.S9S_MB_2U(SCH_1):HP_LVC3_OCP_V3_1_ATTN_OUT_SW_N    I50 @S9S_MB_2U_LIB.S9S_MB_2U(SCH_1):PAGE153

R1150 Q_RES_0402LF-10K,1%,1/16W,CHIPA
     1 P3V3_AUX @S9S_MB_2U_LIB.S9S_MB_2U(SCH_1):P3V3_AUX    I74 @S9S_MB_2U_LIB.S9S_MB_2U(SCH_1):PAGE153
     2 HP_LVC3_OCP_V3_1_PRSNT2_N @S9S_MB_2U_LIB.S9S_MB_2U(SCH_1):HP_LVC3_OCP_V3_1_PRSNT2_N    I74 @S9S_MB_2U_LIB.S9S_MB_2U(SCH_1):PAGE153

R1184 Q_RES_0402LF-0,5%,1/16W,CHIP,CA
     1 JTAG_BMC_DBP_TMS_R @S9S_MB_2U_LIB.S9S_MB_2U(SCH_1):JTAG_BMC_DBP_TMS_R    I14 @S9S_MB_2U_LIB.S9S_MB_2U(SCH_1):PAGE226
     2 JTAG_BMC_DBP_TMS @S9S_MB_2U_LIB.S9S_MB_2U(SCH_1):JTAG_BMC_DBP_TMS    I14 @S9S_MB_2U_LIB.S9S_MB_2U(SCH_1):PAGE226

R1194 Q_RES_0402LF-4.75K,1%,1/16W,EMA
     1 P3V3_AUX @S9S_MB_2U_LIB.S9S_MB_2U(SCH_1):P3V3_AUX   I277 @S9S_MB_2U_LIB.S9S_MB_2U(SCH_1):PAGE197
     2 FM_CK440_MXCK_25M_100M @S9S_MB_2U_LIB.S9S_MB_2U(SCH_1):FM_CK440_MXCK_25M_100M   I277 @S9S_MB_2U_LIB.S9S_MB_2U(SCH_1):PAGE197

R1195 Q_RES_0402LF-130,1%,1/16W,CHIPA
     1 P3V3_AUX @S9S_MB_2U_LIB.S9S_MB_2U(SCH_1):P3V3_AUX   I278 @S9S_MB_2U_LIB.S9S_MB_2U(SCH_1):PAGE207
     2 PU_PLD_HEARTBEAT_LVC3 @S9S_MB_2U_LIB.S9S_MB_2U(SCH_1):PU_PLD_HEARTBEAT_LVC3   I278 @S9S_MB_2U_LIB.S9S_MB_2U(SCH_1):PAGE207

R1196 Q_RES_0402LF-4.75K,1%,1/16W,CHA
     1 FM_CK440_MXCK_25M_100M @S9S_MB_2U_LIB.S9S_MB_2U(SCH_1):FM_CK440_MXCK_25M_100M   I281 @S9S_MB_2U_LIB.S9S_MB_2U(SCH_1):PAGE197
     2    GND @S9S_MB_2U_LIB.S9S_MB_2U(SCH_1):GND   I281 @S9S_MB_2U_LIB.S9S_MB_2U(SCH_1):PAGE197

R1197 Q_RES_0402LF-1K,1%,1/16W,EMPTYA
     1    GND @S9S_MB_2U_LIB.S9S_MB_2U(SCH_1):GND    I50 @S9S_MB_2U_LIB.S9S_MB_2U(SCH_1):PAGE174
     2 PD_SUSCLK @S9S_MB_2U_LIB.S9S_MB_2U(SCH_1):PD_SUSCLK    I50 @S9S_MB_2U_LIB.S9S_MB_2U(SCH_1):PAGE174

R1198 Q_RES_0402LF-10K,1%,1/16W,CHIPA
     1 P3V3_AUX @S9S_MB_2U_LIB.S9S_MB_2U(SCH_1):P3V3_AUX    I48 @S9S_MB_2U_LIB.S9S_MB_2U(SCH_1):PAGE174
     2 PU_ACPRESENT @S9S_MB_2U_LIB.S9S_MB_2U(SCH_1):PU_ACPRESENT    I48 @S9S_MB_2U_LIB.S9S_MB_2U(SCH_1):PAGE174

R1200 Q_RES_0402LF-100,1%,1/16W,CHIPA
     1 FM_PCH_TRIGGER0_N @S9S_MB_2U_LIB.S9S_MB_2U(SCH_1):FM_PCH_TRIGGER0_N    I60 @S9S_MB_2U_LIB.S9S_MB_2U(SCH_1):PAGE174
     2 FM_PCH_TRIGGER0_R_N @S9S_MB_2U_LIB.S9S_MB_2U(SCH_1):FM_PCH_TRIGGER0_R_N    I60 @S9S_MB_2U_LIB.S9S_MB_2U(SCH_1):PAGE174

R1201 Q_RES_0402LF-49.9,1%,1/16W,CHIA
     1 FM_PCH_TRIGGER1_N @S9S_MB_2U_LIB.S9S_MB_2U(SCH_1):FM_PCH_TRIGGER1_N    I58 @S9S_MB_2U_LIB.S9S_MB_2U(SCH_1):PAGE174
     2 FM_PCH_TRIGGER1_R_N @S9S_MB_2U_LIB.S9S_MB_2U(SCH_1):FM_PCH_TRIGGER1_R_N    I58 @S9S_MB_2U_LIB.S9S_MB_2U(SCH_1):PAGE174

R1202 Q_RES_0402LF-20K,1%,1/16W,CHIPA
     1 P3V3_RTC_AUX @S9S_MB_2U_LIB.S9S_MB_2U(SCH_1):P3V3_RTC_AUX    I70 @S9S_MB_2U_LIB.S9S_MB_2U(SCH_1):PAGE177
     2 RST_SRTCRST_N @S9S_MB_2U_LIB.S9S_MB_2U(SCH_1):RST_SRTCRST_N    I70 @S9S_MB_2U_LIB.S9S_MB_2U(SCH_1):PAGE177

R1203 Q_RES_0402LF-1K,1%,1/16W,CHIP,A
     1 P3V_BAT @S9S_MB_2U_LIB.S9S_MB_2U(SCH_1):P3V_BAT    I62 @S9S_MB_2U_LIB.S9S_MB_2U(SCH_1):PAGE177
     2 P3V_BAT_R @S9S_MB_2U_LIB.S9S_MB_2U(SCH_1):P3V_BAT_R    I62 @S9S_MB_2U_LIB.S9S_MB_2U(SCH_1):PAGE177

R1204 Q_RES_0402LF-10K,1%,1/16W,EMPTA
     1 P3V3_AUX @S9S_MB_2U_LIB.S9S_MB_2U(SCH_1):P3V3_AUX   I273 @S9S_MB_2U_LIB.S9S_MB_2U(SCH_1):PAGE197
     2 PU_CK440_SHFT_LD_N @S9S_MB_2U_LIB.S9S_MB_2U(SCH_1):PU_CK440_SHFT_LD_N   I273 @S9S_MB_2U_LIB.S9S_MB_2U(SCH_1):PAGE197

R1205 Q_RES_0402LF-33.2,1%,1/16W,CHIA
     1 RST_PLTRST_N @S9S_MB_2U_LIB.S9S_MB_2U(SCH_1):RST_PLTRST_N     I7 @S9S_MB_2U_LIB.S9S_MB_2U(SCH_1):PAGE212
     2 RST_PLTRST_PLD_N @S9S_MB_2U_LIB.S9S_MB_2U(SCH_1):RST_PLTRST_PLD_N     I7 @S9S_MB_2U_LIB.S9S_MB_2U(SCH_1):PAGE212

R1206 Q_RES_0402LF-33.2,1%,1/16W,CHIA
     1 RST_MB_STBY_R_N @S9S_MB_2U_LIB.S9S_MB_2U(SCH_1):RST_MB_STBY_R_N    I10 @S9S_MB_2U_LIB.S9S_MB_2U(SCH_1):PAGE212
     2 RST_MB_STBY_N @S9S_MB_2U_LIB.S9S_MB_2U(SCH_1):RST_MB_STBY_N    I10 @S9S_MB_2U_LIB.S9S_MB_2U(SCH_1):PAGE212

R1207 Q_RES_0402LF-33.2,1%,1/16W,CHIA
     1 RST_RSMRST_PLD_R_N @S9S_MB_2U_LIB.S9S_MB_2U(SCH_1):RST_RSMRST_PLD_R_N    I15 @S9S_MB_2U_LIB.S9S_MB_2U(SCH_1):PAGE212
     2 RST_RSMRST_PCH_N @S9S_MB_2U_LIB.S9S_MB_2U(SCH_1):RST_RSMRST_PCH_N    I15 @S9S_MB_2U_LIB.S9S_MB_2U(SCH_1):PAGE212

R1214 Q_RES_0402LF-0,5%,1/16W,CHIP,CA
     1 IRQ_LPC_PIRQA_N_ESPI_ALERT0_N @S9S_MB_2U_LIB.S9S_MB_2U(SCH_1):IRQ_LPC_PIRQA_N_ESPI_ALERT0_N    I33 @S9S_MB_2U_LIB.S9S_MB_2U(SCH_1):PAGE190
     2 IRQ_LPC_PIRQA_N_ESPI_ALERT0_R_N @S9S_MB_2U_LIB.S9S_MB_2U(SCH_1):IRQ_LPC_PIRQA_N_ESPI_ALERT0_R_N    I33 @S9S_MB_2U_LIB.S9S_MB_2U(SCH_1):PAGE190

R1215 Q_RES_0402LF-49.9,1%,1/16W,CHIA
     1 IRQ_ESPI_LPC_SERIRQ_ALERT_N @S9S_MB_2U_LIB.S9S_MB_2U(SCH_1):IRQ_ESPI_LPC_SERIRQ_ALERT_N    I38 @S9S_MB_2U_LIB.S9S_MB_2U(SCH_1):PAGE190
     2 IRQ_ESPI_LPC_SERIRQ_ALERT_R_N @S9S_MB_2U_LIB.S9S_MB_2U(SCH_1):IRQ_ESPI_LPC_SERIRQ_ALERT_R_N    I38 @S9S_MB_2U_LIB.S9S_MB_2U(SCH_1):PAGE190

R1216 Q_RES_0402LF-1.5K,1%,1/16W,CHIA
     1 P3V3_AUX @S9S_MB_2U_LIB.S9S_MB_2U(SCH_1):P3V3_AUX     I1 @S9S_MB_2U_LIB.S9S_MB_2U(SCH_1):PAGE80
     2 FM_S3M_CPU0_CPLD_CRC_ERROR @S9S_MB_2U_LIB.S9S_MB_2U(SCH_1):FM_S3M_CPU0_CPLD_CRC_ERROR     I1 @S9S_MB_2U_LIB.S9S_MB_2U(SCH_1):PAGE80

R1217 Q_RES_0402LF-1.5K,1%,1/16W,CHIA
     1 P3V3_AUX @S9S_MB_2U_LIB.S9S_MB_2U(SCH_1):P3V3_AUX    I22 @S9S_MB_2U_LIB.S9S_MB_2U(SCH_1):PAGE80
     2 FM_S3M_CPU1_CPLD_CRC_ERROR @S9S_MB_2U_LIB.S9S_MB_2U(SCH_1):FM_S3M_CPU1_CPLD_CRC_ERROR    I22 @S9S_MB_2U_LIB.S9S_MB_2U(SCH_1):PAGE80

R1220 Q_RES_0402LF-1K,1%,1/16W,EMPTYA
     1 P3V3_AUX @S9S_MB_2U_LIB.S9S_MB_2U(SCH_1):P3V3_AUX    I63 @S9S_MB_2U_LIB.S9S_MB_2U(SCH_1):PAGE188
     2 FM_PCH_MCRO_LDO @S9S_MB_2U_LIB.S9S_MB_2U(SCH_1):FM_PCH_MCRO_LDO    I63 @S9S_MB_2U_LIB.S9S_MB_2U(SCH_1):PAGE188

R1221 Q_RES_0402LF-1K,1%,1/16W,CHIP,A
     1 FM_PCH_MCRO_LDO @S9S_MB_2U_LIB.S9S_MB_2U(SCH_1):FM_PCH_MCRO_LDO    I64 @S9S_MB_2U_LIB.S9S_MB_2U(SCH_1):PAGE188
     2    GND @S9S_MB_2U_LIB.S9S_MB_2U(SCH_1):GND    I64 @S9S_MB_2U_LIB.S9S_MB_2U(SCH_1):PAGE188

R1226 Q_RES_0402LF-10K,1%,1/16W,CHIPA
     1 PD_JTAG_CPU0_PLD_TCK @S9S_MB_2U_LIB.S9S_MB_2U(SCH_1):PD_JTAG_CPU0_PLD_TCK    I52 @S9S_MB_2U_LIB.S9S_MB_2U(SCH_1):PAGE43
     2    GND @S9S_MB_2U_LIB.S9S_MB_2U(SCH_1):GND    I52 @S9S_MB_2U_LIB.S9S_MB_2U(SCH_1):PAGE43

R1227 Q_RES_0402LF-10K,1%,1/16W,CHIPA
     1 PD_JTAG_CPU1_PLD_TCK @S9S_MB_2U_LIB.S9S_MB_2U(SCH_1):PD_JTAG_CPU1_PLD_TCK    I56 @S9S_MB_2U_LIB.S9S_MB_2U(SCH_1):PAGE43
     2    GND @S9S_MB_2U_LIB.S9S_MB_2U(SCH_1):GND    I56 @S9S_MB_2U_LIB.S9S_MB_2U(SCH_1):PAGE43

R1229 Q_RES_0402LF-240,1%,1/16W,EMPTA
     1 PVNN_TERM_CPU1 @S9S_MB_2U_LIB.S9S_MB_2U(SCH_1):PVNN_TERM_CPU1   I169 @S9S_MB_2U_LIB.S9S_MB_2U(SCH_1):PAGE119
     2 PUD_XTAL_CPU1_MODE0 @S9S_MB_2U_LIB.S9S_MB_2U(SCH_1):PUD_XTAL_CPU1_MODE0   I169 @S9S_MB_2U_LIB.S9S_MB_2U(SCH_1):PAGE119

R1230 Q_RES_0402LF-240,1%,1/16W,EMPTA
     1 PVNN_TERM_CPU1 @S9S_MB_2U_LIB.S9S_MB_2U(SCH_1):PVNN_TERM_CPU1   I170 @S9S_MB_2U_LIB.S9S_MB_2U(SCH_1):PAGE119
     2 PUD_XTAL_CPU1_MODE1 @S9S_MB_2U_LIB.S9S_MB_2U(SCH_1):PUD_XTAL_CPU1_MODE1   I170 @S9S_MB_2U_LIB.S9S_MB_2U(SCH_1):PAGE119

R1232 Q_RES_0402LF-240,1%,1/16W,EMPTA
     1 PVNN_TERM_CPU0 @S9S_MB_2U_LIB.S9S_MB_2U(SCH_1):PVNN_TERM_CPU0   I156 @S9S_MB_2U_LIB.S9S_MB_2U(SCH_1):PAGE119
     2 PUD_XTAL_CPU0_MODE0 @S9S_MB_2U_LIB.S9S_MB_2U(SCH_1):PUD_XTAL_CPU0_MODE0   I156 @S9S_MB_2U_LIB.S9S_MB_2U(SCH_1):PAGE119

R1233 Q_RES_0402LF-240,1%,1/16W,EMPTA
     1 PVNN_TERM_CPU0 @S9S_MB_2U_LIB.S9S_MB_2U(SCH_1):PVNN_TERM_CPU0   I158 @S9S_MB_2U_LIB.S9S_MB_2U(SCH_1):PAGE119
     2 PUD_XTAL_CPU0_MODE1 @S9S_MB_2U_LIB.S9S_MB_2U(SCH_1):PUD_XTAL_CPU0_MODE1   I158 @S9S_MB_2U_LIB.S9S_MB_2U(SCH_1):PAGE119

R1235 Q_RES_0402LF-240,1%,1/16W,EMPTA
     1    GND @S9S_MB_2U_LIB.S9S_MB_2U(SCH_1):GND   I176 @S9S_MB_2U_LIB.S9S_MB_2U(SCH_1):PAGE119
     2 PUD_XTAL_CPU1_MODE0 @S9S_MB_2U_LIB.S9S_MB_2U(SCH_1):PUD_XTAL_CPU1_MODE0   I176 @S9S_MB_2U_LIB.S9S_MB_2U(SCH_1):PAGE119

R1236 Q_RES_0402LF-240,1%,1/16W,EMPTA
     1    GND @S9S_MB_2U_LIB.S9S_MB_2U(SCH_1):GND   I177 @S9S_MB_2U_LIB.S9S_MB_2U(SCH_1):PAGE119
     2 PUD_XTAL_CPU1_MODE1 @S9S_MB_2U_LIB.S9S_MB_2U(SCH_1):PUD_XTAL_CPU1_MODE1   I177 @S9S_MB_2U_LIB.S9S_MB_2U(SCH_1):PAGE119

R1237 Q_RES_0402LF-240,1%,1/16W,EMPTA
     1    GND @S9S_MB_2U_LIB.S9S_MB_2U(SCH_1):GND   I160 @S9S_MB_2U_LIB.S9S_MB_2U(SCH_1):PAGE119
     2 PD_EXT_CLK_SEL_CPU0 @S9S_MB_2U_LIB.S9S_MB_2U(SCH_1):PD_EXT_CLK_SEL_CPU0   I160 @S9S_MB_2U_LIB.S9S_MB_2U(SCH_1):PAGE119

R1238 Q_RES_0402LF-240,1%,1/16W,EMPTA
     1    GND @S9S_MB_2U_LIB.S9S_MB_2U(SCH_1):GND   I161 @S9S_MB_2U_LIB.S9S_MB_2U(SCH_1):PAGE119
     2 PUD_XTAL_CPU0_MODE0 @S9S_MB_2U_LIB.S9S_MB_2U(SCH_1):PUD_XTAL_CPU0_MODE0   I161 @S9S_MB_2U_LIB.S9S_MB_2U(SCH_1):PAGE119

R1239 Q_RES_0402LF-240,1%,1/16W,EMPTA
     1    GND @S9S_MB_2U_LIB.S9S_MB_2U(SCH_1):GND   I163 @S9S_MB_2U_LIB.S9S_MB_2U(SCH_1):PAGE119
     2 PUD_XTAL_CPU0_MODE1 @S9S_MB_2U_LIB.S9S_MB_2U(SCH_1):PUD_XTAL_CPU0_MODE1   I163 @S9S_MB_2U_LIB.S9S_MB_2U(SCH_1):PAGE119

R1240 Q_RES_0402LF-0,5%,1/16W,CHIP,CA
     1 H_CPU0_PM_FAST_WAKE_N @S9S_MB_2U_LIB.S9S_MB_2U(SCH_1):H_CPU0_PM_FAST_WAKE_N     I9 @S9S_MB_2U_LIB.S9S_MB_2U(SCH_1):PAGE117
     2 H_CPU_PM_FAST_WAKE_N @S9S_MB_2U_LIB.S9S_MB_2U(SCH_1):H_CPU_PM_FAST_WAKE_N     I9 @S9S_MB_2U_LIB.S9S_MB_2U(SCH_1):PAGE117

R1241 Q_RES_0402LF-249,1%,1/16W,CHIPA
     1 H_PMAX_TRIGGER_IO_CPU0 @S9S_MB_2U_LIB.S9S_MB_2U(SCH_1):H_PMAX_TRIGGER_IO_CPU0    I17 @S9S_MB_2U_LIB.S9S_MB_2U(SCH_1):PAGE117
     2    GND @S9S_MB_2U_LIB.S9S_MB_2U(SCH_1):GND    I17 @S9S_MB_2U_LIB.S9S_MB_2U(SCH_1):PAGE117

R1242 Q_RES_0402LF-301,1%,1/16W,CHIPA
     1 PVNN_TERM_CPU0 @S9S_MB_2U_LIB.S9S_MB_2U(SCH_1):PVNN_TERM_CPU0    I13 @S9S_MB_2U_LIB.S9S_MB_2U(SCH_1):PAGE117
     2 H_CPU_PM_FAST_WAKE_N @S9S_MB_2U_LIB.S9S_MB_2U(SCH_1):H_CPU_PM_FAST_WAKE_N    I13 @S9S_MB_2U_LIB.S9S_MB_2U(SCH_1):PAGE117

R1243 Q_RES_0402LF-249,1%,1/16W,CHIPA
     1 H_PMAX_TRIGGER_IO_CPU1 @S9S_MB_2U_LIB.S9S_MB_2U(SCH_1):H_PMAX_TRIGGER_IO_CPU1    I19 @S9S_MB_2U_LIB.S9S_MB_2U(SCH_1):PAGE117
     2    GND @S9S_MB_2U_LIB.S9S_MB_2U(SCH_1):GND    I19 @S9S_MB_2U_LIB.S9S_MB_2U(SCH_1):PAGE117

R1244 Q_RES_0402LF-301,1%,1/16W,CHIPA
     1 PVNN_TERM_CPU1 @S9S_MB_2U_LIB.S9S_MB_2U(SCH_1):PVNN_TERM_CPU1    I16 @S9S_MB_2U_LIB.S9S_MB_2U(SCH_1):PAGE117
     2 H_CPU_PM_FAST_WAKE_N @S9S_MB_2U_LIB.S9S_MB_2U(SCH_1):H_CPU_PM_FAST_WAKE_N    I16 @S9S_MB_2U_LIB.S9S_MB_2U(SCH_1):PAGE117

R1247 Q_RES_0402LF-0,5%,1/16W,CHIP,CA
     1 FM_PCH_CPU_PWR_DEBUG_N @S9S_MB_2U_LIB.S9S_MB_2U(SCH_1):FM_PCH_CPU_PWR_DEBUG_N    I14 @S9S_MB_2U_LIB.S9S_MB_2U(SCH_1):PAGE191
     2 FM_CPU_FBRK_DEBUG_N @S9S_MB_2U_LIB.S9S_MB_2U(SCH_1):FM_CPU_FBRK_DEBUG_N    I14 @S9S_MB_2U_LIB.S9S_MB_2U(SCH_1):PAGE191

R1249 Q_RES_0402LF-0,5%,1/16W,CHIP,CA
     1 FM_THERMTRIP_DLY_LVC1_N @S9S_MB_2U_LIB.S9S_MB_2U(SCH_1):FM_THERMTRIP_DLY_LVC1_N     I2 @S9S_MB_2U_LIB.S9S_MB_2U(SCH_1):PAGE191
     2 H_THERMTRIP_LVC1_N @S9S_MB_2U_LIB.S9S_MB_2U(SCH_1):H_THERMTRIP_LVC1_N     I2 @S9S_MB_2U_LIB.S9S_MB_2U(SCH_1):PAGE191

R1253 Q_RES_0402LF-1K,1%,1/16W,CHIP,A
     1 PGPPA_AUX @S9S_MB_2U_LIB.S9S_MB_2U(SCH_1):PGPPA_AUX    I23 @S9S_MB_2U_LIB.S9S_MB_2U(SCH_1):PAGE192
     2 IRQ_LPC_PIRQA_N_ESPI_ALERT0_N @S9S_MB_2U_LIB.S9S_MB_2U(SCH_1):IRQ_LPC_PIRQA_N_ESPI_ALERT0_N    I23 @S9S_MB_2U_LIB.S9S_MB_2U(SCH_1):PAGE192

R1254 Q_RES_0402LF-10K,1%,1/16W,CHIPA
     1 PGPPA_AUX @S9S_MB_2U_LIB.S9S_MB_2U(SCH_1):PGPPA_AUX    I24 @S9S_MB_2U_LIB.S9S_MB_2U(SCH_1):PAGE192
     2 IRQ_LPC_SERIRQ_ESPI_CS1_N @S9S_MB_2U_LIB.S9S_MB_2U(SCH_1):IRQ_LPC_SERIRQ_ESPI_CS1_N    I24 @S9S_MB_2U_LIB.S9S_MB_2U(SCH_1):PAGE192

R1255 Q_RES_0402LF-1K,1%,1/16W,CHIP,A
     1 PGPPA_AUX @S9S_MB_2U_LIB.S9S_MB_2U(SCH_1):PGPPA_AUX    I26 @S9S_MB_2U_LIB.S9S_MB_2U(SCH_1):PAGE192
     2 ESPI_ALERT1_N_LPC_RCIN_N @S9S_MB_2U_LIB.S9S_MB_2U(SCH_1):ESPI_ALERT1_N_LPC_RCIN_N    I26 @S9S_MB_2U_LIB.S9S_MB_2U(SCH_1):PAGE192

R1257 Q_RES_0402LF-10K,1%,1/16W,CHIPA
     1 P3V3_AUX @S9S_MB_2U_LIB.S9S_MB_2U(SCH_1):P3V3_AUX     I4 @S9S_MB_2U_LIB.S9S_MB_2U(SCH_1):PAGE192
     2 PU_PCH_VRALERT_N @S9S_MB_2U_LIB.S9S_MB_2U(SCH_1):PU_PCH_VRALERT_N     I4 @S9S_MB_2U_LIB.S9S_MB_2U(SCH_1):PAGE192

R1259 Q_RES_0402LF-10K,1%,1/16W,CHIPA
     1 P3V3_AUX @S9S_MB_2U_LIB.S9S_MB_2U(SCH_1):P3V3_AUX     I8 @S9S_MB_2U_LIB.S9S_MB_2U(SCH_1):PAGE192
     2 PU_LPC_PME_N @S9S_MB_2U_LIB.S9S_MB_2U(SCH_1):PU_LPC_PME_N     I8 @S9S_MB_2U_LIB.S9S_MB_2U(SCH_1):PAGE192

R1260 Q_RES_0402LF-10K,1%,1/16W,EMPTA
     1 P1V05_PCH_AUX @S9S_MB_2U_LIB.S9S_MB_2U(SCH_1):P1V05_PCH_AUX    I17 @S9S_MB_2U_LIB.S9S_MB_2U(SCH_1):PAGE192
     2 H_CPU_ERR0_PCH_R_N @S9S_MB_2U_LIB.S9S_MB_2U(SCH_1):H_CPU_ERR0_PCH_R_N    I17 @S9S_MB_2U_LIB.S9S_MB_2U(SCH_1):PAGE192

R1262 Q_RES_0402LF-10K,1%,1/16W,EMPTA
     1 P1V05_PCH_AUX @S9S_MB_2U_LIB.S9S_MB_2U(SCH_1):P1V05_PCH_AUX    I11 @S9S_MB_2U_LIB.S9S_MB_2U(SCH_1):PAGE192
     2 H_CPU_ERR2_PCH_R_N @S9S_MB_2U_LIB.S9S_MB_2U(SCH_1):H_CPU_ERR2_PCH_R_N    I11 @S9S_MB_2U_LIB.S9S_MB_2U(SCH_1):PAGE192

R1263 Q_RES_0402LF-33.2,1%,1/16W,CHIA
     1 FM_PLT_BMC_THERMTRIP_R_N @S9S_MB_2U_LIB.S9S_MB_2U(SCH_1):FM_PLT_BMC_THERMTRIP_R_N    I29 @S9S_MB_2U_LIB.S9S_MB_2U(SCH_1):PAGE191
     2 FM_PCH_BMC_THERMTRIP_N @S9S_MB_2U_LIB.S9S_MB_2U(SCH_1):FM_PCH_BMC_THERMTRIP_N    I29 @S9S_MB_2U_LIB.S9S_MB_2U(SCH_1):PAGE191

R1266 Q_RES_0402LF-75,1%,1/16W,CHIP,A
     1 P1V05_PCH_AUX @S9S_MB_2U_LIB.S9S_MB_2U(SCH_1):P1V05_PCH_AUX    I38 @S9S_MB_2U_LIB.S9S_MB_2U(SCH_1):PAGE191
     2 H_THERMTRIP_LVC1_N @S9S_MB_2U_LIB.S9S_MB_2U(SCH_1):H_THERMTRIP_LVC1_N    I38 @S9S_MB_2U_LIB.S9S_MB_2U(SCH_1):PAGE191

R1267 Q_RES_0402LF-1K,1%,1/16W,CHIP,A
     1 PU_CK440_SHFT_LD_N @S9S_MB_2U_LIB.S9S_MB_2U(SCH_1):PU_CK440_SHFT_LD_N   I276 @S9S_MB_2U_LIB.S9S_MB_2U(SCH_1):PAGE197
     2    GND @S9S_MB_2U_LIB.S9S_MB_2U(SCH_1):GND   I276 @S9S_MB_2U_LIB.S9S_MB_2U(SCH_1):PAGE197

R1268 Q_RES_0402LF-33.2,1%,1/16W,CHIA
     1 IRQ_BMC_PCH_NMI_R @S9S_MB_2U_LIB.S9S_MB_2U(SCH_1):IRQ_BMC_PCH_NMI_R   I222 @S9S_MB_2U_LIB.S9S_MB_2U(SCH_1):PAGE175
     2 IRQ_BMC_PCH_NMI @S9S_MB_2U_LIB.S9S_MB_2U(SCH_1):IRQ_BMC_PCH_NMI   I222 @S9S_MB_2U_LIB.S9S_MB_2U(SCH_1):PAGE175

R1269 Q_RES_0402LF-4.75K,1%,1/16W,CHA
     1 IRQ_BMC_PCH_NMI @S9S_MB_2U_LIB.S9S_MB_2U(SCH_1):IRQ_BMC_PCH_NMI   I225 @S9S_MB_2U_LIB.S9S_MB_2U(SCH_1):PAGE175
     2    GND @S9S_MB_2U_LIB.S9S_MB_2U(SCH_1):GND   I225 @S9S_MB_2U_LIB.S9S_MB_2U(SCH_1):PAGE175

R1270 Q_RES_0402LF-240,1%,1/16W,EMPTA
     1 PD_CPU1_PROCDIS_COD_GTL_N @S9S_MB_2U_LIB.S9S_MB_2U(SCH_1):PD_CPU1_PROCDIS_COD_GTL_N    I55 @S9S_MB_2U_LIB.S9S_MB_2U(SCH_1):PAGE44
     2    GND @S9S_MB_2U_LIB.S9S_MB_2U(SCH_1):GND    I55 @S9S_MB_2U_LIB.S9S_MB_2U(SCH_1):PAGE44

R1271 Q_RES_0402LF-2.21K,1%,1/16W,EMA
     1 P3V3_AUX @S9S_MB_2U_LIB.S9S_MB_2U(SCH_1):P3V3_AUX     I5 @S9S_MB_2U_LIB.S9S_MB_2U(SCH_1):PAGE183
     2 FM_PCH_SATA_RAID_KEY @S9S_MB_2U_LIB.S9S_MB_2U(SCH_1):FM_PCH_SATA_RAID_KEY     I5 @S9S_MB_2U_LIB.S9S_MB_2U(SCH_1):PAGE183

R1273 Q_RES_0402LF-22,1%,1/16W,CHIP,A
     1 CLK_100M_OCP_SFF_2_R_DP @S9S_MB_2U_LIB.S9S_MB_2U(SCH_1):CLK_100M_OCP_SFF_2_R_DP    I44 @S9S_MB_2U_LIB.S9S_MB_2U(SCH_1):PAGE198
     2 CLK_100M_OCP_SFF_2_DP @S9S_MB_2U_LIB.S9S_MB_2U(SCH_1):CLK_100M_OCP_SFF_2_DP    I44 @S9S_MB_2U_LIB.S9S_MB_2U(SCH_1):PAGE198

R1274 Q_RES_0402LF-22,1%,1/16W,CHIP,A
     1 CLK_100M_OCP_SFF_2_R_DN @S9S_MB_2U_LIB.S9S_MB_2U(SCH_1):CLK_100M_OCP_SFF_2_R_DN    I43 @S9S_MB_2U_LIB.S9S_MB_2U(SCH_1):PAGE198
     2 CLK_100M_OCP_SFF_2_DN @S9S_MB_2U_LIB.S9S_MB_2U(SCH_1):CLK_100M_OCP_SFF_2_DN    I43 @S9S_MB_2U_LIB.S9S_MB_2U(SCH_1):PAGE198

R1275 Q_RES_0402LF-22,1%,1/16W,CHIP,A
     1 CLK_100M_OCP_SFF_3_R_DP @S9S_MB_2U_LIB.S9S_MB_2U(SCH_1):CLK_100M_OCP_SFF_3_R_DP    I24 @S9S_MB_2U_LIB.S9S_MB_2U(SCH_1):PAGE198
     2 CLK_100M_OCP_SFF_3_DP @S9S_MB_2U_LIB.S9S_MB_2U(SCH_1):CLK_100M_OCP_SFF_3_DP    I24 @S9S_MB_2U_LIB.S9S_MB_2U(SCH_1):PAGE198

R1276 Q_RES_0402LF-22,1%,1/16W,CHIP,A
     1 CLK_100M_OCP_SFF_3_R_DN @S9S_MB_2U_LIB.S9S_MB_2U(SCH_1):CLK_100M_OCP_SFF_3_R_DN    I23 @S9S_MB_2U_LIB.S9S_MB_2U(SCH_1):PAGE198
     2 CLK_100M_OCP_SFF_3_DN @S9S_MB_2U_LIB.S9S_MB_2U(SCH_1):CLK_100M_OCP_SFF_3_DN    I23 @S9S_MB_2U_LIB.S9S_MB_2U(SCH_1):PAGE198

R1289 Q_RES_0402LF-100K,1%,1/16W,CHIA
     1 FB_BMC_ISOLATE @S9S_MB_2U_LIB.S9S_MB_2U(SCH_1):FB_BMC_ISOLATE    I21 @S9S_MB_2U_LIB.S9S_MB_2U(SCH_1):PAGE151
     2    GND @S9S_MB_2U_LIB.S9S_MB_2U(SCH_1):GND    I21 @S9S_MB_2U_LIB.S9S_MB_2U(SCH_1):PAGE151

R1290 Q_RES_0402LF-22,1%,1/16W,EMPTYA
     1 OCP_SFF_RBT_ARB_IN_R @S9S_MB_2U_LIB.S9S_MB_2U(SCH_1):OCP_SFF_RBT_ARB_IN_R    I81 @S9S_MB_2U_LIB.S9S_MB_2U(SCH_1):PAGE151
     2 OCP_SFF_RBT_ARB_IN @S9S_MB_2U_LIB.S9S_MB_2U(SCH_1):OCP_SFF_RBT_ARB_IN    I81 @S9S_MB_2U_LIB.S9S_MB_2U(SCH_1):PAGE151

R1291 Q_RES_0402LF-22,1%,1/16W,CHIP,A
     1 NCSI_BMC_CRS_DV_R @S9S_MB_2U_LIB.S9S_MB_2U(SCH_1):NCSI_BMC_CRS_DV_R    I69 @S9S_MB_2U_LIB.S9S_MB_2U(SCH_1):PAGE151
     2 RMII_OCP_BMC_CRSDV @S9S_MB_2U_LIB.S9S_MB_2U(SCH_1):RMII_OCP_BMC_CRSDV    I69 @S9S_MB_2U_LIB.S9S_MB_2U(SCH_1):PAGE151

R1292 Q_RES_0402LF-22,1%,1/16W,CHIP,A
     1 NCSI_BMC_RXD0_R @S9S_MB_2U_LIB.S9S_MB_2U(SCH_1):NCSI_BMC_RXD0_R    I68 @S9S_MB_2U_LIB.S9S_MB_2U(SCH_1):PAGE151
     2 RMII_OCP_BMC_RXD_0 @S9S_MB_2U_LIB.S9S_MB_2U(SCH_1):RMII_OCP_BMC_RXD_0    I68 @S9S_MB_2U_LIB.S9S_MB_2U(SCH_1):PAGE151

R1293 Q_RES_0402LF-22,1%,1/16W,CHIP,A
     1 NCSI_BMC_RXD1_R @S9S_MB_2U_LIB.S9S_MB_2U(SCH_1):NCSI_BMC_RXD1_R    I67 @S9S_MB_2U_LIB.S9S_MB_2U(SCH_1):PAGE151
     2 RMII_OCP_BMC_RXD_1 @S9S_MB_2U_LIB.S9S_MB_2U(SCH_1):RMII_OCP_BMC_RXD_1    I67 @S9S_MB_2U_LIB.S9S_MB_2U(SCH_1):PAGE151

R1294 Q_RES_0402LF-0,5%,1/16W,CHIP,CA
     1 NCSI_BMC_TX_EN_R @S9S_MB_2U_LIB.S9S_MB_2U(SCH_1):NCSI_BMC_TX_EN_R    I66 @S9S_MB_2U_LIB.S9S_MB_2U(SCH_1):PAGE151
     2 RMII_BMC_OCP_TX_EN @S9S_MB_2U_LIB.S9S_MB_2U(SCH_1):RMII_BMC_OCP_TX_EN    I66 @S9S_MB_2U_LIB.S9S_MB_2U(SCH_1):PAGE151

R1295 Q_RES_0402LF-0,5%,1/16W,CHIP,CA
     1 NCSI_BMC_TXD0_R @S9S_MB_2U_LIB.S9S_MB_2U(SCH_1):NCSI_BMC_TXD0_R    I65 @S9S_MB_2U_LIB.S9S_MB_2U(SCH_1):PAGE151
     2 RMII_BMC_OCP_TXD_0 @S9S_MB_2U_LIB.S9S_MB_2U(SCH_1):RMII_BMC_OCP_TXD_0    I65 @S9S_MB_2U_LIB.S9S_MB_2U(SCH_1):PAGE151

R1296 Q_RES_0402LF-0,5%,1/16W,CHIP,CA
     1 NCSI_BMC_TXD1_R @S9S_MB_2U_LIB.S9S_MB_2U(SCH_1):NCSI_BMC_TXD1_R    I61 @S9S_MB_2U_LIB.S9S_MB_2U(SCH_1):PAGE151
     2 RMII_BMC_OCP_TXD_1 @S9S_MB_2U_LIB.S9S_MB_2U(SCH_1):RMII_BMC_OCP_TXD_1    I61 @S9S_MB_2U_LIB.S9S_MB_2U(SCH_1):PAGE151

R1297 Q_RES_0402LF-0,5%,1/16W,CHIP,CA
     1 PECI_BMC_R @S9S_MB_2U_LIB.S9S_MB_2U(SCH_1):PECI_BMC_R    I32 @S9S_MB_2U_LIB.S9S_MB_2U(SCH_1):PAGE185
     2 PECI_BMC_B1 @S9S_MB_2U_LIB.S9S_MB_2U(SCH_1):PECI_BMC_B1    I32 @S9S_MB_2U_LIB.S9S_MB_2U(SCH_1):PAGE185

R1298 Q_RES_0402LF-1K,1%,1/16W,EMPTYA
     1 P1V05_PCH_AUX @S9S_MB_2U_LIB.S9S_MB_2U(SCH_1):P1V05_PCH_AUX    I22 @S9S_MB_2U_LIB.S9S_MB_2U(SCH_1):PAGE188
     2 FM_MFG_MODE @S9S_MB_2U_LIB.S9S_MB_2U(SCH_1):FM_MFG_MODE    I22 @S9S_MB_2U_LIB.S9S_MB_2U(SCH_1):PAGE188

R1299 Q_RES_0402LF-10K,1%,1/16W,CHIPA
     1 FM_MFG_MODE @S9S_MB_2U_LIB.S9S_MB_2U(SCH_1):FM_MFG_MODE    I21 @S9S_MB_2U_LIB.S9S_MB_2U(SCH_1):PAGE188
     2    GND @S9S_MB_2U_LIB.S9S_MB_2U(SCH_1):GND    I21 @S9S_MB_2U_LIB.S9S_MB_2U(SCH_1):PAGE188

R1300 Q_RES_0402LF-33.2,1%,1/16W,CHIA
     1 FM_BIOS_POST_CMPLT_N @S9S_MB_2U_LIB.S9S_MB_2U(SCH_1):FM_BIOS_POST_CMPLT_N     I5 @S9S_MB_2U_LIB.S9S_MB_2U(SCH_1):PAGE193
     2 FM_BIOS_POST_CMPLT_BMC_N @S9S_MB_2U_LIB.S9S_MB_2U(SCH_1):FM_BIOS_POST_CMPLT_BMC_N     I5 @S9S_MB_2U_LIB.S9S_MB_2U(SCH_1):PAGE193

R1302 Q_RES_0402LF-2K,1%,1/16W,EMPTYA
     1 PWRGD_DRAMPWRGD_CPU0_AB_R_LVC1 @S9S_MB_2U_LIB.S9S_MB_2U(SCH_1):PWRGD_DRAMPWRGD_CPU0_AB_R_LVC1    I12 @S9S_MB_2U_LIB.S9S_MB_2U(SCH_1):PAGE208
     2    GND @S9S_MB_2U_LIB.S9S_MB_2U(SCH_1):GND    I12 @S9S_MB_2U_LIB.S9S_MB_2U(SCH_1):PAGE208

R1305 Q_RES_0402LF-10K,1%,1/16W,EMPTA
     1 P3V3_AUX @S9S_MB_2U_LIB.S9S_MB_2U(SCH_1):P3V3_AUX   I272 @S9S_MB_2U_LIB.S9S_MB_2U(SCH_1):PAGE197
     2 FM_PLD_CLKS_DEV_EN @S9S_MB_2U_LIB.S9S_MB_2U(SCH_1):FM_PLD_CLKS_DEV_EN   I272 @S9S_MB_2U_LIB.S9S_MB_2U(SCH_1):PAGE197

R1306 Q_RES_0402LF-33.2,1%,1/16W,CHIA
     1 FM_PS_PWROK_DLY_R_SEL @S9S_MB_2U_LIB.S9S_MB_2U(SCH_1):FM_PS_PWROK_DLY_R_SEL    I13 @S9S_MB_2U_LIB.S9S_MB_2U(SCH_1):PAGE193
     2 FM_PS_PWROK_DLY_SEL @S9S_MB_2U_LIB.S9S_MB_2U(SCH_1):FM_PS_PWROK_DLY_SEL    I13 @S9S_MB_2U_LIB.S9S_MB_2U(SCH_1):PAGE193

R1307 Q_RES_0402LF-33.2,1%,1/16W,CHIA
     1 FM_THROTTLE_N @S9S_MB_2U_LIB.S9S_MB_2U(SCH_1):FM_THROTTLE_N     I3 @S9S_MB_2U_LIB.S9S_MB_2U(SCH_1):PAGE193
     2 FM_THROTTLE_R_N @S9S_MB_2U_LIB.S9S_MB_2U(SCH_1):FM_THROTTLE_R_N     I3 @S9S_MB_2U_LIB.S9S_MB_2U(SCH_1):PAGE193

R1308 Q_RES_0402LF-10K,1%,1/16W,EMPTA
     1 FM_RST_PERST_BIT1 @S9S_MB_2U_LIB.S9S_MB_2U(SCH_1):FM_RST_PERST_BIT1    I23 @S9S_MB_2U_LIB.S9S_MB_2U(SCH_1):PAGE209
     2    GND @S9S_MB_2U_LIB.S9S_MB_2U(SCH_1):GND    I23 @S9S_MB_2U_LIB.S9S_MB_2U(SCH_1):PAGE209

R1309 Q_RES_0402LF-33.2,1%,1/16W,CHIA
     1 IRQ_SMI_ACTIVE_N @S9S_MB_2U_LIB.S9S_MB_2U(SCH_1):IRQ_SMI_ACTIVE_N    I10 @S9S_MB_2U_LIB.S9S_MB_2U(SCH_1):PAGE193
     2 IRQ_SMI_ACTIVE_BMC_N @S9S_MB_2U_LIB.S9S_MB_2U(SCH_1):IRQ_SMI_ACTIVE_BMC_N    I10 @S9S_MB_2U_LIB.S9S_MB_2U(SCH_1):PAGE193

R1310 Q_RES_0402LF-33.2,1%,1/16W,CHIA
     1 IRQ_PCH_CPU_NMI_EVENT_R_N @S9S_MB_2U_LIB.S9S_MB_2U(SCH_1):IRQ_PCH_CPU_NMI_EVENT_R_N    I20 @S9S_MB_2U_LIB.S9S_MB_2U(SCH_1):PAGE193
     2 IRQ_PCH_CPU_NMI_EVENT_N @S9S_MB_2U_LIB.S9S_MB_2U(SCH_1):IRQ_PCH_CPU_NMI_EVENT_N    I20 @S9S_MB_2U_LIB.S9S_MB_2U(SCH_1):PAGE193

R1311 Q_RES_0402LF-10K,1%,1/16W,CHIPA
     1 FM_XTAL_INPUT_FREQUENCY_0_MGPIO @S9S_MB_2U_LIB.S9S_MB_2U(SCH_1):FM_XTAL_INPUT_FREQUENCY_0_MGPIO_TEST4    I31 @S9S_MB_2U_LIB.S9S_MB_2U(SCH_1):PAGE188
     2    GND @S9S_MB_2U_LIB.S9S_MB_2U(SCH_1):GND    I31 @S9S_MB_2U_LIB.S9S_MB_2U(SCH_1):PAGE188

R1312 Q_RES_0402LF-10K,1%,1/16W,EMPTA
     1 FM_RST_PERST_BIT2 @S9S_MB_2U_LIB.S9S_MB_2U(SCH_1):FM_RST_PERST_BIT2    I22 @S9S_MB_2U_LIB.S9S_MB_2U(SCH_1):PAGE209
     2    GND @S9S_MB_2U_LIB.S9S_MB_2U(SCH_1):GND    I22 @S9S_MB_2U_LIB.S9S_MB_2U(SCH_1):PAGE209

R1313 Q_RES_0402LF-33.2,1%,1/16W,CHIA
     1 FM_PCH_GLB_RST_WARN_N @S9S_MB_2U_LIB.S9S_MB_2U(SCH_1):FM_PCH_GLB_RST_WARN_N    I21 @S9S_MB_2U_LIB.S9S_MB_2U(SCH_1):PAGE193
     2 FM_PCH_PLD_GLB_RST_WARN_N @S9S_MB_2U_LIB.S9S_MB_2U(SCH_1):FM_PCH_PLD_GLB_RST_WARN_N    I21 @S9S_MB_2U_LIB.S9S_MB_2U(SCH_1):PAGE193

R1316 Q_RES_0603LF-200K,0.1%,1/10W,EA
     1 XTAL_PCH_25M_IN_R @S9S_MB_2U_LIB.S9S_MB_2U(SCH_1):XTAL_PCH_25M_IN_R    I92 @S9S_MB_2U_LIB.S9S_MB_2U(SCH_1):PAGE171
     2 XTAL_PCH_25M_OUT @S9S_MB_2U_LIB.S9S_MB_2U(SCH_1):XTAL_PCH_25M_OUT    I92 @S9S_MB_2U_LIB.S9S_MB_2U(SCH_1):PAGE171

R1317 Q_RES_0402LF-1K,1%,1/16W,CHIP,A
     1 P1V05_PCH_AUX @S9S_MB_2U_LIB.S9S_MB_2U(SCH_1):P1V05_PCH_AUX    I88 @S9S_MB_2U_LIB.S9S_MB_2U(SCH_1):PAGE189
     2 PU_BIOS_RCVR_BOOT @S9S_MB_2U_LIB.S9S_MB_2U(SCH_1):PU_BIOS_RCVR_BOOT    I88 @S9S_MB_2U_LIB.S9S_MB_2U(SCH_1):PAGE189

R1318 Q_RES_0402LF-0,5%,1/16W,CHIP,CA
     1 FM_THERMTRIP_DLY_LVC1_R_N @S9S_MB_2U_LIB.S9S_MB_2U(SCH_1):FM_THERMTRIP_DLY_LVC1_R_N   I130 @S9S_MB_2U_LIB.S9S_MB_2U(SCH_1):PAGE212
     2 FM_THERMTRIP_DLY_LVC1_N @S9S_MB_2U_LIB.S9S_MB_2U(SCH_1):FM_THERMTRIP_DLY_LVC1_N   I130 @S9S_MB_2U_LIB.S9S_MB_2U(SCH_1):PAGE212

R1319 Q_RES_0402LF-2K,1%,1/16W,EMPTYA
     1 SMB_HOST_3V3AUX_SCL @S9S_MB_2U_LIB.S9S_MB_2U(SCH_1):SMB_HOST_3V3AUX_SCL     I2 @S9S_MB_2U_LIB.S9S_MB_2U(SCH_1):PAGE228
     2 P3V3_AUX @S9S_MB_2U_LIB.S9S_MB_2U(SCH_1):P3V3_AUX     I2 @S9S_MB_2U_LIB.S9S_MB_2U(SCH_1):PAGE228

R1320 Q_RES_0402LF-1K,1%,1/16W,CHIP,A
     1 P3V3_AUX @S9S_MB_2U_LIB.S9S_MB_2U(SCH_1):P3V3_AUX    I89 @S9S_MB_2U_LIB.S9S_MB_2U(SCH_1):PAGE189
     2 PU_SWAP_OVERRIDE_N @S9S_MB_2U_LIB.S9S_MB_2U(SCH_1):PU_SWAP_OVERRIDE_N    I89 @S9S_MB_2U_LIB.S9S_MB_2U(SCH_1):PAGE189

R1324 Q_RES_0402LF-1K,1%,1/16W,CHIP,A
     1    GND @S9S_MB_2U_LIB.S9S_MB_2U(SCH_1):GND    I87 @S9S_MB_2U_LIB.S9S_MB_2U(SCH_1):PAGE189
     2 PD_BIOS_IMAGE_SWAP_N @S9S_MB_2U_LIB.S9S_MB_2U(SCH_1):PD_BIOS_IMAGE_SWAP_N    I87 @S9S_MB_2U_LIB.S9S_MB_2U(SCH_1):PAGE189

R1325 Q_RES_0402LF-1K,1%,1/16W,CHIP,A
     1 P3V3_AUX @S9S_MB_2U_LIB.S9S_MB_2U(SCH_1):P3V3_AUX    I93 @S9S_MB_2U_LIB.S9S_MB_2U(SCH_1):PAGE189
     2 PU_FLASH_SECURITY_STRAP @S9S_MB_2U_LIB.S9S_MB_2U(SCH_1):PU_FLASH_SECURITY_STRAP    I93 @S9S_MB_2U_LIB.S9S_MB_2U(SCH_1):PAGE189

R1326 Q_RES_0402LF-2K,1%,1/16W,EMPTYA
     1 PWRGD_DRAMPWRGD_CPU0_CD_R_LVC1 @S9S_MB_2U_LIB.S9S_MB_2U(SCH_1):PWRGD_DRAMPWRGD_CPU0_CD_R_LVC1    I11 @S9S_MB_2U_LIB.S9S_MB_2U(SCH_1):PAGE208
     2    GND @S9S_MB_2U_LIB.S9S_MB_2U(SCH_1):GND    I11 @S9S_MB_2U_LIB.S9S_MB_2U(SCH_1):PAGE208

R1327 Q_RES_0402LF-2K,1%,1/16W,EMPTYA
     1 PWRGD_DRAMPWRGD_CPU0_EF_R_LVC1 @S9S_MB_2U_LIB.S9S_MB_2U(SCH_1):PWRGD_DRAMPWRGD_CPU0_EF_R_LVC1    I14 @S9S_MB_2U_LIB.S9S_MB_2U(SCH_1):PAGE208
     2    GND @S9S_MB_2U_LIB.S9S_MB_2U(SCH_1):GND    I14 @S9S_MB_2U_LIB.S9S_MB_2U(SCH_1):PAGE208

R1328 Q_RES_0402LF-2K,1%,1/16W,EMPTYA
     1 PWRGD_DRAMPWRGD_CPU0_GH_R_LVC1 @S9S_MB_2U_LIB.S9S_MB_2U(SCH_1):PWRGD_DRAMPWRGD_CPU0_GH_R_LVC1    I13 @S9S_MB_2U_LIB.S9S_MB_2U(SCH_1):PAGE208
     2    GND @S9S_MB_2U_LIB.S9S_MB_2U(SCH_1):GND    I13 @S9S_MB_2U_LIB.S9S_MB_2U(SCH_1):PAGE208

R1329 Q_RES_0402LF-2K,1%,1/16W,EMPTYA
     1 PWRGD_DRAMPWRGD_CPU1_AB_R_LVC1 @S9S_MB_2U_LIB.S9S_MB_2U(SCH_1):PWRGD_DRAMPWRGD_CPU1_AB_R_LVC1    I15 @S9S_MB_2U_LIB.S9S_MB_2U(SCH_1):PAGE208
     2    GND @S9S_MB_2U_LIB.S9S_MB_2U(SCH_1):GND    I15 @S9S_MB_2U_LIB.S9S_MB_2U(SCH_1):PAGE208

R1330 Q_RES_0402LF-2K,1%,1/16W,EMPTYA
     1 PWRGD_DRAMPWRGD_CPU1_CD_R_LVC1 @S9S_MB_2U_LIB.S9S_MB_2U(SCH_1):PWRGD_DRAMPWRGD_CPU1_CD_R_LVC1    I16 @S9S_MB_2U_LIB.S9S_MB_2U(SCH_1):PAGE208
     2    GND @S9S_MB_2U_LIB.S9S_MB_2U(SCH_1):GND    I16 @S9S_MB_2U_LIB.S9S_MB_2U(SCH_1):PAGE208

R1331 Q_RES_0402LF-4.7K,5%,1/16W,EMPA
     1 P3V3_AUX @S9S_MB_2U_LIB.S9S_MB_2U(SCH_1):P3V3_AUX    I95 @S9S_MB_2U_LIB.S9S_MB_2U(SCH_1):PAGE231
     2 SMB_FRU_3V3AUX_SCL @S9S_MB_2U_LIB.S9S_MB_2U(SCH_1):SMB_FRU_3V3AUX_SCL    I95 @S9S_MB_2U_LIB.S9S_MB_2U(SCH_1):PAGE231

R1332 Q_RES_0402LF-4.7K,5%,1/16W,EMPA
     1 P3V3_AUX @S9S_MB_2U_LIB.S9S_MB_2U(SCH_1):P3V3_AUX    I93 @S9S_MB_2U_LIB.S9S_MB_2U(SCH_1):PAGE231
     2 SMB_FRU_3V3AUX_SDA @S9S_MB_2U_LIB.S9S_MB_2U(SCH_1):SMB_FRU_3V3AUX_SDA    I93 @S9S_MB_2U_LIB.S9S_MB_2U(SCH_1):PAGE231

R1333 Q_RES_0402LF-1K,1%,1/16W,CHIP,A
     1    GND @S9S_MB_2U_LIB.S9S_MB_2U(SCH_1):GND   I123 @S9S_MB_2U_LIB.S9S_MB_2U(SCH_1):PAGE189
     2 PD_RST_RTCRST_N @S9S_MB_2U_LIB.S9S_MB_2U(SCH_1):PD_RST_RTCRST_N   I123 @S9S_MB_2U_LIB.S9S_MB_2U(SCH_1):PAGE189

R1335 Q_RES_0402LF-1K,1%,1/16W,CHIP,A
     1    GND @S9S_MB_2U_LIB.S9S_MB_2U(SCH_1):GND   I133 @S9S_MB_2U_LIB.S9S_MB_2U(SCH_1):PAGE189
     2 PD_PASSWORD_CLEAR @S9S_MB_2U_LIB.S9S_MB_2U(SCH_1):PD_PASSWORD_CLEAR   I133 @S9S_MB_2U_LIB.S9S_MB_2U(SCH_1):PAGE189

R1336 Q_RES_0402LF-2.2K,5%,1/16W,EMPA
     1 I3C_BMC_SWB_SCL @S9S_MB_2U_LIB.S9S_MB_2U(SCH_1):I3C_BMC_SWB_SCL   I177 @S9S_MB_2U_LIB.S9S_MB_2U(SCH_1):PAGE228
     2 P3V3_AUX @S9S_MB_2U_LIB.S9S_MB_2U(SCH_1):P3V3_AUX   I177 @S9S_MB_2U_LIB.S9S_MB_2U(SCH_1):PAGE228

R1338 Q_RES_0402LF-10K,1%,1/16W,CHIPA
     1 FM_PCH_BIOS_RCVR_MODE @S9S_MB_2U_LIB.S9S_MB_2U(SCH_1):FM_PCH_BIOS_RCVR_MODE   I107 @S9S_MB_2U_LIB.S9S_MB_2U(SCH_1):PAGE189
     2    GND @S9S_MB_2U_LIB.S9S_MB_2U(SCH_1):GND   I107 @S9S_MB_2U_LIB.S9S_MB_2U(SCH_1):PAGE189

R1339 Q_RES_0402LF-10K,1%,1/16W,CHIPA
     1 P3V3_AUX @S9S_MB_2U_LIB.S9S_MB_2U(SCH_1):P3V3_AUX   I100 @S9S_MB_2U_LIB.S9S_MB_2U(SCH_1):PAGE189
     2 FM_BIOS_IMAGE_SWAP_N @S9S_MB_2U_LIB.S9S_MB_2U(SCH_1):FM_BIOS_IMAGE_SWAP_N   I100 @S9S_MB_2U_LIB.S9S_MB_2U(SCH_1):PAGE189

R1340 Q_RES_0402LF-20K,1%,1/16W,CHIPA
     1 P3V3_RTC_AUX @S9S_MB_2U_LIB.S9S_MB_2U(SCH_1):P3V3_RTC_AUX   I127 @S9S_MB_2U_LIB.S9S_MB_2U(SCH_1):PAGE189
     2 RST_RTCRST_N @S9S_MB_2U_LIB.S9S_MB_2U(SCH_1):RST_RTCRST_N   I127 @S9S_MB_2U_LIB.S9S_MB_2U(SCH_1):PAGE189

R1341 Q_RES_0402LF-10K,1%,1/16W,CHIPA
     1 FM_ADR_COMPLETE @S9S_MB_2U_LIB.S9S_MB_2U(SCH_1):FM_ADR_COMPLETE   I106 @S9S_MB_2U_LIB.S9S_MB_2U(SCH_1):PAGE189
     2    GND @S9S_MB_2U_LIB.S9S_MB_2U(SCH_1):GND   I106 @S9S_MB_2U_LIB.S9S_MB_2U(SCH_1):PAGE189

R1342 Q_RES_0402LF-10K,1%,1/16W,CHIPA
     1 P1V05_PCH_AUX @S9S_MB_2U_LIB.S9S_MB_2U(SCH_1):P1V05_PCH_AUX   I114 @S9S_MB_2U_LIB.S9S_MB_2U(SCH_1):PAGE189
     2 FM_ME_RCVR_N @S9S_MB_2U_LIB.S9S_MB_2U(SCH_1):FM_ME_RCVR_N   I114 @S9S_MB_2U_LIB.S9S_MB_2U(SCH_1):PAGE189

R1343 Q_RES_0402LF-10K,1%,1/16W,CHIPA
     1 P1V05_PCH_AUX @S9S_MB_2U_LIB.S9S_MB_2U(SCH_1):P1V05_PCH_AUX   I113 @S9S_MB_2U_LIB.S9S_MB_2U(SCH_1):PAGE189
     2 FM_PASSWORD_CLEAR_N @S9S_MB_2U_LIB.S9S_MB_2U(SCH_1):FM_PASSWORD_CLEAR_N   I113 @S9S_MB_2U_LIB.S9S_MB_2U(SCH_1):PAGE189

R1345 Q_RES_0402LF-0,5%,1/16W,CHIP,CA
     1 JTAG_BMC_DBP_TDI_R @S9S_MB_2U_LIB.S9S_MB_2U(SCH_1):JTAG_BMC_DBP_TDI_R    I13 @S9S_MB_2U_LIB.S9S_MB_2U(SCH_1):PAGE226
     2 JTAG_BMC_DBP_TDI @S9S_MB_2U_LIB.S9S_MB_2U(SCH_1):JTAG_BMC_DBP_TDI    I13 @S9S_MB_2U_LIB.S9S_MB_2U(SCH_1):PAGE226

R1346 Q_RES_0402LF-100,1%,1/16W,CHIPA
     1 P0V7_JTAG_VREF_2 @S9S_MB_2U_LIB.S9S_MB_2U(SCH_1):P0V7_JTAG_VREF_2    I34 @S9S_MB_2U_LIB.S9S_MB_2U(SCH_1):PAGE226
     2    GND @S9S_MB_2U_LIB.S9S_MB_2U(SCH_1):GND    I34 @S9S_MB_2U_LIB.S9S_MB_2U(SCH_1):PAGE226

R1347 Q_RES_0402LF-1K,1%,1/16W,CHIP,A
     1 PD_GTL2014_BMC_JTAG_VREF_1 @S9S_MB_2U_LIB.S9S_MB_2U(SCH_1):PD_GTL2014_BMC_JTAG_VREF_1    I10 @S9S_MB_2U_LIB.S9S_MB_2U(SCH_1):PAGE226
     2    GND @S9S_MB_2U_LIB.S9S_MB_2U(SCH_1):GND    I10 @S9S_MB_2U_LIB.S9S_MB_2U(SCH_1):PAGE226

R1348 Q_RES_0402LF-0,5%,1/16W,CHIP,CA
     1 JTAG_DBP_CPU_GTL_TCK_R1 @S9S_MB_2U_LIB.S9S_MB_2U(SCH_1):JTAG_DBP_CPU_GTL_TCK_R1    I88 @S9S_MB_2U_LIB.S9S_MB_2U(SCH_1):PAGE137
     2 JTAG_DBP_CPU_GTL_TCK @S9S_MB_2U_LIB.S9S_MB_2U(SCH_1):JTAG_DBP_CPU_GTL_TCK    I88 @S9S_MB_2U_LIB.S9S_MB_2U(SCH_1):PAGE137

R1349 Q_RES_0402LF-0,5%,1/16W,CHIP,CA
     1 JTAG_DBP_TCK_PCH_R @S9S_MB_2U_LIB.S9S_MB_2U(SCH_1):JTAG_DBP_TCK_PCH_R    I87 @S9S_MB_2U_LIB.S9S_MB_2U(SCH_1):PAGE137
     2 JTAG_DBP_TCK_PCH @S9S_MB_2U_LIB.S9S_MB_2U(SCH_1):JTAG_DBP_TCK_PCH    I87 @S9S_MB_2U_LIB.S9S_MB_2U(SCH_1):PAGE137

R1350 Q_RES_0402LF-100K,1%,1/16W,CHIA
     1 RMII_OCP_BMC_CRSDV @S9S_MB_2U_LIB.S9S_MB_2U(SCH_1):RMII_OCP_BMC_CRSDV    I73 @S9S_MB_2U_LIB.S9S_MB_2U(SCH_1):PAGE151
     2    GND @S9S_MB_2U_LIB.S9S_MB_2U(SCH_1):GND    I73 @S9S_MB_2U_LIB.S9S_MB_2U(SCH_1):PAGE151

R1351 Q_RES_0402LF-100K,1%,1/16W,CHIA
     1 RMII_OCP_BMC_RXD_0 @S9S_MB_2U_LIB.S9S_MB_2U(SCH_1):RMII_OCP_BMC_RXD_0    I72 @S9S_MB_2U_LIB.S9S_MB_2U(SCH_1):PAGE151
     2    GND @S9S_MB_2U_LIB.S9S_MB_2U(SCH_1):GND    I72 @S9S_MB_2U_LIB.S9S_MB_2U(SCH_1):PAGE151

R1352 Q_RES_0402LF-100K,1%,1/16W,CHIA
     1 RMII_OCP_BMC_RXD_1 @S9S_MB_2U_LIB.S9S_MB_2U(SCH_1):RMII_OCP_BMC_RXD_1    I71 @S9S_MB_2U_LIB.S9S_MB_2U(SCH_1):PAGE151
     2    GND @S9S_MB_2U_LIB.S9S_MB_2U(SCH_1):GND    I71 @S9S_MB_2U_LIB.S9S_MB_2U(SCH_1):PAGE151

R1353 Q_RES_0402LF-100K,1%,1/16W,CHIA
     1 RMII_BMC_OCP_TX_EN @S9S_MB_2U_LIB.S9S_MB_2U(SCH_1):RMII_BMC_OCP_TX_EN    I56 @S9S_MB_2U_LIB.S9S_MB_2U(SCH_1):PAGE151
     2    GND @S9S_MB_2U_LIB.S9S_MB_2U(SCH_1):GND    I56 @S9S_MB_2U_LIB.S9S_MB_2U(SCH_1):PAGE151

R1354 Q_RES_0402LF-100K,1%,1/16W,CHIA
     1 RMII_BMC_OCP_TXD_0 @S9S_MB_2U_LIB.S9S_MB_2U(SCH_1):RMII_BMC_OCP_TXD_0    I55 @S9S_MB_2U_LIB.S9S_MB_2U(SCH_1):PAGE151
     2    GND @S9S_MB_2U_LIB.S9S_MB_2U(SCH_1):GND    I55 @S9S_MB_2U_LIB.S9S_MB_2U(SCH_1):PAGE151

R1355 Q_RES_0402LF-100K,1%,1/16W,CHIA
     1 RMII_BMC_OCP_TXD_1 @S9S_MB_2U_LIB.S9S_MB_2U(SCH_1):RMII_BMC_OCP_TXD_1    I54 @S9S_MB_2U_LIB.S9S_MB_2U(SCH_1):PAGE151
     2    GND @S9S_MB_2U_LIB.S9S_MB_2U(SCH_1):GND    I54 @S9S_MB_2U_LIB.S9S_MB_2U(SCH_1):PAGE151

R1356 Q_RES_0402LF-1K,1%,1/16W,CHIP,A
     1 RMII_BMC_OCP_RX_ER @S9S_MB_2U_LIB.S9S_MB_2U(SCH_1):RMII_BMC_OCP_RX_ER    I53 @S9S_MB_2U_LIB.S9S_MB_2U(SCH_1):PAGE151
     2    GND @S9S_MB_2U_LIB.S9S_MB_2U(SCH_1):GND    I53 @S9S_MB_2U_LIB.S9S_MB_2U(SCH_1):PAGE151

R1365 Q_RES_0402LF-1K,1%,1/16W,CHIP,A
     1 FM_JTAG_TCK_MUX_SEL @S9S_MB_2U_LIB.S9S_MB_2U(SCH_1):FM_JTAG_TCK_MUX_SEL   I116 @S9S_MB_2U_LIB.S9S_MB_2U(SCH_1):PAGE137
     2    GND @S9S_MB_2U_LIB.S9S_MB_2U(SCH_1):GND   I116 @S9S_MB_2U_LIB.S9S_MB_2U(SCH_1):PAGE137

R1366 Q_RES_0402LF-100,1%,1/16W,CHIPA
     1 JTAG_DBP_TDO @S9S_MB_2U_LIB.S9S_MB_2U(SCH_1):JTAG_DBP_TDO    I64 @S9S_MB_2U_LIB.S9S_MB_2U(SCH_1):PAGE226
     2 JTAG_DBP_FB_TDO @S9S_MB_2U_LIB.S9S_MB_2U(SCH_1):JTAG_DBP_FB_TDO    I64 @S9S_MB_2U_LIB.S9S_MB_2U(SCH_1):PAGE226

R1367 Q_RES_0402LF-100,1%,1/16W,CHIPA
     1 JTAG_DBP_PRDY_N @S9S_MB_2U_LIB.S9S_MB_2U(SCH_1):JTAG_DBP_PRDY_N    I65 @S9S_MB_2U_LIB.S9S_MB_2U(SCH_1):PAGE226
     2 JTAG_DBP_PRDY_R_N @S9S_MB_2U_LIB.S9S_MB_2U(SCH_1):JTAG_DBP_PRDY_R_N    I65 @S9S_MB_2U_LIB.S9S_MB_2U(SCH_1):PAGE226

R1368 Q_RES_0402LF-1K,1%,1/16W,CHIP,A
     1 PD_JTAG_DBP_B2 @S9S_MB_2U_LIB.S9S_MB_2U(SCH_1):PD_JTAG_DBP_B2    I48 @S9S_MB_2U_LIB.S9S_MB_2U(SCH_1):PAGE226
     2    GND @S9S_MB_2U_LIB.S9S_MB_2U(SCH_1):GND    I48 @S9S_MB_2U_LIB.S9S_MB_2U(SCH_1):PAGE226

R1369 Q_RES_0402LF-1K,1%,1/16W,CHIP,A
     1 PD_JTAG_DBP_B0 @S9S_MB_2U_LIB.S9S_MB_2U(SCH_1):PD_JTAG_DBP_B0    I47 @S9S_MB_2U_LIB.S9S_MB_2U(SCH_1):PAGE226
     2    GND @S9S_MB_2U_LIB.S9S_MB_2U(SCH_1):GND    I47 @S9S_MB_2U_LIB.S9S_MB_2U(SCH_1):PAGE226

R1370 Q_RES_0402LF-100,1%,1/16W,CHIPA
     1 P3V3_AUX @S9S_MB_2U_LIB.S9S_MB_2U(SCH_1):P3V3_AUX    I98 @S9S_MB_2U_LIB.S9S_MB_2U(SCH_1):PAGE137
     2 FM_REMOTE_DEBUG_DET_R @S9S_MB_2U_LIB.S9S_MB_2U(SCH_1):FM_REMOTE_DEBUG_DET_R    I98 @S9S_MB_2U_LIB.S9S_MB_2U(SCH_1):PAGE137

R1371 Q_RES_0402LF-130,1%,1/16W,CHIPA
     1 LED_RST_PLD_CPU0_DRAM_AB_N @S9S_MB_2U_LIB.S9S_MB_2U(SCH_1):LED_RST_PLD_CPU0_DRAM_AB_N    I49 @S9S_MB_2U_LIB.S9S_MB_2U(SCH_1):PAGE304
     2 P3V3_AUX @S9S_MB_2U_LIB.S9S_MB_2U(SCH_1):P3V3_AUX    I49 @S9S_MB_2U_LIB.S9S_MB_2U(SCH_1):PAGE304

R1374 Q_RES_0402LF-1K,1%,1/16W,CHIP,A
     1 PD_JTAG_BMC_NTRST_N @S9S_MB_2U_LIB.S9S_MB_2U(SCH_1):PD_JTAG_BMC_NTRST_N   I103 @S9S_MB_2U_LIB.S9S_MB_2U(SCH_1):PAGE137
     2    GND @S9S_MB_2U_LIB.S9S_MB_2U(SCH_1):GND   I103 @S9S_MB_2U_LIB.S9S_MB_2U(SCH_1):PAGE137

R1375 Q_RES_0402LF-10K,1%,1/16W,CHIPA
     1 FM_BMC_EN_DET @S9S_MB_2U_LIB.S9S_MB_2U(SCH_1):FM_BMC_EN_DET    I97 @S9S_MB_2U_LIB.S9S_MB_2U(SCH_1):PAGE137
     2    GND @S9S_MB_2U_LIB.S9S_MB_2U(SCH_1):GND    I97 @S9S_MB_2U_LIB.S9S_MB_2U(SCH_1):PAGE137

R1380 Q_RES_0402LF-1K,1%,1/16W,CHIP,A
     1 P3V3_AUX @S9S_MB_2U_LIB.S9S_MB_2U(SCH_1):P3V3_AUX    I31 @S9S_MB_2U_LIB.S9S_MB_2U(SCH_1):PAGE226
     2 JTAG_BMC_DBP_TDO @S9S_MB_2U_LIB.S9S_MB_2U(SCH_1):JTAG_BMC_DBP_TDO    I31 @S9S_MB_2U_LIB.S9S_MB_2U(SCH_1):PAGE226

R1381 Q_RES_0402LF-1K,1%,1/16W,CHIP,A
     1 P3V3_AUX @S9S_MB_2U_LIB.S9S_MB_2U(SCH_1):P3V3_AUX     I7 @S9S_MB_2U_LIB.S9S_MB_2U(SCH_1):PAGE226
     2 FM_BMC_CPU_FBRK_OUT_N @S9S_MB_2U_LIB.S9S_MB_2U(SCH_1):FM_BMC_CPU_FBRK_OUT_N     I7 @S9S_MB_2U_LIB.S9S_MB_2U(SCH_1):PAGE226

R1382 Q_RES_0402LF-1K,1%,1/16W,CHIP,A
     1 P3V3_AUX @S9S_MB_2U_LIB.S9S_MB_2U(SCH_1):P3V3_AUX    I20 @S9S_MB_2U_LIB.S9S_MB_2U(SCH_1):PAGE226
     2 JTAG_DBP_BMC_PRDY_N @S9S_MB_2U_LIB.S9S_MB_2U(SCH_1):JTAG_DBP_BMC_PRDY_N    I20 @S9S_MB_2U_LIB.S9S_MB_2U(SCH_1):PAGE226

R1383 Q_RES_0402LF-1K,1%,1/16W,CHIP,A
     1 P3V3_AUX @S9S_MB_2U_LIB.S9S_MB_2U(SCH_1):P3V3_AUX     I1 @S9S_MB_2U_LIB.S9S_MB_2U(SCH_1):PAGE226
     2 JTAG_BMC_DBP_PREQ_N @S9S_MB_2U_LIB.S9S_MB_2U(SCH_1):JTAG_BMC_DBP_PREQ_N     I1 @S9S_MB_2U_LIB.S9S_MB_2U(SCH_1):PAGE226

R1384 Q_RES_0402LF-2K,1%,1/16W,EMPTYA
     1 SMB_SML0_3V3AUX_SCL @S9S_MB_2U_LIB.S9S_MB_2U(SCH_1):SMB_SML0_3V3AUX_SCL     I4 @S9S_MB_2U_LIB.S9S_MB_2U(SCH_1):PAGE228
     2 P3V3_AUX @S9S_MB_2U_LIB.S9S_MB_2U(SCH_1):P3V3_AUX     I4 @S9S_MB_2U_LIB.S9S_MB_2U(SCH_1):PAGE228

R1385 Q_RES_0402LF-2K,1%,1/16W,EMPTYA
     1 SMB_SML0_3V3AUX_SDA @S9S_MB_2U_LIB.S9S_MB_2U(SCH_1):SMB_SML0_3V3AUX_SDA     I5 @S9S_MB_2U_LIB.S9S_MB_2U(SCH_1):PAGE228
     2 P3V3_AUX @S9S_MB_2U_LIB.S9S_MB_2U(SCH_1):P3V3_AUX     I5 @S9S_MB_2U_LIB.S9S_MB_2U(SCH_1):PAGE228

R1386 Q_RES_0402LF-2K,1%,1/16W,EMPTYA
     1 SMB_SML1_PMBUS_3V3AUX_PCH_SCL @S9S_MB_2U_LIB.S9S_MB_2U(SCH_1):SMB_SML1_PMBUS_3V3AUX_PCH_SCL     I6 @S9S_MB_2U_LIB.S9S_MB_2U(SCH_1):PAGE228
     2 P3V3_AUX @S9S_MB_2U_LIB.S9S_MB_2U(SCH_1):P3V3_AUX     I6 @S9S_MB_2U_LIB.S9S_MB_2U(SCH_1):PAGE228

R1387 Q_RES_0402LF-2K,1%,1/16W,EMPTYA
     1 SMB_SML1_PMBUS_3V3AUX_PCH_SDA @S9S_MB_2U_LIB.S9S_MB_2U(SCH_1):SMB_SML1_PMBUS_3V3AUX_PCH_SDA     I7 @S9S_MB_2U_LIB.S9S_MB_2U(SCH_1):PAGE228
     2 P3V3_AUX @S9S_MB_2U_LIB.S9S_MB_2U(SCH_1):P3V3_AUX     I7 @S9S_MB_2U_LIB.S9S_MB_2U(SCH_1):PAGE228

R1388 Q_RES_0402LF-2K,1%,1/16W,EMPTYA
     1 PWRGD_DRAMPWRGD_CPU1_EF_R_LVC1 @S9S_MB_2U_LIB.S9S_MB_2U(SCH_1):PWRGD_DRAMPWRGD_CPU1_EF_R_LVC1    I17 @S9S_MB_2U_LIB.S9S_MB_2U(SCH_1):PAGE208
     2    GND @S9S_MB_2U_LIB.S9S_MB_2U(SCH_1):GND    I17 @S9S_MB_2U_LIB.S9S_MB_2U(SCH_1):PAGE208

R1389 Q_RES_0402LF-0,5%,1/16W,CHIP,CA
     1 FM_P1V05_PCH_AUX_EN @S9S_MB_2U_LIB.S9S_MB_2U(SCH_1):FM_P1V05_PCH_AUX_EN    I27 @S9S_MB_2U_LIB.S9S_MB_2U(SCH_1):PAGE248
     2 FM_P1V05_PCH_AUX_R_EN @S9S_MB_2U_LIB.S9S_MB_2U(SCH_1):FM_P1V05_PCH_AUX_R_EN    I27 @S9S_MB_2U_LIB.S9S_MB_2U(SCH_1):PAGE248

R1390 Q_RES_0402LF-1K,1%,1/16W,EMPTYA
     1 FM_PLD_CLKS_DEV_EN @S9S_MB_2U_LIB.S9S_MB_2U(SCH_1):FM_PLD_CLKS_DEV_EN   I275 @S9S_MB_2U_LIB.S9S_MB_2U(SCH_1):PAGE197
     2    GND @S9S_MB_2U_LIB.S9S_MB_2U(SCH_1):GND   I275 @S9S_MB_2U_LIB.S9S_MB_2U(SCH_1):PAGE197

R1391 Q_RES_0402LF-240,1%,1/16W,EMPTA
     1    GND @S9S_MB_2U_LIB.S9S_MB_2U(SCH_1):GND    I61 @S9S_MB_2U_LIB.S9S_MB_2U(SCH_1):PAGE120
     2 FM_S3M_CPU0_LVC1_GPIO_2 @S9S_MB_2U_LIB.S9S_MB_2U(SCH_1):FM_S3M_CPU0_LVC1_GPIO_2    I61 @S9S_MB_2U_LIB.S9S_MB_2U(SCH_1):PAGE120

R1392 Q_RES_0402LF-240,1%,1/16W,EMPTA
     1    GND @S9S_MB_2U_LIB.S9S_MB_2U(SCH_1):GND    I62 @S9S_MB_2U_LIB.S9S_MB_2U(SCH_1):PAGE120
     2 FM_S3M_CPU0_LVC1_GPIO_3 @S9S_MB_2U_LIB.S9S_MB_2U(SCH_1):FM_S3M_CPU0_LVC1_GPIO_3    I62 @S9S_MB_2U_LIB.S9S_MB_2U(SCH_1):PAGE120

R1393 Q_RES_0402LF-240,1%,1/16W,EMPTA
     1    GND @S9S_MB_2U_LIB.S9S_MB_2U(SCH_1):GND    I66 @S9S_MB_2U_LIB.S9S_MB_2U(SCH_1):PAGE120
     2 FM_S3M_CPU1_LVC1_GPIO_2 @S9S_MB_2U_LIB.S9S_MB_2U(SCH_1):FM_S3M_CPU1_LVC1_GPIO_2    I66 @S9S_MB_2U_LIB.S9S_MB_2U(SCH_1):PAGE120

R1394 Q_RES_0402LF-240,1%,1/16W,EMPTA
     1    GND @S9S_MB_2U_LIB.S9S_MB_2U(SCH_1):GND    I67 @S9S_MB_2U_LIB.S9S_MB_2U(SCH_1):PAGE120
     2 FM_S3M_CPU1_LVC1_GPIO_3 @S9S_MB_2U_LIB.S9S_MB_2U(SCH_1):FM_S3M_CPU1_LVC1_GPIO_3    I67 @S9S_MB_2U_LIB.S9S_MB_2U(SCH_1):PAGE120

R1395 Q_RES_0402LF-33.2,1%,1/16W,CHIA
     1 SPI_PCH_TPM_CS_N @S9S_MB_2U_LIB.S9S_MB_2U(SCH_1):SPI_PCH_TPM_CS_N   I102 @S9S_MB_2U_LIB.S9S_MB_2U(SCH_1):PAGE177
     2 SPI_TPM_CS_N @S9S_MB_2U_LIB.S9S_MB_2U(SCH_1):SPI_TPM_CS_N   I102 @S9S_MB_2U_LIB.S9S_MB_2U(SCH_1):PAGE177

R1396 Q_RES_0402LF-10K,1%,1/16W,CHIPA
     1 FM_M2_SSD_0_PEDET @S9S_MB_2U_LIB.S9S_MB_2U(SCH_1):FM_M2_SSD_0_PEDET   I167 @S9S_MB_2U_LIB.S9S_MB_2U(SCH_1):PAGE182
     2 P3V3_AUX @S9S_MB_2U_LIB.S9S_MB_2U(SCH_1):P3V3_AUX   I167 @S9S_MB_2U_LIB.S9S_MB_2U(SCH_1):PAGE182

R1398 Q_RES_0402LF-2K,1%,1/16W,EMPTYA
     1 PWRGD_CPU1_LVC1_R @S9S_MB_2U_LIB.S9S_MB_2U(SCH_1):PWRGD_CPU1_LVC1_R    I22 @S9S_MB_2U_LIB.S9S_MB_2U(SCH_1):PAGE208
     2    GND @S9S_MB_2U_LIB.S9S_MB_2U(SCH_1):GND    I22 @S9S_MB_2U_LIB.S9S_MB_2U(SCH_1):PAGE208

R1399 Q_RES_0402LF-10K,1%,1/16W,CHIPA
     1 FM_PFR_DSW_PWROK_N @S9S_MB_2U_LIB.S9S_MB_2U(SCH_1):FM_PFR_DSW_PWROK_N    I17 @S9S_MB_2U_LIB.S9S_MB_2U(SCH_1):PAGE209
     2 P3V3_AUX @S9S_MB_2U_LIB.S9S_MB_2U(SCH_1):P3V3_AUX    I17 @S9S_MB_2U_LIB.S9S_MB_2U(SCH_1):PAGE209

R1401 Q_RES_0402LF-10K,1%,1/16W,CHIPA
     1 PU_MAIN_FPGA_CONFIG_DONE @S9S_MB_2U_LIB.S9S_MB_2U(SCH_1):PU_MAIN_FPGA_CONFIG_DONE    I16 @S9S_MB_2U_LIB.S9S_MB_2U(SCH_1):PAGE209
     2 P3V3_AUX @S9S_MB_2U_LIB.S9S_MB_2U(SCH_1):P3V3_AUX    I16 @S9S_MB_2U_LIB.S9S_MB_2U(SCH_1):PAGE209

R1402 Q_RES_0402LF-2K,1%,1/16W,CHIP,A
     1 PWRGD_SYS_PWROK @S9S_MB_2U_LIB.S9S_MB_2U(SCH_1):PWRGD_SYS_PWROK    I23 @S9S_MB_2U_LIB.S9S_MB_2U(SCH_1):PAGE208
     2    GND @S9S_MB_2U_LIB.S9S_MB_2U(SCH_1):GND    I23 @S9S_MB_2U_LIB.S9S_MB_2U(SCH_1):PAGE208

R1403 Q_RES_0402LF-2K,1%,1/16W,CHIP,A
     1 PWRGD_PCH_PWROK @S9S_MB_2U_LIB.S9S_MB_2U(SCH_1):PWRGD_PCH_PWROK    I24 @S9S_MB_2U_LIB.S9S_MB_2U(SCH_1):PAGE208
     2    GND @S9S_MB_2U_LIB.S9S_MB_2U(SCH_1):GND    I24 @S9S_MB_2U_LIB.S9S_MB_2U(SCH_1):PAGE208

R1404 Q_RES_0402LF-2K,1%,1/16W,CHIP,A
     1 FM_PCH_P1V8_AUX_EN @S9S_MB_2U_LIB.S9S_MB_2U(SCH_1):FM_PCH_P1V8_AUX_EN    I25 @S9S_MB_2U_LIB.S9S_MB_2U(SCH_1):PAGE208
     2    GND @S9S_MB_2U_LIB.S9S_MB_2U(SCH_1):GND    I25 @S9S_MB_2U_LIB.S9S_MB_2U(SCH_1):PAGE208

R1405 Q_RES_0402LF-2K,1%,1/16W,CHIP,A
     1 FM_PVCCIN_CPU0_R_EN @S9S_MB_2U_LIB.S9S_MB_2U(SCH_1):FM_PVCCIN_CPU0_R_EN    I26 @S9S_MB_2U_LIB.S9S_MB_2U(SCH_1):PAGE208
     2    GND @S9S_MB_2U_LIB.S9S_MB_2U(SCH_1):GND    I26 @S9S_MB_2U_LIB.S9S_MB_2U(SCH_1):PAGE208

R1406 Q_RES_0402LF-2K,1%,1/16W,CHIP,A
     1 FM_PVCCIN_CPU1_R_EN @S9S_MB_2U_LIB.S9S_MB_2U(SCH_1):FM_PVCCIN_CPU1_R_EN    I51 @S9S_MB_2U_LIB.S9S_MB_2U(SCH_1):PAGE208
     2    GND @S9S_MB_2U_LIB.S9S_MB_2U(SCH_1):GND    I51 @S9S_MB_2U_LIB.S9S_MB_2U(SCH_1):PAGE208

R1407 Q_RES_0402LF-2K,1%,1/16W,CHIP,A
     1 FM_PVCCINFAON_CPU0_R_EN @S9S_MB_2U_LIB.S9S_MB_2U(SCH_1):FM_PVCCINFAON_CPU0_R_EN    I52 @S9S_MB_2U_LIB.S9S_MB_2U(SCH_1):PAGE208
     2    GND @S9S_MB_2U_LIB.S9S_MB_2U(SCH_1):GND    I52 @S9S_MB_2U_LIB.S9S_MB_2U(SCH_1):PAGE208

R1408 Q_RES_0402LF-2K,1%,1/16W,CHIP,A
     1 FM_PVCCINFAON_CPU1_R_EN @S9S_MB_2U_LIB.S9S_MB_2U(SCH_1):FM_PVCCINFAON_CPU1_R_EN    I53 @S9S_MB_2U_LIB.S9S_MB_2U(SCH_1):PAGE208
     2    GND @S9S_MB_2U_LIB.S9S_MB_2U(SCH_1):GND    I53 @S9S_MB_2U_LIB.S9S_MB_2U(SCH_1):PAGE208

R1409 Q_RES_0402LF-2K,1%,1/16W,CHIP,A
     1 FM_PVCCFA_EHV_CPU0_R_EN @S9S_MB_2U_LIB.S9S_MB_2U(SCH_1):FM_PVCCFA_EHV_CPU0_R_EN    I55 @S9S_MB_2U_LIB.S9S_MB_2U(SCH_1):PAGE208
     2    GND @S9S_MB_2U_LIB.S9S_MB_2U(SCH_1):GND    I55 @S9S_MB_2U_LIB.S9S_MB_2U(SCH_1):PAGE208

R1410 Q_RES_0402LF-2K,1%,1/16W,CHIP,A
     1 FM_PVCCFA_EHV_CPU1_R_EN @S9S_MB_2U_LIB.S9S_MB_2U(SCH_1):FM_PVCCFA_EHV_CPU1_R_EN    I54 @S9S_MB_2U_LIB.S9S_MB_2U(SCH_1):PAGE208
     2    GND @S9S_MB_2U_LIB.S9S_MB_2U(SCH_1):GND    I54 @S9S_MB_2U_LIB.S9S_MB_2U(SCH_1):PAGE208

R1411 Q_RES_0402LF-2K,1%,1/16W,CHIP,A
     1 FM_PVCCFA_EHV_FIVRA_CPU0_R_EN @S9S_MB_2U_LIB.S9S_MB_2U(SCH_1):FM_PVCCFA_EHV_FIVRA_CPU0_R_EN    I56 @S9S_MB_2U_LIB.S9S_MB_2U(SCH_1):PAGE208
     2    GND @S9S_MB_2U_LIB.S9S_MB_2U(SCH_1):GND    I56 @S9S_MB_2U_LIB.S9S_MB_2U(SCH_1):PAGE208

R1412 Q_RES_0402LF-2K,1%,1/16W,CHIP,A
     1 FM_PVCCFA_EHV_FIVRA_CPU1_R_EN @S9S_MB_2U_LIB.S9S_MB_2U(SCH_1):FM_PVCCFA_EHV_FIVRA_CPU1_R_EN    I57 @S9S_MB_2U_LIB.S9S_MB_2U(SCH_1):PAGE208
     2    GND @S9S_MB_2U_LIB.S9S_MB_2U(SCH_1):GND    I57 @S9S_MB_2U_LIB.S9S_MB_2U(SCH_1):PAGE208

R1413 Q_RES_0402LF-2K,1%,1/16W,CHIP,A
     1 FM_PVCCD_HV_CPU0_EN @S9S_MB_2U_LIB.S9S_MB_2U(SCH_1):FM_PVCCD_HV_CPU0_EN    I59 @S9S_MB_2U_LIB.S9S_MB_2U(SCH_1):PAGE208
     2    GND @S9S_MB_2U_LIB.S9S_MB_2U(SCH_1):GND    I59 @S9S_MB_2U_LIB.S9S_MB_2U(SCH_1):PAGE208

R1414 Q_RES_0402LF-2K,1%,1/16W,CHIP,A
     1 FM_PVCCD_HV_CPU1_EN @S9S_MB_2U_LIB.S9S_MB_2U(SCH_1):FM_PVCCD_HV_CPU1_EN    I58 @S9S_MB_2U_LIB.S9S_MB_2U(SCH_1):PAGE208
     2    GND @S9S_MB_2U_LIB.S9S_MB_2U(SCH_1):GND    I58 @S9S_MB_2U_LIB.S9S_MB_2U(SCH_1):PAGE208

R1415 Q_RES_0402LF-2K,1%,1/16W,EMPTYA
     1 RST_CPU0_LVC1_R_N @S9S_MB_2U_LIB.S9S_MB_2U(SCH_1):RST_CPU0_LVC1_R_N     I4 @S9S_MB_2U_LIB.S9S_MB_2U(SCH_1):PAGE208
     2    GND @S9S_MB_2U_LIB.S9S_MB_2U(SCH_1):GND     I4 @S9S_MB_2U_LIB.S9S_MB_2U(SCH_1):PAGE208

R1416 Q_RES_0402LF-2K,1%,1/16W,EMPTYA
     1 RST_CPU1_LVC1_R_N @S9S_MB_2U_LIB.S9S_MB_2U(SCH_1):RST_CPU1_LVC1_R_N     I5 @S9S_MB_2U_LIB.S9S_MB_2U(SCH_1):PAGE208
     2    GND @S9S_MB_2U_LIB.S9S_MB_2U(SCH_1):GND     I5 @S9S_MB_2U_LIB.S9S_MB_2U(SCH_1):PAGE208

R1417 Q_RES_0402LF-2K,1%,1/16W,CHIP,A
     1 RST_PCIE_CPU0_DEV_PERST_N @S9S_MB_2U_LIB.S9S_MB_2U(SCH_1):RST_PCIE_CPU0_DEV_PERST_N     I7 @S9S_MB_2U_LIB.S9S_MB_2U(SCH_1):PAGE208
     2    GND @S9S_MB_2U_LIB.S9S_MB_2U(SCH_1):GND     I7 @S9S_MB_2U_LIB.S9S_MB_2U(SCH_1):PAGE208

R1418 Q_RES_0402LF-2K,1%,1/16W,CHIP,A
     1 RST_PCIE_CPU1_DEV_PERST_N @S9S_MB_2U_LIB.S9S_MB_2U(SCH_1):RST_PCIE_CPU1_DEV_PERST_N     I6 @S9S_MB_2U_LIB.S9S_MB_2U(SCH_1):PAGE208
     2    GND @S9S_MB_2U_LIB.S9S_MB_2U(SCH_1):GND     I6 @S9S_MB_2U_LIB.S9S_MB_2U(SCH_1):PAGE208

R1419 Q_RES_0402LF-2K,1%,1/16W,CHIP,A
     1 RST_PCIE_PCH_DEV_PERST_N @S9S_MB_2U_LIB.S9S_MB_2U(SCH_1):RST_PCIE_PCH_DEV_PERST_N     I8 @S9S_MB_2U_LIB.S9S_MB_2U(SCH_1):PAGE208
     2    GND @S9S_MB_2U_LIB.S9S_MB_2U(SCH_1):GND     I8 @S9S_MB_2U_LIB.S9S_MB_2U(SCH_1):PAGE208

R1420 Q_RES_0402LF-2K,1%,1/16W,CHIP,A
     1 RST_PLTRST_PLD_B_N @S9S_MB_2U_LIB.S9S_MB_2U(SCH_1):RST_PLTRST_PLD_B_N     I9 @S9S_MB_2U_LIB.S9S_MB_2U(SCH_1):PAGE208
     2    GND @S9S_MB_2U_LIB.S9S_MB_2U(SCH_1):GND     I9 @S9S_MB_2U_LIB.S9S_MB_2U(SCH_1):PAGE208

R1421 Q_RES_0402LF-2K,1%,1/16W,CHIP,A
     1 RST_RSMRST_PLD_R_N @S9S_MB_2U_LIB.S9S_MB_2U(SCH_1):RST_RSMRST_PLD_R_N    I10 @S9S_MB_2U_LIB.S9S_MB_2U(SCH_1):PAGE208
     2    GND @S9S_MB_2U_LIB.S9S_MB_2U(SCH_1):GND    I10 @S9S_MB_2U_LIB.S9S_MB_2U(SCH_1):PAGE208

R1423 Q_RES_0402LF-33.2,1%,1/16W,CHIA
     1 PWRGD_SYS_PWROK_R @S9S_MB_2U_LIB.S9S_MB_2U(SCH_1):PWRGD_SYS_PWROK_R    I44 @S9S_MB_2U_LIB.S9S_MB_2U(SCH_1):PAGE211
     2 PWRGD_SYS_PWROK @S9S_MB_2U_LIB.S9S_MB_2U(SCH_1):PWRGD_SYS_PWROK    I44 @S9S_MB_2U_LIB.S9S_MB_2U(SCH_1):PAGE211

R1434 Q_RES_0402LF-10K,1%,1/16W,CHIPA
     1 FM_SYS_THROTTLE_R_N @S9S_MB_2U_LIB.S9S_MB_2U(SCH_1):FM_SYS_THROTTLE_R_N    I44 @S9S_MB_2U_LIB.S9S_MB_2U(SCH_1):PAGE209
     2 P3V3_AUX @S9S_MB_2U_LIB.S9S_MB_2U(SCH_1):P3V3_AUX    I44 @S9S_MB_2U_LIB.S9S_MB_2U(SCH_1):PAGE209

R1435 Q_RES_0402LF-10K,1%,1/16W,CHIPA
     1 FM_ADR_TRIGGER_N @S9S_MB_2U_LIB.S9S_MB_2U(SCH_1):FM_ADR_TRIGGER_N    I43 @S9S_MB_2U_LIB.S9S_MB_2U(SCH_1):PAGE209
     2 P3V3_AUX @S9S_MB_2U_LIB.S9S_MB_2U(SCH_1):P3V3_AUX    I43 @S9S_MB_2U_LIB.S9S_MB_2U(SCH_1):PAGE209

R1437 Q_RES_0402LF-10K,1%,1/16W,CHIPA
     1 FM_PLD_HEARTBEAT_LVC3 @S9S_MB_2U_LIB.S9S_MB_2U(SCH_1):FM_PLD_HEARTBEAT_LVC3    I42 @S9S_MB_2U_LIB.S9S_MB_2U(SCH_1):PAGE209
     2 P3V3_AUX @S9S_MB_2U_LIB.S9S_MB_2U(SCH_1):P3V3_AUX    I42 @S9S_MB_2U_LIB.S9S_MB_2U(SCH_1):PAGE209

R1440 Q_RES_0402LF-10K,1%,1/16W,EMPTA
     1 JTAG_PLD_TDO_R @S9S_MB_2U_LIB.S9S_MB_2U(SCH_1):JTAG_PLD_TDO_R    I41 @S9S_MB_2U_LIB.S9S_MB_2U(SCH_1):PAGE209
     2 P3V3_AUX @S9S_MB_2U_LIB.S9S_MB_2U(SCH_1):P3V3_AUX    I41 @S9S_MB_2U_LIB.S9S_MB_2U(SCH_1):PAGE209

R1442 Q_RES_0402LF-33.2,1%,1/16W,CHIA
     1 PWRGD_PCH_PWROK_R @S9S_MB_2U_LIB.S9S_MB_2U(SCH_1):PWRGD_PCH_PWROK_R    I48 @S9S_MB_2U_LIB.S9S_MB_2U(SCH_1):PAGE211
     2 PWRGD_PCH_PWROK @S9S_MB_2U_LIB.S9S_MB_2U(SCH_1):PWRGD_PCH_PWROK    I48 @S9S_MB_2U_LIB.S9S_MB_2U(SCH_1):PAGE211

R1443 Q_RES_0402LF-33.2,1%,1/16W,CHIA
     1 PWRGD_CPUPWRGD_LVC1 @S9S_MB_2U_LIB.S9S_MB_2U(SCH_1):PWRGD_CPUPWRGD_LVC1    I49 @S9S_MB_2U_LIB.S9S_MB_2U(SCH_1):PAGE211
     2 PWRGD_CPUPWRGD_LVC1_R @S9S_MB_2U_LIB.S9S_MB_2U(SCH_1):PWRGD_CPUPWRGD_LVC1_R    I49 @S9S_MB_2U_LIB.S9S_MB_2U(SCH_1):PAGE211

R1444 Q_RES_0402LF-33.2,1%,1/16W,CHIA
     1 PWRGD_P1V8_PCH_AUX @S9S_MB_2U_LIB.S9S_MB_2U(SCH_1):PWRGD_P1V8_PCH_AUX    I54 @S9S_MB_2U_LIB.S9S_MB_2U(SCH_1):PAGE211
     2 PWRGD_P1V8_PCH_AUX_PLD @S9S_MB_2U_LIB.S9S_MB_2U(SCH_1):PWRGD_P1V8_PCH_AUX_PLD    I54 @S9S_MB_2U_LIB.S9S_MB_2U(SCH_1):PAGE211

R1445 Q_RES_0402LF-2K,1%,1/16W,CHIP,A
     1 FM_PVNN_MAIN_CPU0_EN @S9S_MB_2U_LIB.S9S_MB_2U(SCH_1):FM_PVNN_MAIN_CPU0_EN    I11 @S9S_MB_2U_LIB.S9S_MB_2U(SCH_1):PAGE268
     2    GND @S9S_MB_2U_LIB.S9S_MB_2U(SCH_1):GND    I11 @S9S_MB_2U_LIB.S9S_MB_2U(SCH_1):PAGE268

R1446 Q_RES_0402LF-33.2,1%,1/16W,CHIA
     1 PWRGD_PS_PWROK_PLD_ISO @S9S_MB_2U_LIB.S9S_MB_2U(SCH_1):PWRGD_PS_PWROK_PLD_ISO    I29 @S9S_MB_2U_LIB.S9S_MB_2U(SCH_1):PAGE213
     2 PWRGD_PS_PWROK_PLD_ISO_R @S9S_MB_2U_LIB.S9S_MB_2U(SCH_1):PWRGD_PS_PWROK_PLD_ISO_R    I29 @S9S_MB_2U_LIB.S9S_MB_2U(SCH_1):PAGE213

R1447 Q_RES_0402LF-33.2,1%,1/16W,CHIA
     1 FM_CPU0_SKTOCC_LVT3_N @S9S_MB_2U_LIB.S9S_MB_2U(SCH_1):FM_CPU0_SKTOCC_LVT3_N    I68 @S9S_MB_2U_LIB.S9S_MB_2U(SCH_1):PAGE211
     2 FM_CPU0_SKTOCC_LVT3_PLD_N @S9S_MB_2U_LIB.S9S_MB_2U(SCH_1):FM_CPU0_SKTOCC_LVT3_PLD_N    I68 @S9S_MB_2U_LIB.S9S_MB_2U(SCH_1):PAGE211

R1448 Q_RES_0402LF-33.2,1%,1/16W,CHIA
     1 FM_CPU1_SKTOCC_LVT3_N @S9S_MB_2U_LIB.S9S_MB_2U(SCH_1):FM_CPU1_SKTOCC_LVT3_N    I62 @S9S_MB_2U_LIB.S9S_MB_2U(SCH_1):PAGE211
     2 FM_CPU1_SKTOCC_LVT3_PLD_N @S9S_MB_2U_LIB.S9S_MB_2U(SCH_1):FM_CPU1_SKTOCC_LVT3_PLD_N    I62 @S9S_MB_2U_LIB.S9S_MB_2U(SCH_1):PAGE211

R1449 Q_RES_0402LF-10K,1%,1/16W,CHIPA
     1 P3V3_AUX @S9S_MB_2U_LIB.S9S_MB_2U(SCH_1):P3V3_AUX    I41 @S9S_MB_2U_LIB.S9S_MB_2U(SCH_1):PAGE192
     2 FM_BIOS_POST_CMPLT_N @S9S_MB_2U_LIB.S9S_MB_2U(SCH_1):FM_BIOS_POST_CMPLT_N    I41 @S9S_MB_2U_LIB.S9S_MB_2U(SCH_1):PAGE192

R1450 Q_RES_0402LF-10K,1%,1/16W,CHIPA
     1 P3V3_AUX @S9S_MB_2U_LIB.S9S_MB_2U(SCH_1):P3V3_AUX    I42 @S9S_MB_2U_LIB.S9S_MB_2U(SCH_1):PAGE192
     2 FM_THROTTLE_N @S9S_MB_2U_LIB.S9S_MB_2U(SCH_1):FM_THROTTLE_N    I42 @S9S_MB_2U_LIB.S9S_MB_2U(SCH_1):PAGE192

R1451 Q_RES_0402LF-2K,1%,1/16W,CHIP,A
     1 PU_SMB_SML3_3V3AUX_PCH_SCL @S9S_MB_2U_LIB.S9S_MB_2U(SCH_1):PU_SMB_SML3_3V3AUX_PCH_SCL   I109 @S9S_MB_2U_LIB.S9S_MB_2U(SCH_1):PAGE175
     2 P3V3_AUX @S9S_MB_2U_LIB.S9S_MB_2U(SCH_1):P3V3_AUX   I109 @S9S_MB_2U_LIB.S9S_MB_2U(SCH_1):PAGE175

R1452 Q_RES_0402LF-2K,1%,1/16W,CHIP,A
     1 PU_SMB_SML3_3V3AUX_PCH_SDA @S9S_MB_2U_LIB.S9S_MB_2U(SCH_1):PU_SMB_SML3_3V3AUX_PCH_SDA   I112 @S9S_MB_2U_LIB.S9S_MB_2U(SCH_1):PAGE175
     2 P3V3_AUX @S9S_MB_2U_LIB.S9S_MB_2U(SCH_1):P3V3_AUX   I112 @S9S_MB_2U_LIB.S9S_MB_2U(SCH_1):PAGE175

R1453 Q_RES_0402LF-2K,1%,1/16W,CHIP,A
     1 PU_SMB_SML4_3V3AUX_PCH_SCL @S9S_MB_2U_LIB.S9S_MB_2U(SCH_1):PU_SMB_SML4_3V3AUX_PCH_SCL   I120 @S9S_MB_2U_LIB.S9S_MB_2U(SCH_1):PAGE175
     2 P3V3_AUX @S9S_MB_2U_LIB.S9S_MB_2U(SCH_1):P3V3_AUX   I120 @S9S_MB_2U_LIB.S9S_MB_2U(SCH_1):PAGE175

R1454 Q_RES_0402LF-2K,1%,1/16W,CHIP,A
     1 PU_SMB_SML4_3V3AUX_PCH_SDA @S9S_MB_2U_LIB.S9S_MB_2U(SCH_1):PU_SMB_SML4_3V3AUX_PCH_SDA   I121 @S9S_MB_2U_LIB.S9S_MB_2U(SCH_1):PAGE175
     2 P3V3_AUX @S9S_MB_2U_LIB.S9S_MB_2U(SCH_1):P3V3_AUX   I121 @S9S_MB_2U_LIB.S9S_MB_2U(SCH_1):PAGE175

R1455 Q_RES_0402LF-49.9,1%,1/16W,CHIA
     1 FM_ADR_MODE0_R @S9S_MB_2U_LIB.S9S_MB_2U(SCH_1):FM_ADR_MODE0_R    I27 @S9S_MB_2U_LIB.S9S_MB_2U(SCH_1):PAGE193
     2 FM_ADR_MODE0 @S9S_MB_2U_LIB.S9S_MB_2U(SCH_1):FM_ADR_MODE0    I27 @S9S_MB_2U_LIB.S9S_MB_2U(SCH_1):PAGE193

R1456 Q_RES_0402LF-49.9,1%,1/16W,CHIA
     1 FM_CPU_RMCA_CATERR_DLY_LVT3_R_N @S9S_MB_2U_LIB.S9S_MB_2U(SCH_1):FM_CPU_RMCA_CATERR_DLY_LVT3_R_N    I28 @S9S_MB_2U_LIB.S9S_MB_2U(SCH_1):PAGE193
     2 FM_CPU_RMCA_CATERR_DLY_N @S9S_MB_2U_LIB.S9S_MB_2U(SCH_1):FM_CPU_RMCA_CATERR_DLY_N    I28 @S9S_MB_2U_LIB.S9S_MB_2U(SCH_1):PAGE193

R1457 Q_RES_0402LF-10K,1%,1/16W,CHIPA
     1 FM_XTAL_INPUT_FREQUENCY_1_MGPIO @S9S_MB_2U_LIB.S9S_MB_2U(SCH_1):FM_XTAL_INPUT_FREQUENCY_1_MGPIO_TEST5    I36 @S9S_MB_2U_LIB.S9S_MB_2U(SCH_1):PAGE188
     2    GND @S9S_MB_2U_LIB.S9S_MB_2U(SCH_1):GND    I36 @S9S_MB_2U_LIB.S9S_MB_2U(SCH_1):PAGE188

R1458 Q_RES_0402LF-10K,1%,1/16W,CHIPA
     1 P3V3_AUX @S9S_MB_2U_LIB.S9S_MB_2U(SCH_1):P3V3_AUX    I50 @S9S_MB_2U_LIB.S9S_MB_2U(SCH_1):PAGE192
     2 IRQ_SMI_ACTIVE_N @S9S_MB_2U_LIB.S9S_MB_2U(SCH_1):IRQ_SMI_ACTIVE_N    I50 @S9S_MB_2U_LIB.S9S_MB_2U(SCH_1):PAGE192

R1459 Q_RES_0402LF-10K,1%,1/16W,CHIPA
     1 P3V3_AUX @S9S_MB_2U_LIB.S9S_MB_2U(SCH_1):P3V3_AUX    I51 @S9S_MB_2U_LIB.S9S_MB_2U(SCH_1):PAGE192
     2 IRQ_PCH_CPU_NMI_EVENT_R_N @S9S_MB_2U_LIB.S9S_MB_2U(SCH_1):IRQ_PCH_CPU_NMI_EVENT_R_N    I51 @S9S_MB_2U_LIB.S9S_MB_2U(SCH_1):PAGE192

R1460 Q_RES_0402LF-2.2K,5%,1/16W,EMPA
     1 I3C_BMC_SWB_SDA @S9S_MB_2U_LIB.S9S_MB_2U(SCH_1):I3C_BMC_SWB_SDA   I176 @S9S_MB_2U_LIB.S9S_MB_2U(SCH_1):PAGE228
     2 P3V3_AUX @S9S_MB_2U_LIB.S9S_MB_2U(SCH_1):P3V3_AUX   I176 @S9S_MB_2U_LIB.S9S_MB_2U(SCH_1):PAGE228

R1461 Q_RES_0402LF-0,5%,1/16W,CHIP,CA
     1 FM_EUP_LOT6_N @S9S_MB_2U_LIB.S9S_MB_2U(SCH_1):FM_EUP_LOT6_N    I80 @S9S_MB_2U_LIB.S9S_MB_2U(SCH_1):PAGE177
     2 FM_SUSACK_N @S9S_MB_2U_LIB.S9S_MB_2U(SCH_1):FM_SUSACK_N    I80 @S9S_MB_2U_LIB.S9S_MB_2U(SCH_1):PAGE177

R1462 Q_RES_0402LF-1K,1%,1/16W,CHIP,A
     1 PD_CK440_SBI_CLK @S9S_MB_2U_LIB.S9S_MB_2U(SCH_1):PD_CK440_SBI_CLK   I274 @S9S_MB_2U_LIB.S9S_MB_2U(SCH_1):PAGE197
     2    GND @S9S_MB_2U_LIB.S9S_MB_2U(SCH_1):GND   I274 @S9S_MB_2U_LIB.S9S_MB_2U(SCH_1):PAGE197

R1463 Q_RES_0402LF-0,5%,1/16W,CHIP,CA
     1 P1V05_PCH_AUX @S9S_MB_2U_LIB.S9S_MB_2U(SCH_1):P1V05_PCH_AUX   I129 @S9S_MB_2U_LIB.S9S_MB_2U(SCH_1):PAGE181
     2 P1V05_PCH_PLL_AUX @S9S_MB_2U_LIB.S9S_MB_2U(SCH_1):P1V05_PCH_PLL_AUX   I129 @S9S_MB_2U_LIB.S9S_MB_2U(SCH_1):PAGE181

R1464 Q_RES_0402LF-0,5%,1/16W,CHIP,CA
     1 P1V8_PCH_AUX @S9S_MB_2U_LIB.S9S_MB_2U(SCH_1):P1V8_PCH_AUX   I144 @S9S_MB_2U_LIB.S9S_MB_2U(SCH_1):PAGE181
     2 P1V8_PCH_PLL_AUX @S9S_MB_2U_LIB.S9S_MB_2U(SCH_1):P1V8_PCH_PLL_AUX   I144 @S9S_MB_2U_LIB.S9S_MB_2U(SCH_1):PAGE181

R1465 Q_RES_0402LF-10K,1%,1/16W,EMPTA
     1 P3V3_AUX @S9S_MB_2U_LIB.S9S_MB_2U(SCH_1):P3V3_AUX     I3 @S9S_MB_2U_LIB.S9S_MB_2U(SCH_1):PAGE312
     2 IRQ_BMC_CPU_NMI_R1 @S9S_MB_2U_LIB.S9S_MB_2U(SCH_1):IRQ_BMC_CPU_NMI_R1     I3 @S9S_MB_2U_LIB.S9S_MB_2U(SCH_1):PAGE312

R1467 Q_RES_0402LF-4.7K,1%,1/16W,EMPA
     1 P3V3_AUX @S9S_MB_2U_LIB.S9S_MB_2U(SCH_1):P3V3_AUX   I178 @S9S_MB_2U_LIB.S9S_MB_2U(SCH_1):PAGE314
     2 SMB_1_PLD_3V3AUX_SCL_R1 @S9S_MB_2U_LIB.S9S_MB_2U(SCH_1):SMB_1_PLD_3V3AUX_SCL_R1   I178 @S9S_MB_2U_LIB.S9S_MB_2U(SCH_1):PAGE314

R1469 Q_RES_0402LF-33.2,1%,1/16W,CHIA
     1 RST_PLTRST_PLD_B_N @S9S_MB_2U_LIB.S9S_MB_2U(SCH_1):RST_PLTRST_PLD_B_N    I55 @S9S_MB_2U_LIB.S9S_MB_2U(SCH_1):PAGE212
     2 RST_PLTRST_B_N @S9S_MB_2U_LIB.S9S_MB_2U(SCH_1):RST_PLTRST_B_N    I55 @S9S_MB_2U_LIB.S9S_MB_2U(SCH_1):PAGE212

R1470 Q_RES_0402LF-33.2,1%,1/16W,CHIA
     1 RST_PLTRST_PLD_B_N @S9S_MB_2U_LIB.S9S_MB_2U(SCH_1):RST_PLTRST_PLD_B_N    I56 @S9S_MB_2U_LIB.S9S_MB_2U(SCH_1):PAGE212
     2 RST_PLTRST_B_MUX_N @S9S_MB_2U_LIB.S9S_MB_2U(SCH_1):RST_PLTRST_B_MUX_N    I56 @S9S_MB_2U_LIB.S9S_MB_2U(SCH_1):PAGE212

R1471 Q_RES_0402LF-4.75K,1%,1/16W,CHA
     1 P3V3_AUX @S9S_MB_2U_LIB.S9S_MB_2U(SCH_1):P3V3_AUX   I267 @S9S_MB_2U_LIB.S9S_MB_2U(SCH_1):PAGE197
     2 FM_CLK_CK440_SS_EN @S9S_MB_2U_LIB.S9S_MB_2U(SCH_1):FM_CLK_CK440_SS_EN   I267 @S9S_MB_2U_LIB.S9S_MB_2U(SCH_1):PAGE197

R1472 Q_RES_0402LF-33.2,1%,1/16W,CHIA
     1 JTAG_DBP_PRESENT_R_N @S9S_MB_2U_LIB.S9S_MB_2U(SCH_1):JTAG_DBP_PRESENT_R_N   I144 @S9S_MB_2U_LIB.S9S_MB_2U(SCH_1):PAGE133
     2 FM_BMC_DBP_PRESENT_R_N @S9S_MB_2U_LIB.S9S_MB_2U(SCH_1):FM_BMC_DBP_PRESENT_R_N   I144 @S9S_MB_2U_LIB.S9S_MB_2U(SCH_1):PAGE133

R1473 Q_RES_0402LF-1K,1%,1/16W,CHIP,A
     1 FM_RST_PERST_BIT1 @S9S_MB_2U_LIB.S9S_MB_2U(SCH_1):FM_RST_PERST_BIT1    I37 @S9S_MB_2U_LIB.S9S_MB_2U(SCH_1):PAGE209
     2 P3V3_AUX @S9S_MB_2U_LIB.S9S_MB_2U(SCH_1):P3V3_AUX    I37 @S9S_MB_2U_LIB.S9S_MB_2U(SCH_1):PAGE209

R1474 Q_RES_0402LF-1K,1%,1/16W,CHIP,A
     1 FM_RST_PERST_BIT2 @S9S_MB_2U_LIB.S9S_MB_2U(SCH_1):FM_RST_PERST_BIT2    I36 @S9S_MB_2U_LIB.S9S_MB_2U(SCH_1):PAGE209
     2 P3V3_AUX @S9S_MB_2U_LIB.S9S_MB_2U(SCH_1):P3V3_AUX    I36 @S9S_MB_2U_LIB.S9S_MB_2U(SCH_1):PAGE209

R1475 Q_RES_0402LF-1K,1%,1/16W,EMPTYA
     1 P3V3_AUX @S9S_MB_2U_LIB.S9S_MB_2U(SCH_1):P3V3_AUX    I44 @S9S_MB_2U_LIB.S9S_MB_2U(SCH_1):PAGE188
     2 FM_PCH_RING_OSC_BYPASS_MGPIO_TE @S9S_MB_2U_LIB.S9S_MB_2U(SCH_1):FM_PCH_RING_OSC_BYPASS_MGPIO_TEST2    I44 @S9S_MB_2U_LIB.S9S_MB_2U(SCH_1):PAGE188

R1476 Q_RES_0402LF-1K,1%,1/16W,CHIP,A
     1 FM_PCH_RING_OSC_BYPASS_MGPIO_TE @S9S_MB_2U_LIB.S9S_MB_2U(SCH_1):FM_PCH_RING_OSC_BYPASS_MGPIO_TEST2    I43 @S9S_MB_2U_LIB.S9S_MB_2U(SCH_1):PAGE188
     2    GND @S9S_MB_2U_LIB.S9S_MB_2U(SCH_1):GND    I43 @S9S_MB_2U_LIB.S9S_MB_2U(SCH_1):PAGE188

R1477 Q_RES_0402LF-1K,1%,1/16W,EMPTYA
     1 P3V3_AUX @S9S_MB_2U_LIB.S9S_MB_2U(SCH_1):P3V3_AUX    I47 @S9S_MB_2U_LIB.S9S_MB_2U(SCH_1):PAGE188
     2 FM_PCH_XTAL_INPUT_MODE_MGPIO_TE @S9S_MB_2U_LIB.S9S_MB_2U(SCH_1):FM_PCH_XTAL_INPUT_MODE_MGPIO_TEST3    I47 @S9S_MB_2U_LIB.S9S_MB_2U(SCH_1):PAGE188

R1478 Q_RES_0402LF-10K,1%,1/16W,CHIPA
     1 FM_PCH_XTAL_INPUT_MODE_MGPIO_TE @S9S_MB_2U_LIB.S9S_MB_2U(SCH_1):FM_PCH_XTAL_INPUT_MODE_MGPIO_TEST3    I50 @S9S_MB_2U_LIB.S9S_MB_2U(SCH_1):PAGE188
     2    GND @S9S_MB_2U_LIB.S9S_MB_2U(SCH_1):GND    I50 @S9S_MB_2U_LIB.S9S_MB_2U(SCH_1):PAGE188

R1479 Q_RES_0402LF-10,1%,1/16W,CHIP,A
     1 ESPI_LFRAME_N_BMC_CS0_N @S9S_MB_2U_LIB.S9S_MB_2U(SCH_1):ESPI_LFRAME_N_BMC_CS0_N   I102 @S9S_MB_2U_LIB.S9S_MB_2U(SCH_1):PAGE190
     2 ESPI_HOST_LPC_BMC_LFRAME_N @S9S_MB_2U_LIB.S9S_MB_2U(SCH_1):ESPI_HOST_LPC_BMC_LFRAME_N   I102 @S9S_MB_2U_LIB.S9S_MB_2U(SCH_1):PAGE190

R1483 Q_RES_0402LF-10K,1%,1/16W,EMPTA
     1 P3V3_AUX @S9S_MB_2U_LIB.S9S_MB_2U(SCH_1):P3V3_AUX   I265 @S9S_MB_2U_LIB.S9S_MB_2U(SCH_1):PAGE197
     2 FM_CK440Q_DEV_25M_EN @S9S_MB_2U_LIB.S9S_MB_2U(SCH_1):FM_CK440Q_DEV_25M_EN   I265 @S9S_MB_2U_LIB.S9S_MB_2U(SCH_1):PAGE197

R1484 Q_RES_0402LF-1K,1%,1/16W,EMPTYA
     1 FM_CK440Q_DEV_25M_EN @S9S_MB_2U_LIB.S9S_MB_2U(SCH_1):FM_CK440Q_DEV_25M_EN   I268 @S9S_MB_2U_LIB.S9S_MB_2U(SCH_1):PAGE197
     2    GND @S9S_MB_2U_LIB.S9S_MB_2U(SCH_1):GND   I268 @S9S_MB_2U_LIB.S9S_MB_2U(SCH_1):PAGE197

R1485 Q_RES_0402LF-200,1%,1/16W,EMPTA
     1 PVNN_TERM_CPU0 @S9S_MB_2U_LIB.S9S_MB_2U(SCH_1):PVNN_TERM_CPU0    I75 @S9S_MB_2U_LIB.S9S_MB_2U(SCH_1):PAGE174
     2 FM_PCH_TRIGGER0_R_N @S9S_MB_2U_LIB.S9S_MB_2U(SCH_1):FM_PCH_TRIGGER0_R_N    I75 @S9S_MB_2U_LIB.S9S_MB_2U(SCH_1):PAGE174

R1486 Q_RES_0402LF-200,1%,1/16W,EMPTA
     1 PVNN_TERM_CPU0 @S9S_MB_2U_LIB.S9S_MB_2U(SCH_1):PVNN_TERM_CPU0    I74 @S9S_MB_2U_LIB.S9S_MB_2U(SCH_1):PAGE174
     2 FM_PCH_TRIGGER1_R_N @S9S_MB_2U_LIB.S9S_MB_2U(SCH_1):FM_PCH_TRIGGER1_R_N    I74 @S9S_MB_2U_LIB.S9S_MB_2U(SCH_1):PAGE174

R1487 Q_RES_0402LF-100,1%,1/16W,CHIPA
     1 FM_PCH_SATA_RAID_KEY @S9S_MB_2U_LIB.S9S_MB_2U(SCH_1):FM_PCH_SATA_RAID_KEY   I125 @S9S_MB_2U_LIB.S9S_MB_2U(SCH_1):PAGE175
     2    GND @S9S_MB_2U_LIB.S9S_MB_2U(SCH_1):GND   I125 @S9S_MB_2U_LIB.S9S_MB_2U(SCH_1):PAGE175

R1492 Q_RES_0402LF-10K,1%,1/16W,CHIPA
     1 FM_DIS_PS_PWROK_DLY @S9S_MB_2U_LIB.S9S_MB_2U(SCH_1):FM_DIS_PS_PWROK_DLY    I35 @S9S_MB_2U_LIB.S9S_MB_2U(SCH_1):PAGE209
     2 P3V3_AUX @S9S_MB_2U_LIB.S9S_MB_2U(SCH_1):P3V3_AUX    I35 @S9S_MB_2U_LIB.S9S_MB_2U(SCH_1):PAGE209

R1493 Q_RES_0402LF-1K,1%,1/16W,CHIP,A
     1 P3V3_AUX @S9S_MB_2U_LIB.S9S_MB_2U(SCH_1):P3V3_AUX   I191 @S9S_MB_2U_LIB.S9S_MB_2U(SCH_1):PAGE312
     2 PU_FORCE_PWRON @S9S_MB_2U_LIB.S9S_MB_2U(SCH_1):PU_FORCE_PWRON   I191 @S9S_MB_2U_LIB.S9S_MB_2U(SCH_1):PAGE312

R1494 Q_RES_0402LF-1K,1%,1/16W,EMPTYA
     1 FM_DIS_PS_PWROK_DLY @S9S_MB_2U_LIB.S9S_MB_2U(SCH_1):FM_DIS_PS_PWROK_DLY    I21 @S9S_MB_2U_LIB.S9S_MB_2U(SCH_1):PAGE209
     2    GND @S9S_MB_2U_LIB.S9S_MB_2U(SCH_1):GND    I21 @S9S_MB_2U_LIB.S9S_MB_2U(SCH_1):PAGE209

R1495 Q_RES_0402LF-10K,1%,1/16W,CHIPA
     1 PD_FORCE_PWRON @S9S_MB_2U_LIB.S9S_MB_2U(SCH_1):PD_FORCE_PWRON   I190 @S9S_MB_2U_LIB.S9S_MB_2U(SCH_1):PAGE312
     2    GND @S9S_MB_2U_LIB.S9S_MB_2U(SCH_1):GND   I190 @S9S_MB_2U_LIB.S9S_MB_2U(SCH_1):PAGE312

R1496 Q_RES_0402LF-10K,1%,1/16W,CHIPA
     1 P3V3_AUX @S9S_MB_2U_LIB.S9S_MB_2U(SCH_1):P3V3_AUX    I71 @S9S_MB_2U_LIB.S9S_MB_2U(SCH_1):PAGE188
     2 FM_PCH_DFXTESTMODE @S9S_MB_2U_LIB.S9S_MB_2U(SCH_1):FM_PCH_DFXTESTMODE    I71 @S9S_MB_2U_LIB.S9S_MB_2U(SCH_1):PAGE188

R1497 Q_RES_0402LF-12K,1%,1/16W,EMPTA
     1 FM_PCH_DFXTESTMODE @S9S_MB_2U_LIB.S9S_MB_2U(SCH_1):FM_PCH_DFXTESTMODE    I70 @S9S_MB_2U_LIB.S9S_MB_2U(SCH_1):PAGE188
     2    GND @S9S_MB_2U_LIB.S9S_MB_2U(SCH_1):GND    I70 @S9S_MB_2U_LIB.S9S_MB_2U(SCH_1):PAGE188

R1498 Q_RES_0402LF-1K,1%,1/16W,EMPTYA
     1 P1V05_PCH_AUX @S9S_MB_2U_LIB.S9S_MB_2U(SCH_1):P1V05_PCH_AUX    I76 @S9S_MB_2U_LIB.S9S_MB_2U(SCH_1):PAGE188
     2 FM_BIOS_ADV_FUNCTIONS @S9S_MB_2U_LIB.S9S_MB_2U(SCH_1):FM_BIOS_ADV_FUNCTIONS    I76 @S9S_MB_2U_LIB.S9S_MB_2U(SCH_1):PAGE188

R1499 Q_RES_0402LF-1K,1%,1/16W,CHIP,A
     1 FM_BIOS_ADV_FUNCTIONS @S9S_MB_2U_LIB.S9S_MB_2U(SCH_1):FM_BIOS_ADV_FUNCTIONS    I77 @S9S_MB_2U_LIB.S9S_MB_2U(SCH_1):PAGE188
     2    GND @S9S_MB_2U_LIB.S9S_MB_2U(SCH_1):GND    I77 @S9S_MB_2U_LIB.S9S_MB_2U(SCH_1):PAGE188

R1500 Q_RES_0402LF-4.75K,1%,1/16W,CHA
     1 PD_CK440_SBI_DATA_IN @S9S_MB_2U_LIB.S9S_MB_2U(SCH_1):PD_CK440_SBI_DATA_IN   I271 @S9S_MB_2U_LIB.S9S_MB_2U(SCH_1):PAGE197
     2    GND @S9S_MB_2U_LIB.S9S_MB_2U(SCH_1):GND   I271 @S9S_MB_2U_LIB.S9S_MB_2U(SCH_1):PAGE197

R1502 Q_RES_0402LF-4.75K,1%,1/16W,CHA
     1 FM_CLK_CK440_SS_EN @S9S_MB_2U_LIB.S9S_MB_2U(SCH_1):FM_CLK_CK440_SS_EN   I270 @S9S_MB_2U_LIB.S9S_MB_2U(SCH_1):PAGE197
     2    GND @S9S_MB_2U_LIB.S9S_MB_2U(SCH_1):GND   I270 @S9S_MB_2U_LIB.S9S_MB_2U(SCH_1):PAGE197

R1504 Q_RES_0402LF-33.2,1%,1/16W,CHIA
     1 RST_OCP_V3_1_BUF_N @S9S_MB_2U_LIB.S9S_MB_2U(SCH_1):RST_OCP_V3_1_BUF_N    I10 @S9S_MB_2U_LIB.S9S_MB_2U(SCH_1):PAGE152
     2 RST_PERST2_OCP_SFF_N @S9S_MB_2U_LIB.S9S_MB_2U(SCH_1):RST_PERST2_OCP_SFF_N    I10 @S9S_MB_2U_LIB.S9S_MB_2U(SCH_1):PAGE152

R1505 Q_RES_0402LF-33.2,1%,1/16W,CHIA
     1 RST_OCP_V3_1_BUF_N @S9S_MB_2U_LIB.S9S_MB_2U(SCH_1):RST_OCP_V3_1_BUF_N    I13 @S9S_MB_2U_LIB.S9S_MB_2U(SCH_1):PAGE152
     2 RST_PERST3_OCP_SFF_N @S9S_MB_2U_LIB.S9S_MB_2U(SCH_1):RST_PERST3_OCP_SFF_N    I13 @S9S_MB_2U_LIB.S9S_MB_2U(SCH_1):PAGE152

R1514 Q_RES_0402LF-33.2,1%,1/16W,CHIA
     1 RST_PCIE_CPU0_DEV_PERST_N @S9S_MB_2U_LIB.S9S_MB_2U(SCH_1):RST_PCIE_CPU0_DEV_PERST_N   I105 @S9S_MB_2U_LIB.S9S_MB_2U(SCH_1):PAGE212
     2 RST_OCP_V3_1_N @S9S_MB_2U_LIB.S9S_MB_2U(SCH_1):RST_OCP_V3_1_N   I105 @S9S_MB_2U_LIB.S9S_MB_2U(SCH_1):PAGE212

R1520 Q_RES_0402LF-33.2,1%,1/16W,CHIA
     1 RST_PCIE_CPU1_DEV_PERST_N @S9S_MB_2U_LIB.S9S_MB_2U(SCH_1):RST_PCIE_CPU1_DEV_PERST_N   I113 @S9S_MB_2U_LIB.S9S_MB_2U(SCH_1):PAGE212
     2 RST_OCP_V3_2_N @S9S_MB_2U_LIB.S9S_MB_2U(SCH_1):RST_OCP_V3_2_N   I113 @S9S_MB_2U_LIB.S9S_MB_2U(SCH_1):PAGE212

R1525 Q_RES_0402LF-0,5%,1/16W,CHIP,CA
     1 SMB_HOST_3V3AUX_SCL_R @S9S_MB_2U_LIB.S9S_MB_2U(SCH_1):SMB_HOST_3V3AUX_SCL_R    I40 @S9S_MB_2U_LIB.S9S_MB_2U(SCH_1):PAGE228
     2 SMB_HOST_CLK_3V3AUX_SCL @S9S_MB_2U_LIB.S9S_MB_2U(SCH_1):SMB_HOST_CLK_3V3AUX_SCL    I40 @S9S_MB_2U_LIB.S9S_MB_2U(SCH_1):PAGE228

R1526 Q_RES_0402LF-33.2,1%,1/16W,CHIA
     1 SMB_HOST_3V3AUX_SDA_R @S9S_MB_2U_LIB.S9S_MB_2U(SCH_1):SMB_HOST_3V3AUX_SDA_R    I41 @S9S_MB_2U_LIB.S9S_MB_2U(SCH_1):PAGE228
     2 SMB_HOST_CLK_3V3AUX_SDA @S9S_MB_2U_LIB.S9S_MB_2U(SCH_1):SMB_HOST_CLK_3V3AUX_SDA    I41 @S9S_MB_2U_LIB.S9S_MB_2U(SCH_1):PAGE228

R1527 Q_RES_0402LF-1K,1%,1/16W,CHIP,A
     1 FM_CLK_GEN1_OE0_N @S9S_MB_2U_LIB.S9S_MB_2U(SCH_1):FM_CLK_GEN1_OE0_N   I269 @S9S_MB_2U_LIB.S9S_MB_2U(SCH_1):PAGE197
     2    GND @S9S_MB_2U_LIB.S9S_MB_2U(SCH_1):GND   I269 @S9S_MB_2U_LIB.S9S_MB_2U(SCH_1):PAGE197

R1541 Q_RES_0402LF-100K,1%,1/16W,CHIA
     1    GND @S9S_MB_2U_LIB.S9S_MB_2U(SCH_1):GND    I92 @S9S_MB_2U_LIB.S9S_MB_2U(SCH_1):PAGE212
     2 RST_PLTRST_N @S9S_MB_2U_LIB.S9S_MB_2U(SCH_1):RST_PLTRST_N    I92 @S9S_MB_2U_LIB.S9S_MB_2U(SCH_1):PAGE212

R1543 Q_RES_0402LF-0,5%,1/16W,CHIP,CA
     1 OCP_SFF_CLK_OE_N @S9S_MB_2U_LIB.S9S_MB_2U(SCH_1):OCP_SFF_CLK_OE_N   I534 @S9S_MB_2U_LIB.S9S_MB_2U(SCH_1):PAGE195
     2 FM_DB2000_9_OE_N @S9S_MB_2U_LIB.S9S_MB_2U(SCH_1):FM_DB2000_9_OE_N   I534 @S9S_MB_2U_LIB.S9S_MB_2U(SCH_1):PAGE195

R1545 Q_RES_0402LF-2K,1%,1/16W,CHIP,A
     1 SMB_SML0B_3V3AUX_SCL @S9S_MB_2U_LIB.S9S_MB_2U(SCH_1):SMB_SML0B_3V3AUX_SCL   I137 @S9S_MB_2U_LIB.S9S_MB_2U(SCH_1):PAGE175
     2 P3V3_AUX @S9S_MB_2U_LIB.S9S_MB_2U(SCH_1):P3V3_AUX   I137 @S9S_MB_2U_LIB.S9S_MB_2U(SCH_1):PAGE175

R1546 Q_RES_0402LF-2K,1%,1/16W,CHIP,A
     1 SMB_SML0B_3V3AUX_SDA @S9S_MB_2U_LIB.S9S_MB_2U(SCH_1):SMB_SML0B_3V3AUX_SDA   I138 @S9S_MB_2U_LIB.S9S_MB_2U(SCH_1):PAGE175
     2 P3V3_AUX @S9S_MB_2U_LIB.S9S_MB_2U(SCH_1):P3V3_AUX   I138 @S9S_MB_2U_LIB.S9S_MB_2U(SCH_1):PAGE175

R1547 Q_RES_0402LF-0,5%,1/16W,CHIP,CA
     1 FM_TPM_PRSNT_R_N @S9S_MB_2U_LIB.S9S_MB_2U(SCH_1):FM_TPM_PRSNT_R_N   I139 @S9S_MB_2U_LIB.S9S_MB_2U(SCH_1):PAGE314
     2 FM_TPM_PRSNT_N @S9S_MB_2U_LIB.S9S_MB_2U(SCH_1):FM_TPM_PRSNT_N   I139 @S9S_MB_2U_LIB.S9S_MB_2U(SCH_1):PAGE314

R1551 Q_RES_0402LF-4.7K,1%,1/16W,EMPA
     1 P3V3_AUX @S9S_MB_2U_LIB.S9S_MB_2U(SCH_1):P3V3_AUX   I179 @S9S_MB_2U_LIB.S9S_MB_2U(SCH_1):PAGE314
     2 SMB_1_PLD_3V3AUX_SDA_R1 @S9S_MB_2U_LIB.S9S_MB_2U(SCH_1):SMB_1_PLD_3V3AUX_SDA_R1   I179 @S9S_MB_2U_LIB.S9S_MB_2U(SCH_1):PAGE314

R1554 Q_RES_0402LF-10K,1%,1/16W,CHIPA
     1 P3V3_AUX @S9S_MB_2U_LIB.S9S_MB_2U(SCH_1):P3V3_AUX    I62 @S9S_MB_2U_LIB.S9S_MB_2U(SCH_1):PAGE192
     2 FM_ME_AUTHN_FAIL @S9S_MB_2U_LIB.S9S_MB_2U(SCH_1):FM_ME_AUTHN_FAIL    I62 @S9S_MB_2U_LIB.S9S_MB_2U(SCH_1):PAGE192

R1558 Q_RES_0402LF-10K,1%,1/16W,EMPTA
     1 FM_CPU_RMCA_CATERR_LVT3_R_N @S9S_MB_2U_LIB.S9S_MB_2U(SCH_1):FM_CPU_RMCA_CATERR_LVT3_R_N    I15 @S9S_MB_2U_LIB.S9S_MB_2U(SCH_1):PAGE209
     2 P3V3_AUX @S9S_MB_2U_LIB.S9S_MB_2U(SCH_1):P3V3_AUX    I15 @S9S_MB_2U_LIB.S9S_MB_2U(SCH_1):PAGE209

R1571 Q_RES_0402LF-100K,1%,1/16W,CHIA
     1 MB0_P12V_STBY_PWRGD @S9S_MB_2U_LIB.S9S_MB_2U(SCH_1):MB0_P12V_STBY_PWRGD    I72 @S9S_MB_2U_LIB.S9S_MB_2U(SCH_1):PAGE245
     2 P3V3_AUX_EN @S9S_MB_2U_LIB.S9S_MB_2U(SCH_1):P3V3_AUX_EN    I72 @S9S_MB_2U_LIB.S9S_MB_2U(SCH_1):PAGE245

R1581 Q_RES_0402LF-2K,1%,1/16W,CHIP,A
     1 PU_SMB_PCH_PLD_3V3AUX_SCL @S9S_MB_2U_LIB.S9S_MB_2U(SCH_1):PU_SMB_PCH_PLD_3V3AUX_SCL   I142 @S9S_MB_2U_LIB.S9S_MB_2U(SCH_1):PAGE175
     2 P3V3_AUX @S9S_MB_2U_LIB.S9S_MB_2U(SCH_1):P3V3_AUX   I142 @S9S_MB_2U_LIB.S9S_MB_2U(SCH_1):PAGE175

R1582 Q_RES_0402LF-2K,1%,1/16W,CHIP,A
     1 PU_SMB_PCH_PLD_3V3AUX_SDA @S9S_MB_2U_LIB.S9S_MB_2U(SCH_1):PU_SMB_PCH_PLD_3V3AUX_SDA   I141 @S9S_MB_2U_LIB.S9S_MB_2U(SCH_1):PAGE175
     2 P3V3_AUX @S9S_MB_2U_LIB.S9S_MB_2U(SCH_1):P3V3_AUX   I141 @S9S_MB_2U_LIB.S9S_MB_2U(SCH_1):PAGE175

R1583 Q_RES_0402LF-10K,1%,1/16W,CHIPA
     1 PU_PCH_PLD_3V3AUX_ALERT_N @S9S_MB_2U_LIB.S9S_MB_2U(SCH_1):PU_PCH_PLD_3V3AUX_ALERT_N   I144 @S9S_MB_2U_LIB.S9S_MB_2U(SCH_1):PAGE175
     2 P3V3_AUX @S9S_MB_2U_LIB.S9S_MB_2U(SCH_1):P3V3_AUX   I144 @S9S_MB_2U_LIB.S9S_MB_2U(SCH_1):PAGE175

R1592 Q_RES_0402LF-10K,1%,1/16W,CHIPA
     1 P3V3_OCP_SFF @S9S_MB_2U_LIB.S9S_MB_2U(SCH_1):P3V3_OCP_SFF    I37 @S9S_MB_2U_LIB.S9S_MB_2U(SCH_1):PAGE152
     2 PU_OCP_SFF_WAKE_OE @S9S_MB_2U_LIB.S9S_MB_2U(SCH_1):PU_OCP_SFF_WAKE_OE    I37 @S9S_MB_2U_LIB.S9S_MB_2U(SCH_1):PAGE152

R1593 Q_RES_0402LF-4.7K,1%,1/16W,CHIA
     1 P3V3_AUX @S9S_MB_2U_LIB.S9S_MB_2U(SCH_1):P3V3_AUX    I42 @S9S_MB_2U_LIB.S9S_MB_2U(SCH_1):PAGE152
     2 OCP_SFF_PWRBRK_BUFF_N @S9S_MB_2U_LIB.S9S_MB_2U(SCH_1):OCP_SFF_PWRBRK_BUFF_N    I42 @S9S_MB_2U_LIB.S9S_MB_2U(SCH_1):PAGE152

R1594 Q_RES_0402LF-33.2,1%,1/16W,CHIA
     1 OCP_SFF_WAKE_BUFF_N @S9S_MB_2U_LIB.S9S_MB_2U(SCH_1):OCP_SFF_WAKE_BUFF_N    I26 @S9S_MB_2U_LIB.S9S_MB_2U(SCH_1):PAGE152
     2 OCP_SFF_WAKE_BUFF_R_N @S9S_MB_2U_LIB.S9S_MB_2U(SCH_1):OCP_SFF_WAKE_BUFF_R_N    I26 @S9S_MB_2U_LIB.S9S_MB_2U(SCH_1):PAGE152

R1595 Q_RES_0402LF-33.2,1%,1/16W,CHIA
     1 OCP_SFF_PWRBRK_BUFF_N @S9S_MB_2U_LIB.S9S_MB_2U(SCH_1):OCP_SFF_PWRBRK_BUFF_N    I40 @S9S_MB_2U_LIB.S9S_MB_2U(SCH_1):PAGE152
     2 OCP_SFF_PWRBRK_N @S9S_MB_2U_LIB.S9S_MB_2U(SCH_1):OCP_SFF_PWRBRK_N    I40 @S9S_MB_2U_LIB.S9S_MB_2U(SCH_1):PAGE152

R1600 Q_RES_0402LF-33.2,1%,1/16W,CHIA
     1 IRQ_SML0_ALERT_N @S9S_MB_2U_LIB.S9S_MB_2U(SCH_1):IRQ_SML0_ALERT_N   I148 @S9S_MB_2U_LIB.S9S_MB_2U(SCH_1):PAGE175
     2 IRQ_SML0_ALERT_R_N @S9S_MB_2U_LIB.S9S_MB_2U(SCH_1):IRQ_SML0_ALERT_R_N   I148 @S9S_MB_2U_LIB.S9S_MB_2U(SCH_1):PAGE175

R1601 Q_RES_0402LF-10K,1%,1/16W,CHIPA
     1 IRQ_SML0_ALERT_N @S9S_MB_2U_LIB.S9S_MB_2U(SCH_1):IRQ_SML0_ALERT_N   I151 @S9S_MB_2U_LIB.S9S_MB_2U(SCH_1):PAGE175
     2 P3V3_AUX @S9S_MB_2U_LIB.S9S_MB_2U(SCH_1):P3V3_AUX   I151 @S9S_MB_2U_LIB.S9S_MB_2U(SCH_1):PAGE175

R1605 Q_RES_0402LF-1K,1%,1/16W,CHIP,A
     1 PD_M2_0_DEVSLP @S9S_MB_2U_LIB.S9S_MB_2U(SCH_1):PD_M2_0_DEVSLP   I105 @S9S_MB_2U_LIB.S9S_MB_2U(SCH_1):PAGE182
     2    GND @S9S_MB_2U_LIB.S9S_MB_2U(SCH_1):GND   I105 @S9S_MB_2U_LIB.S9S_MB_2U(SCH_1):PAGE182

R1606 Q_RES_0402LF-33.2,1%,1/16W,CHIA
     1 FM_OCP_SFF_PWR_GOOD @S9S_MB_2U_LIB.S9S_MB_2U(SCH_1):FM_OCP_SFF_PWR_GOOD   I109 @S9S_MB_2U_LIB.S9S_MB_2U(SCH_1):PAGE314
     2 FM_OCP_SFF_PWR_GOOD_R @S9S_MB_2U_LIB.S9S_MB_2U(SCH_1):FM_OCP_SFF_PWR_GOOD_R   I109 @S9S_MB_2U_LIB.S9S_MB_2U(SCH_1):PAGE314

R1607 Q_RES_0402LF-0,5%,1/16W,EMPTY,A
     1 FM_PS_EN_PLD_R @S9S_MB_2U_LIB.S9S_MB_2U(SCH_1):FM_PS_EN_PLD_R    I10 @S9S_MB_2U_LIB.S9S_MB_2U(SCH_1):PAGE246
     2 VR_P5V_EN @S9S_MB_2U_LIB.S9S_MB_2U(SCH_1):VR_P5V_EN    I10 @S9S_MB_2U_LIB.S9S_MB_2U(SCH_1):PAGE246

R1640 Q_RES_0402LF-0,5%,1/16W,CHIP,CA
     1 FM_P5V_EN @S9S_MB_2U_LIB.S9S_MB_2U(SCH_1):FM_P5V_EN     I9 @S9S_MB_2U_LIB.S9S_MB_2U(SCH_1):PAGE246
     2 VR_P5V_EN @S9S_MB_2U_LIB.S9S_MB_2U(SCH_1):VR_P5V_EN     I9 @S9S_MB_2U_LIB.S9S_MB_2U(SCH_1):PAGE246

R1641 Q_RES_0402LF-100K,1%,1/16W,CHIA
     1 VR_P5V_EN @S9S_MB_2U_LIB.S9S_MB_2U(SCH_1):VR_P5V_EN    I14 @S9S_MB_2U_LIB.S9S_MB_2U(SCH_1):PAGE246
     2    GND @S9S_MB_2U_LIB.S9S_MB_2U(SCH_1):GND    I14 @S9S_MB_2U_LIB.S9S_MB_2U(SCH_1):PAGE246

R1642 Q_RES_0402LF-10K,1%,1/16W,CHIPA
     1 P12V_AUX @S9S_MB_2U_LIB.S9S_MB_2U(SCH_1):P12V_AUX    I22 @S9S_MB_2U_LIB.S9S_MB_2U(SCH_1):PAGE246
     2 VR_P5V_EN_D_R @S9S_MB_2U_LIB.S9S_MB_2U(SCH_1):VR_P5V_EN_D_R    I22 @S9S_MB_2U_LIB.S9S_MB_2U(SCH_1):PAGE246

R1643 Q_RES_0402LF-100K,1%,1/16W,CHIA
     1 P12V_AUX @S9S_MB_2U_LIB.S9S_MB_2U(SCH_1):P12V_AUX    I17 @S9S_MB_2U_LIB.S9S_MB_2U(SCH_1):PAGE246
     2 VR_P5V_EN_N @S9S_MB_2U_LIB.S9S_MB_2U(SCH_1):VR_P5V_EN_N    I17 @S9S_MB_2U_LIB.S9S_MB_2U(SCH_1):PAGE246

R1648 Q_RES_0402LF-0,5%,1/16W,EMPTY,A
     1 SMB_S3M_CPU0_3V3AUX_SDA @S9S_MB_2U_LIB.S9S_MB_2U(SCH_1):SMB_S3M_CPU0_3V3AUX_SDA     I3 @S9S_MB_2U_LIB.S9S_MB_2U(SCH_1):PAGE224
     2 SMB_S3M_CPU1_3V3AUX_SDA @S9S_MB_2U_LIB.S9S_MB_2U(SCH_1):SMB_S3M_CPU1_3V3AUX_SDA     I3 @S9S_MB_2U_LIB.S9S_MB_2U(SCH_1):PAGE224

R1650 Q_RES_0402LF-0,5%,1/16W,CHIP,CA
     1 PWRGD_P1V05_PCH_AUX_R @S9S_MB_2U_LIB.S9S_MB_2U(SCH_1):PWRGD_P1V05_PCH_AUX_R    I51 @S9S_MB_2U_LIB.S9S_MB_2U(SCH_1):PAGE248
     2 PWRGD_P1V05_PCH_AUX @S9S_MB_2U_LIB.S9S_MB_2U(SCH_1):PWRGD_P1V05_PCH_AUX    I51 @S9S_MB_2U_LIB.S9S_MB_2U(SCH_1):PAGE248

R1652 Q_RES_0402LF-0,5%,1/16W,CHIP,CA
     1 PWRGD_PVNN_MAIN_CPU0_R @S9S_MB_2U_LIB.S9S_MB_2U(SCH_1):PWRGD_PVNN_MAIN_CPU0_R    I33 @S9S_MB_2U_LIB.S9S_MB_2U(SCH_1):PAGE268
     2 PWRGD_PVNN_MAIN_CPU0 @S9S_MB_2U_LIB.S9S_MB_2U(SCH_1):PWRGD_PVNN_MAIN_CPU0    I33 @S9S_MB_2U_LIB.S9S_MB_2U(SCH_1):PAGE268

R1654 Q_RES_0402LF-1K,1%,1/16W,CHIP,A
     1 VR_P5V_EN_D_R @S9S_MB_2U_LIB.S9S_MB_2U(SCH_1):VR_P5V_EN_D_R    I27 @S9S_MB_2U_LIB.S9S_MB_2U(SCH_1):PAGE246
     2 VR_P5V_EN_D_R1 @S9S_MB_2U_LIB.S9S_MB_2U(SCH_1):VR_P5V_EN_D_R1    I27 @S9S_MB_2U_LIB.S9S_MB_2U(SCH_1):PAGE246

R1655 Q_RES_0402LF-10K,1%,1/16W,CHIPA
     1 P12V_AUX @S9S_MB_2U_LIB.S9S_MB_2U(SCH_1):P12V_AUX     I6 @S9S_MB_2U_LIB.S9S_MB_2U(SCH_1):PAGE246
     2 PWRGD_P5V_ISO_R @S9S_MB_2U_LIB.S9S_MB_2U(SCH_1):PWRGD_P5V_ISO_R     I6 @S9S_MB_2U_LIB.S9S_MB_2U(SCH_1):PAGE246

R1656 Q_RES_0402LF-33.2,1%,1/16W,CHIA
     1 IRQ_SML1_PMBUS_ALERT_N @S9S_MB_2U_LIB.S9S_MB_2U(SCH_1):IRQ_SML1_PMBUS_ALERT_N   I178 @S9S_MB_2U_LIB.S9S_MB_2U(SCH_1):PAGE175
     2 IRQ_SML1_PMBUS_PLD_ALERT_N @S9S_MB_2U_LIB.S9S_MB_2U(SCH_1):IRQ_SML1_PMBUS_PLD_ALERT_N   I178 @S9S_MB_2U_LIB.S9S_MB_2U(SCH_1):PAGE175

R1657 Q_RES_0402LF-33.2,1%,1/16W,CHIA
     1 IRQ_SML1_PMBUS_ALERT_N @S9S_MB_2U_LIB.S9S_MB_2U(SCH_1):IRQ_SML1_PMBUS_ALERT_N   I180 @S9S_MB_2U_LIB.S9S_MB_2U(SCH_1):PAGE175
     2 IRQ_SML1_PMBUS_BMC_ALERT_N @S9S_MB_2U_LIB.S9S_MB_2U(SCH_1):IRQ_SML1_PMBUS_BMC_ALERT_N   I180 @S9S_MB_2U_LIB.S9S_MB_2U(SCH_1):PAGE175

R1659 Q_RES_0402LF-10K,1%,1/16W,CHIPA
     1 FM_PMBUS_ALERT_B_EN @S9S_MB_2U_LIB.S9S_MB_2U(SCH_1):FM_PMBUS_ALERT_B_EN   I181 @S9S_MB_2U_LIB.S9S_MB_2U(SCH_1):PAGE175
     2 P3V3_AUX @S9S_MB_2U_LIB.S9S_MB_2U(SCH_1):P3V3_AUX   I181 @S9S_MB_2U_LIB.S9S_MB_2U(SCH_1):PAGE175

R1660 Q_RES_0402LF-10K,1%,1/16W,EMPTA
     1 FM_SLP_SUS_RSM_RST_N @S9S_MB_2U_LIB.S9S_MB_2U(SCH_1):FM_SLP_SUS_RSM_RST_N    I14 @S9S_MB_2U_LIB.S9S_MB_2U(SCH_1):PAGE209
     2 P3V3_AUX @S9S_MB_2U_LIB.S9S_MB_2U(SCH_1):P3V3_AUX    I14 @S9S_MB_2U_LIB.S9S_MB_2U(SCH_1):PAGE209

R1661 Q_RES_0402LF-33.2,1%,1/16W,CHIA
     1 SMB_VR_3V3AUX_SCL @S9S_MB_2U_LIB.S9S_MB_2U(SCH_1):SMB_VR_3V3AUX_SCL    I89 @S9S_MB_2U_LIB.S9S_MB_2U(SCH_1):PAGE228
     2 SMB_VR_3V3AUX_SCL_R @S9S_MB_2U_LIB.S9S_MB_2U(SCH_1):SMB_VR_3V3AUX_SCL_R    I89 @S9S_MB_2U_LIB.S9S_MB_2U(SCH_1):PAGE228

R1662 Q_RES_0402LF-33.2,1%,1/16W,CHIA
     1 SMB_VR_3V3AUX_SDA @S9S_MB_2U_LIB.S9S_MB_2U(SCH_1):SMB_VR_3V3AUX_SDA    I90 @S9S_MB_2U_LIB.S9S_MB_2U(SCH_1):PAGE228
     2 SMB_VR_3V3AUX_SDA_R @S9S_MB_2U_LIB.S9S_MB_2U(SCH_1):SMB_VR_3V3AUX_SDA_R    I90 @S9S_MB_2U_LIB.S9S_MB_2U(SCH_1):PAGE228

R1671 Q_RES_0402LF-0,5%,1/16W,CHIP,CA
     1 OCP_SFF_AUX_PWR_EN @S9S_MB_2U_LIB.S9S_MB_2U(SCH_1):OCP_SFF_AUX_PWR_EN    I51 @S9S_MB_2U_LIB.S9S_MB_2U(SCH_1):PAGE150
     2 OCP_SFF_AUX_PWR_EN_R @S9S_MB_2U_LIB.S9S_MB_2U(SCH_1):OCP_SFF_AUX_PWR_EN_R    I51 @S9S_MB_2U_LIB.S9S_MB_2U(SCH_1):PAGE150

R1673 Q_RES_0402LF-10K,1%,1/16W,CHIPA
     1 P3V3_E1S_0 @S9S_MB_2U_LIB.S9S_MB_2U(SCH_1):P3V3_E1S_0   I312 @S9S_MB_2U_LIB.S9S_MB_2U(SCH_1):PAGE297
     2 RST_SMB_E1S_0_N @S9S_MB_2U_LIB.S9S_MB_2U(SCH_1):RST_SMB_E1S_0_N   I312 @S9S_MB_2U_LIB.S9S_MB_2U(SCH_1):PAGE297

R1675 Q_RES_0402LF-2.49K,1%,1/16W,CHA
     1 FM_PCIE_EV_BIF_EN @S9S_MB_2U_LIB.S9S_MB_2U(SCH_1):FM_PCIE_EV_BIF_EN    I82 @S9S_MB_2U_LIB.S9S_MB_2U(SCH_1):PAGE174
     2 P3V3_AUX @S9S_MB_2U_LIB.S9S_MB_2U(SCH_1):P3V3_AUX    I82 @S9S_MB_2U_LIB.S9S_MB_2U(SCH_1):PAGE174

R1676 Q_RES_0402LF-1K,1%,1/16W,EMPTYA
     1 FM_PCIE_EV_BIF_EN @S9S_MB_2U_LIB.S9S_MB_2U(SCH_1):FM_PCIE_EV_BIF_EN    I94 @S9S_MB_2U_LIB.S9S_MB_2U(SCH_1):PAGE174
     2    GND @S9S_MB_2U_LIB.S9S_MB_2U(SCH_1):GND    I94 @S9S_MB_2U_LIB.S9S_MB_2U(SCH_1):PAGE174

R1680 Q_RES_0402LF-0,5%,1/16W,CHIP,CA
     1 FM_PLD_CLK_25M_EN @S9S_MB_2U_LIB.S9S_MB_2U(SCH_1):FM_PLD_CLK_25M_EN   I252 @S9S_MB_2U_LIB.S9S_MB_2U(SCH_1):PAGE197
     2 FM_CK440Q_DEV_25M_EN @S9S_MB_2U_LIB.S9S_MB_2U(SCH_1):FM_CK440Q_DEV_25M_EN   I252 @S9S_MB_2U_LIB.S9S_MB_2U(SCH_1):PAGE197

R1681 Q_RES_0402LF-10K,1%,1/16W,CHIPA
     1 P3V3_AUX @S9S_MB_2U_LIB.S9S_MB_2U(SCH_1):P3V3_AUX    I47 @S9S_MB_2U_LIB.S9S_MB_2U(SCH_1):PAGE314
     2 PU_RST_DEDI_BUSY_PLD_N @S9S_MB_2U_LIB.S9S_MB_2U(SCH_1):PU_RST_DEDI_BUSY_PLD_N    I47 @S9S_MB_2U_LIB.S9S_MB_2U(SCH_1):PAGE314

R1688 Q_RES_0402LF-100K,1%,1/16W,CHIA
     1 P12V_AUX @S9S_MB_2U_LIB.S9S_MB_2U(SCH_1):P12V_AUX    I18 @S9S_MB_2U_LIB.S9S_MB_2U(SCH_1):PAGE232
     2 FM_COMP_P3V3_AUX_VIN @S9S_MB_2U_LIB.S9S_MB_2U(SCH_1):FM_COMP_P3V3_AUX_VIN    I18 @S9S_MB_2U_LIB.S9S_MB_2U(SCH_1):PAGE232

R1689 Q_RES_0402LF-6.19K,1%,1/16W,CHA
     1 FM_COMP_P3V3_AUX_VIN @S9S_MB_2U_LIB.S9S_MB_2U(SCH_1):FM_COMP_P3V3_AUX_VIN    I16 @S9S_MB_2U_LIB.S9S_MB_2U(SCH_1):PAGE232
     2    GND @S9S_MB_2U_LIB.S9S_MB_2U(SCH_1):GND    I16 @S9S_MB_2U_LIB.S9S_MB_2U(SCH_1):PAGE232

R1690 Q_RES_0402LF-10K,1%,1/16W,CHIPA
     1 P3V3_AUX @S9S_MB_2U_LIB.S9S_MB_2U(SCH_1):P3V3_AUX    I22 @S9S_MB_2U_LIB.S9S_MB_2U(SCH_1):PAGE232
     2 FM_COMP_P3V3_AUX_ENIN @S9S_MB_2U_LIB.S9S_MB_2U(SCH_1):FM_COMP_P3V3_AUX_ENIN    I22 @S9S_MB_2U_LIB.S9S_MB_2U(SCH_1):PAGE232

R1691 Q_RES_0402LF-10K,1%,1/16W,EMPTA
     1 P3V3_AUX @S9S_MB_2U_LIB.S9S_MB_2U(SCH_1):P3V3_AUX     I4 @S9S_MB_2U_LIB.S9S_MB_2U(SCH_1):PAGE232
     2 PWRGD_DSW_PWROK_R1 @S9S_MB_2U_LIB.S9S_MB_2U(SCH_1):PWRGD_DSW_PWROK_R1     I4 @S9S_MB_2U_LIB.S9S_MB_2U(SCH_1):PAGE232

R1692 Q_RES_0402LF-100K,1%,1/16W,CHIA
     1 PWRGD_DSW_PWROK_R1 @S9S_MB_2U_LIB.S9S_MB_2U(SCH_1):PWRGD_DSW_PWROK_R1     I3 @S9S_MB_2U_LIB.S9S_MB_2U(SCH_1):PAGE232
     2    GND @S9S_MB_2U_LIB.S9S_MB_2U(SCH_1):GND     I3 @S9S_MB_2U_LIB.S9S_MB_2U(SCH_1):PAGE232

R1693 Q_RES_0402LF-33.2,1%,1/16W,CHIA
     1 PWRGD_DSW_PWROK_R2 @S9S_MB_2U_LIB.S9S_MB_2U(SCH_1):PWRGD_DSW_PWROK_R2    I32 @S9S_MB_2U_LIB.S9S_MB_2U(SCH_1):PAGE232
     2 PWRGD_DSW_PWROK @S9S_MB_2U_LIB.S9S_MB_2U(SCH_1):PWRGD_DSW_PWROK    I32 @S9S_MB_2U_LIB.S9S_MB_2U(SCH_1):PAGE232

R1694 Q_RES_0402LF-10K,1%,1/16W,CHIPA
     1 P3V3_AUX @S9S_MB_2U_LIB.S9S_MB_2U(SCH_1):P3V3_AUX    I33 @S9S_MB_2U_LIB.S9S_MB_2U(SCH_1):PAGE232
     2 PWRGD_DSW_PWROK @S9S_MB_2U_LIB.S9S_MB_2U(SCH_1):PWRGD_DSW_PWROK    I33 @S9S_MB_2U_LIB.S9S_MB_2U(SCH_1):PAGE232

R1695 Q_RES_0402LF-0,5%,1/16W,EMPTY,A
     1 PWRGD_DSW_PWROK @S9S_MB_2U_LIB.S9S_MB_2U(SCH_1):PWRGD_DSW_PWROK    I36 @S9S_MB_2U_LIB.S9S_MB_2U(SCH_1):PAGE232
     2 RST_RSMRST_PCH_N @S9S_MB_2U_LIB.S9S_MB_2U(SCH_1):RST_RSMRST_PCH_N    I36 @S9S_MB_2U_LIB.S9S_MB_2U(SCH_1):PAGE232

R1700 Q_RES_0402LF-200K,1%,1/16W,CHIA
     1 P3V3_AUX @S9S_MB_2U_LIB.S9S_MB_2U(SCH_1):P3V3_AUX    I72 @S9S_MB_2U_LIB.S9S_MB_2U(SCH_1):PAGE183
     2 SMB_PCIE_M2_0_EN @S9S_MB_2U_LIB.S9S_MB_2U(SCH_1):SMB_PCIE_M2_0_EN    I72 @S9S_MB_2U_LIB.S9S_MB_2U(SCH_1):PAGE183

R1702 Q_RES_0402LF-4.7K,5%,1/16W,CHIA
     1 P1V8_PCH_AUX @S9S_MB_2U_LIB.S9S_MB_2U(SCH_1):P1V8_PCH_AUX    I43 @S9S_MB_2U_LIB.S9S_MB_2U(SCH_1):PAGE183
     2 SMB_M2_P0_1V8AUX_SDA_R @S9S_MB_2U_LIB.S9S_MB_2U(SCH_1):SMB_M2_P0_1V8AUX_SDA_R    I43 @S9S_MB_2U_LIB.S9S_MB_2U(SCH_1):PAGE183

R1703 Q_RES_0402LF-4.7K,5%,1/16W,CHIA
     1 P1V8_PCH_AUX @S9S_MB_2U_LIB.S9S_MB_2U(SCH_1):P1V8_PCH_AUX    I45 @S9S_MB_2U_LIB.S9S_MB_2U(SCH_1):PAGE183
     2 SMB_M2_P0_1V8AUX_SCL_R @S9S_MB_2U_LIB.S9S_MB_2U(SCH_1):SMB_M2_P0_1V8AUX_SCL_R    I45 @S9S_MB_2U_LIB.S9S_MB_2U(SCH_1):PAGE183

R1706 Q_RES_0402LF-10K,1%,1/16W,EMPTA
     1   P3V3 @S9S_MB_2U_LIB.S9S_MB_2U(SCH_1):P3V3    I89 @S9S_MB_2U_LIB.S9S_MB_2U(SCH_1):PAGE246
     2 PWRGD_P3V3_R1 @S9S_MB_2U_LIB.S9S_MB_2U(SCH_1):PWRGD_P3V3_R1    I89 @S9S_MB_2U_LIB.S9S_MB_2U(SCH_1):PAGE246

R1710 Q_RES_0402LF-49.9,1%,1/16W,CHIA
     1 FM_PLD_REV_N @S9S_MB_2U_LIB.S9S_MB_2U(SCH_1):FM_PLD_REV_N    I38 @S9S_MB_2U_LIB.S9S_MB_2U(SCH_1):PAGE312
     2 FM_PLD_REV_R_N @S9S_MB_2U_LIB.S9S_MB_2U(SCH_1):FM_PLD_REV_R_N    I38 @S9S_MB_2U_LIB.S9S_MB_2U(SCH_1):PAGE312

R1712 Q_RES_0402LF-4.7K,5%,1/16W,EMPA
     1 SMB_VR_3V3AUX_SDA_R3 @S9S_MB_2U_LIB.S9S_MB_2U(SCH_1):SMB_VR_3V3AUX_SDA_R3    I42 @S9S_MB_2U_LIB.S9S_MB_2U(SCH_1):PAGE252
     2 P3V3_AUX @S9S_MB_2U_LIB.S9S_MB_2U(SCH_1):P3V3_AUX    I42 @S9S_MB_2U_LIB.S9S_MB_2U(SCH_1):PAGE252

R1713 Q_RES_0402LF-4.7K,5%,1/16W,EMPA
     1 SMB_VR_3V3AUX_SCL_R3 @S9S_MB_2U_LIB.S9S_MB_2U(SCH_1):SMB_VR_3V3AUX_SCL_R3    I40 @S9S_MB_2U_LIB.S9S_MB_2U(SCH_1):PAGE252
     2 P3V3_AUX @S9S_MB_2U_LIB.S9S_MB_2U(SCH_1):P3V3_AUX    I40 @S9S_MB_2U_LIB.S9S_MB_2U(SCH_1):PAGE252

R1714 Q_RES_0402LF-0,5%,1/16W,CHIP,CA
     1 SMB_SML1_PMBUS_HSC_SDA @S9S_MB_2U_LIB.S9S_MB_2U(SCH_1):SMB_SML1_PMBUS_HSC_SDA    I37 @S9S_MB_2U_LIB.S9S_MB_2U(SCH_1):PAGE303
     2 SMB_SML1_PMBUS_HSC_R_SDA @S9S_MB_2U_LIB.S9S_MB_2U(SCH_1):SMB_SML1_PMBUS_HSC_R_SDA    I37 @S9S_MB_2U_LIB.S9S_MB_2U(SCH_1):PAGE303

R1717 Q_RES_0402LF-49.9,1%,1/16W,CHIA
     1 PVNN_TERM_CPU0 @S9S_MB_2U_LIB.S9S_MB_2U(SCH_1):PVNN_TERM_CPU0    I25 @S9S_MB_2U_LIB.S9S_MB_2U(SCH_1):PAGE264
     2 SVID_CLK1_CPU0_R @S9S_MB_2U_LIB.S9S_MB_2U(SCH_1):SVID_CLK1_CPU0_R    I25 @S9S_MB_2U_LIB.S9S_MB_2U(SCH_1):PAGE264

R1718 Q_RES_0402LF-49.9,1%,1/16W,CHIA
     1 PVNN_TERM_CPU1 @S9S_MB_2U_LIB.S9S_MB_2U(SCH_1):PVNN_TERM_CPU1    I33 @S9S_MB_2U_LIB.S9S_MB_2U(SCH_1):PAGE282
     2 SVID_CLK1_CPU1_R @S9S_MB_2U_LIB.S9S_MB_2U(SCH_1):SVID_CLK1_CPU1_R    I33 @S9S_MB_2U_LIB.S9S_MB_2U(SCH_1):PAGE282

R1719 Q_RES_0402LF-33.2,1%,1/16W,CHIA
     1 OCP_SFF_AUX_PWR_EN @S9S_MB_2U_LIB.S9S_MB_2U(SCH_1):OCP_SFF_AUX_PWR_EN     I5 @S9S_MB_2U_LIB.S9S_MB_2U(SCH_1):PAGE151
     2 OCP_SFF_AUX_PWR_EN_R1 @S9S_MB_2U_LIB.S9S_MB_2U(SCH_1):OCP_SFF_AUX_PWR_EN_R1     I5 @S9S_MB_2U_LIB.S9S_MB_2U(SCH_1):PAGE151

R1720 Q_RES_0402LF-0,5%,1/16W,EMPTY,A
     1 XTAL_PCH_25M_IN_R @S9S_MB_2U_LIB.S9S_MB_2U(SCH_1):XTAL_PCH_25M_IN_R   I103 @S9S_MB_2U_LIB.S9S_MB_2U(SCH_1):PAGE171
     2 XTAL_PCH_25M_IN @S9S_MB_2U_LIB.S9S_MB_2U(SCH_1):XTAL_PCH_25M_IN   I103 @S9S_MB_2U_LIB.S9S_MB_2U(SCH_1):PAGE171

R1721 Q_RES_0402LF-0,5%,1/16W,CHIP,CA
     1 XTAL_PCH_RTC2_R @S9S_MB_2U_LIB.S9S_MB_2U(SCH_1):XTAL_PCH_RTC2_R   I104 @S9S_MB_2U_LIB.S9S_MB_2U(SCH_1):PAGE171
     2 XTAL_PCH_RTC2 @S9S_MB_2U_LIB.S9S_MB_2U(SCH_1):XTAL_PCH_RTC2   I104 @S9S_MB_2U_LIB.S9S_MB_2U(SCH_1):PAGE171

R1724 Q_RES_0402LF-0,5%,1/16W,CHIP,CA
     1 XTAL_CLK_GEN1_25M_X1_R @S9S_MB_2U_LIB.S9S_MB_2U(SCH_1):XTAL_CLK_GEN1_25M_X1_R   I392 @S9S_MB_2U_LIB.S9S_MB_2U(SCH_1):PAGE197
     2 XTAL_CLK_GEN1_25M_X1 @S9S_MB_2U_LIB.S9S_MB_2U(SCH_1):XTAL_CLK_GEN1_25M_X1   I392 @S9S_MB_2U_LIB.S9S_MB_2U(SCH_1):PAGE197

R1735 Q_RES_0402LF-100,1%,1/16W,CHIPA
     1 PVNN_TERM_CPU0 @S9S_MB_2U_LIB.S9S_MB_2U(SCH_1):PVNN_TERM_CPU0    I24 @S9S_MB_2U_LIB.S9S_MB_2U(SCH_1):PAGE264
     2 SVID_DIO1_CPU0_R @S9S_MB_2U_LIB.S9S_MB_2U(SCH_1):SVID_DIO1_CPU0_R    I24 @S9S_MB_2U_LIB.S9S_MB_2U(SCH_1):PAGE264

R1736 Q_RES_0402LF-33.2,1%,1/16W,CHIA
     1 FM_PCH_SLP_SUS_N @S9S_MB_2U_LIB.S9S_MB_2U(SCH_1):FM_PCH_SLP_SUS_N    I99 @S9S_MB_2U_LIB.S9S_MB_2U(SCH_1):PAGE174
     2 FM_SLP_SUS_RSM_RST_N @S9S_MB_2U_LIB.S9S_MB_2U(SCH_1):FM_SLP_SUS_RSM_RST_N    I99 @S9S_MB_2U_LIB.S9S_MB_2U(SCH_1):PAGE174

R1741 Q_RES_0402LF-1K,1%,1/16W,CHIP,A
     1 FM_RST_PERST_BIT0 @S9S_MB_2U_LIB.S9S_MB_2U(SCH_1):FM_RST_PERST_BIT0    I38 @S9S_MB_2U_LIB.S9S_MB_2U(SCH_1):PAGE209
     2 P3V3_AUX @S9S_MB_2U_LIB.S9S_MB_2U(SCH_1):P3V3_AUX    I38 @S9S_MB_2U_LIB.S9S_MB_2U(SCH_1):PAGE209

R1742 Q_RES_0402LF-10K,1%,1/16W,EMPTA
     1 FM_RST_PERST_BIT0 @S9S_MB_2U_LIB.S9S_MB_2U(SCH_1):FM_RST_PERST_BIT0    I24 @S9S_MB_2U_LIB.S9S_MB_2U(SCH_1):PAGE209
     2    GND @S9S_MB_2U_LIB.S9S_MB_2U(SCH_1):GND    I24 @S9S_MB_2U_LIB.S9S_MB_2U(SCH_1):PAGE209

R1744 Q_RES_0402LF-0,5%,1/16W,CHIP,CA
     1 FM_BMC_PWRBTN_OUT_N @S9S_MB_2U_LIB.S9S_MB_2U(SCH_1):FM_BMC_PWRBTN_OUT_N    I94 @S9S_MB_2U_LIB.S9S_MB_2U(SCH_1):PAGE212
     2 FM_BMC_PWRBTN_N @S9S_MB_2U_LIB.S9S_MB_2U(SCH_1):FM_BMC_PWRBTN_N    I94 @S9S_MB_2U_LIB.S9S_MB_2U(SCH_1):PAGE212

R1745 Q_RES_0402LF-0,5%,1/16W,EMPTY,A
     1 FM_COMP_P3V3_AUX_ENIN @S9S_MB_2U_LIB.S9S_MB_2U(SCH_1):FM_COMP_P3V3_AUX_ENIN    I21 @S9S_MB_2U_LIB.S9S_MB_2U(SCH_1):PAGE232
     2 FM_PFR_DSW_PWROK_N @S9S_MB_2U_LIB.S9S_MB_2U(SCH_1):FM_PFR_DSW_PWROK_N    I21 @S9S_MB_2U_LIB.S9S_MB_2U(SCH_1):PAGE232

R1747 Q_RES_0805LF-0,5%,1/8W,CHIP,CSA
     1 P1V8_PCH_AUX @S9S_MB_2U_LIB.S9S_MB_2U(SCH_1):P1V8_PCH_AUX     I2 @S9S_MB_2U_LIB.S9S_MB_2U(SCH_1):PAGE243
     2 PGPPA_AUX @S9S_MB_2U_LIB.S9S_MB_2U(SCH_1):PGPPA_AUX     I2 @S9S_MB_2U_LIB.S9S_MB_2U(SCH_1):PAGE243

R1748 Q_RES_0402LF-0,5%,1/16W,CHIP,CA
     1 FM_ESPI_PLD_EN @S9S_MB_2U_LIB.S9S_MB_2U(SCH_1):FM_ESPI_PLD_EN    I54 @S9S_MB_2U_LIB.S9S_MB_2U(SCH_1):PAGE190
     2 FM_ESPI_PLD_R_EN_BUF @S9S_MB_2U_LIB.S9S_MB_2U(SCH_1):FM_ESPI_PLD_R_EN_BUF    I54 @S9S_MB_2U_LIB.S9S_MB_2U(SCH_1):PAGE190

R1749 Q_RES_0402LF-10K,1%,1/16W,EMPTA
     1 FM_ESPI_PLD_R1_EN @S9S_MB_2U_LIB.S9S_MB_2U(SCH_1):FM_ESPI_PLD_R1_EN    I89 @S9S_MB_2U_LIB.S9S_MB_2U(SCH_1):PAGE190
     2    GND @S9S_MB_2U_LIB.S9S_MB_2U(SCH_1):GND    I89 @S9S_MB_2U_LIB.S9S_MB_2U(SCH_1):PAGE190

R1750 Q_RES_0402LF-1K,1%,1/16W,CHIP,A
     1 PGPPA_AUX @S9S_MB_2U_LIB.S9S_MB_2U(SCH_1):PGPPA_AUX    I87 @S9S_MB_2U_LIB.S9S_MB_2U(SCH_1):PAGE190
     2 FM_ESPI_PLD_R_EN_BUF @S9S_MB_2U_LIB.S9S_MB_2U(SCH_1):FM_ESPI_PLD_R_EN_BUF    I87 @S9S_MB_2U_LIB.S9S_MB_2U(SCH_1):PAGE190

R1751 Q_RES_0402LF-33.2,1%,1/16W,CHIA
     1 SGPIO_DO_0 @S9S_MB_2U_LIB.S9S_MB_2U(SCH_1):SGPIO_DO_0    I81 @S9S_MB_2U_LIB.S9S_MB_2U(SCH_1):PAGE211
     2 SGPIO_DEBUG_PLD_DOUT @S9S_MB_2U_LIB.S9S_MB_2U(SCH_1):SGPIO_DEBUG_PLD_DOUT    I81 @S9S_MB_2U_LIB.S9S_MB_2U(SCH_1):PAGE211

R1752 Q_RES_0402LF-33.2,1%,1/16W,CHIA
     1 SGPIO_CLK_0 @S9S_MB_2U_LIB.S9S_MB_2U(SCH_1):SGPIO_CLK_0    I82 @S9S_MB_2U_LIB.S9S_MB_2U(SCH_1):PAGE211
     2 SGPIO_DEBUG_PLD_CLK @S9S_MB_2U_LIB.S9S_MB_2U(SCH_1):SGPIO_DEBUG_PLD_CLK    I82 @S9S_MB_2U_LIB.S9S_MB_2U(SCH_1):PAGE211

R1753 Q_RES_0402LF-33.2,1%,1/16W,CHIA
     1 SGPIO_DI_0 @S9S_MB_2U_LIB.S9S_MB_2U(SCH_1):SGPIO_DI_0    I84 @S9S_MB_2U_LIB.S9S_MB_2U(SCH_1):PAGE211
     2 SGPIO_DEBUG_PLD_DIN @S9S_MB_2U_LIB.S9S_MB_2U(SCH_1):SGPIO_DEBUG_PLD_DIN    I84 @S9S_MB_2U_LIB.S9S_MB_2U(SCH_1):PAGE211

R1754 Q_RES_0402LF-33.2,1%,1/16W,CHIA
     1 SGPIO_LD_0 @S9S_MB_2U_LIB.S9S_MB_2U(SCH_1):SGPIO_LD_0    I88 @S9S_MB_2U_LIB.S9S_MB_2U(SCH_1):PAGE211
     2 SGPIO_DEBUG_PLD_LD_N @S9S_MB_2U_LIB.S9S_MB_2U(SCH_1):SGPIO_DEBUG_PLD_LD_N    I88 @S9S_MB_2U_LIB.S9S_MB_2U(SCH_1):PAGE211

R1755 Q_RES_0402LF-33.2,1%,1/16W,CHIA
     1 SGPIO_DO_1 @S9S_MB_2U_LIB.S9S_MB_2U(SCH_1):SGPIO_DO_1    I96 @S9S_MB_2U_LIB.S9S_MB_2U(SCH_1):PAGE211
     2 SGPIO_BMC_DOUT @S9S_MB_2U_LIB.S9S_MB_2U(SCH_1):SGPIO_BMC_DOUT    I96 @S9S_MB_2U_LIB.S9S_MB_2U(SCH_1):PAGE211

R1756 Q_RES_0402LF-33.2,1%,1/16W,CHIA
     1 SGPIO_CLK_1 @S9S_MB_2U_LIB.S9S_MB_2U(SCH_1):SGPIO_CLK_1    I98 @S9S_MB_2U_LIB.S9S_MB_2U(SCH_1):PAGE211
     2 SGPIO_BMC_CLK @S9S_MB_2U_LIB.S9S_MB_2U(SCH_1):SGPIO_BMC_CLK    I98 @S9S_MB_2U_LIB.S9S_MB_2U(SCH_1):PAGE211

R1757 Q_RES_0402LF-33.2,1%,1/16W,CHIA
     1 SGPIO_DI_1 @S9S_MB_2U_LIB.S9S_MB_2U(SCH_1):SGPIO_DI_1    I99 @S9S_MB_2U_LIB.S9S_MB_2U(SCH_1):PAGE211
     2 SGPIO_BMC_DIN_R @S9S_MB_2U_LIB.S9S_MB_2U(SCH_1):SGPIO_BMC_DIN_R    I99 @S9S_MB_2U_LIB.S9S_MB_2U(SCH_1):PAGE211

R1758 Q_RES_0402LF-33.2,1%,1/16W,CHIA
     1 SGPIO_LD_1 @S9S_MB_2U_LIB.S9S_MB_2U(SCH_1):SGPIO_LD_1    I91 @S9S_MB_2U_LIB.S9S_MB_2U(SCH_1):PAGE211
     2 SGPIO_BMC_LD_N @S9S_MB_2U_LIB.S9S_MB_2U(SCH_1):SGPIO_BMC_LD_N    I91 @S9S_MB_2U_LIB.S9S_MB_2U(SCH_1):PAGE211

R1763 Q_RES_0402LF-10K,1%,1/16W,EMPTA
     1 PGPPA_AUX @S9S_MB_2U_LIB.S9S_MB_2U(SCH_1):PGPPA_AUX     I7 @S9S_MB_2U_LIB.S9S_MB_2U(SCH_1):PAGE243
     2 FM_LPC_ESPI_SEL @S9S_MB_2U_LIB.S9S_MB_2U(SCH_1):FM_LPC_ESPI_SEL     I7 @S9S_MB_2U_LIB.S9S_MB_2U(SCH_1):PAGE243

R1764 Q_RES_0402LF-1K,1%,1/16W,EMPTYA
     1 FM_LPC_ESPI_SEL @S9S_MB_2U_LIB.S9S_MB_2U(SCH_1):FM_LPC_ESPI_SEL     I8 @S9S_MB_2U_LIB.S9S_MB_2U(SCH_1):PAGE243
     2    GND @S9S_MB_2U_LIB.S9S_MB_2U(SCH_1):GND     I8 @S9S_MB_2U_LIB.S9S_MB_2U(SCH_1):PAGE243

R1765 Q_RES_0805LF-0,5%,1/8W,EMPTY,CA
     1 PGPPA_AUX @S9S_MB_2U_LIB.S9S_MB_2U(SCH_1):PGPPA_AUX    I13 @S9S_MB_2U_LIB.S9S_MB_2U(SCH_1):PAGE243
     2 P3V3_AUX @S9S_MB_2U_LIB.S9S_MB_2U(SCH_1):P3V3_AUX    I13 @S9S_MB_2U_LIB.S9S_MB_2U(SCH_1):PAGE243

R1785 Q_RES_0402LF-4.7K,1%,1/16W,CHIA
     1 P3V3_AUX_ADC @S9S_MB_2U_LIB.S9S_MB_2U(SCH_1):P3V3_AUX_ADC   I149 @S9S_MB_2U_LIB.S9S_MB_2U(SCH_1):PAGE239
     2    GND @S9S_MB_2U_LIB.S9S_MB_2U(SCH_1):GND   I149 @S9S_MB_2U_LIB.S9S_MB_2U(SCH_1):PAGE239

R1791 Q_RES_0402LF-9.09K,1%,1/16W,CHA
     1 P5V_ADC @S9S_MB_2U_LIB.S9S_MB_2U(SCH_1):P5V_ADC   I163 @S9S_MB_2U_LIB.S9S_MB_2U(SCH_1):PAGE239
     2    GND @S9S_MB_2U_LIB.S9S_MB_2U(SCH_1):GND   I163 @S9S_MB_2U_LIB.S9S_MB_2U(SCH_1):PAGE239

R1792 Q_RES_0402LF-0,5%,1/16W,EMPTY,A
     1 SMB_VR_3V3AUX_SDA_R1 @S9S_MB_2U_LIB.S9S_MB_2U(SCH_1):SMB_VR_3V3AUX_SDA_R1    I20 @S9S_MB_2U_LIB.S9S_MB_2U(SCH_1):PAGE239
     2 SMB_SEN_MAM_3V3AUX_SDA @S9S_MB_2U_LIB.S9S_MB_2U(SCH_1):SMB_SEN_MAM_3V3AUX_SDA    I20 @S9S_MB_2U_LIB.S9S_MB_2U(SCH_1):PAGE239

R1793 Q_RES_0402LF-0,5%,1/16W,EMPTY,A
     1 SMB_VR_3V3AUX_SCL_R1 @S9S_MB_2U_LIB.S9S_MB_2U(SCH_1):SMB_VR_3V3AUX_SCL_R1    I19 @S9S_MB_2U_LIB.S9S_MB_2U(SCH_1):PAGE239
     2 SMB_SEN_MAM_3V3AUX_SCL @S9S_MB_2U_LIB.S9S_MB_2U(SCH_1):SMB_SEN_MAM_3V3AUX_SCL    I19 @S9S_MB_2U_LIB.S9S_MB_2U(SCH_1):PAGE239

R1798 Q_RES_0402LF-0,5%,1/16W,CHIP,CA
     1 ROT_P1_RST_IND_N_R @S9S_MB_2U_LIB.S9S_MB_2U(SCH_1):ROT_P1_RST_IND_N_R    I20 @S9S_MB_2U_LIB.S9S_MB_2U(SCH_1):PAGE227
     2 ROT_P1_RST_IND_N @S9S_MB_2U_LIB.S9S_MB_2U(SCH_1):ROT_P1_RST_IND_N    I20 @S9S_MB_2U_LIB.S9S_MB_2U(SCH_1):PAGE227

R1799 Q_RES_0402LF-7.87K,1%,1/16W,CHA
     1 P12V_AUX @S9S_MB_2U_LIB.S9S_MB_2U(SCH_1):P12V_AUX   I173 @S9S_MB_2U_LIB.S9S_MB_2U(SCH_1):PAGE239
     2 P12V_AUX_ADC @S9S_MB_2U_LIB.S9S_MB_2U(SCH_1):P12V_AUX_ADC   I173 @S9S_MB_2U_LIB.S9S_MB_2U(SCH_1):PAGE239

R1800 Q_RES_0402LF-1.21K,1%,1/16W,CHA
     1 P12V_AUX_ADC @S9S_MB_2U_LIB.S9S_MB_2U(SCH_1):P12V_AUX_ADC   I174 @S9S_MB_2U_LIB.S9S_MB_2U(SCH_1):PAGE239
     2    GND @S9S_MB_2U_LIB.S9S_MB_2U(SCH_1):GND   I174 @S9S_MB_2U_LIB.S9S_MB_2U(SCH_1):PAGE239

R1801 Q_RES_0402LF-0,5%,1/16W,CHIP,CA
     1 PRSNT0_N @S9S_MB_2U_LIB.S9S_MB_2U(SCH_1):PRSNT0_N   I172 @S9S_MB_2U_LIB.S9S_MB_2U(SCH_1):PAGE227
     2    GND @S9S_MB_2U_LIB.S9S_MB_2U(SCH_1):GND   I172 @S9S_MB_2U_LIB.S9S_MB_2U(SCH_1):PAGE227

R1809 Q_RES_0402LF-20K,1%,1/16W,CHIPA
     1 P3V3_AUX @S9S_MB_2U_LIB.S9S_MB_2U(SCH_1):P3V3_AUX    I89 @S9S_MB_2U_LIB.S9S_MB_2U(SCH_1):PAGE186
     2 FM_ADR_MODE0 @S9S_MB_2U_LIB.S9S_MB_2U(SCH_1):FM_ADR_MODE0    I89 @S9S_MB_2U_LIB.S9S_MB_2U(SCH_1):PAGE186

R1810 Q_RES_0402LF-1K,1%,1/16W,EMPTYA
     1 FM_ADR_MODE0 @S9S_MB_2U_LIB.S9S_MB_2U(SCH_1):FM_ADR_MODE0    I88 @S9S_MB_2U_LIB.S9S_MB_2U(SCH_1):PAGE186
     2    GND @S9S_MB_2U_LIB.S9S_MB_2U(SCH_1):GND    I88 @S9S_MB_2U_LIB.S9S_MB_2U(SCH_1):PAGE186

R1811 Q_RES_0402LF-33.2,1%,1/16W,CHIA
     1 RST_SGPIO_RESET_N @S9S_MB_2U_LIB.S9S_MB_2U(SCH_1):RST_SGPIO_RESET_N   I110 @S9S_MB_2U_LIB.S9S_MB_2U(SCH_1):PAGE211
     2 RST_SGPIO_RESET_N_R @S9S_MB_2U_LIB.S9S_MB_2U(SCH_1):RST_SGPIO_RESET_N_R   I110 @S9S_MB_2U_LIB.S9S_MB_2U(SCH_1):PAGE211

R1812 Q_RES_0402LF-33.2,1%,1/16W,CHIA
     1 IRQ_SGPIO_INTR_N @S9S_MB_2U_LIB.S9S_MB_2U(SCH_1):IRQ_SGPIO_INTR_N   I111 @S9S_MB_2U_LIB.S9S_MB_2U(SCH_1):PAGE211
     2 IRQ_SGPIO_INTR_N_R @S9S_MB_2U_LIB.S9S_MB_2U(SCH_1):IRQ_SGPIO_INTR_N_R   I111 @S9S_MB_2U_LIB.S9S_MB_2U(SCH_1):PAGE211

R1813 Q_RES_0402LF-10K,1%,1/16W,EMPTA
     1 P3V3_AUX @S9S_MB_2U_LIB.S9S_MB_2U(SCH_1):P3V3_AUX    I79 @S9S_MB_2U_LIB.S9S_MB_2U(SCH_1):PAGE226
     2 FM_JTAG_BMC_MUX_SEL @S9S_MB_2U_LIB.S9S_MB_2U(SCH_1):FM_JTAG_BMC_MUX_SEL    I79 @S9S_MB_2U_LIB.S9S_MB_2U(SCH_1):PAGE226

R1814 Q_RES_0402LF-1K,1%,1/16W,EMPTYA
     1 FM_JTAG_BMC_MUX_SEL @S9S_MB_2U_LIB.S9S_MB_2U(SCH_1):FM_JTAG_BMC_MUX_SEL    I77 @S9S_MB_2U_LIB.S9S_MB_2U(SCH_1):PAGE226
     2    GND @S9S_MB_2U_LIB.S9S_MB_2U(SCH_1):GND    I77 @S9S_MB_2U_LIB.S9S_MB_2U(SCH_1):PAGE226

R1815 Q_RES_0402LF-0,5%,1/16W,CHIP,CA
     1 FM_BMC_PWRBTN_OUT_N @S9S_MB_2U_LIB.S9S_MB_2U(SCH_1):FM_BMC_PWRBTN_OUT_N    I26 @S9S_MB_2U_LIB.S9S_MB_2U(SCH_1):PAGE227
     2 FM_BMC_PWRBTN_OUT_R_N @S9S_MB_2U_LIB.S9S_MB_2U(SCH_1):FM_BMC_PWRBTN_OUT_R_N    I26 @S9S_MB_2U_LIB.S9S_MB_2U(SCH_1):PAGE227

R1816 Q_RES_0402LF-0,5%,1/16W,CHIP,CA
     1 PWRGD_PS_PWROK @S9S_MB_2U_LIB.S9S_MB_2U(SCH_1):PWRGD_PS_PWROK    I27 @S9S_MB_2U_LIB.S9S_MB_2U(SCH_1):PAGE227
     2 PWRGD_PS_PWROK_R @S9S_MB_2U_LIB.S9S_MB_2U(SCH_1):PWRGD_PS_PWROK_R    I27 @S9S_MB_2U_LIB.S9S_MB_2U(SCH_1):PAGE227

R1820 Q_RES_0402LF-10K,1%,1/16W,CHIPA
     1 P3V3_AUX @S9S_MB_2U_LIB.S9S_MB_2U(SCH_1):P3V3_AUX    I35 @S9S_MB_2U_LIB.S9S_MB_2U(SCH_1):PAGE191
     2 FM_PLT_BMC_THERMTRIP_R_N @S9S_MB_2U_LIB.S9S_MB_2U(SCH_1):FM_PLT_BMC_THERMTRIP_R_N    I35 @S9S_MB_2U_LIB.S9S_MB_2U(SCH_1):PAGE191

R1821 Q_RES_0402LF-200,1%,1/16W,CHIPA
     1 FM_SPD_REMOTE_EN_R @S9S_MB_2U_LIB.S9S_MB_2U(SCH_1):FM_SPD_REMOTE_EN_R    I53 @S9S_MB_2U_LIB.S9S_MB_2U(SCH_1):PAGE217
     2 FM_SPD_REMOTE_EN @S9S_MB_2U_LIB.S9S_MB_2U(SCH_1):FM_SPD_REMOTE_EN    I53 @S9S_MB_2U_LIB.S9S_MB_2U(SCH_1):PAGE217

R1822 Q_RES_0402LF-10K,1%,1/16W,CHIPA
     1 P3V3_AUX @S9S_MB_2U_LIB.S9S_MB_2U(SCH_1):P3V3_AUX    I18 @S9S_MB_2U_LIB.S9S_MB_2U(SCH_1):PAGE219
     2 RST_SMB_SWITCH_N @S9S_MB_2U_LIB.S9S_MB_2U(SCH_1):RST_SMB_SWITCH_N    I18 @S9S_MB_2U_LIB.S9S_MB_2U(SCH_1):PAGE219

R1823 Q_RES_0402LF-1K,1%,1/16W,CHIP,A
     1 P3V3_AUX @S9S_MB_2U_LIB.S9S_MB_2U(SCH_1):P3V3_AUX     I4 @S9S_MB_2U_LIB.S9S_MB_2U(SCH_1):PAGE311
     2 RST_MB_STBY_R_N @S9S_MB_2U_LIB.S9S_MB_2U(SCH_1):RST_MB_STBY_R_N     I4 @S9S_MB_2U_LIB.S9S_MB_2U(SCH_1):PAGE311

R1824 Q_RES_0402LF-10K,1%,1/16W,CHIPA
     1 P3V3_OCP_SFF @S9S_MB_2U_LIB.S9S_MB_2U(SCH_1):P3V3_OCP_SFF    I62 @S9S_MB_2U_LIB.S9S_MB_2U(SCH_1):PAGE152
     2 IRQ_LVC3_OCP_SFF_WAKE_N @S9S_MB_2U_LIB.S9S_MB_2U(SCH_1):IRQ_LVC3_OCP_SFF_WAKE_N    I62 @S9S_MB_2U_LIB.S9S_MB_2U(SCH_1):PAGE152

R1827 Q_RES_0402LF-33.2,1%,1/16W,CHIA
     1 USB_OC1_REAR_R_N @S9S_MB_2U_LIB.S9S_MB_2U(SCH_1):USB_OC1_REAR_R_N   I193 @S9S_MB_2U_LIB.S9S_MB_2U(SCH_1):PAGE175
     2 USB_OC1_REAR_N @S9S_MB_2U_LIB.S9S_MB_2U(SCH_1):USB_OC1_REAR_N   I193 @S9S_MB_2U_LIB.S9S_MB_2U(SCH_1):PAGE175

R1828 Q_RES_0402LF-10K,1%,1/16W,CHIPA
     1 USB_OC1_REAR_R_N @S9S_MB_2U_LIB.S9S_MB_2U(SCH_1):USB_OC1_REAR_R_N   I188 @S9S_MB_2U_LIB.S9S_MB_2U(SCH_1):PAGE175
     2 P3V3_AUX @S9S_MB_2U_LIB.S9S_MB_2U(SCH_1):P3V3_AUX   I188 @S9S_MB_2U_LIB.S9S_MB_2U(SCH_1):PAGE175

R1831 Q_RES_0402LF-0,5%,1/16W,EMPTY,A
     1 JTAG_DBP_BMC_PRDY_N @S9S_MB_2U_LIB.S9S_MB_2U(SCH_1):JTAG_DBP_BMC_PRDY_N    I82 @S9S_MB_2U_LIB.S9S_MB_2U(SCH_1):PAGE226
     2 JTAG_DBP_BMC_PRDY_R_N @S9S_MB_2U_LIB.S9S_MB_2U(SCH_1):JTAG_DBP_BMC_PRDY_R_N    I82 @S9S_MB_2U_LIB.S9S_MB_2U(SCH_1):PAGE226

R1832 Q_RES_0402LF-0,5%,1/16W,EMPTY,A
     1 JTAG_BMC_DBP_PREQ_N @S9S_MB_2U_LIB.S9S_MB_2U(SCH_1):JTAG_BMC_DBP_PREQ_N    I80 @S9S_MB_2U_LIB.S9S_MB_2U(SCH_1):PAGE226
     2 JTAG_DBP_BMC_PREQ_R_N @S9S_MB_2U_LIB.S9S_MB_2U(SCH_1):JTAG_DBP_BMC_PREQ_R_N    I80 @S9S_MB_2U_LIB.S9S_MB_2U(SCH_1):PAGE226

R1833 Q_RES_0402LF-0,5%,1/16W,EMPTY,A
     1 FM_JTAG_BMC_MUX_SEL_R @S9S_MB_2U_LIB.S9S_MB_2U(SCH_1):FM_JTAG_BMC_MUX_SEL_R   I167 @S9S_MB_2U_LIB.S9S_MB_2U(SCH_1):PAGE313
     2 FM_JTAG_BMC_MUX_SEL @S9S_MB_2U_LIB.S9S_MB_2U(SCH_1):FM_JTAG_BMC_MUX_SEL   I167 @S9S_MB_2U_LIB.S9S_MB_2U(SCH_1):PAGE313

R1837 Q_RES_4P_12-0.001,1%,3W,SMLF,CA
     1 P12V_AUX @S9S_MB_2U_LIB.S9S_MB_2U(SCH_1):P12V_AUX     I3 @S9S_MB_2U_LIB.S9S_MB_2U(SCH_1):PAGE240
     2 P12V_S3_AUX_CPU1_NVDIMM @S9S_MB_2U_LIB.S9S_MB_2U(SCH_1):P12V_S3_AUX_CPU1_NVDIMM     I3 @S9S_MB_2U_LIB.S9S_MB_2U(SCH_1):PAGE240
     3 P12V_AUX_CPU1_DIMM_ISEN_P @S9S_MB_2U_LIB.S9S_MB_2U(SCH_1):P12V_AUX_CPU1_DIMM_ISEN_P     I3 @S9S_MB_2U_LIB.S9S_MB_2U(SCH_1):PAGE240
     4 P12V_AUX_CPU1_DIMM_ISEN_N @S9S_MB_2U_LIB.S9S_MB_2U(SCH_1):P12V_AUX_CPU1_DIMM_ISEN_N     I3 @S9S_MB_2U_LIB.S9S_MB_2U(SCH_1):PAGE240

R1838 Q_RES_4P_12-0.001,1%,3W,SMLF,CA
     1 P12V_AUX @S9S_MB_2U_LIB.S9S_MB_2U(SCH_1):P12V_AUX    I11 @S9S_MB_2U_LIB.S9S_MB_2U(SCH_1):PAGE240
     2 P12V_S3_AUX_CPU0_NVDIMM @S9S_MB_2U_LIB.S9S_MB_2U(SCH_1):P12V_S3_AUX_CPU0_NVDIMM    I11 @S9S_MB_2U_LIB.S9S_MB_2U(SCH_1):PAGE240
     3 P12V_AUX_CPU0_DIMM_ISEN_P @S9S_MB_2U_LIB.S9S_MB_2U(SCH_1):P12V_AUX_CPU0_DIMM_ISEN_P    I11 @S9S_MB_2U_LIB.S9S_MB_2U(SCH_1):PAGE240
     4 P12V_AUX_CPU0_DIMM_ISEN_N @S9S_MB_2U_LIB.S9S_MB_2U(SCH_1):P12V_AUX_CPU0_DIMM_ISEN_N    I11 @S9S_MB_2U_LIB.S9S_MB_2U(SCH_1):PAGE240

R1839 Q_RES_0402LF-0,5%,1/16W,EMPTY,A
     1 RST_PFR_OVR_RTC @S9S_MB_2U_LIB.S9S_MB_2U(SCH_1):RST_PFR_OVR_RTC    I85 @S9S_MB_2U_LIB.S9S_MB_2U(SCH_1):PAGE177
     2 RST_RTCRST_N @S9S_MB_2U_LIB.S9S_MB_2U(SCH_1):RST_RTCRST_N    I85 @S9S_MB_2U_LIB.S9S_MB_2U(SCH_1):PAGE177

R1840 Q_RES_0402LF-0,5%,1/16W,EMPTY,A
     1 RST_PFR_OVR_SRTC @S9S_MB_2U_LIB.S9S_MB_2U(SCH_1):RST_PFR_OVR_SRTC    I89 @S9S_MB_2U_LIB.S9S_MB_2U(SCH_1):PAGE177
     2 RST_SRTCRST_N @S9S_MB_2U_LIB.S9S_MB_2U(SCH_1):RST_SRTCRST_N    I89 @S9S_MB_2U_LIB.S9S_MB_2U(SCH_1):PAGE177

R1841 Q_RES_0402LF-10K,1%,1/16W,CHIPA
     1 P3V3_AUX @S9S_MB_2U_LIB.S9S_MB_2U(SCH_1):P3V3_AUX   I275 @S9S_MB_2U_LIB.S9S_MB_2U(SCH_1):PAGE207
     2 FM_CPU_RMCA_CATERR_LVT3_R_N @S9S_MB_2U_LIB.S9S_MB_2U(SCH_1):FM_CPU_RMCA_CATERR_LVT3_R_N   I275 @S9S_MB_2U_LIB.S9S_MB_2U(SCH_1):PAGE207

R1843 Q_RES_0402LF-33.2,1%,1/16W,CHIA
     1 RST_PFR_OVR_RTC_R @S9S_MB_2U_LIB.S9S_MB_2U(SCH_1):RST_PFR_OVR_RTC_R   I122 @S9S_MB_2U_LIB.S9S_MB_2U(SCH_1):PAGE211
     2 RST_PFR_OVR_RTC @S9S_MB_2U_LIB.S9S_MB_2U(SCH_1):RST_PFR_OVR_RTC   I122 @S9S_MB_2U_LIB.S9S_MB_2U(SCH_1):PAGE211

R1844 Q_RES_0402LF-33.2,1%,1/16W,CHIA
     1 RST_PFR_OVR_SRTC_R @S9S_MB_2U_LIB.S9S_MB_2U(SCH_1):RST_PFR_OVR_SRTC_R   I123 @S9S_MB_2U_LIB.S9S_MB_2U(SCH_1):PAGE211
     2 RST_PFR_OVR_SRTC @S9S_MB_2U_LIB.S9S_MB_2U(SCH_1):RST_PFR_OVR_SRTC   I123 @S9S_MB_2U_LIB.S9S_MB_2U(SCH_1):PAGE211

R1853 Q_RES_0402LF-0,5%,1/16W,CHIP,CA
     1 VIRTUAL_RESEAT_FPGA_R_N @S9S_MB_2U_LIB.S9S_MB_2U(SCH_1):VIRTUAL_RESEAT_FPGA_R_N   I138 @S9S_MB_2U_LIB.S9S_MB_2U(SCH_1):PAGE314
     2 VIRTUAL_RESEAT_FPGA_N @S9S_MB_2U_LIB.S9S_MB_2U(SCH_1):VIRTUAL_RESEAT_FPGA_N   I138 @S9S_MB_2U_LIB.S9S_MB_2U(SCH_1):PAGE314

R1854 Q_RES_0402LF-10K,1%,1/16W,CHIPA
     1 P3V3_AUX @S9S_MB_2U_LIB.S9S_MB_2U(SCH_1):P3V3_AUX     I2 @S9S_MB_2U_LIB.S9S_MB_2U(SCH_1):PAGE229
     2 FM_SCM_PRSNT1_N @S9S_MB_2U_LIB.S9S_MB_2U(SCH_1):FM_SCM_PRSNT1_N     I2 @S9S_MB_2U_LIB.S9S_MB_2U(SCH_1):PAGE229

R1856 Q_RES_0402LF-100,1%,1/16W,CHIPA
     1 FM_SCM_PRSNT1_N @S9S_MB_2U_LIB.S9S_MB_2U(SCH_1):FM_SCM_PRSNT1_N     I3 @S9S_MB_2U_LIB.S9S_MB_2U(SCH_1):PAGE229
     2 FM_SCM_PRSNT1_R_N @S9S_MB_2U_LIB.S9S_MB_2U(SCH_1):FM_SCM_PRSNT1_R_N     I3 @S9S_MB_2U_LIB.S9S_MB_2U(SCH_1):PAGE229

R1857 Q_RES_0402LF-10K,1%,1/16W,CHIPA
     1 P3V3_AUX @S9S_MB_2U_LIB.S9S_MB_2U(SCH_1):P3V3_AUX    I18 @S9S_MB_2U_LIB.S9S_MB_2U(SCH_1):PAGE229
     2 P12V_SCM_EN @S9S_MB_2U_LIB.S9S_MB_2U(SCH_1):P12V_SCM_EN    I18 @S9S_MB_2U_LIB.S9S_MB_2U(SCH_1):PAGE229

R1868 Q_RES_0402LF-10,1%,1/16W,CHIP,A
     1 ESPI_LAD0_DATA_IO3 @S9S_MB_2U_LIB.S9S_MB_2U(SCH_1):ESPI_LAD0_DATA_IO3    I96 @S9S_MB_2U_LIB.S9S_MB_2U(SCH_1):PAGE190
     2 ESPI_LPC_LAD0_IO3 @S9S_MB_2U_LIB.S9S_MB_2U(SCH_1):ESPI_LPC_LAD0_IO3    I96 @S9S_MB_2U_LIB.S9S_MB_2U(SCH_1):PAGE190

R1869 Q_RES_0402LF-10,1%,1/16W,CHIP,A
     1 ESPI_LAD0_DATA_IO2 @S9S_MB_2U_LIB.S9S_MB_2U(SCH_1):ESPI_LAD0_DATA_IO2    I97 @S9S_MB_2U_LIB.S9S_MB_2U(SCH_1):PAGE190
     2 ESPI_LPC_LAD0_IO2 @S9S_MB_2U_LIB.S9S_MB_2U(SCH_1):ESPI_LPC_LAD0_IO2    I97 @S9S_MB_2U_LIB.S9S_MB_2U(SCH_1):PAGE190

R1870 Q_RES_0402LF-10,1%,1/16W,CHIP,A
     1 ESPI_LAD0_DATA_IO1 @S9S_MB_2U_LIB.S9S_MB_2U(SCH_1):ESPI_LAD0_DATA_IO1    I98 @S9S_MB_2U_LIB.S9S_MB_2U(SCH_1):PAGE190
     2 ESPI_LPC_LAD0_IO1 @S9S_MB_2U_LIB.S9S_MB_2U(SCH_1):ESPI_LPC_LAD0_IO1    I98 @S9S_MB_2U_LIB.S9S_MB_2U(SCH_1):PAGE190

R1871 Q_RES_0402LF-10,1%,1/16W,CHIP,A
     1 ESPI_LAD0_DATA_IO0 @S9S_MB_2U_LIB.S9S_MB_2U(SCH_1):ESPI_LAD0_DATA_IO0    I99 @S9S_MB_2U_LIB.S9S_MB_2U(SCH_1):PAGE190
     2 ESPI_LPC_LAD0_IO0 @S9S_MB_2U_LIB.S9S_MB_2U(SCH_1):ESPI_LPC_LAD0_IO0    I99 @S9S_MB_2U_LIB.S9S_MB_2U(SCH_1):PAGE190

R1872 Q_RES_0402LF-10,1%,1/16W,CHIP,A
     1 CLK_24M_66M_LPC0_ESPI @S9S_MB_2U_LIB.S9S_MB_2U(SCH_1):CLK_24M_66M_LPC0_ESPI   I100 @S9S_MB_2U_LIB.S9S_MB_2U(SCH_1):PAGE190
     2 ESPI_HOST_LPC_BMC_CLK @S9S_MB_2U_LIB.S9S_MB_2U(SCH_1):ESPI_HOST_LPC_BMC_CLK   I100 @S9S_MB_2U_LIB.S9S_MB_2U(SCH_1):PAGE190

R1895 Q_RES_0402LF-100,1%,1/16W,CHIPA
     1 OCP_SFF_PRSNTA_R_N @S9S_MB_2U_LIB.S9S_MB_2U(SCH_1):OCP_SFF_PRSNTA_R_N   I149 @S9S_MB_2U_LIB.S9S_MB_2U(SCH_1):PAGE150
     2    GND @S9S_MB_2U_LIB.S9S_MB_2U(SCH_1):GND   I149 @S9S_MB_2U_LIB.S9S_MB_2U(SCH_1):PAGE150

R1896 Q_RES_0402LF-100,1%,1/16W,CHIPA
     1 OCP_SFF_ISO_BIF0_EN @S9S_MB_2U_LIB.S9S_MB_2U(SCH_1):OCP_SFF_ISO_BIF0_EN    I43 @S9S_MB_2U_LIB.S9S_MB_2U(SCH_1):PAGE151
     2    GND @S9S_MB_2U_LIB.S9S_MB_2U(SCH_1):GND    I43 @S9S_MB_2U_LIB.S9S_MB_2U(SCH_1):PAGE151

R1897 Q_RES_0402LF-100,1%,1/16W,CHIPA
     1 OCP_SFF_ISO_BIF1_EN @S9S_MB_2U_LIB.S9S_MB_2U(SCH_1):OCP_SFF_ISO_BIF1_EN    I50 @S9S_MB_2U_LIB.S9S_MB_2U(SCH_1):PAGE151
     2    GND @S9S_MB_2U_LIB.S9S_MB_2U(SCH_1):GND    I50 @S9S_MB_2U_LIB.S9S_MB_2U(SCH_1):PAGE151

R1898 Q_RES_0402LF-100,1%,1/16W,CHIPA
     1 OCP_SFF_ISO_BIF2_EN @S9S_MB_2U_LIB.S9S_MB_2U(SCH_1):OCP_SFF_ISO_BIF2_EN    I52 @S9S_MB_2U_LIB.S9S_MB_2U(SCH_1):PAGE151
     2    GND @S9S_MB_2U_LIB.S9S_MB_2U(SCH_1):GND    I52 @S9S_MB_2U_LIB.S9S_MB_2U(SCH_1):PAGE151

R1905 Q_RES_0402LF-1K,1%,1/16W,CHIP,A
     1 P3V3_AUX @S9S_MB_2U_LIB.S9S_MB_2U(SCH_1):P3V3_AUX    I13 @S9S_MB_2U_LIB.S9S_MB_2U(SCH_1):PAGE153
     2 OCP_SFF_PRSNT0_R_N @S9S_MB_2U_LIB.S9S_MB_2U(SCH_1):OCP_SFF_PRSNT0_R_N    I13 @S9S_MB_2U_LIB.S9S_MB_2U(SCH_1):PAGE153

R1906 Q_RES_0402LF-1K,1%,1/16W,CHIP,A
     1 P3V3_AUX @S9S_MB_2U_LIB.S9S_MB_2U(SCH_1):P3V3_AUX     I7 @S9S_MB_2U_LIB.S9S_MB_2U(SCH_1):PAGE153
     2 OCP_SFF_PRSNT2_R_N @S9S_MB_2U_LIB.S9S_MB_2U(SCH_1):OCP_SFF_PRSNT2_R_N     I7 @S9S_MB_2U_LIB.S9S_MB_2U(SCH_1):PAGE153

R1907 Q_RES_0402LF-1K,1%,1/16W,CHIP,A
     1 P3V3_AUX @S9S_MB_2U_LIB.S9S_MB_2U(SCH_1):P3V3_AUX    I25 @S9S_MB_2U_LIB.S9S_MB_2U(SCH_1):PAGE153
     2 OCP_SFF_PRSNT1_R_N @S9S_MB_2U_LIB.S9S_MB_2U(SCH_1):OCP_SFF_PRSNT1_R_N    I25 @S9S_MB_2U_LIB.S9S_MB_2U(SCH_1):PAGE153

R1908 Q_RES_0402LF-1K,1%,1/16W,CHIP,A
     1 P3V3_AUX @S9S_MB_2U_LIB.S9S_MB_2U(SCH_1):P3V3_AUX    I22 @S9S_MB_2U_LIB.S9S_MB_2U(SCH_1):PAGE153
     2 OCP_SFF_PRSNT3_R_N @S9S_MB_2U_LIB.S9S_MB_2U(SCH_1):OCP_SFF_PRSNT3_R_N    I22 @S9S_MB_2U_LIB.S9S_MB_2U(SCH_1):PAGE153

R1919 Q_RES_0402LF-33.2,1%,1/16W,CHIA
     1 PWRGD_P3V3_AUX @S9S_MB_2U_LIB.S9S_MB_2U(SCH_1):PWRGD_P3V3_AUX   I127 @S9S_MB_2U_LIB.S9S_MB_2U(SCH_1):PAGE211
     2 PWRGD_P3V3_AUX_PLD @S9S_MB_2U_LIB.S9S_MB_2U(SCH_1):PWRGD_P3V3_AUX_PLD   I127 @S9S_MB_2U_LIB.S9S_MB_2U(SCH_1):PAGE211

R1921 Q_RES_0402LF-33.2,1%,1/16W,CHIA
     1 FM_SMB_CPU0_ALERT @S9S_MB_2U_LIB.S9S_MB_2U(SCH_1):FM_SMB_CPU0_ALERT   I132 @S9S_MB_2U_LIB.S9S_MB_2U(SCH_1):PAGE154
     2 FM_SMB_PEHPCPU0_PCIE_ALERT_N @S9S_MB_2U_LIB.S9S_MB_2U(SCH_1):FM_SMB_PEHPCPU0_PCIE_ALERT_N   I132 @S9S_MB_2U_LIB.S9S_MB_2U(SCH_1):PAGE154

R1929 Q_RES_0402LF-10K,1%,1/16W,CHIPA
     1    GND @S9S_MB_2U_LIB.S9S_MB_2U(SCH_1):GND    I37 @S9S_MB_2U_LIB.S9S_MB_2U(SCH_1):PAGE150
     2 OCP_SFF_AUX_PWR_EN @S9S_MB_2U_LIB.S9S_MB_2U(SCH_1):OCP_SFF_AUX_PWR_EN    I37 @S9S_MB_2U_LIB.S9S_MB_2U(SCH_1):PAGE150

R1930 Q_RES_0402LF-10K,1%,1/16W,CHIPA
     1    GND @S9S_MB_2U_LIB.S9S_MB_2U(SCH_1):GND    I36 @S9S_MB_2U_LIB.S9S_MB_2U(SCH_1):PAGE150
     2 OCP_SFF_MAIN_PWR_EN @S9S_MB_2U_LIB.S9S_MB_2U(SCH_1):OCP_SFF_MAIN_PWR_EN    I36 @S9S_MB_2U_LIB.S9S_MB_2U(SCH_1):PAGE150

R1932 Q_RES_0402LF-33.2,1%,1/16W,CHIA
     1 SMB_S3M_CPU0_PIROM_3V3AUX_SCL @S9S_MB_2U_LIB.S9S_MB_2U(SCH_1):SMB_S3M_CPU0_PIROM_3V3AUX_SCL   I109 @S9S_MB_2U_LIB.S9S_MB_2U(SCH_1):PAGE14
     2 SMB_S3M_CPU0_PIROM_3V3AUX_SCL_1 @S9S_MB_2U_LIB.S9S_MB_2U(SCH_1):SMB_S3M_CPU0_PIROM_3V3AUX_SCL_R1   I109 @S9S_MB_2U_LIB.S9S_MB_2U(SCH_1):PAGE14

R1933 Q_RES_0402LF-33.2,1%,1/16W,CHIA
     1 SMB_S3M_CPU0_PIROM_3V3AUX_SDA @S9S_MB_2U_LIB.S9S_MB_2U(SCH_1):SMB_S3M_CPU0_PIROM_3V3AUX_SDA   I110 @S9S_MB_2U_LIB.S9S_MB_2U(SCH_1):PAGE14
     2 SMB_S3M_CPU0_PIROM_3V3AUX_SDA_1 @S9S_MB_2U_LIB.S9S_MB_2U(SCH_1):SMB_S3M_CPU0_PIROM_3V3AUX_SDA_R1   I110 @S9S_MB_2U_LIB.S9S_MB_2U(SCH_1):PAGE14

R1934 Q_RES_0402LF-33.2,1%,1/16W,CHIA
     1 SMB_S3M_CPU1_PIROM_3V3AUX_SCL @S9S_MB_2U_LIB.S9S_MB_2U(SCH_1):SMB_S3M_CPU1_PIROM_3V3AUX_SCL    I81 @S9S_MB_2U_LIB.S9S_MB_2U(SCH_1):PAGE45
     2 SMB_S3M_CPU1_PIROM_3V3AUX_SCL_1 @S9S_MB_2U_LIB.S9S_MB_2U(SCH_1):SMB_S3M_CPU1_PIROM_3V3AUX_SCL_R1    I81 @S9S_MB_2U_LIB.S9S_MB_2U(SCH_1):PAGE45

R1935 Q_RES_0402LF-33.2,1%,1/16W,CHIA
     1 SMB_S3M_CPU1_PIROM_3V3AUX_SDA @S9S_MB_2U_LIB.S9S_MB_2U(SCH_1):SMB_S3M_CPU1_PIROM_3V3AUX_SDA    I82 @S9S_MB_2U_LIB.S9S_MB_2U(SCH_1):PAGE45
     2 SMB_S3M_CPU1_PIROM_3V3AUX_SDA_1 @S9S_MB_2U_LIB.S9S_MB_2U(SCH_1):SMB_S3M_CPU1_PIROM_3V3AUX_SDA_R1    I82 @S9S_MB_2U_LIB.S9S_MB_2U(SCH_1):PAGE45

R1944 Q_RES_0402LF-0,5%,1/16W,CHIP,CA
     1 IRQ_PCH_SCI_WHEA_R_N @S9S_MB_2U_LIB.S9S_MB_2U(SCH_1):IRQ_PCH_SCI_WHEA_R_N   I170 @S9S_MB_2U_LIB.S9S_MB_2U(SCH_1):PAGE312
     2 IRQ_PCH_SCI_WHEA_N @S9S_MB_2U_LIB.S9S_MB_2U(SCH_1):IRQ_PCH_SCI_WHEA_N   I170 @S9S_MB_2U_LIB.S9S_MB_2U(SCH_1):PAGE312

R1950 Q_RES_0402LF-0,5%,1/16W,CHIP,CA
     1 FM_COMP_P3V3_AUX_VIN @S9S_MB_2U_LIB.S9S_MB_2U(SCH_1):FM_COMP_P3V3_AUX_VIN    I20 @S9S_MB_2U_LIB.S9S_MB_2U(SCH_1):PAGE232
     2 FM_COMP_P3V3_AUX_VIN_R @S9S_MB_2U_LIB.S9S_MB_2U(SCH_1):FM_COMP_P3V3_AUX_VIN_R    I20 @S9S_MB_2U_LIB.S9S_MB_2U(SCH_1):PAGE232

R1955 Q_RES_0402LF-10K,1%,1/16W,CHIPA
     1 P3V3_AUX @S9S_MB_2U_LIB.S9S_MB_2U(SCH_1):P3V3_AUX    I72 @S9S_MB_2U_LIB.S9S_MB_2U(SCH_1):PAGE192
     2 FM_PCHHOT_N @S9S_MB_2U_LIB.S9S_MB_2U(SCH_1):FM_PCHHOT_N    I72 @S9S_MB_2U_LIB.S9S_MB_2U(SCH_1):PAGE192

R1958 Q_RES_0402LF-10K,1%,1/16W,CHIPA
     1 P3V3_AUX @S9S_MB_2U_LIB.S9S_MB_2U(SCH_1):P3V3_AUX   I303 @S9S_MB_2U_LIB.S9S_MB_2U(SCH_1):PAGE197
     2 PU_CLK_PFT_LOST_N @S9S_MB_2U_LIB.S9S_MB_2U(SCH_1):PU_CLK_PFT_LOST_N   I303 @S9S_MB_2U_LIB.S9S_MB_2U(SCH_1):PAGE197

R1959 Q_RES_0402LF-0,5%,1/16W,CHIP,CA
     1 H_CPU0_PMDOWN_PCH_R2 @S9S_MB_2U_LIB.S9S_MB_2U(SCH_1):H_CPU0_PMDOWN_PCH_R2   I115 @S9S_MB_2U_LIB.S9S_MB_2U(SCH_1):PAGE14
     2 H_CPU0_PMDOWN_PCH_R @S9S_MB_2U_LIB.S9S_MB_2U(SCH_1):H_CPU0_PMDOWN_PCH_R   I115 @S9S_MB_2U_LIB.S9S_MB_2U(SCH_1):PAGE14

R1960 Q_RES_0402LF-0,5%,1/16W,CHIP,CA
     1 H_CPU0_PMSYNC_PCH_R2 @S9S_MB_2U_LIB.S9S_MB_2U(SCH_1):H_CPU0_PMSYNC_PCH_R2   I117 @S9S_MB_2U_LIB.S9S_MB_2U(SCH_1):PAGE14
     2 H_CPU0_PMSYNC_PCH_R @S9S_MB_2U_LIB.S9S_MB_2U(SCH_1):H_CPU0_PMSYNC_PCH_R   I117 @S9S_MB_2U_LIB.S9S_MB_2U(SCH_1):PAGE14

R1961 Q_RES_0402LF-10K,1%,1/16W,CHIPA
     1 PGPPA_AUX @S9S_MB_2U_LIB.S9S_MB_2U(SCH_1):PGPPA_AUX    I70 @S9S_MB_2U_LIB.S9S_MB_2U(SCH_1):PAGE190
     2 ESPI_LFRAME_N_BMC_CS0_N @S9S_MB_2U_LIB.S9S_MB_2U(SCH_1):ESPI_LFRAME_N_BMC_CS0_N    I70 @S9S_MB_2U_LIB.S9S_MB_2U(SCH_1):PAGE190

R1962 Q_RES_0402LF-20K,1%,1/16W,EMPTA
     1 FM_PCH_CONSENT_STRAP_N @S9S_MB_2U_LIB.S9S_MB_2U(SCH_1):FM_PCH_CONSENT_STRAP_N    I90 @S9S_MB_2U_LIB.S9S_MB_2U(SCH_1):PAGE186
     2    GND @S9S_MB_2U_LIB.S9S_MB_2U(SCH_1):GND    I90 @S9S_MB_2U_LIB.S9S_MB_2U(SCH_1):PAGE186

R1995 Q_RES_0402LF-33.2,1%,1/16W,CHIA
     1 FM_PCH_SLP_S3_N @S9S_MB_2U_LIB.S9S_MB_2U(SCH_1):FM_PCH_SLP_S3_N    I86 @S9S_MB_2U_LIB.S9S_MB_2U(SCH_1):PAGE212
     2 FM_SLPS3_PLD_N @S9S_MB_2U_LIB.S9S_MB_2U(SCH_1):FM_SLPS3_PLD_N    I86 @S9S_MB_2U_LIB.S9S_MB_2U(SCH_1):PAGE212

R1996 Q_RES_0402LF-33.2,1%,1/16W,CHIA
     1 FM_PCH_SLP_S4_N @S9S_MB_2U_LIB.S9S_MB_2U(SCH_1):FM_PCH_SLP_S4_N    I87 @S9S_MB_2U_LIB.S9S_MB_2U(SCH_1):PAGE212
     2 FM_SLPS4_PLD_N @S9S_MB_2U_LIB.S9S_MB_2U(SCH_1):FM_SLPS4_PLD_N    I87 @S9S_MB_2U_LIB.S9S_MB_2U(SCH_1):PAGE212

R2071 Q_RES_0402LF-0,5%,1/16W,EMPTY,A
     1 FM_BMC_SUSACK_R_N @S9S_MB_2U_LIB.S9S_MB_2U(SCH_1):FM_BMC_SUSACK_R_N   I137 @S9S_MB_2U_LIB.S9S_MB_2U(SCH_1):PAGE314
     2 FM_SUSACK_N @S9S_MB_2U_LIB.S9S_MB_2U(SCH_1):FM_SUSACK_N   I137 @S9S_MB_2U_LIB.S9S_MB_2U(SCH_1):PAGE314

R2113 Q_RES_0402LF-33.2,1%,1/16W,CHIA
     1 RST_PCIE_PCH_DEV_BUF_M2_0_PERST @S9S_MB_2U_LIB.S9S_MB_2U(SCH_1):RST_PCIE_PCH_DEV_BUF_M2_0_PERST_N   I344 @S9S_MB_2U_LIB.S9S_MB_2U(SCH_1):PAGE182
     2 RST_PCIE_PCH_DEV_0_N @S9S_MB_2U_LIB.S9S_MB_2U(SCH_1):RST_PCIE_PCH_DEV_0_N   I344 @S9S_MB_2U_LIB.S9S_MB_2U(SCH_1):PAGE182

R2114 Q_RES_0402LF-0,5%,1/16W,CHIP,CA
     1 SMB_PCIE_E1S_ISO_EN_R2 @S9S_MB_2U_LIB.S9S_MB_2U(SCH_1):SMB_PCIE_E1S_ISO_EN_R2   I302 @S9S_MB_2U_LIB.S9S_MB_2U(SCH_1):PAGE297
     2 SMB_PCIE_E1S_ISO_EN @S9S_MB_2U_LIB.S9S_MB_2U(SCH_1):SMB_PCIE_E1S_ISO_EN   I302 @S9S_MB_2U_LIB.S9S_MB_2U(SCH_1):PAGE297

R2121 Q_RES_0402LF-4.7K,5%,1/16W,CHIA
     1 P3V3_AUX @S9S_MB_2U_LIB.S9S_MB_2U(SCH_1):P3V3_AUX   I337 @S9S_MB_2U_LIB.S9S_MB_2U(SCH_1):PAGE182
     2 RST_PCIE_PCH_DEV_BUF_M2_0_PERST @S9S_MB_2U_LIB.S9S_MB_2U(SCH_1):RST_PCIE_PCH_DEV_BUF_M2_0_PERST_N   I337 @S9S_MB_2U_LIB.S9S_MB_2U(SCH_1):PAGE182

R2125 Q_RES_0402LF-4.7K,5%,1/16W,CHIA
     1 P3V3_AUX @S9S_MB_2U_LIB.S9S_MB_2U(SCH_1):P3V3_AUX   I296 @S9S_MB_2U_LIB.S9S_MB_2U(SCH_1):PAGE297
     2 SMB_PCIE_E1S_ISO_EN @S9S_MB_2U_LIB.S9S_MB_2U(SCH_1):SMB_PCIE_E1S_ISO_EN   I296 @S9S_MB_2U_LIB.S9S_MB_2U(SCH_1):PAGE297

R2132 Q_RES_0402LF-0,5%,1/16W,EMPTY,A
     1 JTAG_TRC_PCH_PTI<6> @S9S_MB_2U_LIB.S9S_MB_2U(SCH_1):JTAG_TRC_PCH_PTI(6)    I91 @S9S_MB_2U_LIB.S9S_MB_2U(SCH_1):PAGE190
     2 FM_ESPI_PLD_R1_EN @S9S_MB_2U_LIB.S9S_MB_2U(SCH_1):FM_ESPI_PLD_R1_EN    I91 @S9S_MB_2U_LIB.S9S_MB_2U(SCH_1):PAGE190

R2133 Q_RES_0402LF-1K,1%,1/16W,CHIP,A
     1 P3V3_AUX @S9S_MB_2U_LIB.S9S_MB_2U(SCH_1):P3V3_AUX    I86 @S9S_MB_2U_LIB.S9S_MB_2U(SCH_1):PAGE189
     2 PU_ESPI_ENABLE_STRAP @S9S_MB_2U_LIB.S9S_MB_2U(SCH_1):PU_ESPI_ENABLE_STRAP    I86 @S9S_MB_2U_LIB.S9S_MB_2U(SCH_1):PAGE189

R2134 Q_RES_0402LF-10K,1%,1/16W,CHIPA
     1 JTAG_TRC_PCH_PTI<6> @S9S_MB_2U_LIB.S9S_MB_2U(SCH_1):JTAG_TRC_PCH_PTI(6)   I109 @S9S_MB_2U_LIB.S9S_MB_2U(SCH_1):PAGE189
     2    GND @S9S_MB_2U_LIB.S9S_MB_2U(SCH_1):GND   I109 @S9S_MB_2U_LIB.S9S_MB_2U(SCH_1):PAGE189

R2155 Q_RES_0402LF-0,5%,1/16W,CHIP,CA
     1 FM_BMC_READY_R_PLD_N @S9S_MB_2U_LIB.S9S_MB_2U(SCH_1):FM_BMC_READY_R_PLD_N   I177 @S9S_MB_2U_LIB.S9S_MB_2U(SCH_1):PAGE312
     2 FM_BMC_READY_R_N @S9S_MB_2U_LIB.S9S_MB_2U(SCH_1):FM_BMC_READY_R_N   I177 @S9S_MB_2U_LIB.S9S_MB_2U(SCH_1):PAGE312

R2204 Q_RES_0402LF-2.2K,5%,1/16W,EMPA
     1 P3V3_AUX @S9S_MB_2U_LIB.S9S_MB_2U(SCH_1):P3V3_AUX    I57 @S9S_MB_2U_LIB.S9S_MB_2U(SCH_1):PAGE219
     2 SMB_PCIE0_3V3AUX_SCL @S9S_MB_2U_LIB.S9S_MB_2U(SCH_1):SMB_PCIE0_3V3AUX_SCL    I57 @S9S_MB_2U_LIB.S9S_MB_2U(SCH_1):PAGE219

R2205 Q_RES_0402LF-2.2K,5%,1/16W,EMPA
     1 P3V3_AUX @S9S_MB_2U_LIB.S9S_MB_2U(SCH_1):P3V3_AUX    I56 @S9S_MB_2U_LIB.S9S_MB_2U(SCH_1):PAGE219
     2 SMB_PCIE0_3V3AUX_SDA @S9S_MB_2U_LIB.S9S_MB_2U(SCH_1):SMB_PCIE0_3V3AUX_SDA    I56 @S9S_MB_2U_LIB.S9S_MB_2U(SCH_1):PAGE219

R2208 Q_RES_0402LF-0,5%,1/16W,CHIP,CA
     1 SMB_S3M_CPU0_3V3AUX_SDA_R @S9S_MB_2U_LIB.S9S_MB_2U(SCH_1):SMB_S3M_CPU0_3V3AUX_SDA_R    I62 @S9S_MB_2U_LIB.S9S_MB_2U(SCH_1):PAGE224
     2 SMB_S3M_CPU0_3V3AUX_SDA @S9S_MB_2U_LIB.S9S_MB_2U(SCH_1):SMB_S3M_CPU0_3V3AUX_SDA    I62 @S9S_MB_2U_LIB.S9S_MB_2U(SCH_1):PAGE224

R2209 Q_RES_0402LF-0,5%,1/16W,CHIP,CA
     1 SMB_S3M_CPU0_3V3AUX_SCL_R @S9S_MB_2U_LIB.S9S_MB_2U(SCH_1):SMB_S3M_CPU0_3V3AUX_SCL_R    I63 @S9S_MB_2U_LIB.S9S_MB_2U(SCH_1):PAGE224
     2 SMB_S3M_CPU0_3V3AUX_SCL @S9S_MB_2U_LIB.S9S_MB_2U(SCH_1):SMB_S3M_CPU0_3V3AUX_SCL    I63 @S9S_MB_2U_LIB.S9S_MB_2U(SCH_1):PAGE224

R2210 Q_RES_0402LF-0,5%,1/16W,CHIP,CA
     1 SMB_S3M_CPU1_3V3AUX_SDA_R @S9S_MB_2U_LIB.S9S_MB_2U(SCH_1):SMB_S3M_CPU1_3V3AUX_SDA_R    I64 @S9S_MB_2U_LIB.S9S_MB_2U(SCH_1):PAGE224
     2 SMB_S3M_CPU1_3V3AUX_SDA @S9S_MB_2U_LIB.S9S_MB_2U(SCH_1):SMB_S3M_CPU1_3V3AUX_SDA    I64 @S9S_MB_2U_LIB.S9S_MB_2U(SCH_1):PAGE224

R2211 Q_RES_0402LF-0,5%,1/16W,CHIP,CA
     1 SMB_S3M_CPU1_3V3AUX_SCL_R @S9S_MB_2U_LIB.S9S_MB_2U(SCH_1):SMB_S3M_CPU1_3V3AUX_SCL_R    I65 @S9S_MB_2U_LIB.S9S_MB_2U(SCH_1):PAGE224
     2 SMB_S3M_CPU1_3V3AUX_SCL @S9S_MB_2U_LIB.S9S_MB_2U(SCH_1):SMB_S3M_CPU1_3V3AUX_SCL    I65 @S9S_MB_2U_LIB.S9S_MB_2U(SCH_1):PAGE224

R2212 Q_RES_0402LF-2.2K,5%,1/16W,EMPA
     1 SMB_S3M_CPU_3V3AUX_SCL @S9S_MB_2U_LIB.S9S_MB_2U(SCH_1):SMB_S3M_CPU_3V3AUX_SCL   I202 @S9S_MB_2U_LIB.S9S_MB_2U(SCH_1):PAGE228
     2 P3V3_AUX @S9S_MB_2U_LIB.S9S_MB_2U(SCH_1):P3V3_AUX   I202 @S9S_MB_2U_LIB.S9S_MB_2U(SCH_1):PAGE228

R2213 Q_RES_0402LF-2.2K,5%,1/16W,EMPA
     1 SMB_S3M_CPU_3V3AUX_SDA @S9S_MB_2U_LIB.S9S_MB_2U(SCH_1):SMB_S3M_CPU_3V3AUX_SDA   I203 @S9S_MB_2U_LIB.S9S_MB_2U(SCH_1):PAGE228
     2 P3V3_AUX @S9S_MB_2U_LIB.S9S_MB_2U(SCH_1):P3V3_AUX   I203 @S9S_MB_2U_LIB.S9S_MB_2U(SCH_1):PAGE228

R2219 Q_RES_0402LF-26.7K,1%,1/16W,CHA
     1 P12V_AUX @S9S_MB_2U_LIB.S9S_MB_2U(SCH_1):P12V_AUX   I100 @S9S_MB_2U_LIB.S9S_MB_2U(SCH_1):PAGE326
     2 A_P12V_STBY_ADR_TRIGGER @S9S_MB_2U_LIB.S9S_MB_2U(SCH_1):A_P12V_STBY_ADR_TRIGGER   I100 @S9S_MB_2U_LIB.S9S_MB_2U(SCH_1):PAGE326

R2221 Q_RES_0402LF-26.7K,1%,1/16W,CHA
     1 P12V_AUX @S9S_MB_2U_LIB.S9S_MB_2U(SCH_1):P12V_AUX    I20 @S9S_MB_2U_LIB.S9S_MB_2U(SCH_1):PAGE326
     2 A_P12V_STBY_FP_TRIGGER @S9S_MB_2U_LIB.S9S_MB_2U(SCH_1):A_P12V_STBY_FP_TRIGGER    I20 @S9S_MB_2U_LIB.S9S_MB_2U(SCH_1):PAGE326

R2222 Q_RES_0402LF-1K,1%,1/16W,CHIP,A
     1 A_P12V_STBY_FP_TRIGGER @S9S_MB_2U_LIB.S9S_MB_2U(SCH_1):A_P12V_STBY_FP_TRIGGER    I17 @S9S_MB_2U_LIB.S9S_MB_2U(SCH_1):PAGE326
     2    GND @S9S_MB_2U_LIB.S9S_MB_2U(SCH_1):GND    I17 @S9S_MB_2U_LIB.S9S_MB_2U(SCH_1):PAGE326

R2227 Q_RES_0402LF-1K,1%,1/16W,CHIP,A
     1 A_P12V_STBY_ADR_TRIGGER @S9S_MB_2U_LIB.S9S_MB_2U(SCH_1):A_P12V_STBY_ADR_TRIGGER   I101 @S9S_MB_2U_LIB.S9S_MB_2U(SCH_1):PAGE326
     2    GND @S9S_MB_2U_LIB.S9S_MB_2U(SCH_1):GND   I101 @S9S_MB_2U_LIB.S9S_MB_2U(SCH_1):PAGE326

R2230 Q_RES_0402LF-10K,1%,1/16W,CHIPA
     1 P3V3_AUX @S9S_MB_2U_LIB.S9S_MB_2U(SCH_1):P3V3_AUX    I39 @S9S_MB_2U_LIB.S9S_MB_2U(SCH_1):PAGE326
     2 A_P12V_STBY_FPH_GATE @S9S_MB_2U_LIB.S9S_MB_2U(SCH_1):A_P12V_STBY_FPH_GATE    I39 @S9S_MB_2U_LIB.S9S_MB_2U(SCH_1):PAGE326

R2232 Q_RES_0402LF-10K,1%,1/16W,CHIPA
     1 P1V05_PCH_AUX @S9S_MB_2U_LIB.S9S_MB_2U(SCH_1):P1V05_PCH_AUX    I75 @S9S_MB_2U_LIB.S9S_MB_2U(SCH_1):PAGE184
     2 FAB_REV_ID0 @S9S_MB_2U_LIB.S9S_MB_2U(SCH_1):FAB_REV_ID0    I75 @S9S_MB_2U_LIB.S9S_MB_2U(SCH_1):PAGE184

R2233 Q_RES_0402LF-10K,1%,1/16W,CHIPA
     1 P3V3_AUX @S9S_MB_2U_LIB.S9S_MB_2U(SCH_1):P3V3_AUX    I41 @S9S_MB_2U_LIB.S9S_MB_2U(SCH_1):PAGE326
     2 FM_UV_ADR_TRIGGER_N @S9S_MB_2U_LIB.S9S_MB_2U(SCH_1):FM_UV_ADR_TRIGGER_N    I41 @S9S_MB_2U_LIB.S9S_MB_2U(SCH_1):PAGE326

R2234 Q_RES_0402LF-10K,1%,1/16W,EMPTA
     1 P1V05_PCH_AUX @S9S_MB_2U_LIB.S9S_MB_2U(SCH_1):P1V05_PCH_AUX    I12 @S9S_MB_2U_LIB.S9S_MB_2U(SCH_1):PAGE184
     2 FM_BOARD_SKU_ID4 @S9S_MB_2U_LIB.S9S_MB_2U(SCH_1):FM_BOARD_SKU_ID4    I12 @S9S_MB_2U_LIB.S9S_MB_2U(SCH_1):PAGE184

R2235 Q_RES_0402LF-1K,1%,1/16W,CHIP,A
     1 FM_BOARD_SKU_ID4 @S9S_MB_2U_LIB.S9S_MB_2U(SCH_1):FM_BOARD_SKU_ID4     I9 @S9S_MB_2U_LIB.S9S_MB_2U(SCH_1):PAGE184
     2    GND @S9S_MB_2U_LIB.S9S_MB_2U(SCH_1):GND     I9 @S9S_MB_2U_LIB.S9S_MB_2U(SCH_1):PAGE184

R2236 Q_RES_0402LF-100K,1%,1/16W,EMPA
     1 P12V_AUX @S9S_MB_2U_LIB.S9S_MB_2U(SCH_1):P12V_AUX     I7 @S9S_MB_2U_LIB.S9S_MB_2U(SCH_1):PAGE326
     2 A_HSC_INAP @S9S_MB_2U_LIB.S9S_MB_2U(SCH_1):A_HSC_INAP     I7 @S9S_MB_2U_LIB.S9S_MB_2U(SCH_1):PAGE326

R2238 Q_RES_0402LF-4.99K,1%,1/16W,EMA
     1 A_HSC_INAP @S9S_MB_2U_LIB.S9S_MB_2U(SCH_1):A_HSC_INAP     I2 @S9S_MB_2U_LIB.S9S_MB_2U(SCH_1):PAGE326
     2    GND @S9S_MB_2U_LIB.S9S_MB_2U(SCH_1):GND     I2 @S9S_MB_2U_LIB.S9S_MB_2U(SCH_1):PAGE326

R2240 Q_RES_0402LF-10K,1%,1/16W,EMPTA
     1 P1V05_PCH_AUX @S9S_MB_2U_LIB.S9S_MB_2U(SCH_1):P1V05_PCH_AUX    I49 @S9S_MB_2U_LIB.S9S_MB_2U(SCH_1):PAGE184
     2 FM_BOARD_SKU_ID1 @S9S_MB_2U_LIB.S9S_MB_2U(SCH_1):FM_BOARD_SKU_ID1    I49 @S9S_MB_2U_LIB.S9S_MB_2U(SCH_1):PAGE184

R2241 Q_RES_0402LF-1K,1%,1/16W,CHIP,A
     1 FM_BOARD_SKU_ID1 @S9S_MB_2U_LIB.S9S_MB_2U(SCH_1):FM_BOARD_SKU_ID1    I28 @S9S_MB_2U_LIB.S9S_MB_2U(SCH_1):PAGE184
     2    GND @S9S_MB_2U_LIB.S9S_MB_2U(SCH_1):GND    I28 @S9S_MB_2U_LIB.S9S_MB_2U(SCH_1):PAGE184

R2242 Q_RES_0402LF-10K,1%,1/16W,EMPTA
     1 P1V05_PCH_AUX @S9S_MB_2U_LIB.S9S_MB_2U(SCH_1):P1V05_PCH_AUX    I50 @S9S_MB_2U_LIB.S9S_MB_2U(SCH_1):PAGE184
     2 FM_BOARD_SKU_ID0 @S9S_MB_2U_LIB.S9S_MB_2U(SCH_1):FM_BOARD_SKU_ID0    I50 @S9S_MB_2U_LIB.S9S_MB_2U(SCH_1):PAGE184

R2243 Q_RES_0402LF-1K,1%,1/16W,CHIP,A
     1 FM_BOARD_SKU_ID0 @S9S_MB_2U_LIB.S9S_MB_2U(SCH_1):FM_BOARD_SKU_ID0    I30 @S9S_MB_2U_LIB.S9S_MB_2U(SCH_1):PAGE184
     2    GND @S9S_MB_2U_LIB.S9S_MB_2U(SCH_1):GND    I30 @S9S_MB_2U_LIB.S9S_MB_2U(SCH_1):PAGE184

R2244 Q_RES_0402LF-10K,1%,1/16W,CHIPA
     1 ROT_P1_RST_IND_N_R @S9S_MB_2U_LIB.S9S_MB_2U(SCH_1):ROT_P1_RST_IND_N_R    I39 @S9S_MB_2U_LIB.S9S_MB_2U(SCH_1):PAGE209
     2 P3V3_AUX @S9S_MB_2U_LIB.S9S_MB_2U(SCH_1):P3V3_AUX    I39 @S9S_MB_2U_LIB.S9S_MB_2U(SCH_1):PAGE209

R2252 Q_RES_0402LF-100K,1%,1/16W,EMPA
     1 PECI_MUX_SEL_R @S9S_MB_2U_LIB.S9S_MB_2U(SCH_1):PECI_MUX_SEL_R    I42 @S9S_MB_2U_LIB.S9S_MB_2U(SCH_1):PAGE185
     2    GND @S9S_MB_2U_LIB.S9S_MB_2U(SCH_1):GND    I42 @S9S_MB_2U_LIB.S9S_MB_2U(SCH_1):PAGE185

R2253 Q_RES_0402LF-4.75K,1%,1/16W,CHA
     1 P3V3_AUX @S9S_MB_2U_LIB.S9S_MB_2U(SCH_1):P3V3_AUX    I39 @S9S_MB_2U_LIB.S9S_MB_2U(SCH_1):PAGE185
     2 PECI_MUX_SEL_R @S9S_MB_2U_LIB.S9S_MB_2U(SCH_1):PECI_MUX_SEL_R    I39 @S9S_MB_2U_LIB.S9S_MB_2U(SCH_1):PAGE185

R2255 Q_RES_0402LF-0,5%,1/16W,CHIP,CA
     1 PECI_MUX_SEL_R @S9S_MB_2U_LIB.S9S_MB_2U(SCH_1):PECI_MUX_SEL_R    I41 @S9S_MB_2U_LIB.S9S_MB_2U(SCH_1):PAGE185
     2 FM_PECI_MUX_SEL_N @S9S_MB_2U_LIB.S9S_MB_2U(SCH_1):FM_PECI_MUX_SEL_N    I41 @S9S_MB_2U_LIB.S9S_MB_2U(SCH_1):PAGE185

R2256 Q_RES_0402LF-0,5%,1/16W,EMPTY,A
     1 USB2_7_R_DP @S9S_MB_2U_LIB.S9S_MB_2U(SCH_1):USB2_7_R_DP   I167 @S9S_MB_2U_LIB.S9S_MB_2U(SCH_1):PAGE227
     2 USB2_7_DP @S9S_MB_2U_LIB.S9S_MB_2U(SCH_1):USB2_7_DP   I167 @S9S_MB_2U_LIB.S9S_MB_2U(SCH_1):PAGE227

R2257 Q_RES_0402LF-0,5%,1/16W,EMPTY,A
     1 USB2_7_R_DN @S9S_MB_2U_LIB.S9S_MB_2U(SCH_1):USB2_7_R_DN   I164 @S9S_MB_2U_LIB.S9S_MB_2U(SCH_1):PAGE227
     2 USB2_7_DN @S9S_MB_2U_LIB.S9S_MB_2U(SCH_1):USB2_7_DN   I164 @S9S_MB_2U_LIB.S9S_MB_2U(SCH_1):PAGE227

R2268 Q_RES_0402LF-0,5%,1/16W,CHIP,CA
     1 RST_SMB_SWITCH_N @S9S_MB_2U_LIB.S9S_MB_2U(SCH_1):RST_SMB_SWITCH_N    I41 @S9S_MB_2U_LIB.S9S_MB_2U(SCH_1):PAGE219
     2 PU_RST_SMB_PCIE0_N @S9S_MB_2U_LIB.S9S_MB_2U(SCH_1):PU_RST_SMB_PCIE0_N    I41 @S9S_MB_2U_LIB.S9S_MB_2U(SCH_1):PAGE219

R2282 Q_RES_0402LF-10K,1%,1/16W,CHIPA
     1 P3V3_AUX @S9S_MB_2U_LIB.S9S_MB_2U(SCH_1):P3V3_AUX   I169 @S9S_MB_2U_LIB.S9S_MB_2U(SCH_1):PAGE297
     2 E1S_0_PRSNT @S9S_MB_2U_LIB.S9S_MB_2U(SCH_1):E1S_0_PRSNT   I169 @S9S_MB_2U_LIB.S9S_MB_2U(SCH_1):PAGE297

R2287 Q_RES_0402LF-10K,1%,1/16W,CHIPA
     1 P3V3_E1S_0 @S9S_MB_2U_LIB.S9S_MB_2U(SCH_1):P3V3_E1S_0   I313 @S9S_MB_2U_LIB.S9S_MB_2U(SCH_1):PAGE297
     2 E1S_0_PERST1_CLKREQ_N @S9S_MB_2U_LIB.S9S_MB_2U(SCH_1):E1S_0_PERST1_CLKREQ_N   I313 @S9S_MB_2U_LIB.S9S_MB_2U(SCH_1):PAGE297

R2296 Q_RES_0402LF-1K,1%,1/16W,CHIP,A
     1 E1S_0_PWRDIS @S9S_MB_2U_LIB.S9S_MB_2U(SCH_1):E1S_0_PWRDIS   I293 @S9S_MB_2U_LIB.S9S_MB_2U(SCH_1):PAGE297
     2    GND @S9S_MB_2U_LIB.S9S_MB_2U(SCH_1):GND   I293 @S9S_MB_2U_LIB.S9S_MB_2U(SCH_1):PAGE297

R2304 Q_RES_0402LF-10K,1%,1/16W,CHIPA
     1 P3V3_AUX @S9S_MB_2U_LIB.S9S_MB_2U(SCH_1):P3V3_AUX   I159 @S9S_MB_2U_LIB.S9S_MB_2U(SCH_1):PAGE297
     2 E1S_0_PRSNT_N @S9S_MB_2U_LIB.S9S_MB_2U(SCH_1):E1S_0_PRSNT_N   I159 @S9S_MB_2U_LIB.S9S_MB_2U(SCH_1):PAGE297

R2308 Q_RES_0402LF-10K,1%,1/16W,EMPTA
     1 P3V3_AUX @S9S_MB_2U_LIB.S9S_MB_2U(SCH_1):P3V3_AUX    I84 @S9S_MB_2U_LIB.S9S_MB_2U(SCH_1):PAGE224
     2 PCA9543_S3M_ADDR1 @S9S_MB_2U_LIB.S9S_MB_2U(SCH_1):PCA9543_S3M_ADDR1    I84 @S9S_MB_2U_LIB.S9S_MB_2U(SCH_1):PAGE224

R2309 Q_RES_0402LF-1K,1%,1/16W,CHIP,A
     1 PCA9543_S3M_ADDR1 @S9S_MB_2U_LIB.S9S_MB_2U(SCH_1):PCA9543_S3M_ADDR1    I85 @S9S_MB_2U_LIB.S9S_MB_2U(SCH_1):PAGE224
     2    GND @S9S_MB_2U_LIB.S9S_MB_2U(SCH_1):GND    I85 @S9S_MB_2U_LIB.S9S_MB_2U(SCH_1):PAGE224

R2310 Q_RES_0402LF-10K,1%,1/16W,EMPTA
     1 P3V3_AUX @S9S_MB_2U_LIB.S9S_MB_2U(SCH_1):P3V3_AUX    I83 @S9S_MB_2U_LIB.S9S_MB_2U(SCH_1):PAGE224
     2 PCA9543_S3M_ADDR0 @S9S_MB_2U_LIB.S9S_MB_2U(SCH_1):PCA9543_S3M_ADDR0    I83 @S9S_MB_2U_LIB.S9S_MB_2U(SCH_1):PAGE224

R2311 Q_RES_0402LF-1K,1%,1/16W,CHIP,A
     1 PCA9543_S3M_ADDR0 @S9S_MB_2U_LIB.S9S_MB_2U(SCH_1):PCA9543_S3M_ADDR0    I86 @S9S_MB_2U_LIB.S9S_MB_2U(SCH_1):PAGE224
     2    GND @S9S_MB_2U_LIB.S9S_MB_2U(SCH_1):GND    I86 @S9S_MB_2U_LIB.S9S_MB_2U(SCH_1):PAGE224

R2312 Q_RES_0402LF-10K,1%,1/16W,CHIPA
     1 P3V3_AUX @S9S_MB_2U_LIB.S9S_MB_2U(SCH_1):P3V3_AUX   I101 @S9S_MB_2U_LIB.S9S_MB_2U(SCH_1):PAGE224
     2 PCA9545_S3M_INT_N @S9S_MB_2U_LIB.S9S_MB_2U(SCH_1):PCA9545_S3M_INT_N   I101 @S9S_MB_2U_LIB.S9S_MB_2U(SCH_1):PAGE224

R2313 Q_RES_0402LF-0,5%,1/16W,CHIP,CA
     1 RST_SMB_SWITCH_N @S9S_MB_2U_LIB.S9S_MB_2U(SCH_1):RST_SMB_SWITCH_N    I97 @S9S_MB_2U_LIB.S9S_MB_2U(SCH_1):PAGE224
     2 RST_SMB_S3M_N @S9S_MB_2U_LIB.S9S_MB_2U(SCH_1):RST_SMB_S3M_N    I97 @S9S_MB_2U_LIB.S9S_MB_2U(SCH_1):PAGE224

R2315 Q_RES_0402LF-10K,1%,1/16W,CHIPA
     1 P3V3_AUX @S9S_MB_2U_LIB.S9S_MB_2U(SCH_1):P3V3_AUX   I103 @S9S_MB_2U_LIB.S9S_MB_2U(SCH_1):PAGE224
     2 PCA9543_S3M_INT0_N @S9S_MB_2U_LIB.S9S_MB_2U(SCH_1):PCA9543_S3M_INT0_N   I103 @S9S_MB_2U_LIB.S9S_MB_2U(SCH_1):PAGE224

R2316 Q_RES_0402LF-0,5%,1/16W,CHIP,CA
     1 PWRGD_P5V_AUX_R @S9S_MB_2U_LIB.S9S_MB_2U(SCH_1):PWRGD_P5V_AUX_R    I28 @S9S_MB_2U_LIB.S9S_MB_2U(SCH_1):PAGE244
     2 PWRGD_P5V_AUX @S9S_MB_2U_LIB.S9S_MB_2U(SCH_1):PWRGD_P5V_AUX    I28 @S9S_MB_2U_LIB.S9S_MB_2U(SCH_1):PAGE244

R2317 Q_RES_0402LF-10K,1%,1/16W,CHIPA
     1 P3V3_E1S_0 @S9S_MB_2U_LIB.S9S_MB_2U(SCH_1):P3V3_E1S_0   I264 @S9S_MB_2U_LIB.S9S_MB_2U(SCH_1):PAGE297
     2 PU_E1S_0_DUALPORT_EN_N @S9S_MB_2U_LIB.S9S_MB_2U(SCH_1):PU_E1S_0_DUALPORT_EN_N   I264 @S9S_MB_2U_LIB.S9S_MB_2U(SCH_1):PAGE297

R2322 Q_RES_0402LF-49.9,1%,1/16W,EMPA
     1 PVNN_TERM_CPU0 @S9S_MB_2U_LIB.S9S_MB_2U(SCH_1):PVNN_TERM_CPU0    I36 @S9S_MB_2U_LIB.S9S_MB_2U(SCH_1):PAGE260
     2 SVID_CLK0_CPU0_R @S9S_MB_2U_LIB.S9S_MB_2U(SCH_1):SVID_CLK0_CPU0_R    I36 @S9S_MB_2U_LIB.S9S_MB_2U(SCH_1):PAGE260

R2330 Q_RES_0402LF-0,5%,1/16W,EMPTY,A
     1 PWRGD_DSW_PWROK_R4 @S9S_MB_2U_LIB.S9S_MB_2U(SCH_1):PWRGD_DSW_PWROK_R4    I33 @S9S_MB_2U_LIB.S9S_MB_2U(SCH_1):PAGE326
     2 PWRGD_DSW_PWROK @S9S_MB_2U_LIB.S9S_MB_2U(SCH_1):PWRGD_DSW_PWROK    I33 @S9S_MB_2U_LIB.S9S_MB_2U(SCH_1):PAGE326

R2332 Q_RES_0402LF-2K,1%,1/16W,CHIP,A
     1 FM_PVPP_HBM_CPU0_EN @S9S_MB_2U_LIB.S9S_MB_2U(SCH_1):FM_PVPP_HBM_CPU0_EN    I14 @S9S_MB_2U_LIB.S9S_MB_2U(SCH_1):PAGE267
     2    GND @S9S_MB_2U_LIB.S9S_MB_2U(SCH_1):GND    I14 @S9S_MB_2U_LIB.S9S_MB_2U(SCH_1):PAGE267

R2338 Q_RES_0402LF-10K,1%,1/16W,EMPTA
     1 P3V3_AUX @S9S_MB_2U_LIB.S9S_MB_2U(SCH_1):P3V3_AUX     I5 @S9S_MB_2U_LIB.S9S_MB_2U(SCH_1):PAGE268
     2 FM_PVNN_MAIN_CPU0_EN @S9S_MB_2U_LIB.S9S_MB_2U(SCH_1):FM_PVNN_MAIN_CPU0_EN     I5 @S9S_MB_2U_LIB.S9S_MB_2U(SCH_1):PAGE268

R2339 Q_RES_0402LF-22,5%,1/16W,CHIP,A
     1 LED_CPU_RMCA_CATERR_R @S9S_MB_2U_LIB.S9S_MB_2U(SCH_1):LED_CPU_RMCA_CATERR_R   I268 @S9S_MB_2U_LIB.S9S_MB_2U(SCH_1):PAGE207
     2    GND @S9S_MB_2U_LIB.S9S_MB_2U(SCH_1):GND   I268 @S9S_MB_2U_LIB.S9S_MB_2U(SCH_1):PAGE207

R2342 Q_RES_0402LF-10K,1%,1/16W,CHIPA
     1 P3V3_AUX @S9S_MB_2U_LIB.S9S_MB_2U(SCH_1):P3V3_AUX    I75 @S9S_MB_2U_LIB.S9S_MB_2U(SCH_1):PAGE192
     2 FM_DEBUG_PORT_PRSNT_R_N @S9S_MB_2U_LIB.S9S_MB_2U(SCH_1):FM_DEBUG_PORT_PRSNT_R_N    I75 @S9S_MB_2U_LIB.S9S_MB_2U(SCH_1):PAGE192

R2343 Q_RES_0402LF-10K,1%,1/16W,EMPTA
     1 P5V_AUX_VCC @S9S_MB_2U_LIB.S9S_MB_2U(SCH_1):P5V_AUX_VCC    I41 @S9S_MB_2U_LIB.S9S_MB_2U(SCH_1):PAGE314
     2 PWRGD_P5V_AUX @S9S_MB_2U_LIB.S9S_MB_2U(SCH_1):PWRGD_P5V_AUX    I41 @S9S_MB_2U_LIB.S9S_MB_2U(SCH_1):PAGE314

R2344 Q_RES_0402LF-4.7K,5%,1/16W,CHIA
     1 P3V3_AUX @S9S_MB_2U_LIB.S9S_MB_2U(SCH_1):P3V3_AUX    I45 @S9S_MB_2U_LIB.S9S_MB_2U(SCH_1):PAGE314
     2 PWRGD_P5V_AUX_R1 @S9S_MB_2U_LIB.S9S_MB_2U(SCH_1):PWRGD_P5V_AUX_R1    I45 @S9S_MB_2U_LIB.S9S_MB_2U(SCH_1):PAGE314

R2345 Q_RES_0402LF-49.9,1%,1/16W,EMPA
     1 PVNN_TERM_CPU1 @S9S_MB_2U_LIB.S9S_MB_2U(SCH_1):PVNN_TERM_CPU1    I15 @S9S_MB_2U_LIB.S9S_MB_2U(SCH_1):PAGE278
     2 SVID_CLK0_CPU1_R @S9S_MB_2U_LIB.S9S_MB_2U(SCH_1):SVID_CLK0_CPU1_R    I15 @S9S_MB_2U_LIB.S9S_MB_2U(SCH_1):PAGE278

R2346 Q_RES_0402LF-4.7K,5%,1/16W,CHIA
     1 P3V3_AUX @S9S_MB_2U_LIB.S9S_MB_2U(SCH_1):P3V3_AUX    I51 @S9S_MB_2U_LIB.S9S_MB_2U(SCH_1):PAGE314
     2 PWRGD_P5V_AUX_R2 @S9S_MB_2U_LIB.S9S_MB_2U(SCH_1):PWRGD_P5V_AUX_R2    I51 @S9S_MB_2U_LIB.S9S_MB_2U(SCH_1):PAGE314

R2347 Q_RES_0402LF-0,5%,1/16W,CHIP,CA
     1 FM_REMOTE_DEBUG_DET_R @S9S_MB_2U_LIB.S9S_MB_2U(SCH_1):FM_REMOTE_DEBUG_DET_R   I183 @S9S_MB_2U_LIB.S9S_MB_2U(SCH_1):PAGE312
     2 FM_REMOTE_DEBUG_DET @S9S_MB_2U_LIB.S9S_MB_2U(SCH_1):FM_REMOTE_DEBUG_DET   I183 @S9S_MB_2U_LIB.S9S_MB_2U(SCH_1):PAGE312

R2348 Q_RES_0402LF-0,5%,1/16W,CHIP,CA
     1 FM_DEBUG_PORT_PRSNT_N @S9S_MB_2U_LIB.S9S_MB_2U(SCH_1):FM_DEBUG_PORT_PRSNT_N   I184 @S9S_MB_2U_LIB.S9S_MB_2U(SCH_1):PAGE312
     2 FM_DEBUG_PORT_PRSNT_R_N @S9S_MB_2U_LIB.S9S_MB_2U(SCH_1):FM_DEBUG_PORT_PRSNT_R_N   I184 @S9S_MB_2U_LIB.S9S_MB_2U(SCH_1):PAGE312

R2350 Q_RES_0402LF-0,5%,1/16W,CHIP,CA
     1 FM_PS_EN_PLD_BUF1 @S9S_MB_2U_LIB.S9S_MB_2U(SCH_1):FM_PS_EN_PLD_BUF1   I157 @S9S_MB_2U_LIB.S9S_MB_2U(SCH_1):PAGE297
     2 FM_PS_EN_PLD_BUF1_R1 @S9S_MB_2U_LIB.S9S_MB_2U(SCH_1):FM_PS_EN_PLD_BUF1_R1   I157 @S9S_MB_2U_LIB.S9S_MB_2U(SCH_1):PAGE297

R2354 Q_RES_0402LF-100,1%,1/16W,EMPTA
     1 PVNN_TERM_CPU1 @S9S_MB_2U_LIB.S9S_MB_2U(SCH_1):PVNN_TERM_CPU1    I14 @S9S_MB_2U_LIB.S9S_MB_2U(SCH_1):PAGE278
     2 SVID_DIO0_CPU1_R @S9S_MB_2U_LIB.S9S_MB_2U(SCH_1):SVID_DIO0_CPU1_R    I14 @S9S_MB_2U_LIB.S9S_MB_2U(SCH_1):PAGE278

R2355 Q_RES_0402LF-4.7K,5%,1/16W,EMPA
     1 P3V3_AUX @S9S_MB_2U_LIB.S9S_MB_2U(SCH_1):P3V3_AUX     I7 @S9S_MB_2U_LIB.S9S_MB_2U(SCH_1):PAGE213
     2 FM_PS_EN_PLD_BUF1 @S9S_MB_2U_LIB.S9S_MB_2U(SCH_1):FM_PS_EN_PLD_BUF1     I7 @S9S_MB_2U_LIB.S9S_MB_2U(SCH_1):PAGE213

R2356 Q_RES_0402LF-10K,1%,1/16W,CHIPA
     1 P5V_AUX_VCC @S9S_MB_2U_LIB.S9S_MB_2U(SCH_1):P5V_AUX_VCC    I27 @S9S_MB_2U_LIB.S9S_MB_2U(SCH_1):PAGE244
     2 PWRGD_P5V_AUX_R @S9S_MB_2U_LIB.S9S_MB_2U(SCH_1):PWRGD_P5V_AUX_R    I27 @S9S_MB_2U_LIB.S9S_MB_2U(SCH_1):PAGE244

R2357 Q_RES_0402LF-10K,1%,1/16W,CHIPA
     1 P3V3_AUX @S9S_MB_2U_LIB.S9S_MB_2U(SCH_1):P3V3_AUX    I32 @S9S_MB_2U_LIB.S9S_MB_2U(SCH_1):PAGE248
     2 PWRGD_P1V05_PCH_AUX_R @S9S_MB_2U_LIB.S9S_MB_2U(SCH_1):PWRGD_P1V05_PCH_AUX_R    I32 @S9S_MB_2U_LIB.S9S_MB_2U(SCH_1):PAGE248

R2358 Q_RES_0402LF-0,5%,1/16W,CHIP,CA
     1 FM_PCH_P1V8_AUX_EN @S9S_MB_2U_LIB.S9S_MB_2U(SCH_1):FM_PCH_P1V8_AUX_EN    I17 @S9S_MB_2U_LIB.S9S_MB_2U(SCH_1):PAGE249
     2 FM_PCH_P1V8_AUX_EN_R @S9S_MB_2U_LIB.S9S_MB_2U(SCH_1):FM_PCH_P1V8_AUX_EN_R    I17 @S9S_MB_2U_LIB.S9S_MB_2U(SCH_1):PAGE249

R2359 Q_RES_0402LF-10K,1%,1/16W,CHIPA
     1 P3V3_AUX @S9S_MB_2U_LIB.S9S_MB_2U(SCH_1):P3V3_AUX    I31 @S9S_MB_2U_LIB.S9S_MB_2U(SCH_1):PAGE249
     2 PWRGD_P1V8_PCH_AUX_R @S9S_MB_2U_LIB.S9S_MB_2U(SCH_1):PWRGD_P1V8_PCH_AUX_R    I31 @S9S_MB_2U_LIB.S9S_MB_2U(SCH_1):PAGE249

R2360 Q_RES_0402LF-0,5%,1/16W,CHIP,CA
     1 PWRGD_P1V8_PCH_AUX_R @S9S_MB_2U_LIB.S9S_MB_2U(SCH_1):PWRGD_P1V8_PCH_AUX_R    I34 @S9S_MB_2U_LIB.S9S_MB_2U(SCH_1):PAGE249
     2 PWRGD_P1V8_PCH_AUX @S9S_MB_2U_LIB.S9S_MB_2U(SCH_1):PWRGD_P1V8_PCH_AUX    I34 @S9S_MB_2U_LIB.S9S_MB_2U(SCH_1):PAGE249

R2362 Q_RES_0402LF-33.2,1%,1/16W,CHIA
     1 H_CPU0_PMDOWN_CPU1_R @S9S_MB_2U_LIB.S9S_MB_2U(SCH_1):H_CPU0_PMDOWN_CPU1_R   I122 @S9S_MB_2U_LIB.S9S_MB_2U(SCH_1):PAGE14
     2 H_CPU0_PMDOWN_CPU1_R1 @S9S_MB_2U_LIB.S9S_MB_2U(SCH_1):H_CPU0_PMDOWN_CPU1_R1   I122 @S9S_MB_2U_LIB.S9S_MB_2U(SCH_1):PAGE14

R2363 Q_RES_0402LF-10,1%,1/16W,CHIP,A
     1 RST_ESPI_RESET_N @S9S_MB_2U_LIB.S9S_MB_2U(SCH_1):RST_ESPI_RESET_N   I101 @S9S_MB_2U_LIB.S9S_MB_2U(SCH_1):PAGE190
     2 RST_ESPI_RESET_N_R @S9S_MB_2U_LIB.S9S_MB_2U(SCH_1):RST_ESPI_RESET_N_R   I101 @S9S_MB_2U_LIB.S9S_MB_2U(SCH_1):PAGE190

R2365 Q_RES_0402LF-1K,1%,1/16W,CHIP,A
     1 P3V3_AUX @S9S_MB_2U_LIB.S9S_MB_2U(SCH_1):P3V3_AUX    I50 @S9S_MB_2U_LIB.S9S_MB_2U(SCH_1):PAGE252
     2 PWRGD_PVCCIN_CPU0_R @S9S_MB_2U_LIB.S9S_MB_2U(SCH_1):PWRGD_PVCCIN_CPU0_R    I50 @S9S_MB_2U_LIB.S9S_MB_2U(SCH_1):PAGE252

R2366 Q_RES_0402LF-0,5%,1/16W,CHIP,CA
     1 PWRGD_PVCCIN_CPU0 @S9S_MB_2U_LIB.S9S_MB_2U(SCH_1):PWRGD_PVCCIN_CPU0    I49 @S9S_MB_2U_LIB.S9S_MB_2U(SCH_1):PAGE252
     2 PWRGD_PVCCIN_CPU0_R @S9S_MB_2U_LIB.S9S_MB_2U(SCH_1):PWRGD_PVCCIN_CPU0_R    I49 @S9S_MB_2U_LIB.S9S_MB_2U(SCH_1):PAGE252

R2367 Q_RES_0402LF-10K,1%,1/16W,EMPTA
     1 P3V3_AUX @S9S_MB_2U_LIB.S9S_MB_2U(SCH_1):P3V3_AUX    I14 @S9S_MB_2U_LIB.S9S_MB_2U(SCH_1):PAGE285
     2 FM_PVPP_HBM_CPU1_EN @S9S_MB_2U_LIB.S9S_MB_2U(SCH_1):FM_PVPP_HBM_CPU1_EN    I14 @S9S_MB_2U_LIB.S9S_MB_2U(SCH_1):PAGE285

R2368 Q_RES_0402LF-150,1%,1/16W,CHIPA
     1 SVID_CLK0_CPU0_R @S9S_MB_2U_LIB.S9S_MB_2U(SCH_1):SVID_CLK0_CPU0_R    I44 @S9S_MB_2U_LIB.S9S_MB_2U(SCH_1):PAGE252
     2 SVID_CLK_PVCCIN_CPU0_R @S9S_MB_2U_LIB.S9S_MB_2U(SCH_1):SVID_CLK_PVCCIN_CPU0_R    I44 @S9S_MB_2U_LIB.S9S_MB_2U(SCH_1):PAGE252

R2369 Q_RES_0402LF-0,5%,1/16W,CHIP,CA
     1 SVID_DIO0_CPU0_R @S9S_MB_2U_LIB.S9S_MB_2U(SCH_1):SVID_DIO0_CPU0_R    I43 @S9S_MB_2U_LIB.S9S_MB_2U(SCH_1):PAGE252
     2 SVID_DIO_PVCCIN_CPU0_R @S9S_MB_2U_LIB.S9S_MB_2U(SCH_1):SVID_DIO_PVCCIN_CPU0_R    I43 @S9S_MB_2U_LIB.S9S_MB_2U(SCH_1):PAGE252

R2370 Q_RES_0402LF-0,5%,1/16W,CHIP,CA
     1 SVID_ALERT0_CPU0_R_N @S9S_MB_2U_LIB.S9S_MB_2U(SCH_1):SVID_ALERT0_CPU0_R_N    I41 @S9S_MB_2U_LIB.S9S_MB_2U(SCH_1):PAGE252
     2 SVID_ALERT_PVCCIN_CPU0_R @S9S_MB_2U_LIB.S9S_MB_2U(SCH_1):SVID_ALERT_PVCCIN_CPU0_R    I41 @S9S_MB_2U_LIB.S9S_MB_2U(SCH_1):PAGE252

R2371 Q_RES_0402LF-33.2,1%,1/16W,CHIA
     1 SMB_VR_3V3AUX_SCL_R3 @S9S_MB_2U_LIB.S9S_MB_2U(SCH_1):SMB_VR_3V3AUX_SCL_R3    I80 @S9S_MB_2U_LIB.S9S_MB_2U(SCH_1):PAGE252
     2 SMB_CLK_PVCCIN_CPU0 @S9S_MB_2U_LIB.S9S_MB_2U(SCH_1):SMB_CLK_PVCCIN_CPU0    I80 @S9S_MB_2U_LIB.S9S_MB_2U(SCH_1):PAGE252

R2372 Q_RES_0402LF-33.2,1%,1/16W,CHIA
     1 SMB_VR_3V3AUX_SDA_R3 @S9S_MB_2U_LIB.S9S_MB_2U(SCH_1):SMB_VR_3V3AUX_SDA_R3    I78 @S9S_MB_2U_LIB.S9S_MB_2U(SCH_1):PAGE252
     2 SMB_DIO_PVCCIN_CPU0 @S9S_MB_2U_LIB.S9S_MB_2U(SCH_1):SMB_DIO_PVCCIN_CPU0    I78 @S9S_MB_2U_LIB.S9S_MB_2U(SCH_1):PAGE252

R2373 Q_RES_0402LF-1K,1%,1/16W,CHIP,A
     1 P3V3_AUX @S9S_MB_2U_LIB.S9S_MB_2U(SCH_1):P3V3_AUX    I23 @S9S_MB_2U_LIB.S9S_MB_2U(SCH_1):PAGE252
     2 IRQ_PVCCIN_CPU0_VRHOT_R_N @S9S_MB_2U_LIB.S9S_MB_2U(SCH_1):IRQ_PVCCIN_CPU0_VRHOT_R_N    I23 @S9S_MB_2U_LIB.S9S_MB_2U(SCH_1):PAGE252

R2374 Q_RES_0402LF-2K,1%,1/16W,CHIP,A
     1 FM_PVPP_HBM_CPU1_EN @S9S_MB_2U_LIB.S9S_MB_2U(SCH_1):FM_PVPP_HBM_CPU1_EN    I13 @S9S_MB_2U_LIB.S9S_MB_2U(SCH_1):PAGE285
     2    GND @S9S_MB_2U_LIB.S9S_MB_2U(SCH_1):GND    I13 @S9S_MB_2U_LIB.S9S_MB_2U(SCH_1):PAGE285

R2375 Q_RES_0402LF-1K,1%,1/16W,CHIP,A
     1 P3V3_AUX @S9S_MB_2U_LIB.S9S_MB_2U(SCH_1):P3V3_AUX    I19 @S9S_MB_2U_LIB.S9S_MB_2U(SCH_1):PAGE252
     2 PVCCIN_CPU0_PIN_ALERT @S9S_MB_2U_LIB.S9S_MB_2U(SCH_1):PVCCIN_CPU0_PIN_ALERT    I19 @S9S_MB_2U_LIB.S9S_MB_2U(SCH_1):PAGE252

R2376 Q_RES_0402LF-0,5%,1/16W,CHIP,CA
     1 IRQ_PSYS_CRIT_N @S9S_MB_2U_LIB.S9S_MB_2U(SCH_1):IRQ_PSYS_CRIT_N    I17 @S9S_MB_2U_LIB.S9S_MB_2U(SCH_1):PAGE252
     2 PVCCIN_CPU0_PIN_ALERT @S9S_MB_2U_LIB.S9S_MB_2U(SCH_1):PVCCIN_CPU0_PIN_ALERT    I17 @S9S_MB_2U_LIB.S9S_MB_2U(SCH_1):PAGE252

R2377 Q_RES_0402LF-1K,1%,1/16W,CHIP,A
     1 P3V3_AUX @S9S_MB_2U_LIB.S9S_MB_2U(SCH_1):P3V3_AUX    I54 @S9S_MB_2U_LIB.S9S_MB_2U(SCH_1):PAGE252
     2 PWRGD_PVCCFA_EHV_FIVRA_CPU0_R @S9S_MB_2U_LIB.S9S_MB_2U(SCH_1):PWRGD_PVCCFA_EHV_FIVRA_CPU0_R    I54 @S9S_MB_2U_LIB.S9S_MB_2U(SCH_1):PAGE252

R2379 Q_RES_0402LF-0,5%,1/16W,CHIP,CA
     1 PWRGD_PVCCFA_EHV_FIVRA_CPU0 @S9S_MB_2U_LIB.S9S_MB_2U(SCH_1):PWRGD_PVCCFA_EHV_FIVRA_CPU0    I55 @S9S_MB_2U_LIB.S9S_MB_2U(SCH_1):PAGE252
     2 PWRGD_PVCCFA_EHV_FIVRA_CPU0_R @S9S_MB_2U_LIB.S9S_MB_2U(SCH_1):PWRGD_PVCCFA_EHV_FIVRA_CPU0_R    I55 @S9S_MB_2U_LIB.S9S_MB_2U(SCH_1):PAGE252

R2380 Q_RES_0402LF-0,5%,1/16W,CHIP,CA
     1 PWRGD_PVPP_HBM_CPU1_R @S9S_MB_2U_LIB.S9S_MB_2U(SCH_1):PWRGD_PVPP_HBM_CPU1_R    I37 @S9S_MB_2U_LIB.S9S_MB_2U(SCH_1):PAGE285
     2 PWRGD_PVPP_HBM_CPU1 @S9S_MB_2U_LIB.S9S_MB_2U(SCH_1):PWRGD_PVPP_HBM_CPU1    I37 @S9S_MB_2U_LIB.S9S_MB_2U(SCH_1):PAGE285

R2381 Q_RES_0402LF-49.9,1%,1/16W,CHIA
     1 SVID_CLK0_CPU0_R @S9S_MB_2U_LIB.S9S_MB_2U(SCH_1):SVID_CLK0_CPU0_R   I125 @S9S_MB_2U_LIB.S9S_MB_2U(SCH_1):PAGE252
     2 PVNN_TERM_CPU0 @S9S_MB_2U_LIB.S9S_MB_2U(SCH_1):PVNN_TERM_CPU0   I125 @S9S_MB_2U_LIB.S9S_MB_2U(SCH_1):PAGE252

R2382 Q_RES_0402LF-49.9,1%,1/16W,EMPA
     1 SVID_ALERT0_CPU0_R_N @S9S_MB_2U_LIB.S9S_MB_2U(SCH_1):SVID_ALERT0_CPU0_R_N   I123 @S9S_MB_2U_LIB.S9S_MB_2U(SCH_1):PAGE252
     2 PVNN_TERM_CPU0 @S9S_MB_2U_LIB.S9S_MB_2U(SCH_1):PVNN_TERM_CPU0   I123 @S9S_MB_2U_LIB.S9S_MB_2U(SCH_1):PAGE252

R2383 Q_RES_0402LF-1K,1%,1/16W,CHIP,A
     1 P3V3_AUX @S9S_MB_2U_LIB.S9S_MB_2U(SCH_1):P3V3_AUX    I59 @S9S_MB_2U_LIB.S9S_MB_2U(SCH_1):PAGE260
     2 PWRGD_PVCCINFAON_CPU0_R @S9S_MB_2U_LIB.S9S_MB_2U(SCH_1):PWRGD_PVCCINFAON_CPU0_R    I59 @S9S_MB_2U_LIB.S9S_MB_2U(SCH_1):PAGE260

R2384 Q_RES_0402LF-10K,1%,1/16W,EMPTA
     1 P3V3_AUX @S9S_MB_2U_LIB.S9S_MB_2U(SCH_1):P3V3_AUX     I5 @S9S_MB_2U_LIB.S9S_MB_2U(SCH_1):PAGE286
     2 FM_PVNN_MAIN_CPU1_EN @S9S_MB_2U_LIB.S9S_MB_2U(SCH_1):FM_PVNN_MAIN_CPU1_EN     I5 @S9S_MB_2U_LIB.S9S_MB_2U(SCH_1):PAGE286

R2385 Q_RES_0402LF-2K,1%,1/16W,CHIP,A
     1 FM_PVNN_MAIN_CPU1_EN @S9S_MB_2U_LIB.S9S_MB_2U(SCH_1):FM_PVNN_MAIN_CPU1_EN     I7 @S9S_MB_2U_LIB.S9S_MB_2U(SCH_1):PAGE286
     2    GND @S9S_MB_2U_LIB.S9S_MB_2U(SCH_1):GND     I7 @S9S_MB_2U_LIB.S9S_MB_2U(SCH_1):PAGE286

R2386 Q_RES_0402LF-100,1%,1/16W,EMPTA
     1 PVNN_TERM_CPU0 @S9S_MB_2U_LIB.S9S_MB_2U(SCH_1):PVNN_TERM_CPU0    I37 @S9S_MB_2U_LIB.S9S_MB_2U(SCH_1):PAGE260
     2 SVID_DIO0_CPU0_R @S9S_MB_2U_LIB.S9S_MB_2U(SCH_1):SVID_DIO0_CPU0_R    I37 @S9S_MB_2U_LIB.S9S_MB_2U(SCH_1):PAGE260

R2387 Q_RES_0402LF-0,5%,1/16W,CHIP,CA
     1 PWRGD_PVNN_MAIN_CPU1_R @S9S_MB_2U_LIB.S9S_MB_2U(SCH_1):PWRGD_PVNN_MAIN_CPU1_R    I29 @S9S_MB_2U_LIB.S9S_MB_2U(SCH_1):PAGE286
     2 PWRGD_PVNN_MAIN_CPU1 @S9S_MB_2U_LIB.S9S_MB_2U(SCH_1):PWRGD_PVNN_MAIN_CPU1    I29 @S9S_MB_2U_LIB.S9S_MB_2U(SCH_1):PAGE286

R2388 Q_RES_0402LF-0,5%,1/16W,CHIP,CA
     1 SVID_DIO0_CPU0_R @S9S_MB_2U_LIB.S9S_MB_2U(SCH_1):SVID_DIO0_CPU0_R    I57 @S9S_MB_2U_LIB.S9S_MB_2U(SCH_1):PAGE260
     2 SVID_DIO_PVCCINFAON_CPU0_R @S9S_MB_2U_LIB.S9S_MB_2U(SCH_1):SVID_DIO_PVCCINFAON_CPU0_R    I57 @S9S_MB_2U_LIB.S9S_MB_2U(SCH_1):PAGE260

R2389 Q_RES_0402LF-0,5%,1/16W,CHIP,CA
     1 SVID_ALERT0_CPU0_R_N @S9S_MB_2U_LIB.S9S_MB_2U(SCH_1):SVID_ALERT0_CPU0_R_N    I52 @S9S_MB_2U_LIB.S9S_MB_2U(SCH_1):PAGE260
     2 SVID_ALERT_PVCCINFAON_CPU0_R @S9S_MB_2U_LIB.S9S_MB_2U(SCH_1):SVID_ALERT_PVCCINFAON_CPU0_R    I52 @S9S_MB_2U_LIB.S9S_MB_2U(SCH_1):PAGE260

R2390 Q_RES_0402LF-0,5%,1/16W,CHIP,CA
     1 SMB_VR_3V3AUX_SCL_R2 @S9S_MB_2U_LIB.S9S_MB_2U(SCH_1):SMB_VR_3V3AUX_SCL_R2    I53 @S9S_MB_2U_LIB.S9S_MB_2U(SCH_1):PAGE260
     2 SMB_CLK_PVCCINFAON_CPU0 @S9S_MB_2U_LIB.S9S_MB_2U(SCH_1):SMB_CLK_PVCCINFAON_CPU0    I53 @S9S_MB_2U_LIB.S9S_MB_2U(SCH_1):PAGE260

R2391 Q_RES_0402LF-0,5%,1/16W,CHIP,CA
     1 SMB_VR_3V3AUX_SDA_R2 @S9S_MB_2U_LIB.S9S_MB_2U(SCH_1):SMB_VR_3V3AUX_SDA_R2    I51 @S9S_MB_2U_LIB.S9S_MB_2U(SCH_1):PAGE260
     2 SMB_DIO_PVCCINFAON_CPU0 @S9S_MB_2U_LIB.S9S_MB_2U(SCH_1):SMB_DIO_PVCCINFAON_CPU0    I51 @S9S_MB_2U_LIB.S9S_MB_2U(SCH_1):PAGE260

R2392 Q_RES_0402LF-1K,1%,1/16W,CHIP,A
     1 P3V3_AUX @S9S_MB_2U_LIB.S9S_MB_2U(SCH_1):P3V3_AUX    I18 @S9S_MB_2U_LIB.S9S_MB_2U(SCH_1):PAGE260
     2 PVCCINFAON_CPU0_VR_FAULT @S9S_MB_2U_LIB.S9S_MB_2U(SCH_1):PVCCINFAON_CPU0_VR_FAULT    I18 @S9S_MB_2U_LIB.S9S_MB_2U(SCH_1):PAGE260

R2393 Q_RES_0402LF-1K,1%,1/16W,CHIP,A
     1 P3V3_AUX @S9S_MB_2U_LIB.S9S_MB_2U(SCH_1):P3V3_AUX    I17 @S9S_MB_2U_LIB.S9S_MB_2U(SCH_1):PAGE260
     2 PVCCINFAON_CPU0_PIN_ALERT @S9S_MB_2U_LIB.S9S_MB_2U(SCH_1):PVCCINFAON_CPU0_PIN_ALERT    I17 @S9S_MB_2U_LIB.S9S_MB_2U(SCH_1):PAGE260

R2394 Q_RES_0402LF-0,5%,1/16W,CHIP,CA
     1 FM_PVCCFA_EHV_CPU0_EN @S9S_MB_2U_LIB.S9S_MB_2U(SCH_1):FM_PVCCFA_EHV_CPU0_EN    I14 @S9S_MB_2U_LIB.S9S_MB_2U(SCH_1):PAGE260
     2 PVCCFA_EHV_CPU0_EN_R @S9S_MB_2U_LIB.S9S_MB_2U(SCH_1):PVCCFA_EHV_CPU0_EN_R    I14 @S9S_MB_2U_LIB.S9S_MB_2U(SCH_1):PAGE260

R2396 Q_RES_0402LF-1K,1%,1/16W,CHIP,A
     1 P3V3_AUX @S9S_MB_2U_LIB.S9S_MB_2U(SCH_1):P3V3_AUX    I13 @S9S_MB_2U_LIB.S9S_MB_2U(SCH_1):PAGE260
     2 PWRGD_PVCCFA_EHV_CPU0_R @S9S_MB_2U_LIB.S9S_MB_2U(SCH_1):PWRGD_PVCCFA_EHV_CPU0_R    I13 @S9S_MB_2U_LIB.S9S_MB_2U(SCH_1):PAGE260

R2397 Q_RES_0402LF-0,5%,1/16W,CHIP,CA
     1 PWRGD_PVCCFA_EHV_CPU0 @S9S_MB_2U_LIB.S9S_MB_2U(SCH_1):PWRGD_PVCCFA_EHV_CPU0    I11 @S9S_MB_2U_LIB.S9S_MB_2U(SCH_1):PAGE260
     2 PWRGD_PVCCFA_EHV_CPU0_R @S9S_MB_2U_LIB.S9S_MB_2U(SCH_1):PWRGD_PVCCFA_EHV_CPU0_R    I11 @S9S_MB_2U_LIB.S9S_MB_2U(SCH_1):PAGE260

R2398 Q_RES_0402LF-1K,1%,1/16W,CHIP,A
     1 P3V3_AUX @S9S_MB_2U_LIB.S9S_MB_2U(SCH_1):P3V3_AUX    I79 @S9S_MB_2U_LIB.S9S_MB_2U(SCH_1):PAGE260
     2 IRQ_PVCCFA_CPU0_VRHOT_R_N @S9S_MB_2U_LIB.S9S_MB_2U(SCH_1):IRQ_PVCCFA_CPU0_VRHOT_R_N    I79 @S9S_MB_2U_LIB.S9S_MB_2U(SCH_1):PAGE260

R2399 Q_RES_0402LF-150,1%,1/16W,CHIPA
     1 SVID_CLK1_CPU0_R @S9S_MB_2U_LIB.S9S_MB_2U(SCH_1):SVID_CLK1_CPU0_R    I43 @S9S_MB_2U_LIB.S9S_MB_2U(SCH_1):PAGE264
     2 SVID_CLK_PVCCD_HV_CPU0_R @S9S_MB_2U_LIB.S9S_MB_2U(SCH_1):SVID_CLK_PVCCD_HV_CPU0_R    I43 @S9S_MB_2U_LIB.S9S_MB_2U(SCH_1):PAGE264

R2400 Q_RES_0402LF-0,5%,1/16W,CHIP,CA
     1 SVID_DIO1_CPU0_R @S9S_MB_2U_LIB.S9S_MB_2U(SCH_1):SVID_DIO1_CPU0_R    I42 @S9S_MB_2U_LIB.S9S_MB_2U(SCH_1):PAGE264
     2 SVID_DIO_PVCCD_HV_CPU0_R @S9S_MB_2U_LIB.S9S_MB_2U(SCH_1):SVID_DIO_PVCCD_HV_CPU0_R    I42 @S9S_MB_2U_LIB.S9S_MB_2U(SCH_1):PAGE264

R2401 Q_RES_0402LF-0,5%,1/16W,CHIP,CA
     1 SVID_ALERT1_CPU0_R_N @S9S_MB_2U_LIB.S9S_MB_2U(SCH_1):SVID_ALERT1_CPU0_R_N    I40 @S9S_MB_2U_LIB.S9S_MB_2U(SCH_1):PAGE264
     2 SVID_ALERT_PVCCD_HV_CPU0_R @S9S_MB_2U_LIB.S9S_MB_2U(SCH_1):SVID_ALERT_PVCCD_HV_CPU0_R    I40 @S9S_MB_2U_LIB.S9S_MB_2U(SCH_1):PAGE264

R2402 Q_RES_0402LF-0,5%,1/16W,CHIP,CA
     1 SMB_VR_3V3AUX_SCL_R2 @S9S_MB_2U_LIB.S9S_MB_2U(SCH_1):SMB_VR_3V3AUX_SCL_R2    I39 @S9S_MB_2U_LIB.S9S_MB_2U(SCH_1):PAGE264
     2 SMB_CLK_PVCCD_HV_CPU0 @S9S_MB_2U_LIB.S9S_MB_2U(SCH_1):SMB_CLK_PVCCD_HV_CPU0    I39 @S9S_MB_2U_LIB.S9S_MB_2U(SCH_1):PAGE264

R2403 Q_RES_0402LF-0,5%,1/16W,CHIP,CA
     1 SMB_VR_3V3AUX_SDA_R2 @S9S_MB_2U_LIB.S9S_MB_2U(SCH_1):SMB_VR_3V3AUX_SDA_R2    I38 @S9S_MB_2U_LIB.S9S_MB_2U(SCH_1):PAGE264
     2 SMB_DIO_PVCCD_HV_CPU0 @S9S_MB_2U_LIB.S9S_MB_2U(SCH_1):SMB_DIO_PVCCD_HV_CPU0    I38 @S9S_MB_2U_LIB.S9S_MB_2U(SCH_1):PAGE264

R2404 Q_RES_0402LF-1K,1%,1/16W,CHIP,A
     1 P3V3_AUX @S9S_MB_2U_LIB.S9S_MB_2U(SCH_1):P3V3_AUX    I85 @S9S_MB_2U_LIB.S9S_MB_2U(SCH_1):PAGE264
     2 IRQ_PVCCD_CPU0_VRHOT_LVC3_N @S9S_MB_2U_LIB.S9S_MB_2U(SCH_1):IRQ_PVCCD_CPU0_VRHOT_LVC3_N    I85 @S9S_MB_2U_LIB.S9S_MB_2U(SCH_1):PAGE264

R2405 Q_RES_0402LF-0,5%,1/16W,CHIP,CA
     1 IRQ_PVCCD_CPU0_VRHOT_LVC3_R_N @S9S_MB_2U_LIB.S9S_MB_2U(SCH_1):IRQ_PVCCD_CPU0_VRHOT_LVC3_R_N    I60 @S9S_MB_2U_LIB.S9S_MB_2U(SCH_1):PAGE264
     2 IRQ_PVCCD_CPU0_VRHOT_LVC3_N @S9S_MB_2U_LIB.S9S_MB_2U(SCH_1):IRQ_PVCCD_CPU0_VRHOT_LVC3_N    I60 @S9S_MB_2U_LIB.S9S_MB_2U(SCH_1):PAGE264

R2406 Q_RES_0402LF-10K,1%,1/16W,EMPTA
     1 P3V3_AUX @S9S_MB_2U_LIB.S9S_MB_2U(SCH_1):P3V3_AUX     I9 @S9S_MB_2U_LIB.S9S_MB_2U(SCH_1):PAGE267
     2 FM_PVPP_HBM_CPU0_EN @S9S_MB_2U_LIB.S9S_MB_2U(SCH_1):FM_PVPP_HBM_CPU0_EN     I9 @S9S_MB_2U_LIB.S9S_MB_2U(SCH_1):PAGE267

R2407 Q_RES_0402LF-10K,1%,1/16W,CHIPA
     1 P3V3_AUX @S9S_MB_2U_LIB.S9S_MB_2U(SCH_1):P3V3_AUX    I45 @S9S_MB_2U_LIB.S9S_MB_2U(SCH_1):PAGE267
     2 PWRGD_PVPP_HBM_CPU0_R @S9S_MB_2U_LIB.S9S_MB_2U(SCH_1):PWRGD_PVPP_HBM_CPU0_R    I45 @S9S_MB_2U_LIB.S9S_MB_2U(SCH_1):PAGE267

R2408 Q_RES_0402LF-0,5%,1/16W,CHIP,CA
     1 PWRGD_PVPP_HBM_CPU0_R @S9S_MB_2U_LIB.S9S_MB_2U(SCH_1):PWRGD_PVPP_HBM_CPU0_R    I29 @S9S_MB_2U_LIB.S9S_MB_2U(SCH_1):PAGE267
     2 PWRGD_PVPP_HBM_CPU0 @S9S_MB_2U_LIB.S9S_MB_2U(SCH_1):PWRGD_PVPP_HBM_CPU0    I29 @S9S_MB_2U_LIB.S9S_MB_2U(SCH_1):PAGE267

R2409 Q_RES_0402LF-10K,1%,1/16W,CHIPA
     1 P3V3_AUX @S9S_MB_2U_LIB.S9S_MB_2U(SCH_1):P3V3_AUX    I32 @S9S_MB_2U_LIB.S9S_MB_2U(SCH_1):PAGE268
     2 PWRGD_PVNN_MAIN_CPU0_R @S9S_MB_2U_LIB.S9S_MB_2U(SCH_1):PWRGD_PVNN_MAIN_CPU0_R    I32 @S9S_MB_2U_LIB.S9S_MB_2U(SCH_1):PAGE268

R2410 Q_RES_0402LF-33.2,1%,1/16W,CHIA
     1 SMB_M2_P0_1V8AUX_SDA_R @S9S_MB_2U_LIB.S9S_MB_2U(SCH_1):SMB_M2_P0_1V8AUX_SDA_R    I65 @S9S_MB_2U_LIB.S9S_MB_2U(SCH_1):PAGE183
     2 SMB_M2_P0_1V8AUX_SDA @S9S_MB_2U_LIB.S9S_MB_2U(SCH_1):SMB_M2_P0_1V8AUX_SDA    I65 @S9S_MB_2U_LIB.S9S_MB_2U(SCH_1):PAGE183

R2411 Q_RES_0402LF-33.2,1%,1/16W,CHIA
     1 SMB_M2_P0_1V8AUX_SCL_R @S9S_MB_2U_LIB.S9S_MB_2U(SCH_1):SMB_M2_P0_1V8AUX_SCL_R    I66 @S9S_MB_2U_LIB.S9S_MB_2U(SCH_1):PAGE183
     2 SMB_M2_P0_1V8AUX_SCL @S9S_MB_2U_LIB.S9S_MB_2U(SCH_1):SMB_M2_P0_1V8AUX_SCL    I66 @S9S_MB_2U_LIB.S9S_MB_2U(SCH_1):PAGE183

R2412 Q_RES_0402LF-0,5%,1/16W,CHIP,CA
     1 PWRGD_DSW_PWROK @S9S_MB_2U_LIB.S9S_MB_2U(SCH_1):PWRGD_DSW_PWROK    I83 @S9S_MB_2U_LIB.S9S_MB_2U(SCH_1):PAGE313
     2 PWRGD_DSW_PWROK_R3 @S9S_MB_2U_LIB.S9S_MB_2U(SCH_1):PWRGD_DSW_PWROK_R3    I83 @S9S_MB_2U_LIB.S9S_MB_2U(SCH_1):PAGE313

R2413 Q_RES_0402LF-0,5%,1/16W,CHIP,CA
     1 SMB_2_BMC_GPU_SCL @S9S_MB_2U_LIB.S9S_MB_2U(SCH_1):SMB_2_BMC_GPU_SCL    I86 @S9S_MB_2U_LIB.S9S_MB_2U(SCH_1):PAGE227
     2 SMB_PCIE2_3V3AUX_SCL_R0 @S9S_MB_2U_LIB.S9S_MB_2U(SCH_1):SMB_PCIE2_3V3AUX_SCL_R0    I86 @S9S_MB_2U_LIB.S9S_MB_2U(SCH_1):PAGE227

R2414 Q_RES_0402LF-0,5%,1/16W,CHIP,CA
     1 SMB_2_BMC_GPU_SDA @S9S_MB_2U_LIB.S9S_MB_2U(SCH_1):SMB_2_BMC_GPU_SDA    I85 @S9S_MB_2U_LIB.S9S_MB_2U(SCH_1):PAGE227
     2 SMB_PCIE2_3V3AUX_SDA_R0 @S9S_MB_2U_LIB.S9S_MB_2U(SCH_1):SMB_PCIE2_3V3AUX_SDA_R0    I85 @S9S_MB_2U_LIB.S9S_MB_2U(SCH_1):PAGE227

R2415 Q_RES_0402LF-0,5%,1/16W,CHIP,CA
     1 SMB_1_BMC_GPU_SCL @S9S_MB_2U_LIB.S9S_MB_2U(SCH_1):SMB_1_BMC_GPU_SCL    I25 @S9S_MB_2U_LIB.S9S_MB_2U(SCH_1):PAGE227
     2 SMB_PCIE3_3V3AUX_SCL_R @S9S_MB_2U_LIB.S9S_MB_2U(SCH_1):SMB_PCIE3_3V3AUX_SCL_R    I25 @S9S_MB_2U_LIB.S9S_MB_2U(SCH_1):PAGE227

R2416 Q_RES_0402LF-0,5%,1/16W,CHIP,CA
     1 SMB_1_BMC_GPU_SDA @S9S_MB_2U_LIB.S9S_MB_2U(SCH_1):SMB_1_BMC_GPU_SDA    I24 @S9S_MB_2U_LIB.S9S_MB_2U(SCH_1):PAGE227
     2 SMB_PCIE3_3V3AUX_SDA_R @S9S_MB_2U_LIB.S9S_MB_2U(SCH_1):SMB_PCIE3_3V3AUX_SDA_R    I24 @S9S_MB_2U_LIB.S9S_MB_2U(SCH_1):PAGE227

R2417 Q_RES_0402LF-33.2,1%,1/16W,CHIA
     1 SMB_S3M_CPU_3V3AUX_SCL @S9S_MB_2U_LIB.S9S_MB_2U(SCH_1):SMB_S3M_CPU_3V3AUX_SCL    I22 @S9S_MB_2U_LIB.S9S_MB_2U(SCH_1):PAGE227
     2 SMB_S3M_CPU_3V3AUX_SCL_R0 @S9S_MB_2U_LIB.S9S_MB_2U(SCH_1):SMB_S3M_CPU_3V3AUX_SCL_R0    I22 @S9S_MB_2U_LIB.S9S_MB_2U(SCH_1):PAGE227

R2418 Q_RES_0402LF-33.2,1%,1/16W,CHIA
     1 SMB_S3M_CPU_3V3AUX_SDA @S9S_MB_2U_LIB.S9S_MB_2U(SCH_1):SMB_S3M_CPU_3V3AUX_SDA    I23 @S9S_MB_2U_LIB.S9S_MB_2U(SCH_1):PAGE227
     2 SMB_S3M_CPU_3V3AUX_SDA_R0 @S9S_MB_2U_LIB.S9S_MB_2U(SCH_1):SMB_S3M_CPU_3V3AUX_SDA_R0    I23 @S9S_MB_2U_LIB.S9S_MB_2U(SCH_1):PAGE227

R2419 Q_RES_0402LF-33.2,1%,1/16W,CHIA
     1 SMB_HOST_3V3AUX_SCL @S9S_MB_2U_LIB.S9S_MB_2U(SCH_1):SMB_HOST_3V3AUX_SCL   I100 @S9S_MB_2U_LIB.S9S_MB_2U(SCH_1):PAGE227
     2 SMB_HOST_3V3AUX_SCL_R0 @S9S_MB_2U_LIB.S9S_MB_2U(SCH_1):SMB_HOST_3V3AUX_SCL_R0   I100 @S9S_MB_2U_LIB.S9S_MB_2U(SCH_1):PAGE227

R2420 Q_RES_0402LF-33.2,1%,1/16W,CHIA
     1 SMB_HOST_3V3AUX_SDA @S9S_MB_2U_LIB.S9S_MB_2U(SCH_1):SMB_HOST_3V3AUX_SDA    I98 @S9S_MB_2U_LIB.S9S_MB_2U(SCH_1):PAGE227
     2 SMB_HOST_3V3AUX_SDA_R0 @S9S_MB_2U_LIB.S9S_MB_2U(SCH_1):SMB_HOST_3V3AUX_SDA_R0    I98 @S9S_MB_2U_LIB.S9S_MB_2U(SCH_1):PAGE227

R2421 Q_RES_0402LF-33.2,1%,1/16W,CHIA
     1 SMB_VR_SENSOR_3V3AUX_SCL @S9S_MB_2U_LIB.S9S_MB_2U(SCH_1):SMB_VR_SENSOR_3V3AUX_SCL    I99 @S9S_MB_2U_LIB.S9S_MB_2U(SCH_1):PAGE227
     2 SMB_VR_3V3AUX_SCL_R0 @S9S_MB_2U_LIB.S9S_MB_2U(SCH_1):SMB_VR_3V3AUX_SCL_R0    I99 @S9S_MB_2U_LIB.S9S_MB_2U(SCH_1):PAGE227

R2422 Q_RES_0402LF-33.2,1%,1/16W,CHIA
     1 SMB_VR_SENSOR_3V3AUX_SDA @S9S_MB_2U_LIB.S9S_MB_2U(SCH_1):SMB_VR_SENSOR_3V3AUX_SDA    I95 @S9S_MB_2U_LIB.S9S_MB_2U(SCH_1):PAGE227
     2 SMB_VR_3V3AUX_SDA_R0 @S9S_MB_2U_LIB.S9S_MB_2U(SCH_1):SMB_VR_3V3AUX_SDA_R0    I95 @S9S_MB_2U_LIB.S9S_MB_2U(SCH_1):PAGE227

R2423 Q_RES_0402LF-33.2,1%,1/16W,CHIA
     1 SMB_SML1_PMBUS_3V3AUX_PCH_SCL @S9S_MB_2U_LIB.S9S_MB_2U(SCH_1):SMB_SML1_PMBUS_3V3AUX_PCH_SCL    I97 @S9S_MB_2U_LIB.S9S_MB_2U(SCH_1):PAGE227
     2 SMB_SML1_PMBUS_3V3AUX_PCH_SCL_R @S9S_MB_2U_LIB.S9S_MB_2U(SCH_1):SMB_SML1_PMBUS_3V3AUX_PCH_SCL_R0    I97 @S9S_MB_2U_LIB.S9S_MB_2U(SCH_1):PAGE227

R2424 Q_RES_0402LF-33.2,1%,1/16W,CHIA
     1 SMB_SML1_PMBUS_3V3AUX_PCH_SDA @S9S_MB_2U_LIB.S9S_MB_2U(SCH_1):SMB_SML1_PMBUS_3V3AUX_PCH_SDA    I96 @S9S_MB_2U_LIB.S9S_MB_2U(SCH_1):PAGE227
     2 SMB_SML1_PMBUS_3V3AUX_PCH_SDA_R @S9S_MB_2U_LIB.S9S_MB_2U(SCH_1):SMB_SML1_PMBUS_3V3AUX_PCH_SDA_R0    I96 @S9S_MB_2U_LIB.S9S_MB_2U(SCH_1):PAGE227

R2425 Q_RES_0402LF-33.2,1%,1/16W,CHIA
     1 SMB_OCP_V3_2_3V3AUX_SCL @S9S_MB_2U_LIB.S9S_MB_2U(SCH_1):SMB_OCP_V3_2_3V3AUX_SCL    I93 @S9S_MB_2U_LIB.S9S_MB_2U(SCH_1):PAGE227
     2 SMB_OCP_V3_2_3V3AUX_SCL_R0 @S9S_MB_2U_LIB.S9S_MB_2U(SCH_1):SMB_OCP_V3_2_3V3AUX_SCL_R0    I93 @S9S_MB_2U_LIB.S9S_MB_2U(SCH_1):PAGE227

R2426 Q_RES_0402LF-100,1%,1/16W,EMPTA
     1 E1S_0_PERST1_CLKREQ_N @S9S_MB_2U_LIB.S9S_MB_2U(SCH_1):E1S_0_PERST1_CLKREQ_N   I311 @S9S_MB_2U_LIB.S9S_MB_2U(SCH_1):PAGE297
     2    GND @S9S_MB_2U_LIB.S9S_MB_2U(SCH_1):GND   I311 @S9S_MB_2U_LIB.S9S_MB_2U(SCH_1):PAGE297

R2449 Q_RES_0402LF-33.2,1%,1/16W,CHIA
     1 SMB_VR_3V3AUX_SCL @S9S_MB_2U_LIB.S9S_MB_2U(SCH_1):SMB_VR_3V3AUX_SCL   I206 @S9S_MB_2U_LIB.S9S_MB_2U(SCH_1):PAGE228
     2 SMB_VR_3V3AUX_SCL_R1 @S9S_MB_2U_LIB.S9S_MB_2U(SCH_1):SMB_VR_3V3AUX_SCL_R1   I206 @S9S_MB_2U_LIB.S9S_MB_2U(SCH_1):PAGE228

R2450 Q_RES_0402LF-33.2,1%,1/16W,CHIA
     1 SMB_VR_3V3AUX_SDA @S9S_MB_2U_LIB.S9S_MB_2U(SCH_1):SMB_VR_3V3AUX_SDA   I207 @S9S_MB_2U_LIB.S9S_MB_2U(SCH_1):PAGE228
     2 SMB_VR_3V3AUX_SDA_R1 @S9S_MB_2U_LIB.S9S_MB_2U(SCH_1):SMB_VR_3V3AUX_SDA_R1   I207 @S9S_MB_2U_LIB.S9S_MB_2U(SCH_1):PAGE228

R2451 Q_RES_0402LF-10K,1%,1/16W,EMPTA
     1 P3V3_AUX @S9S_MB_2U_LIB.S9S_MB_2U(SCH_1):P3V3_AUX    I94 @S9S_MB_2U_LIB.S9S_MB_2U(SCH_1):PAGE190
     2 FM_ESPI_PLD_R1_EN @S9S_MB_2U_LIB.S9S_MB_2U(SCH_1):FM_ESPI_PLD_R1_EN    I94 @S9S_MB_2U_LIB.S9S_MB_2U(SCH_1):PAGE190

R2452 Q_RES_0402LF-0,5%,1/16W,CHIP,CA
     1 FM_ESPI_PLD_R_EN @S9S_MB_2U_LIB.S9S_MB_2U(SCH_1):FM_ESPI_PLD_R_EN    I84 @S9S_MB_2U_LIB.S9S_MB_2U(SCH_1):PAGE313
     2 FM_ESPI_PLD_R1_EN @S9S_MB_2U_LIB.S9S_MB_2U(SCH_1):FM_ESPI_PLD_R1_EN    I84 @S9S_MB_2U_LIB.S9S_MB_2U(SCH_1):PAGE313

R2453 Q_RES_0402LF-33.2,1%,1/16W,CHIA
     1 SMB_VR_3V3AUX_SCL_R @S9S_MB_2U_LIB.S9S_MB_2U(SCH_1):SMB_VR_3V3AUX_SCL_R   I219 @S9S_MB_2U_LIB.S9S_MB_2U(SCH_1):PAGE228
     2 SMB_VR_3V3AUX_SCL_R2 @S9S_MB_2U_LIB.S9S_MB_2U(SCH_1):SMB_VR_3V3AUX_SCL_R2   I219 @S9S_MB_2U_LIB.S9S_MB_2U(SCH_1):PAGE228

R2454 Q_RES_0402LF-33.2,1%,1/16W,CHIA
     1 SMB_VR_3V3AUX_SDA_R @S9S_MB_2U_LIB.S9S_MB_2U(SCH_1):SMB_VR_3V3AUX_SDA_R   I218 @S9S_MB_2U_LIB.S9S_MB_2U(SCH_1):PAGE228
     2 SMB_VR_3V3AUX_SDA_R2 @S9S_MB_2U_LIB.S9S_MB_2U(SCH_1):SMB_VR_3V3AUX_SDA_R2   I218 @S9S_MB_2U_LIB.S9S_MB_2U(SCH_1):PAGE228

R2455 Q_RES_0402LF-33.2,1%,1/16W,CHIA
     1 SMB_VR_3V3AUX_SCL_R @S9S_MB_2U_LIB.S9S_MB_2U(SCH_1):SMB_VR_3V3AUX_SCL_R   I217 @S9S_MB_2U_LIB.S9S_MB_2U(SCH_1):PAGE228
     2 SMB_VR_3V3AUX_SCL_R3 @S9S_MB_2U_LIB.S9S_MB_2U(SCH_1):SMB_VR_3V3AUX_SCL_R3   I217 @S9S_MB_2U_LIB.S9S_MB_2U(SCH_1):PAGE228

R2456 Q_RES_0402LF-33.2,1%,1/16W,CHIA
     1 SMB_VR_3V3AUX_SDA_R @S9S_MB_2U_LIB.S9S_MB_2U(SCH_1):SMB_VR_3V3AUX_SDA_R   I216 @S9S_MB_2U_LIB.S9S_MB_2U(SCH_1):PAGE228
     2 SMB_VR_3V3AUX_SDA_R3 @S9S_MB_2U_LIB.S9S_MB_2U(SCH_1):SMB_VR_3V3AUX_SDA_R3   I216 @S9S_MB_2U_LIB.S9S_MB_2U(SCH_1):PAGE228

R2457 Q_RES_0402LF-100K,1%,1/16W,CHIA
     1 E1S_0_EN @S9S_MB_2U_LIB.S9S_MB_2U(SCH_1):E1S_0_EN   I165 @S9S_MB_2U_LIB.S9S_MB_2U(SCH_1):PAGE297
     2    GND @S9S_MB_2U_LIB.S9S_MB_2U(SCH_1):GND   I165 @S9S_MB_2U_LIB.S9S_MB_2U(SCH_1):PAGE297

R2473 Q_RES_0402LF-49.9,1%,1/16W,CHIA
     1 FB_BMC_ISOLATE_R1 @S9S_MB_2U_LIB.S9S_MB_2U(SCH_1):FB_BMC_ISOLATE_R1    I83 @S9S_MB_2U_LIB.S9S_MB_2U(SCH_1):PAGE151
     2 FB_BMC_ISOLATE @S9S_MB_2U_LIB.S9S_MB_2U(SCH_1):FB_BMC_ISOLATE    I83 @S9S_MB_2U_LIB.S9S_MB_2U(SCH_1):PAGE151

R2474 Q_RES_0402LF-0,5%,1/16W,EMPTY,A
     1 FM_NCSI_OCP_V3_1_R_OE @S9S_MB_2U_LIB.S9S_MB_2U(SCH_1):FM_NCSI_OCP_V3_1_R_OE    I19 @S9S_MB_2U_LIB.S9S_MB_2U(SCH_1):PAGE151
     2 FB_BMC_ISOLATE @S9S_MB_2U_LIB.S9S_MB_2U(SCH_1):FB_BMC_ISOLATE    I19 @S9S_MB_2U_LIB.S9S_MB_2U(SCH_1):PAGE151

R2476 Q_RES_0402LF-200K,1%,1/16W,EMPA
     1 SMB_PCIE_M2_0_EN @S9S_MB_2U_LIB.S9S_MB_2U(SCH_1):SMB_PCIE_M2_0_EN    I70 @S9S_MB_2U_LIB.S9S_MB_2U(SCH_1):PAGE183
     2 PWRGD_P1V8_PCH_AUX @S9S_MB_2U_LIB.S9S_MB_2U(SCH_1):PWRGD_P1V8_PCH_AUX    I70 @S9S_MB_2U_LIB.S9S_MB_2U(SCH_1):PAGE183

R2477 Q_RES_0402LF-33.2,1%,1/16W,CHIA
     1 SMB_PEHPCPU0_LVC3_SCL_R0 @S9S_MB_2U_LIB.S9S_MB_2U(SCH_1):SMB_PEHPCPU0_LVC3_SCL_R0    I88 @S9S_MB_2U_LIB.S9S_MB_2U(SCH_1):PAGE223
     2 SMB_PEHPCPU0_LVC3_SCL @S9S_MB_2U_LIB.S9S_MB_2U(SCH_1):SMB_PEHPCPU0_LVC3_SCL    I88 @S9S_MB_2U_LIB.S9S_MB_2U(SCH_1):PAGE223

R2478 Q_RES_0402LF-33.2,1%,1/16W,CHIA
     1 SMB_PEHPCPU0_LVC3_SDA_R0 @S9S_MB_2U_LIB.S9S_MB_2U(SCH_1):SMB_PEHPCPU0_LVC3_SDA_R0    I89 @S9S_MB_2U_LIB.S9S_MB_2U(SCH_1):PAGE223
     2 SMB_PEHPCPU0_LVC3_SDA @S9S_MB_2U_LIB.S9S_MB_2U(SCH_1):SMB_PEHPCPU0_LVC3_SDA    I89 @S9S_MB_2U_LIB.S9S_MB_2U(SCH_1):PAGE223

R2479 Q_RES_0402LF-33.2,1%,1/16W,CHIA
     1 SMB_PEHPCPU1_LVC3_SCL_R0 @S9S_MB_2U_LIB.S9S_MB_2U(SCH_1):SMB_PEHPCPU1_LVC3_SCL_R0    I76 @S9S_MB_2U_LIB.S9S_MB_2U(SCH_1):PAGE223
     2 SMB_PEHPCPU1_LVC3_SCL @S9S_MB_2U_LIB.S9S_MB_2U(SCH_1):SMB_PEHPCPU1_LVC3_SCL    I76 @S9S_MB_2U_LIB.S9S_MB_2U(SCH_1):PAGE223

R2480 Q_RES_0402LF-33.2,1%,1/16W,CHIA
     1 SMB_PEHPCPU1_LVC3_SDA_R0 @S9S_MB_2U_LIB.S9S_MB_2U(SCH_1):SMB_PEHPCPU1_LVC3_SDA_R0    I77 @S9S_MB_2U_LIB.S9S_MB_2U(SCH_1):PAGE223
     2 SMB_PEHPCPU1_LVC3_SDA @S9S_MB_2U_LIB.S9S_MB_2U(SCH_1):SMB_PEHPCPU1_LVC3_SDA    I77 @S9S_MB_2U_LIB.S9S_MB_2U(SCH_1):PAGE223

R2481 Q_RES_0402LF-4.75K,1%,1/16W,EMA
     1 P3V3_AUX @S9S_MB_2U_LIB.S9S_MB_2U(SCH_1):P3V3_AUX   I280 @S9S_MB_2U_LIB.S9S_MB_2U(SCH_1):PAGE197
     2 CLK_CK440_SMB_ADDR1 @S9S_MB_2U_LIB.S9S_MB_2U(SCH_1):CLK_CK440_SMB_ADDR1   I280 @S9S_MB_2U_LIB.S9S_MB_2U(SCH_1):PAGE197

R2486 Q_RES_0402LF-10K,1%,1/16W,CHIPA
     1 P3V3_AUX @S9S_MB_2U_LIB.S9S_MB_2U(SCH_1):P3V3_AUX    I40 @S9S_MB_2U_LIB.S9S_MB_2U(SCH_1):PAGE232
     2 PWRGD_P3V3_AUX_R2 @S9S_MB_2U_LIB.S9S_MB_2U(SCH_1):PWRGD_P3V3_AUX_R2    I40 @S9S_MB_2U_LIB.S9S_MB_2U(SCH_1):PAGE232

R2487 Q_RES_0402LF-4.7K,1%,1/16W,EMPA
     1 P3V3_AUX @S9S_MB_2U_LIB.S9S_MB_2U(SCH_1):P3V3_AUX    I71 @S9S_MB_2U_LIB.S9S_MB_2U(SCH_1):PAGE152
     2 IRQ_LVC3_WAKE_BUF_N @S9S_MB_2U_LIB.S9S_MB_2U(SCH_1):IRQ_LVC3_WAKE_BUF_N    I71 @S9S_MB_2U_LIB.S9S_MB_2U(SCH_1):PAGE152

R2488 Q_RES_0402LF-4.7K,1%,1/16W,CHIA
     1 P3V3_AUX @S9S_MB_2U_LIB.S9S_MB_2U(SCH_1):P3V3_AUX    I74 @S9S_MB_2U_LIB.S9S_MB_2U(SCH_1):PAGE152
     2 OCP_SFF_WAKE_BUFF_N @S9S_MB_2U_LIB.S9S_MB_2U(SCH_1):OCP_SFF_WAKE_BUFF_N    I74 @S9S_MB_2U_LIB.S9S_MB_2U(SCH_1):PAGE152

R2489 Q_RES_0402LF-33.2,1%,1/16W,CHIA
     1 IRQ_LVC3_WAKE_BUF_N @S9S_MB_2U_LIB.S9S_MB_2U(SCH_1):IRQ_LVC3_WAKE_BUF_N    I75 @S9S_MB_2U_LIB.S9S_MB_2U(SCH_1):PAGE152
     2 IRQ_LVC3_WAKE_N @S9S_MB_2U_LIB.S9S_MB_2U(SCH_1):IRQ_LVC3_WAKE_N    I75 @S9S_MB_2U_LIB.S9S_MB_2U(SCH_1):PAGE152

R2490 Q_RES_0402LF-1K,1%,1/16W,CHIP,A
     1 PWRGD_FAIL_CPU0_AB @S9S_MB_2U_LIB.S9S_MB_2U(SCH_1):PWRGD_FAIL_CPU0_AB    I46 @S9S_MB_2U_LIB.S9S_MB_2U(SCH_1):PAGE115
     2 PWRGD_FAIL_CPU0_AB_R1 @S9S_MB_2U_LIB.S9S_MB_2U(SCH_1):PWRGD_FAIL_CPU0_AB_R1    I46 @S9S_MB_2U_LIB.S9S_MB_2U(SCH_1):PAGE115

R2491 Q_RES_0402LF-1K,1%,1/16W,CHIP,A
     1 PWRGD_FAIL_CPU0_CD @S9S_MB_2U_LIB.S9S_MB_2U(SCH_1):PWRGD_FAIL_CPU0_CD    I42 @S9S_MB_2U_LIB.S9S_MB_2U(SCH_1):PAGE115
     2 PWRGD_FAIL_CPU0_CD_R1 @S9S_MB_2U_LIB.S9S_MB_2U(SCH_1):PWRGD_FAIL_CPU0_CD_R1    I42 @S9S_MB_2U_LIB.S9S_MB_2U(SCH_1):PAGE115

R2492 Q_RES_0402LF-1K,1%,1/16W,CHIP,A
     1 PWRGD_FAIL_CPU0_EF @S9S_MB_2U_LIB.S9S_MB_2U(SCH_1):PWRGD_FAIL_CPU0_EF    I41 @S9S_MB_2U_LIB.S9S_MB_2U(SCH_1):PAGE115
     2 PWRGD_FAIL_CPU0_EF_R1 @S9S_MB_2U_LIB.S9S_MB_2U(SCH_1):PWRGD_FAIL_CPU0_EF_R1    I41 @S9S_MB_2U_LIB.S9S_MB_2U(SCH_1):PAGE115

R2493 Q_RES_0402LF-1K,1%,1/16W,CHIP,A
     1 PWRGD_FAIL_CPU0_GH @S9S_MB_2U_LIB.S9S_MB_2U(SCH_1):PWRGD_FAIL_CPU0_GH    I38 @S9S_MB_2U_LIB.S9S_MB_2U(SCH_1):PAGE115
     2 PWRGD_FAIL_CPU0_GH_R1 @S9S_MB_2U_LIB.S9S_MB_2U(SCH_1):PWRGD_FAIL_CPU0_GH_R1    I38 @S9S_MB_2U_LIB.S9S_MB_2U(SCH_1):PAGE115

R2494 Q_RES_0402LF-1K,1%,1/16W,CHIP,A
     1 PWRGD_FAIL_CPU1_AB @S9S_MB_2U_LIB.S9S_MB_2U(SCH_1):PWRGD_FAIL_CPU1_AB    I18 @S9S_MB_2U_LIB.S9S_MB_2U(SCH_1):PAGE115
     2 PWRGD_FAIL_CPU1_AB_R1 @S9S_MB_2U_LIB.S9S_MB_2U(SCH_1):PWRGD_FAIL_CPU1_AB_R1    I18 @S9S_MB_2U_LIB.S9S_MB_2U(SCH_1):PAGE115

R2495 Q_RES_0402LF-1K,1%,1/16W,CHIP,A
     1 PWRGD_FAIL_CPU1_CD @S9S_MB_2U_LIB.S9S_MB_2U(SCH_1):PWRGD_FAIL_CPU1_CD    I17 @S9S_MB_2U_LIB.S9S_MB_2U(SCH_1):PAGE115
     2 PWRGD_FAIL_CPU1_CD_R1 @S9S_MB_2U_LIB.S9S_MB_2U(SCH_1):PWRGD_FAIL_CPU1_CD_R1    I17 @S9S_MB_2U_LIB.S9S_MB_2U(SCH_1):PAGE115

R2496 Q_RES_0402LF-1K,1%,1/16W,CHIP,A
     1 PWRGD_FAIL_CPU1_EF @S9S_MB_2U_LIB.S9S_MB_2U(SCH_1):PWRGD_FAIL_CPU1_EF    I12 @S9S_MB_2U_LIB.S9S_MB_2U(SCH_1):PAGE115
     2 PWRGD_FAIL_CPU1_EF_R1 @S9S_MB_2U_LIB.S9S_MB_2U(SCH_1):PWRGD_FAIL_CPU1_EF_R1    I12 @S9S_MB_2U_LIB.S9S_MB_2U(SCH_1):PAGE115

R2497 Q_RES_0402LF-1K,1%,1/16W,CHIP,A
     1 PWRGD_FAIL_CPU1_GH @S9S_MB_2U_LIB.S9S_MB_2U(SCH_1):PWRGD_FAIL_CPU1_GH     I9 @S9S_MB_2U_LIB.S9S_MB_2U(SCH_1):PAGE115
     2 PWRGD_FAIL_CPU1_GH_R1 @S9S_MB_2U_LIB.S9S_MB_2U(SCH_1):PWRGD_FAIL_CPU1_GH_R1     I9 @S9S_MB_2U_LIB.S9S_MB_2U(SCH_1):PAGE115

R2498 Q_RES_0402LF-33.2,1%,1/16W,CHIA
     1 PWRGD_FAIL_CPU0_AB_R1 @S9S_MB_2U_LIB.S9S_MB_2U(SCH_1):PWRGD_FAIL_CPU0_AB_R1    I72 @S9S_MB_2U_LIB.S9S_MB_2U(SCH_1):PAGE115
     2 PWRGD_FAIL_CPU0_AB_R @S9S_MB_2U_LIB.S9S_MB_2U(SCH_1):PWRGD_FAIL_CPU0_AB_R    I72 @S9S_MB_2U_LIB.S9S_MB_2U(SCH_1):PAGE115

R2499 Q_RES_0402LF-33.2,1%,1/16W,CHIA
     1 PWRGD_FAIL_CPU0_CD_R1 @S9S_MB_2U_LIB.S9S_MB_2U(SCH_1):PWRGD_FAIL_CPU0_CD_R1    I71 @S9S_MB_2U_LIB.S9S_MB_2U(SCH_1):PAGE115
     2 PWRGD_FAIL_CPU0_CD_R @S9S_MB_2U_LIB.S9S_MB_2U(SCH_1):PWRGD_FAIL_CPU0_CD_R    I71 @S9S_MB_2U_LIB.S9S_MB_2U(SCH_1):PAGE115

R2500 Q_RES_0402LF-33.2,1%,1/16W,CHIA
     1 PWRGD_FAIL_CPU0_EF_R1 @S9S_MB_2U_LIB.S9S_MB_2U(SCH_1):PWRGD_FAIL_CPU0_EF_R1    I70 @S9S_MB_2U_LIB.S9S_MB_2U(SCH_1):PAGE115
     2 PWRGD_FAIL_CPU0_EF_R @S9S_MB_2U_LIB.S9S_MB_2U(SCH_1):PWRGD_FAIL_CPU0_EF_R    I70 @S9S_MB_2U_LIB.S9S_MB_2U(SCH_1):PAGE115

R2501 Q_RES_0402LF-33.2,1%,1/16W,CHIA
     1 PWRGD_FAIL_CPU0_GH_R1 @S9S_MB_2U_LIB.S9S_MB_2U(SCH_1):PWRGD_FAIL_CPU0_GH_R1    I69 @S9S_MB_2U_LIB.S9S_MB_2U(SCH_1):PAGE115
     2 PWRGD_FAIL_CPU0_GH_R @S9S_MB_2U_LIB.S9S_MB_2U(SCH_1):PWRGD_FAIL_CPU0_GH_R    I69 @S9S_MB_2U_LIB.S9S_MB_2U(SCH_1):PAGE115

R2502 Q_RES_0402LF-33.2,1%,1/16W,CHIA
     1 PWRGD_FAIL_CPU1_AB_R1 @S9S_MB_2U_LIB.S9S_MB_2U(SCH_1):PWRGD_FAIL_CPU1_AB_R1    I68 @S9S_MB_2U_LIB.S9S_MB_2U(SCH_1):PAGE115
     2 PWRGD_FAIL_CPU1_AB_R @S9S_MB_2U_LIB.S9S_MB_2U(SCH_1):PWRGD_FAIL_CPU1_AB_R    I68 @S9S_MB_2U_LIB.S9S_MB_2U(SCH_1):PAGE115

R2503 Q_RES_0402LF-33.2,1%,1/16W,CHIA
     1 PWRGD_FAIL_CPU1_CD_R1 @S9S_MB_2U_LIB.S9S_MB_2U(SCH_1):PWRGD_FAIL_CPU1_CD_R1    I67 @S9S_MB_2U_LIB.S9S_MB_2U(SCH_1):PAGE115
     2 PWRGD_FAIL_CPU1_CD_R @S9S_MB_2U_LIB.S9S_MB_2U(SCH_1):PWRGD_FAIL_CPU1_CD_R    I67 @S9S_MB_2U_LIB.S9S_MB_2U(SCH_1):PAGE115

R2504 Q_RES_0402LF-33.2,1%,1/16W,CHIA
     1 PWRGD_FAIL_CPU1_EF_R1 @S9S_MB_2U_LIB.S9S_MB_2U(SCH_1):PWRGD_FAIL_CPU1_EF_R1    I66 @S9S_MB_2U_LIB.S9S_MB_2U(SCH_1):PAGE115
     2 PWRGD_FAIL_CPU1_EF_R @S9S_MB_2U_LIB.S9S_MB_2U(SCH_1):PWRGD_FAIL_CPU1_EF_R    I66 @S9S_MB_2U_LIB.S9S_MB_2U(SCH_1):PAGE115

R2505 Q_RES_0402LF-33.2,1%,1/16W,CHIA
     1 PWRGD_FAIL_CPU1_GH_R1 @S9S_MB_2U_LIB.S9S_MB_2U(SCH_1):PWRGD_FAIL_CPU1_GH_R1    I65 @S9S_MB_2U_LIB.S9S_MB_2U(SCH_1):PAGE115
     2 PWRGD_FAIL_CPU1_GH_R @S9S_MB_2U_LIB.S9S_MB_2U(SCH_1):PWRGD_FAIL_CPU1_GH_R    I65 @S9S_MB_2U_LIB.S9S_MB_2U(SCH_1):PAGE115

R2506 Q_RES_0402LF-1K,1%,1/16W,CHIP,A
     1 P3V3_AUX @S9S_MB_2U_LIB.S9S_MB_2U(SCH_1):P3V3_AUX    I87 @S9S_MB_2U_LIB.S9S_MB_2U(SCH_1):PAGE226
     2 JTAG_BMC_DBP_TMS @S9S_MB_2U_LIB.S9S_MB_2U(SCH_1):JTAG_BMC_DBP_TMS    I87 @S9S_MB_2U_LIB.S9S_MB_2U(SCH_1):PAGE226

R2507 Q_RES_0402LF-1K,1%,1/16W,CHIP,A
     1 P3V3_AUX @S9S_MB_2U_LIB.S9S_MB_2U(SCH_1):P3V3_AUX    I88 @S9S_MB_2U_LIB.S9S_MB_2U(SCH_1):PAGE226
     2 JTAG_BMC_DBP_TDI @S9S_MB_2U_LIB.S9S_MB_2U(SCH_1):JTAG_BMC_DBP_TDI    I88 @S9S_MB_2U_LIB.S9S_MB_2U(SCH_1):PAGE226

R2508 Q_RES_0402LF-10K,1%,1/16W,EMPTA
     1 P3V3_AUX @S9S_MB_2U_LIB.S9S_MB_2U(SCH_1):P3V3_AUX   I173 @S9S_MB_2U_LIB.S9S_MB_2U(SCH_1):PAGE176
     2 FM_M2_SSD0_E7_PEDET @S9S_MB_2U_LIB.S9S_MB_2U(SCH_1):FM_M2_SSD0_E7_PEDET   I173 @S9S_MB_2U_LIB.S9S_MB_2U(SCH_1):PAGE176

R2509 Q_RES_0402LF-1K,1%,1/16W,EMPTYA
     1 FM_M2_SSD0_E7_PEDET @S9S_MB_2U_LIB.S9S_MB_2U(SCH_1):FM_M2_SSD0_E7_PEDET   I174 @S9S_MB_2U_LIB.S9S_MB_2U(SCH_1):PAGE176
     2    GND @S9S_MB_2U_LIB.S9S_MB_2U(SCH_1):GND   I174 @S9S_MB_2U_LIB.S9S_MB_2U(SCH_1):PAGE176

R2510 Q_RES_0402LF-10K,1%,1/16W,EMPTA
     1 P3V3_AUX @S9S_MB_2U_LIB.S9S_MB_2U(SCH_1):P3V3_AUX   I175 @S9S_MB_2U_LIB.S9S_MB_2U(SCH_1):PAGE176
     2 FM_M2_E1S_E6_PEDET @S9S_MB_2U_LIB.S9S_MB_2U(SCH_1):FM_M2_E1S_E6_PEDET   I175 @S9S_MB_2U_LIB.S9S_MB_2U(SCH_1):PAGE176

R2511 Q_RES_0402LF-1K,1%,1/16W,EMPTYA
     1 FM_M2_E1S_E6_PEDET @S9S_MB_2U_LIB.S9S_MB_2U(SCH_1):FM_M2_E1S_E6_PEDET   I176 @S9S_MB_2U_LIB.S9S_MB_2U(SCH_1):PAGE176
     2    GND @S9S_MB_2U_LIB.S9S_MB_2U(SCH_1):GND   I176 @S9S_MB_2U_LIB.S9S_MB_2U(SCH_1):PAGE176

R2512 Q_RES_0402LF-49.9,1%,1/16W,CHIA
     1 P1V05_PCH_AUX @S9S_MB_2U_LIB.S9S_MB_2U(SCH_1):P1V05_PCH_AUX    I91 @S9S_MB_2U_LIB.S9S_MB_2U(SCH_1):PAGE226
     2 P0V7_JTAG_VREF_2 @S9S_MB_2U_LIB.S9S_MB_2U(SCH_1):P0V7_JTAG_VREF_2    I91 @S9S_MB_2U_LIB.S9S_MB_2U(SCH_1):PAGE226

R2513 Q_RES_0402LF-0,5%,1/16W,CHIP,CA
     1 PD_GTL2014_BMC_JTAG_DIR_2 @S9S_MB_2U_LIB.S9S_MB_2U(SCH_1):PD_GTL2014_BMC_JTAG_DIR_2    I90 @S9S_MB_2U_LIB.S9S_MB_2U(SCH_1):PAGE226
     2    GND @S9S_MB_2U_LIB.S9S_MB_2U(SCH_1):GND    I90 @S9S_MB_2U_LIB.S9S_MB_2U(SCH_1):PAGE226

R2514 Q_RES_0402LF-1K,1%,1/16W,EMPTYA
     1 PU_GTL2014_BMC_JTAG_DIR_1 @S9S_MB_2U_LIB.S9S_MB_2U(SCH_1):PU_GTL2014_BMC_JTAG_DIR_1    I89 @S9S_MB_2U_LIB.S9S_MB_2U(SCH_1):PAGE226
     2    GND @S9S_MB_2U_LIB.S9S_MB_2U(SCH_1):GND    I89 @S9S_MB_2U_LIB.S9S_MB_2U(SCH_1):PAGE226

R2520 Q_RES_0402LF-0,5%,1/16W,CHIP,CA
     1 SMB_VR_3V3AUX_SCL_R3 @S9S_MB_2U_LIB.S9S_MB_2U(SCH_1):SMB_VR_3V3AUX_SCL_R3    I65 @S9S_MB_2U_LIB.S9S_MB_2U(SCH_1):PAGE270
     2 SMB_CLK_PVCCIN_CPU1 @S9S_MB_2U_LIB.S9S_MB_2U(SCH_1):SMB_CLK_PVCCIN_CPU1    I65 @S9S_MB_2U_LIB.S9S_MB_2U(SCH_1):PAGE270

R2521 Q_RES_0402LF-0,5%,1/16W,CHIP,CA
     1 SMB_VR_3V3AUX_SDA_R3 @S9S_MB_2U_LIB.S9S_MB_2U(SCH_1):SMB_VR_3V3AUX_SDA_R3    I66 @S9S_MB_2U_LIB.S9S_MB_2U(SCH_1):PAGE270
     2 SMB_DIO_PVCCIN_CPU1 @S9S_MB_2U_LIB.S9S_MB_2U(SCH_1):SMB_DIO_PVCCIN_CPU1    I66 @S9S_MB_2U_LIB.S9S_MB_2U(SCH_1):PAGE270

R2522 Q_RES_0402LF-1K,1%,1/16W,CHIP,A
     1 P3V3_AUX @S9S_MB_2U_LIB.S9S_MB_2U(SCH_1):P3V3_AUX    I25 @S9S_MB_2U_LIB.S9S_MB_2U(SCH_1):PAGE270
     2 IRQ_PVCCIN_CPU1_VRHOT_R_N @S9S_MB_2U_LIB.S9S_MB_2U(SCH_1):IRQ_PVCCIN_CPU1_VRHOT_R_N    I25 @S9S_MB_2U_LIB.S9S_MB_2U(SCH_1):PAGE270

R2523 Q_RES_0402LF-0,5%,1/16W,CHIP,CA
     1 IRQ_PVCCIN_CPU1_VRHOT_R_N @S9S_MB_2U_LIB.S9S_MB_2U(SCH_1):IRQ_PVCCIN_CPU1_VRHOT_R_N    I36 @S9S_MB_2U_LIB.S9S_MB_2U(SCH_1):PAGE270
     2 IRQ_PVCCIN_CPU1_VRHOT_N @S9S_MB_2U_LIB.S9S_MB_2U(SCH_1):IRQ_PVCCIN_CPU1_VRHOT_N    I36 @S9S_MB_2U_LIB.S9S_MB_2U(SCH_1):PAGE270

R2524 Q_RES_0402LF-1K,1%,1/16W,CHIP,A
     1 P3V3_AUX @S9S_MB_2U_LIB.S9S_MB_2U(SCH_1):P3V3_AUX    I17 @S9S_MB_2U_LIB.S9S_MB_2U(SCH_1):PAGE270
     2 PVCCIN_CPU1_VR_FAULT @S9S_MB_2U_LIB.S9S_MB_2U(SCH_1):PVCCIN_CPU1_VR_FAULT    I17 @S9S_MB_2U_LIB.S9S_MB_2U(SCH_1):PAGE270

R2525 Q_RES_0402LF-1K,1%,1/16W,CHIP,A
     1 P3V3_AUX @S9S_MB_2U_LIB.S9S_MB_2U(SCH_1):P3V3_AUX    I18 @S9S_MB_2U_LIB.S9S_MB_2U(SCH_1):PAGE270
     2 PVCCIN_CPU1_PIN_ALERT @S9S_MB_2U_LIB.S9S_MB_2U(SCH_1):PVCCIN_CPU1_PIN_ALERT    I18 @S9S_MB_2U_LIB.S9S_MB_2U(SCH_1):PAGE270

R2526 Q_RES_0402LF-0,5%,1/16W,CHIP,CA
     1 FM_M2_SSD_0_PEDET @S9S_MB_2U_LIB.S9S_MB_2U(SCH_1):FM_M2_SSD_0_PEDET   I247 @S9S_MB_2U_LIB.S9S_MB_2U(SCH_1):PAGE182
     2 FM_M2_SSD0_E7_PEDET @S9S_MB_2U_LIB.S9S_MB_2U(SCH_1):FM_M2_SSD0_E7_PEDET   I247 @S9S_MB_2U_LIB.S9S_MB_2U(SCH_1):PAGE182

R2528 Q_RES_0402LF-100K,1%,1/16W,CHIA
     1 P12V_AUX @S9S_MB_2U_LIB.S9S_MB_2U(SCH_1):P12V_AUX     I8 @S9S_MB_2U_LIB.S9S_MB_2U(SCH_1):PAGE234
     2 FM_P12V_HSC_EN_N @S9S_MB_2U_LIB.S9S_MB_2U(SCH_1):FM_P12V_HSC_EN_N     I8 @S9S_MB_2U_LIB.S9S_MB_2U(SCH_1):PAGE234

R2529 Q_RES_0402LF-0,5%,1/16W,CHIP,CA
     1 FM_P12V_HSC_EN_N @S9S_MB_2U_LIB.S9S_MB_2U(SCH_1):FM_P12V_HSC_EN_N     I7 @S9S_MB_2U_LIB.S9S_MB_2U(SCH_1):PAGE234
     2 FM_P12V_HSC_EN_R_N @S9S_MB_2U_LIB.S9S_MB_2U(SCH_1):FM_P12V_HSC_EN_R_N     I7 @S9S_MB_2U_LIB.S9S_MB_2U(SCH_1):PAGE234

R2530 Q_RES_0402LF-4.7K,5%,1/16W,CHIA
     1 P12V_AUX @S9S_MB_2U_LIB.S9S_MB_2U(SCH_1):P12V_AUX    I10 @S9S_MB_2U_LIB.S9S_MB_2U(SCH_1):PAGE234
     2 P12V_AUX_BLEEDING @S9S_MB_2U_LIB.S9S_MB_2U(SCH_1):P12V_AUX_BLEEDING    I10 @S9S_MB_2U_LIB.S9S_MB_2U(SCH_1):PAGE234

R2531 Q_RES_0402LF-0,5%,1/16W,CHIP,CA
     1 MB0_P12V_STBY_PWRGD @S9S_MB_2U_LIB.S9S_MB_2U(SCH_1):MB0_P12V_STBY_PWRGD     I3 @S9S_MB_2U_LIB.S9S_MB_2U(SCH_1):PAGE234
     2 FM_P12V_HSC_EN_R @S9S_MB_2U_LIB.S9S_MB_2U(SCH_1):FM_P12V_HSC_EN_R     I3 @S9S_MB_2U_LIB.S9S_MB_2U(SCH_1):PAGE234

R2550 Q_RES_0402LF-0,5%,1/16W,CHIP,CA
     1 FM_PVCCFA_EHV_FIVRA_CPU1_EN @S9S_MB_2U_LIB.S9S_MB_2U(SCH_1):FM_PVCCFA_EHV_FIVRA_CPU1_EN    I19 @S9S_MB_2U_LIB.S9S_MB_2U(SCH_1):PAGE270
     2 PVCCFA_EHV_FIVRA_CPU1_EN_R @S9S_MB_2U_LIB.S9S_MB_2U(SCH_1):PVCCFA_EHV_FIVRA_CPU1_EN_R    I19 @S9S_MB_2U_LIB.S9S_MB_2U(SCH_1):PAGE270

R2551 Q_RES_0402LF-1K,1%,1/16W,CHIP,A
     1 P3V3_AUX @S9S_MB_2U_LIB.S9S_MB_2U(SCH_1):P3V3_AUX    I15 @S9S_MB_2U_LIB.S9S_MB_2U(SCH_1):PAGE270
     2 PWRGD_PVCCFA_EHV_FIVRA_CPU1_R @S9S_MB_2U_LIB.S9S_MB_2U(SCH_1):PWRGD_PVCCFA_EHV_FIVRA_CPU1_R    I15 @S9S_MB_2U_LIB.S9S_MB_2U(SCH_1):PAGE270

R2552 Q_RES_0402LF-0,5%,1/16W,CHIP,CA
     1 PWRGD_PVCCFA_EHV_FIVRA_CPU1 @S9S_MB_2U_LIB.S9S_MB_2U(SCH_1):PWRGD_PVCCFA_EHV_FIVRA_CPU1    I16 @S9S_MB_2U_LIB.S9S_MB_2U(SCH_1):PAGE270
     2 PWRGD_PVCCFA_EHV_FIVRA_CPU1_R @S9S_MB_2U_LIB.S9S_MB_2U(SCH_1):PWRGD_PVCCFA_EHV_FIVRA_CPU1_R    I16 @S9S_MB_2U_LIB.S9S_MB_2U(SCH_1):PAGE270

R2553 Q_RES_0402LF-100,1%,1/16W,CHIPA
     1 SVID_DIO0_CPU1_R @S9S_MB_2U_LIB.S9S_MB_2U(SCH_1):SVID_DIO0_CPU1_R    I99 @S9S_MB_2U_LIB.S9S_MB_2U(SCH_1):PAGE270
     2 PVNN_TERM_CPU1 @S9S_MB_2U_LIB.S9S_MB_2U(SCH_1):PVNN_TERM_CPU1    I99 @S9S_MB_2U_LIB.S9S_MB_2U(SCH_1):PAGE270

R2554 Q_RES_0402LF-49.9,1%,1/16W,CHIA
     1 SVID_CLK0_CPU1_R @S9S_MB_2U_LIB.S9S_MB_2U(SCH_1):SVID_CLK0_CPU1_R   I100 @S9S_MB_2U_LIB.S9S_MB_2U(SCH_1):PAGE270
     2 PVNN_TERM_CPU1 @S9S_MB_2U_LIB.S9S_MB_2U(SCH_1):PVNN_TERM_CPU1   I100 @S9S_MB_2U_LIB.S9S_MB_2U(SCH_1):PAGE270

R2555 Q_RES_0402LF-49.9,1%,1/16W,EMPA
     1 SVID_ALERT0_CPU1_R_N @S9S_MB_2U_LIB.S9S_MB_2U(SCH_1):SVID_ALERT0_CPU1_R_N   I101 @S9S_MB_2U_LIB.S9S_MB_2U(SCH_1):PAGE270
     2 PVNN_TERM_CPU1 @S9S_MB_2U_LIB.S9S_MB_2U(SCH_1):PVNN_TERM_CPU1   I101 @S9S_MB_2U_LIB.S9S_MB_2U(SCH_1):PAGE270

R2556 Q_RES_0402LF-1K,1%,1/16W,CHIP,A
     1 P3V3_AUX @S9S_MB_2U_LIB.S9S_MB_2U(SCH_1):P3V3_AUX   I105 @S9S_MB_2U_LIB.S9S_MB_2U(SCH_1):PAGE278
     2 PWRGD_PVCCINFAON_CPU1_R @S9S_MB_2U_LIB.S9S_MB_2U(SCH_1):PWRGD_PVCCINFAON_CPU1_R   I105 @S9S_MB_2U_LIB.S9S_MB_2U(SCH_1):PAGE278

R2557 Q_RES_0402LF-0,5%,1/16W,CHIP,CA
     1 IRQ_PVCCD_CPU1_VRHOT_LVC3_R_N @S9S_MB_2U_LIB.S9S_MB_2U(SCH_1):IRQ_PVCCD_CPU1_VRHOT_LVC3_R_N    I58 @S9S_MB_2U_LIB.S9S_MB_2U(SCH_1):PAGE282
     2 IRQ_PVCCD_CPU1_VRHOT_LVC3_N @S9S_MB_2U_LIB.S9S_MB_2U(SCH_1):IRQ_PVCCD_CPU1_VRHOT_LVC3_N    I58 @S9S_MB_2U_LIB.S9S_MB_2U(SCH_1):PAGE282

R2558 Q_RES_0402LF-0,5%,1/16W,CHIP,CA
     1 FM_PVCCINFAON_CPU1_EN @S9S_MB_2U_LIB.S9S_MB_2U(SCH_1):FM_PVCCINFAON_CPU1_EN   I104 @S9S_MB_2U_LIB.S9S_MB_2U(SCH_1):PAGE278
     2 PVCCINFAON_CPU1_EN_R @S9S_MB_2U_LIB.S9S_MB_2U(SCH_1):PVCCINFAON_CPU1_EN_R   I104 @S9S_MB_2U_LIB.S9S_MB_2U(SCH_1):PAGE278

R2559 Q_RES_0402LF-150,1%,1/16W,CHIPA
     1 SVID_CLK0_CPU1_R @S9S_MB_2U_LIB.S9S_MB_2U(SCH_1):SVID_CLK0_CPU1_R    I61 @S9S_MB_2U_LIB.S9S_MB_2U(SCH_1):PAGE278
     2 SVID_CLK_PVCCINFAON_CPU1_R @S9S_MB_2U_LIB.S9S_MB_2U(SCH_1):SVID_CLK_PVCCINFAON_CPU1_R    I61 @S9S_MB_2U_LIB.S9S_MB_2U(SCH_1):PAGE278

R2560 Q_RES_0402LF-0,5%,1/16W,CHIP,CA
     1 SVID_DIO0_CPU1_R @S9S_MB_2U_LIB.S9S_MB_2U(SCH_1):SVID_DIO0_CPU1_R    I60 @S9S_MB_2U_LIB.S9S_MB_2U(SCH_1):PAGE278
     2 SVID_DIO_PVCCINFAON_CPU1_R @S9S_MB_2U_LIB.S9S_MB_2U(SCH_1):SVID_DIO_PVCCINFAON_CPU1_R    I60 @S9S_MB_2U_LIB.S9S_MB_2U(SCH_1):PAGE278

R2561 Q_RES_0402LF-0,5%,1/16W,CHIP,CA
     1 SVID_ALERT0_CPU1_R_N @S9S_MB_2U_LIB.S9S_MB_2U(SCH_1):SVID_ALERT0_CPU1_R_N    I59 @S9S_MB_2U_LIB.S9S_MB_2U(SCH_1):PAGE278
     2 SVID_ALERT_PVCCINFAON_CPU1_R @S9S_MB_2U_LIB.S9S_MB_2U(SCH_1):SVID_ALERT_PVCCINFAON_CPU1_R    I59 @S9S_MB_2U_LIB.S9S_MB_2U(SCH_1):PAGE278

R2562 Q_RES_0402LF-0,5%,1/16W,CHIP,CA
     1 OCP_SFF_CLK_OE_N @S9S_MB_2U_LIB.S9S_MB_2U(SCH_1):OCP_SFF_CLK_OE_N   I535 @S9S_MB_2U_LIB.S9S_MB_2U(SCH_1):PAGE195
     2 FM_DB2000_10_OE_N @S9S_MB_2U_LIB.S9S_MB_2U(SCH_1):FM_DB2000_10_OE_N   I535 @S9S_MB_2U_LIB.S9S_MB_2U(SCH_1):PAGE195

R2563 Q_RES_0402LF-0,5%,1/16W,CHIP,CA
     1 SMB_VR_3V3AUX_SDA_R @S9S_MB_2U_LIB.S9S_MB_2U(SCH_1):SMB_VR_3V3AUX_SDA_R    I57 @S9S_MB_2U_LIB.S9S_MB_2U(SCH_1):PAGE278
     2 SMB_DIO_PVCCINFAON_CPU1 @S9S_MB_2U_LIB.S9S_MB_2U(SCH_1):SMB_DIO_PVCCINFAON_CPU1    I57 @S9S_MB_2U_LIB.S9S_MB_2U(SCH_1):PAGE278

R2565 Q_RES_0402LF-0,5%,1/16W,CHIP,CA
     1 SMB_FRU_3V3AUX_SCL_R @S9S_MB_2U_LIB.S9S_MB_2U(SCH_1):SMB_FRU_3V3AUX_SCL_R    I61 @S9S_MB_2U_LIB.S9S_MB_2U(SCH_1):PAGE219
     2 SMB_FRU_3V3AUX_SCL @S9S_MB_2U_LIB.S9S_MB_2U(SCH_1):SMB_FRU_3V3AUX_SCL    I61 @S9S_MB_2U_LIB.S9S_MB_2U(SCH_1):PAGE219

R2566 Q_RES_0402LF-0,5%,1/16W,CHIP,CA
     1 SMB_FRU_3V3AUX_SDA_R @S9S_MB_2U_LIB.S9S_MB_2U(SCH_1):SMB_FRU_3V3AUX_SDA_R    I62 @S9S_MB_2U_LIB.S9S_MB_2U(SCH_1):PAGE219
     2 SMB_FRU_3V3AUX_SDA @S9S_MB_2U_LIB.S9S_MB_2U(SCH_1):SMB_FRU_3V3AUX_SDA    I62 @S9S_MB_2U_LIB.S9S_MB_2U(SCH_1):PAGE219

R2568 Q_RES_0402LF-1K,1%,1/16W,CHIP,A
     1 P3V3_AUX @S9S_MB_2U_LIB.S9S_MB_2U(SCH_1):P3V3_AUX    I50 @S9S_MB_2U_LIB.S9S_MB_2U(SCH_1):PAGE278
     2 PVCCINFAON_CPU1_VR_FAULT @S9S_MB_2U_LIB.S9S_MB_2U(SCH_1):PVCCINFAON_CPU1_VR_FAULT    I50 @S9S_MB_2U_LIB.S9S_MB_2U(SCH_1):PAGE278

R2569 Q_RES_0402LF-1K,1%,1/16W,CHIP,A
     1 P3V3_AUX @S9S_MB_2U_LIB.S9S_MB_2U(SCH_1):P3V3_AUX    I49 @S9S_MB_2U_LIB.S9S_MB_2U(SCH_1):PAGE278
     2 PVCCINFAON_CPU1_PIN_ALERT @S9S_MB_2U_LIB.S9S_MB_2U(SCH_1):PVCCINFAON_CPU1_PIN_ALERT    I49 @S9S_MB_2U_LIB.S9S_MB_2U(SCH_1):PAGE278

R2570 Q_RES_0402LF-0,5%,1/16W,CHIP,CA
     1 FM_PVCCFA_EHV_CPU1_EN @S9S_MB_2U_LIB.S9S_MB_2U(SCH_1):FM_PVCCFA_EHV_CPU1_EN    I31 @S9S_MB_2U_LIB.S9S_MB_2U(SCH_1):PAGE278
     2 PVCCFA_EHV_CPU1_EN_R @S9S_MB_2U_LIB.S9S_MB_2U(SCH_1):PVCCFA_EHV_CPU1_EN_R    I31 @S9S_MB_2U_LIB.S9S_MB_2U(SCH_1):PAGE278

R2571 Q_RES_0402LF-1K,1%,1/16W,CHIP,A
     1 P3V3_AUX @S9S_MB_2U_LIB.S9S_MB_2U(SCH_1):P3V3_AUX    I30 @S9S_MB_2U_LIB.S9S_MB_2U(SCH_1):PAGE278
     2 PWRGD_PVCCFA_EHV_CPU1_R @S9S_MB_2U_LIB.S9S_MB_2U(SCH_1):PWRGD_PVCCFA_EHV_CPU1_R    I30 @S9S_MB_2U_LIB.S9S_MB_2U(SCH_1):PAGE278

R2572 Q_RES_0402LF-0,5%,1/16W,CHIP,CA
     1 PWRGD_PVCCFA_EHV_CPU1 @S9S_MB_2U_LIB.S9S_MB_2U(SCH_1):PWRGD_PVCCFA_EHV_CPU1    I29 @S9S_MB_2U_LIB.S9S_MB_2U(SCH_1):PAGE278
     2 PWRGD_PVCCFA_EHV_CPU1_R @S9S_MB_2U_LIB.S9S_MB_2U(SCH_1):PWRGD_PVCCFA_EHV_CPU1_R    I29 @S9S_MB_2U_LIB.S9S_MB_2U(SCH_1):PAGE278

R2573 Q_RES_0402LF-1K,1%,1/16W,CHIP,A
     1 P3V3_AUX @S9S_MB_2U_LIB.S9S_MB_2U(SCH_1):P3V3_AUX    I73 @S9S_MB_2U_LIB.S9S_MB_2U(SCH_1):PAGE278
     2 IRQ_PVCCFA_CPU1_VRHOT_R_N @S9S_MB_2U_LIB.S9S_MB_2U(SCH_1):IRQ_PVCCFA_CPU1_VRHOT_R_N    I73 @S9S_MB_2U_LIB.S9S_MB_2U(SCH_1):PAGE278

R2574 Q_RES_0402LF-0,5%,1/16W,CHIP,CA
     1 IRQ_PVCCFA_CPU1_VRHOT_N @S9S_MB_2U_LIB.S9S_MB_2U(SCH_1):IRQ_PVCCFA_CPU1_VRHOT_N    I70 @S9S_MB_2U_LIB.S9S_MB_2U(SCH_1):PAGE278
     2 IRQ_PVCCFA_CPU1_VRHOT_R_N @S9S_MB_2U_LIB.S9S_MB_2U(SCH_1):IRQ_PVCCFA_CPU1_VRHOT_R_N    I70 @S9S_MB_2U_LIB.S9S_MB_2U(SCH_1):PAGE278

R2575 Q_RES_0402LF-1K,1%,1/16W,CHIP,A
     1 P3V3_AUX @S9S_MB_2U_LIB.S9S_MB_2U(SCH_1):P3V3_AUX    I46 @S9S_MB_2U_LIB.S9S_MB_2U(SCH_1):PAGE282
     2 PWRGD_PVCCD_HV_CPU1_R @S9S_MB_2U_LIB.S9S_MB_2U(SCH_1):PWRGD_PVCCD_HV_CPU1_R    I46 @S9S_MB_2U_LIB.S9S_MB_2U(SCH_1):PAGE282

R2576 Q_RES_0402LF-0,5%,1/16W,CHIP,CA
     1 PWRGD_PVCCD_HV_CPU1 @S9S_MB_2U_LIB.S9S_MB_2U(SCH_1):PWRGD_PVCCD_HV_CPU1    I44 @S9S_MB_2U_LIB.S9S_MB_2U(SCH_1):PAGE282
     2 PWRGD_PVCCD_HV_CPU1_R @S9S_MB_2U_LIB.S9S_MB_2U(SCH_1):PWRGD_PVCCD_HV_CPU1_R    I44 @S9S_MB_2U_LIB.S9S_MB_2U(SCH_1):PAGE282

R2577 Q_RES_0402LF-0,5%,1/16W,CHIP,CA
     1 FM_PVCCD_HV_CPU1_EN @S9S_MB_2U_LIB.S9S_MB_2U(SCH_1):FM_PVCCD_HV_CPU1_EN    I43 @S9S_MB_2U_LIB.S9S_MB_2U(SCH_1):PAGE282
     2 PVCCD_HV_CPU1_EN_R @S9S_MB_2U_LIB.S9S_MB_2U(SCH_1):PVCCD_HV_CPU1_EN_R    I43 @S9S_MB_2U_LIB.S9S_MB_2U(SCH_1):PAGE282

R2578 Q_RES_0402LF-150,1%,1/16W,CHIPA
     1 SVID_CLK1_CPU1_R @S9S_MB_2U_LIB.S9S_MB_2U(SCH_1):SVID_CLK1_CPU1_R    I42 @S9S_MB_2U_LIB.S9S_MB_2U(SCH_1):PAGE282
     2 SVID_CLK_PVCCD_HV_CPU1_R @S9S_MB_2U_LIB.S9S_MB_2U(SCH_1):SVID_CLK_PVCCD_HV_CPU1_R    I42 @S9S_MB_2U_LIB.S9S_MB_2U(SCH_1):PAGE282

R2579 Q_RES_0402LF-0,5%,1/16W,CHIP,CA
     1 SVID_DIO1_CPU1_R @S9S_MB_2U_LIB.S9S_MB_2U(SCH_1):SVID_DIO1_CPU1_R    I41 @S9S_MB_2U_LIB.S9S_MB_2U(SCH_1):PAGE282
     2 SVID_DIO_PVCCD_HV_CPU1_R @S9S_MB_2U_LIB.S9S_MB_2U(SCH_1):SVID_DIO_PVCCD_HV_CPU1_R    I41 @S9S_MB_2U_LIB.S9S_MB_2U(SCH_1):PAGE282

R2580 Q_RES_0402LF-0,5%,1/16W,CHIP,CA
     1 SVID_ALERT1_CPU1_R_N @S9S_MB_2U_LIB.S9S_MB_2U(SCH_1):SVID_ALERT1_CPU1_R_N    I40 @S9S_MB_2U_LIB.S9S_MB_2U(SCH_1):PAGE282
     2 SVID_ALERT_PVCCD_HV_CPU1_R @S9S_MB_2U_LIB.S9S_MB_2U(SCH_1):SVID_ALERT_PVCCD_HV_CPU1_R    I40 @S9S_MB_2U_LIB.S9S_MB_2U(SCH_1):PAGE282

R2582 Q_RES_0402LF-0,5%,1/16W,CHIP,CA
     1 SMB_VR_3V3AUX_SDA_R @S9S_MB_2U_LIB.S9S_MB_2U(SCH_1):SMB_VR_3V3AUX_SDA_R    I38 @S9S_MB_2U_LIB.S9S_MB_2U(SCH_1):PAGE282
     2 SMB_DIO_PVCCD_HV_CPU1 @S9S_MB_2U_LIB.S9S_MB_2U(SCH_1):SMB_DIO_PVCCD_HV_CPU1    I38 @S9S_MB_2U_LIB.S9S_MB_2U(SCH_1):PAGE282

R2583 Q_RES_0402LF-10K,1%,1/16W,CHIPA
     1 P3V3_AUX @S9S_MB_2U_LIB.S9S_MB_2U(SCH_1):P3V3_AUX    I27 @S9S_MB_2U_LIB.S9S_MB_2U(SCH_1):PAGE285
     2 PWRGD_PVPP_HBM_CPU1_R @S9S_MB_2U_LIB.S9S_MB_2U(SCH_1):PWRGD_PVPP_HBM_CPU1_R    I27 @S9S_MB_2U_LIB.S9S_MB_2U(SCH_1):PAGE285

R2584 Q_RES_0402LF-10K,1%,1/16W,CHIPA
     1 P3V3_AUX @S9S_MB_2U_LIB.S9S_MB_2U(SCH_1):P3V3_AUX    I31 @S9S_MB_2U_LIB.S9S_MB_2U(SCH_1):PAGE286
     2 PWRGD_PVNN_MAIN_CPU1_R @S9S_MB_2U_LIB.S9S_MB_2U(SCH_1):PWRGD_PVNN_MAIN_CPU1_R    I31 @S9S_MB_2U_LIB.S9S_MB_2U(SCH_1):PAGE286

R2585 Q_RES_0402LF-31.6K,1%,1/16W,CHA
     1 HSC_EN @S9S_MB_2U_LIB.S9S_MB_2U(SCH_1):HSC_EN     I7 @S9S_MB_2U_LIB.S9S_MB_2U(SCH_1):PAGE303
     2    GND @S9S_MB_2U_LIB.S9S_MB_2U(SCH_1):GND     I7 @S9S_MB_2U_LIB.S9S_MB_2U(SCH_1):PAGE303

R2586 Q_RES_0402LF-0,5%,1/16W,CHIP,CA
     1 HSC_EN @S9S_MB_2U_LIB.S9S_MB_2U(SCH_1):HSC_EN    I44 @S9S_MB_2U_LIB.S9S_MB_2U(SCH_1):PAGE303
     2 HSC_EN_R @S9S_MB_2U_LIB.S9S_MB_2U(SCH_1):HSC_EN_R    I44 @S9S_MB_2U_LIB.S9S_MB_2U(SCH_1):PAGE303

R2587 Q_RES_0402LF-4.7K,1%,1/16W,CHIA
     1 HSC_VDD @S9S_MB_2U_LIB.S9S_MB_2U(SCH_1):HSC_VDD    I93 @S9S_MB_2U_LIB.S9S_MB_2U(SCH_1):PAGE303
     2 IRQ_HSC_FAULT_N @S9S_MB_2U_LIB.S9S_MB_2U(SCH_1):IRQ_HSC_FAULT_N    I93 @S9S_MB_2U_LIB.S9S_MB_2U(SCH_1):PAGE303

R2588 Q_RES_0402LF-22,1%,1/16W,CHIP,A
     1 HSC_FAULT @S9S_MB_2U_LIB.S9S_MB_2U(SCH_1):HSC_FAULT    I81 @S9S_MB_2U_LIB.S9S_MB_2U(SCH_1):PAGE303
     2 IRQ_HSC_FAULT_N @S9S_MB_2U_LIB.S9S_MB_2U(SCH_1):IRQ_HSC_FAULT_N    I81 @S9S_MB_2U_LIB.S9S_MB_2U(SCH_1):PAGE303

R2589 Q_RES_0402LF-1K,1%,1/16W,CHIP,A
     1 P3V3_AUX @S9S_MB_2U_LIB.S9S_MB_2U(SCH_1):P3V3_AUX    I20 @S9S_MB_2U_LIB.S9S_MB_2U(SCH_1):PAGE252
     2 PVCCIN_CPU0_VR_FAULT @S9S_MB_2U_LIB.S9S_MB_2U(SCH_1):PVCCIN_CPU0_VR_FAULT    I20 @S9S_MB_2U_LIB.S9S_MB_2U(SCH_1):PAGE252

R2590 Q_RES_0402LF-100,1%,1/16W,CHIPA
     1 SVID_DIO0_CPU0_R @S9S_MB_2U_LIB.S9S_MB_2U(SCH_1):SVID_DIO0_CPU0_R   I124 @S9S_MB_2U_LIB.S9S_MB_2U(SCH_1):PAGE252
     2 PVNN_TERM_CPU0 @S9S_MB_2U_LIB.S9S_MB_2U(SCH_1):PVNN_TERM_CPU0   I124 @S9S_MB_2U_LIB.S9S_MB_2U(SCH_1):PAGE252

R2591 Q_RES_0402LF-0,5%,1/16W,CHIP,CA
     1 FM_PVCCIN_CPU0_EN @S9S_MB_2U_LIB.S9S_MB_2U(SCH_1):FM_PVCCIN_CPU0_EN    I48 @S9S_MB_2U_LIB.S9S_MB_2U(SCH_1):PAGE252
     2 PVCCIN_CPU0_EN_R @S9S_MB_2U_LIB.S9S_MB_2U(SCH_1):PVCCIN_CPU0_EN_R    I48 @S9S_MB_2U_LIB.S9S_MB_2U(SCH_1):PAGE252

R2593 Q_RES_0402LF-100,1%,1/16W,CHIPA
     1 PVNN_TERM_CPU1 @S9S_MB_2U_LIB.S9S_MB_2U(SCH_1):PVNN_TERM_CPU1    I29 @S9S_MB_2U_LIB.S9S_MB_2U(SCH_1):PAGE282
     2 SVID_DIO1_CPU1_R @S9S_MB_2U_LIB.S9S_MB_2U(SCH_1):SVID_DIO1_CPU1_R    I29 @S9S_MB_2U_LIB.S9S_MB_2U(SCH_1):PAGE282

R2594 Q_RES_0402LF-0,5%,1/16W,CHIP,CA
     1 FM_PVCCINFAON_CPU0_EN @S9S_MB_2U_LIB.S9S_MB_2U(SCH_1):FM_PVCCINFAON_CPU0_EN    I55 @S9S_MB_2U_LIB.S9S_MB_2U(SCH_1):PAGE260
     2 PVCCINFAON_CPU0_EN_R @S9S_MB_2U_LIB.S9S_MB_2U(SCH_1):PVCCINFAON_CPU0_EN_R    I55 @S9S_MB_2U_LIB.S9S_MB_2U(SCH_1):PAGE260

R2595 Q_RES_0402LF-0,5%,1/16W,CHIP,CA
     1 PWRGD_PVCCINFAON_CPU0 @S9S_MB_2U_LIB.S9S_MB_2U(SCH_1):PWRGD_PVCCINFAON_CPU0    I58 @S9S_MB_2U_LIB.S9S_MB_2U(SCH_1):PAGE260
     2 PWRGD_PVCCINFAON_CPU0_R @S9S_MB_2U_LIB.S9S_MB_2U(SCH_1):PWRGD_PVCCINFAON_CPU0_R    I58 @S9S_MB_2U_LIB.S9S_MB_2U(SCH_1):PAGE260

R2596 Q_RES_0402LF-150,1%,1/16W,CHIPA
     1 SVID_CLK0_CPU0_R @S9S_MB_2U_LIB.S9S_MB_2U(SCH_1):SVID_CLK0_CPU0_R    I56 @S9S_MB_2U_LIB.S9S_MB_2U(SCH_1):PAGE260
     2 SVID_CLK_PVCCINFAON_CPU0_R @S9S_MB_2U_LIB.S9S_MB_2U(SCH_1):SVID_CLK_PVCCINFAON_CPU0_R    I56 @S9S_MB_2U_LIB.S9S_MB_2U(SCH_1):PAGE260

R2597 Q_RES_0402LF-0,5%,1/16W,CHIP,CA
     1 IRQ_PVCCFA_CPU0_VRHOT_N @S9S_MB_2U_LIB.S9S_MB_2U(SCH_1):IRQ_PVCCFA_CPU0_VRHOT_N    I78 @S9S_MB_2U_LIB.S9S_MB_2U(SCH_1):PAGE260
     2 IRQ_PVCCFA_CPU0_VRHOT_R_N @S9S_MB_2U_LIB.S9S_MB_2U(SCH_1):IRQ_PVCCFA_CPU0_VRHOT_R_N    I78 @S9S_MB_2U_LIB.S9S_MB_2U(SCH_1):PAGE260

R2656 Q_RES_0402LF-100,1%,1/16W,EMPTA
     1 HGX_DETECT_N_ISO @S9S_MB_2U_LIB.S9S_MB_2U(SCH_1):HGX_DETECT_N_ISO    I11 @S9S_MB_2U_LIB.S9S_MB_2U(SCH_1):PAGE147
     2    GND @S9S_MB_2U_LIB.S9S_MB_2U(SCH_1):GND    I11 @S9S_MB_2U_LIB.S9S_MB_2U(SCH_1):PAGE147

R2659 Q_RES_0402LF-0,5%,1/16W,CHIP,CA
     1 CLK_100M_SWB_R_DP @S9S_MB_2U_LIB.S9S_MB_2U(SCH_1):CLK_100M_SWB_R_DP    I27 @S9S_MB_2U_LIB.S9S_MB_2U(SCH_1):PAGE196
     2 CLK_100M_SWB_DP @S9S_MB_2U_LIB.S9S_MB_2U(SCH_1):CLK_100M_SWB_DP    I27 @S9S_MB_2U_LIB.S9S_MB_2U(SCH_1):PAGE196

R2660 Q_RES_0402LF-0,5%,1/16W,CHIP,CA
     1 CLK_100M_SWB_R_DN @S9S_MB_2U_LIB.S9S_MB_2U(SCH_1):CLK_100M_SWB_R_DN    I28 @S9S_MB_2U_LIB.S9S_MB_2U(SCH_1):PAGE196
     2 CLK_100M_SWB_DN @S9S_MB_2U_LIB.S9S_MB_2U(SCH_1):CLK_100M_SWB_DN    I28 @S9S_MB_2U_LIB.S9S_MB_2U(SCH_1):PAGE196

R2661 Q_RES_0402LF-33.2,1%,1/16W,CHIA
     1 FM_SWB_PWR_EN @S9S_MB_2U_LIB.S9S_MB_2U(SCH_1):FM_SWB_PWR_EN   I135 @S9S_MB_2U_LIB.S9S_MB_2U(SCH_1):PAGE314
     2 FM_SWB_PWR_EN_R @S9S_MB_2U_LIB.S9S_MB_2U(SCH_1):FM_SWB_PWR_EN_R   I135 @S9S_MB_2U_LIB.S9S_MB_2U(SCH_1):PAGE314

R2662 Q_RES_0402LF-33.2,1%,1/16W,CHIA
     1 FM_GPU_PWR_EN @S9S_MB_2U_LIB.S9S_MB_2U(SCH_1):FM_GPU_PWR_EN   I115 @S9S_MB_2U_LIB.S9S_MB_2U(SCH_1):PAGE314
     2 FM_GPU_PWR_EN_R @S9S_MB_2U_LIB.S9S_MB_2U(SCH_1):FM_GPU_PWR_EN_R   I115 @S9S_MB_2U_LIB.S9S_MB_2U(SCH_1):PAGE314

R2663 Q_RES_0402LF-33.2,1%,1/16W,CHIA
     1 FM_SWB_PWRGD_ISO @S9S_MB_2U_LIB.S9S_MB_2U(SCH_1):FM_SWB_PWRGD_ISO   I114 @S9S_MB_2U_LIB.S9S_MB_2U(SCH_1):PAGE314
     2 FM_SWB_PWRGD_ISO_R @S9S_MB_2U_LIB.S9S_MB_2U(SCH_1):FM_SWB_PWRGD_ISO_R   I114 @S9S_MB_2U_LIB.S9S_MB_2U(SCH_1):PAGE314

R2664 Q_RES_0402LF-33.2,1%,1/16W,CHIA
     1 FM_GPU_PWRGD_ISO @S9S_MB_2U_LIB.S9S_MB_2U(SCH_1):FM_GPU_PWRGD_ISO   I113 @S9S_MB_2U_LIB.S9S_MB_2U(SCH_1):PAGE314
     2 FM_GPU_PWRGD_ISO_R @S9S_MB_2U_LIB.S9S_MB_2U(SCH_1):FM_GPU_PWRGD_ISO_R   I113 @S9S_MB_2U_LIB.S9S_MB_2U(SCH_1):PAGE314

R2666 Q_RES_0402LF-10K,1%,1/16W,CHIPA
     1 SMB_BMC_SWB_EN @S9S_MB_2U_LIB.S9S_MB_2U(SCH_1):SMB_BMC_SWB_EN    I16 @S9S_MB_2U_LIB.S9S_MB_2U(SCH_1):PAGE222
     2    GND @S9S_MB_2U_LIB.S9S_MB_2U(SCH_1):GND    I16 @S9S_MB_2U_LIB.S9S_MB_2U(SCH_1):PAGE222

R2667 Q_RES_0402LF-10K,1%,1/16W,CHIPA
     1 P3V3_AUX @S9S_MB_2U_LIB.S9S_MB_2U(SCH_1):P3V3_AUX    I59 @S9S_MB_2U_LIB.S9S_MB_2U(SCH_1):PAGE222
     2 SMB_BMC_SWB_BUF_R_SCL @S9S_MB_2U_LIB.S9S_MB_2U(SCH_1):SMB_BMC_SWB_BUF_R_SCL    I59 @S9S_MB_2U_LIB.S9S_MB_2U(SCH_1):PAGE222

R2668 Q_RES_0402LF-4.7K,5%,1/16W,EMPA
     1 P3V3_AUX @S9S_MB_2U_LIB.S9S_MB_2U(SCH_1):P3V3_AUX    I75 @S9S_MB_2U_LIB.S9S_MB_2U(SCH_1):PAGE222
     2 I3C_BMC_SWB_BUF_R_SDA @S9S_MB_2U_LIB.S9S_MB_2U(SCH_1):I3C_BMC_SWB_BUF_R_SDA    I75 @S9S_MB_2U_LIB.S9S_MB_2U(SCH_1):PAGE222

R2669 Q_RES_0402LF-10K,1%,1/16W,CHIPA
     1 P3V3_AUX @S9S_MB_2U_LIB.S9S_MB_2U(SCH_1):P3V3_AUX    I61 @S9S_MB_2U_LIB.S9S_MB_2U(SCH_1):PAGE222
     2 SMB_BMC_SWB_BUF_R_SDA @S9S_MB_2U_LIB.S9S_MB_2U(SCH_1):SMB_BMC_SWB_BUF_R_SDA    I61 @S9S_MB_2U_LIB.S9S_MB_2U(SCH_1):PAGE222

R2670 Q_RES_0402LF-4.7K,5%,1/16W,EMPA
     1 P3V3_AUX @S9S_MB_2U_LIB.S9S_MB_2U(SCH_1):P3V3_AUX    I77 @S9S_MB_2U_LIB.S9S_MB_2U(SCH_1):PAGE222
     2 I3C_BMC_SWB_BUF_R_SCL @S9S_MB_2U_LIB.S9S_MB_2U(SCH_1):I3C_BMC_SWB_BUF_R_SCL    I77 @S9S_MB_2U_LIB.S9S_MB_2U(SCH_1):PAGE222

R2671 Q_RES_0402LF-33.2,1%,1/16W,CHIA
     1 SMB_BMC_SWB_BUF_R_SCL @S9S_MB_2U_LIB.S9S_MB_2U(SCH_1):SMB_BMC_SWB_BUF_R_SCL    I65 @S9S_MB_2U_LIB.S9S_MB_2U(SCH_1):PAGE222
     2 SMB_BMC_SWB_BUF_SCL @S9S_MB_2U_LIB.S9S_MB_2U(SCH_1):SMB_BMC_SWB_BUF_SCL    I65 @S9S_MB_2U_LIB.S9S_MB_2U(SCH_1):PAGE222

R2672 Q_RES_0402LF-33.2,1%,1/16W,CHIA
     1 SMB_BMC_SWB_BUF_R_SDA @S9S_MB_2U_LIB.S9S_MB_2U(SCH_1):SMB_BMC_SWB_BUF_R_SDA    I64 @S9S_MB_2U_LIB.S9S_MB_2U(SCH_1):PAGE222
     2 SMB_BMC_SWB_BUF_SDA @S9S_MB_2U_LIB.S9S_MB_2U(SCH_1):SMB_BMC_SWB_BUF_SDA    I64 @S9S_MB_2U_LIB.S9S_MB_2U(SCH_1):PAGE222

R2674 Q_RES_0402LF-27.4,1%,1/16W,CHIA
     1 I3C_BMC_SWB_BUF_R_SDA @S9S_MB_2U_LIB.S9S_MB_2U(SCH_1):I3C_BMC_SWB_BUF_R_SDA    I71 @S9S_MB_2U_LIB.S9S_MB_2U(SCH_1):PAGE222
     2 I3C_BMC_SWB_BUF_SDA @S9S_MB_2U_LIB.S9S_MB_2U(SCH_1):I3C_BMC_SWB_BUF_SDA    I71 @S9S_MB_2U_LIB.S9S_MB_2U(SCH_1):PAGE222

R2675 Q_RES_0402LF-33.2,1%,1/16W,CHIA
     1 I3C_BMC_SWB_BUF_R_SCL @S9S_MB_2U_LIB.S9S_MB_2U(SCH_1):I3C_BMC_SWB_BUF_R_SCL    I72 @S9S_MB_2U_LIB.S9S_MB_2U(SCH_1):PAGE222
     2 I3C_BMC_SWB_BUF_SCL @S9S_MB_2U_LIB.S9S_MB_2U(SCH_1):I3C_BMC_SWB_BUF_SCL    I72 @S9S_MB_2U_LIB.S9S_MB_2U(SCH_1):PAGE222

R2676 Q_RES_0402LF-0,5%,1/16W,CHIP,CA
     1 SMB_BMC_SWB_EN @S9S_MB_2U_LIB.S9S_MB_2U(SCH_1):SMB_BMC_SWB_EN    I19 @S9S_MB_2U_LIB.S9S_MB_2U(SCH_1):PAGE222
     2 SMB_BMC_SWB_EN_R2 @S9S_MB_2U_LIB.S9S_MB_2U(SCH_1):SMB_BMC_SWB_EN_R2    I19 @S9S_MB_2U_LIB.S9S_MB_2U(SCH_1):PAGE222

R2693 Q_RES_0402LF-1K,1%,1/16W,EMPTYA
     1 P3V3_AUX @S9S_MB_2U_LIB.S9S_MB_2U(SCH_1):P3V3_AUX    I76 @S9S_MB_2U_LIB.S9S_MB_2U(SCH_1):PAGE214
     2 TCA9539_0_ADD1 @S9S_MB_2U_LIB.S9S_MB_2U(SCH_1):TCA9539_0_ADD1    I76 @S9S_MB_2U_LIB.S9S_MB_2U(SCH_1):PAGE214

R2694 Q_RES_0402LF-1K,1%,1/16W,CHIP,A
     1 TCA9539_0_ADD1 @S9S_MB_2U_LIB.S9S_MB_2U(SCH_1):TCA9539_0_ADD1    I77 @S9S_MB_2U_LIB.S9S_MB_2U(SCH_1):PAGE214
     2    GND @S9S_MB_2U_LIB.S9S_MB_2U(SCH_1):GND    I77 @S9S_MB_2U_LIB.S9S_MB_2U(SCH_1):PAGE214

R2695 Q_RES_0402LF-1K,1%,1/16W,EMPTYA
     1 P3V3_AUX @S9S_MB_2U_LIB.S9S_MB_2U(SCH_1):P3V3_AUX    I74 @S9S_MB_2U_LIB.S9S_MB_2U(SCH_1):PAGE214
     2 TCA9539_0_ADD0 @S9S_MB_2U_LIB.S9S_MB_2U(SCH_1):TCA9539_0_ADD0    I74 @S9S_MB_2U_LIB.S9S_MB_2U(SCH_1):PAGE214

R2696 Q_RES_0402LF-1K,1%,1/16W,CHIP,A
     1 TCA9539_0_ADD0 @S9S_MB_2U_LIB.S9S_MB_2U(SCH_1):TCA9539_0_ADD0    I75 @S9S_MB_2U_LIB.S9S_MB_2U(SCH_1):PAGE214
     2    GND @S9S_MB_2U_LIB.S9S_MB_2U(SCH_1):GND    I75 @S9S_MB_2U_LIB.S9S_MB_2U(SCH_1):PAGE214

R2703 Q_RES_0402LF-0,5%,1/16W,CHIP,CA
     1 SMB_BMC_SWB_SCL_R4 @S9S_MB_2U_LIB.S9S_MB_2U(SCH_1):SMB_BMC_SWB_SCL_R4    I63 @S9S_MB_2U_LIB.S9S_MB_2U(SCH_1):PAGE219
     2 SMB_BMC_SWB_SCL @S9S_MB_2U_LIB.S9S_MB_2U(SCH_1):SMB_BMC_SWB_SCL    I63 @S9S_MB_2U_LIB.S9S_MB_2U(SCH_1):PAGE219

R2704 Q_RES_0402LF-0,5%,1/16W,CHIP,CA
     1 SMB_BMC_SWB_SDA_R4 @S9S_MB_2U_LIB.S9S_MB_2U(SCH_1):SMB_BMC_SWB_SDA_R4    I64 @S9S_MB_2U_LIB.S9S_MB_2U(SCH_1):PAGE219
     2 SMB_BMC_SWB_SDA @S9S_MB_2U_LIB.S9S_MB_2U(SCH_1):SMB_BMC_SWB_SDA    I64 @S9S_MB_2U_LIB.S9S_MB_2U(SCH_1):PAGE219

R2705 Q_RES_0402LF-0,5%,1/16W,EMPTY,A
     1 SMB_BMC_SWB_R_SCL @S9S_MB_2U_LIB.S9S_MB_2U(SCH_1):SMB_BMC_SWB_R_SCL    I55 @S9S_MB_2U_LIB.S9S_MB_2U(SCH_1):PAGE222
     2 SMB_BMC_SWB_BUF_R_SCL @S9S_MB_2U_LIB.S9S_MB_2U(SCH_1):SMB_BMC_SWB_BUF_R_SCL    I55 @S9S_MB_2U_LIB.S9S_MB_2U(SCH_1):PAGE222

R2706 Q_RES_0402LF-0,5%,1/16W,CHIP,CA
     1 I3C_BMC_SWB_R_SDA @S9S_MB_2U_LIB.S9S_MB_2U(SCH_1):I3C_BMC_SWB_R_SDA    I30 @S9S_MB_2U_LIB.S9S_MB_2U(SCH_1):PAGE222
     2 I3C_BMC_SWB_BUF_R_SDA @S9S_MB_2U_LIB.S9S_MB_2U(SCH_1):I3C_BMC_SWB_BUF_R_SDA    I30 @S9S_MB_2U_LIB.S9S_MB_2U(SCH_1):PAGE222

R2707 Q_RES_0402LF-0,5%,1/16W,CHIP,CA
     1 SMB_BMC_SWB_EN @S9S_MB_2U_LIB.S9S_MB_2U(SCH_1):SMB_BMC_SWB_EN    I44 @S9S_MB_2U_LIB.S9S_MB_2U(SCH_1):PAGE222
     2 SMB_BMC_SWB_EN_R @S9S_MB_2U_LIB.S9S_MB_2U(SCH_1):SMB_BMC_SWB_EN_R    I44 @S9S_MB_2U_LIB.S9S_MB_2U(SCH_1):PAGE222

R2724 Q_RES_0402LF-0,5%,1/16W,EMPTY,A
     1 SMB_BMC_SWB_R_SDA @S9S_MB_2U_LIB.S9S_MB_2U(SCH_1):SMB_BMC_SWB_R_SDA    I54 @S9S_MB_2U_LIB.S9S_MB_2U(SCH_1):PAGE222
     2 SMB_BMC_SWB_BUF_R_SDA @S9S_MB_2U_LIB.S9S_MB_2U(SCH_1):SMB_BMC_SWB_BUF_R_SDA    I54 @S9S_MB_2U_LIB.S9S_MB_2U(SCH_1):PAGE222

R2725 Q_RES_0402LF-0,5%,1/16W,CHIP,CA
     1 I3C_BMC_SWB_R_SCL @S9S_MB_2U_LIB.S9S_MB_2U(SCH_1):I3C_BMC_SWB_R_SCL    I29 @S9S_MB_2U_LIB.S9S_MB_2U(SCH_1):PAGE222
     2 I3C_BMC_SWB_BUF_R_SCL @S9S_MB_2U_LIB.S9S_MB_2U(SCH_1):I3C_BMC_SWB_BUF_R_SCL    I29 @S9S_MB_2U_LIB.S9S_MB_2U(SCH_1):PAGE222

R2726 Q_RES_0402LF-33.2,1%,1/16W,CHIA
     1 PWRGD_CHA_CPU0_DIMM1 @S9S_MB_2U_LIB.S9S_MB_2U(SCH_1):PWRGD_CHA_CPU0_DIMM1    I32 @S9S_MB_2U_LIB.S9S_MB_2U(SCH_1):PAGE114
     2 PWRGD_FAIL_CPU0_AB @S9S_MB_2U_LIB.S9S_MB_2U(SCH_1):PWRGD_FAIL_CPU0_AB    I32 @S9S_MB_2U_LIB.S9S_MB_2U(SCH_1):PAGE114

R2727 Q_RES_0402LF-33.2,1%,1/16W,CHIA
     1 PWRGD_CHA_CPU0_DIMM2 @S9S_MB_2U_LIB.S9S_MB_2U(SCH_1):PWRGD_CHA_CPU0_DIMM2    I31 @S9S_MB_2U_LIB.S9S_MB_2U(SCH_1):PAGE114
     2 PWRGD_FAIL_CPU0_AB @S9S_MB_2U_LIB.S9S_MB_2U(SCH_1):PWRGD_FAIL_CPU0_AB    I31 @S9S_MB_2U_LIB.S9S_MB_2U(SCH_1):PAGE114

R2728 Q_RES_0402LF-33.2,1%,1/16W,CHIA
     1 PWRGD_CHB_CPU0_DIMM1 @S9S_MB_2U_LIB.S9S_MB_2U(SCH_1):PWRGD_CHB_CPU0_DIMM1    I30 @S9S_MB_2U_LIB.S9S_MB_2U(SCH_1):PAGE114
     2 PWRGD_FAIL_CPU0_AB @S9S_MB_2U_LIB.S9S_MB_2U(SCH_1):PWRGD_FAIL_CPU0_AB    I30 @S9S_MB_2U_LIB.S9S_MB_2U(SCH_1):PAGE114

R2729 Q_RES_0402LF-33.2,1%,1/16W,CHIA
     1 PWRGD_CHC_CPU0_DIMM1 @S9S_MB_2U_LIB.S9S_MB_2U(SCH_1):PWRGD_CHC_CPU0_DIMM1    I28 @S9S_MB_2U_LIB.S9S_MB_2U(SCH_1):PAGE114
     2 PWRGD_FAIL_CPU0_CD @S9S_MB_2U_LIB.S9S_MB_2U(SCH_1):PWRGD_FAIL_CPU0_CD    I28 @S9S_MB_2U_LIB.S9S_MB_2U(SCH_1):PAGE114

R2730 Q_RES_0402LF-33.2,1%,1/16W,CHIA
     1 PWRGD_CHC_CPU0_DIMM2 @S9S_MB_2U_LIB.S9S_MB_2U(SCH_1):PWRGD_CHC_CPU0_DIMM2    I27 @S9S_MB_2U_LIB.S9S_MB_2U(SCH_1):PAGE114
     2 PWRGD_FAIL_CPU0_CD @S9S_MB_2U_LIB.S9S_MB_2U(SCH_1):PWRGD_FAIL_CPU0_CD    I27 @S9S_MB_2U_LIB.S9S_MB_2U(SCH_1):PAGE114

R2731 Q_RES_0402LF-33.2,1%,1/16W,CHIA
     1 PWRGD_CHD_CPU0_DIMM1 @S9S_MB_2U_LIB.S9S_MB_2U(SCH_1):PWRGD_CHD_CPU0_DIMM1    I25 @S9S_MB_2U_LIB.S9S_MB_2U(SCH_1):PAGE114
     2 PWRGD_FAIL_CPU0_CD @S9S_MB_2U_LIB.S9S_MB_2U(SCH_1):PWRGD_FAIL_CPU0_CD    I25 @S9S_MB_2U_LIB.S9S_MB_2U(SCH_1):PAGE114

R2732 Q_RES_0402LF-33.2,1%,1/16W,CHIA
     1 PWRGD_CHF_CPU0_DIMM1 @S9S_MB_2U_LIB.S9S_MB_2U(SCH_1):PWRGD_CHF_CPU0_DIMM1    I22 @S9S_MB_2U_LIB.S9S_MB_2U(SCH_1):PAGE114
     2 PWRGD_FAIL_CPU0_EF @S9S_MB_2U_LIB.S9S_MB_2U(SCH_1):PWRGD_FAIL_CPU0_EF    I22 @S9S_MB_2U_LIB.S9S_MB_2U(SCH_1):PAGE114

R2733 Q_RES_0402LF-33.2,1%,1/16W,CHIA
     1 PWRGD_CHF_CPU0_DIMM2 @S9S_MB_2U_LIB.S9S_MB_2U(SCH_1):PWRGD_CHF_CPU0_DIMM2    I21 @S9S_MB_2U_LIB.S9S_MB_2U(SCH_1):PAGE114
     2 PWRGD_FAIL_CPU0_EF @S9S_MB_2U_LIB.S9S_MB_2U(SCH_1):PWRGD_FAIL_CPU0_EF    I21 @S9S_MB_2U_LIB.S9S_MB_2U(SCH_1):PAGE114

R2734 Q_RES_0402LF-33.2,1%,1/16W,CHIA
     1 PWRGD_CHH_CPU0_DIMM1 @S9S_MB_2U_LIB.S9S_MB_2U(SCH_1):PWRGD_CHH_CPU0_DIMM1    I18 @S9S_MB_2U_LIB.S9S_MB_2U(SCH_1):PAGE114
     2 PWRGD_FAIL_CPU0_GH @S9S_MB_2U_LIB.S9S_MB_2U(SCH_1):PWRGD_FAIL_CPU0_GH    I18 @S9S_MB_2U_LIB.S9S_MB_2U(SCH_1):PAGE114

R2735 Q_RES_0402LF-33.2,1%,1/16W,CHIA
     1 PWRGD_CHH_CPU0_DIMM2 @S9S_MB_2U_LIB.S9S_MB_2U(SCH_1):PWRGD_CHH_CPU0_DIMM2    I17 @S9S_MB_2U_LIB.S9S_MB_2U(SCH_1):PAGE114
     2 PWRGD_FAIL_CPU0_GH @S9S_MB_2U_LIB.S9S_MB_2U(SCH_1):PWRGD_FAIL_CPU0_GH    I17 @S9S_MB_2U_LIB.S9S_MB_2U(SCH_1):PAGE114

R2736 Q_RES_0402LF-33.2,1%,1/16W,CHIA
     1 PWRGD_CHF_CPU1_DIMM2 @S9S_MB_2U_LIB.S9S_MB_2U(SCH_1):PWRGD_CHF_CPU1_DIMM2    I61 @S9S_MB_2U_LIB.S9S_MB_2U(SCH_1):PAGE114
     2 PWRGD_FAIL_CPU1_EF @S9S_MB_2U_LIB.S9S_MB_2U(SCH_1):PWRGD_FAIL_CPU1_EF    I61 @S9S_MB_2U_LIB.S9S_MB_2U(SCH_1):PAGE114

R2738 Q_RES_0402LF-33.2,1%,1/16W,CHIA
     1 RST_PERST_SWB_N @S9S_MB_2U_LIB.S9S_MB_2U(SCH_1):RST_PERST_SWB_N   I127 @S9S_MB_2U_LIB.S9S_MB_2U(SCH_1):PAGE212
     2 RST_PERST_SWB_R_N @S9S_MB_2U_LIB.S9S_MB_2U(SCH_1):RST_PERST_SWB_R_N   I127 @S9S_MB_2U_LIB.S9S_MB_2U(SCH_1):PAGE212

R2786 Q_RES_0402LF-0,5%,1/16W,CHIP,CA
     1 USB2_HUB_SWB_DP @S9S_MB_2U_LIB.S9S_MB_2U(SCH_1):USB2_HUB_SWB_DP    I79 @S9S_MB_2U_LIB.S9S_MB_2U(SCH_1):PAGE155
     2 USB2_HUB_BUF_SWB_R_DP @S9S_MB_2U_LIB.S9S_MB_2U(SCH_1):USB2_HUB_BUF_SWB_R_DP    I79 @S9S_MB_2U_LIB.S9S_MB_2U(SCH_1):PAGE155

R2787 Q_RES_0402LF-0,5%,1/16W,CHIP,CA
     1 USB2_HUB_SWB_DN @S9S_MB_2U_LIB.S9S_MB_2U(SCH_1):USB2_HUB_SWB_DN    I78 @S9S_MB_2U_LIB.S9S_MB_2U(SCH_1):PAGE155
     2 USB2_HUB_BUF_SWB_R_DN @S9S_MB_2U_LIB.S9S_MB_2U(SCH_1):USB2_HUB_BUF_SWB_R_DN    I78 @S9S_MB_2U_LIB.S9S_MB_2U(SCH_1):PAGE155

R2788 Q_RES_0402LF-0,5%,1/16W,EMPTY,A
     1 USB2_HOST_BMC_B_BUF_DP @S9S_MB_2U_LIB.S9S_MB_2U(SCH_1):USB2_HOST_BMC_B_BUF_DP    I99 @S9S_MB_2U_LIB.S9S_MB_2U(SCH_1):PAGE155
     2 USB2_HUB_BUF_SWB_R_DP @S9S_MB_2U_LIB.S9S_MB_2U(SCH_1):USB2_HUB_BUF_SWB_R_DP    I99 @S9S_MB_2U_LIB.S9S_MB_2U(SCH_1):PAGE155

R2789 Q_RES_0402LF-0,5%,1/16W,EMPTY,A
     1 USB2_HOST_BMC_B_BUF_DN @S9S_MB_2U_LIB.S9S_MB_2U(SCH_1):USB2_HOST_BMC_B_BUF_DN    I98 @S9S_MB_2U_LIB.S9S_MB_2U(SCH_1):PAGE155
     2 USB2_HUB_BUF_SWB_R_DN @S9S_MB_2U_LIB.S9S_MB_2U(SCH_1):USB2_HUB_BUF_SWB_R_DN    I98 @S9S_MB_2U_LIB.S9S_MB_2U(SCH_1):PAGE155

R2790 Q_RES_0402LF-0,5%,1/16W,EMPTY,A
     1 USB2_HOST_BMC_B_DP @S9S_MB_2U_LIB.S9S_MB_2U(SCH_1):USB2_HOST_BMC_B_DP    I96 @S9S_MB_2U_LIB.S9S_MB_2U(SCH_1):PAGE155
     2 USB2_HOST_BMC_B_BUF_DP @S9S_MB_2U_LIB.S9S_MB_2U(SCH_1):USB2_HOST_BMC_B_BUF_DP    I96 @S9S_MB_2U_LIB.S9S_MB_2U(SCH_1):PAGE155

R2791 Q_RES_0402LF-0,5%,1/16W,EMPTY,A
     1 USB2_HOST_BMC_B_DN @S9S_MB_2U_LIB.S9S_MB_2U(SCH_1):USB2_HOST_BMC_B_DN    I97 @S9S_MB_2U_LIB.S9S_MB_2U(SCH_1):PAGE155
     2 USB2_HOST_BMC_B_BUF_DN @S9S_MB_2U_LIB.S9S_MB_2U(SCH_1):USB2_HOST_BMC_B_BUF_DN    I97 @S9S_MB_2U_LIB.S9S_MB_2U(SCH_1):PAGE155

R2792 Q_RES_0402LF-0,5%,1/16W,CHIP,CA
     1 FM_PDB_BUF_EN @S9S_MB_2U_LIB.S9S_MB_2U(SCH_1):FM_PDB_BUF_EN   I178 @S9S_MB_2U_LIB.S9S_MB_2U(SCH_1):PAGE312
     2 FM_PDB_BUF_EN_R @S9S_MB_2U_LIB.S9S_MB_2U(SCH_1):FM_PDB_BUF_EN_R   I178 @S9S_MB_2U_LIB.S9S_MB_2U(SCH_1):PAGE312

R2796 Q_RES_0402LF-33.2,1%,1/16W,CHIA
     1 FM_PDB_BUF_EN_R @S9S_MB_2U_LIB.S9S_MB_2U(SCH_1):FM_PDB_BUF_EN_R    I10 @S9S_MB_2U_LIB.S9S_MB_2U(SCH_1):PAGE233
     2 FM_MB_PDB_SMB9_R_EN @S9S_MB_2U_LIB.S9S_MB_2U(SCH_1):FM_MB_PDB_SMB9_R_EN    I10 @S9S_MB_2U_LIB.S9S_MB_2U(SCH_1):PAGE233

R2800 Q_RES_0402LF-0,5%,1/16W,EMPTY,A
     1 SMB_FAN_3V3AUX_R_SCL @S9S_MB_2U_LIB.S9S_MB_2U(SCH_1):SMB_FAN_3V3AUX_R_SCL    I15 @S9S_MB_2U_LIB.S9S_MB_2U(SCH_1):PAGE233
     2 SMB_FAN_3V3AUX_BUF_SCL @S9S_MB_2U_LIB.S9S_MB_2U(SCH_1):SMB_FAN_3V3AUX_BUF_SCL    I15 @S9S_MB_2U_LIB.S9S_MB_2U(SCH_1):PAGE233

R2801 Q_RES_0402LF-0,5%,1/16W,EMPTY,A
     1 SMB_FAN_3V3AUX_R_SDA @S9S_MB_2U_LIB.S9S_MB_2U(SCH_1):SMB_FAN_3V3AUX_R_SDA    I14 @S9S_MB_2U_LIB.S9S_MB_2U(SCH_1):PAGE233
     2 SMB_FAN_3V3AUX_BUF_SDA @S9S_MB_2U_LIB.S9S_MB_2U(SCH_1):SMB_FAN_3V3AUX_BUF_SDA    I14 @S9S_MB_2U_LIB.S9S_MB_2U(SCH_1):PAGE233

R2802 Q_RES_0402LF-0,5%,1/16W,CHIP,CA
     1 HPDB_HSC_PWRGD_R @S9S_MB_2U_LIB.S9S_MB_2U(SCH_1):HPDB_HSC_PWRGD_R    I39 @S9S_MB_2U_LIB.S9S_MB_2U(SCH_1):PAGE233
     2 HPDB_HSC_PWRGD @S9S_MB_2U_LIB.S9S_MB_2U(SCH_1):HPDB_HSC_PWRGD    I39 @S9S_MB_2U_LIB.S9S_MB_2U(SCH_1):PAGE233

R2803 Q_RES_0402LF-0,5%,1/16W,CHIP,CA
     1 FM_FAN_PWR_EN_R @S9S_MB_2U_LIB.S9S_MB_2U(SCH_1):FM_FAN_PWR_EN_R    I38 @S9S_MB_2U_LIB.S9S_MB_2U(SCH_1):PAGE233
     2 FM_FAN_PWR_EN @S9S_MB_2U_LIB.S9S_MB_2U(SCH_1):FM_FAN_PWR_EN    I38 @S9S_MB_2U_LIB.S9S_MB_2U(SCH_1):PAGE233

R2805 Q_RES_0402LF-4.7K,5%,1/16W,EMPA
     1 P3V3_AUX @S9S_MB_2U_LIB.S9S_MB_2U(SCH_1):P3V3_AUX    I22 @S9S_MB_2U_LIB.S9S_MB_2U(SCH_1):PAGE233
     2 SMB_FAN_3V3AUX_BUF_SCL @S9S_MB_2U_LIB.S9S_MB_2U(SCH_1):SMB_FAN_3V3AUX_BUF_SCL    I22 @S9S_MB_2U_LIB.S9S_MB_2U(SCH_1):PAGE233

R2807 Q_RES_0402LF-4.7K,5%,1/16W,EMPA
     1 P3V3_AUX @S9S_MB_2U_LIB.S9S_MB_2U(SCH_1):P3V3_AUX    I24 @S9S_MB_2U_LIB.S9S_MB_2U(SCH_1):PAGE233
     2 SMB_FAN_3V3AUX_BUF_SDA @S9S_MB_2U_LIB.S9S_MB_2U(SCH_1):SMB_FAN_3V3AUX_BUF_SDA    I24 @S9S_MB_2U_LIB.S9S_MB_2U(SCH_1):PAGE233

R2811 Q_RES_0402LF-33.2,1%,1/16W,CHIA
     1 SMB_FAN_3V3AUX_BUF_SCL @S9S_MB_2U_LIB.S9S_MB_2U(SCH_1):SMB_FAN_3V3AUX_BUF_SCL    I21 @S9S_MB_2U_LIB.S9S_MB_2U(SCH_1):PAGE233
     2 SMB_FAN_3V3AUX_BUF_R_SCL @S9S_MB_2U_LIB.S9S_MB_2U(SCH_1):SMB_FAN_3V3AUX_BUF_R_SCL    I21 @S9S_MB_2U_LIB.S9S_MB_2U(SCH_1):PAGE233

R2812 Q_RES_0402LF-33.2,1%,1/16W,CHIA
     1 SMB_FAN_3V3AUX_BUF_SDA @S9S_MB_2U_LIB.S9S_MB_2U(SCH_1):SMB_FAN_3V3AUX_BUF_SDA    I20 @S9S_MB_2U_LIB.S9S_MB_2U(SCH_1):PAGE233
     2 SMB_FAN_3V3AUX_BUF_R_SDA @S9S_MB_2U_LIB.S9S_MB_2U(SCH_1):SMB_FAN_3V3AUX_BUF_R_SDA    I20 @S9S_MB_2U_LIB.S9S_MB_2U(SCH_1):PAGE233

R2815 Q_RES_0402LF-100K,1%,1/16W,EMPA
     1 P3V3_AUX @S9S_MB_2U_LIB.S9S_MB_2U(SCH_1):P3V3_AUX    I68 @S9S_MB_2U_LIB.S9S_MB_2U(SCH_1):PAGE140
     2 BMC_MONITER_R @S9S_MB_2U_LIB.S9S_MB_2U(SCH_1):BMC_MONITER_R    I68 @S9S_MB_2U_LIB.S9S_MB_2U(SCH_1):PAGE140

R2820 Q_RES_0402LF-4.7K,5%,1/16W,EMPA
     1 P3V3_AUX @S9S_MB_2U_LIB.S9S_MB_2U(SCH_1):P3V3_AUX    I78 @S9S_MB_2U_LIB.S9S_MB_2U(SCH_1):PAGE140
     2 BMC_MONITER_BUF_R @S9S_MB_2U_LIB.S9S_MB_2U(SCH_1):BMC_MONITER_BUF_R    I78 @S9S_MB_2U_LIB.S9S_MB_2U(SCH_1):PAGE140

R2828 Q_RES_0402LF-100K,1%,1/16W,CHIA
     1 P3V3_AUX @S9S_MB_2U_LIB.S9S_MB_2U(SCH_1):P3V3_AUX    I66 @S9S_MB_2U_LIB.S9S_MB_2U(SCH_1):PAGE145
     2 RST_BMC_FROM_SWB_N @S9S_MB_2U_LIB.S9S_MB_2U(SCH_1):RST_BMC_FROM_SWB_N    I66 @S9S_MB_2U_LIB.S9S_MB_2U(SCH_1):PAGE145

R2829 Q_RES_0402LF-100K,1%,1/16W,EMPA
     1 RST_BMC_FROM_SWB_N @S9S_MB_2U_LIB.S9S_MB_2U(SCH_1):RST_BMC_FROM_SWB_N    I58 @S9S_MB_2U_LIB.S9S_MB_2U(SCH_1):PAGE145
     2    GND @S9S_MB_2U_LIB.S9S_MB_2U(SCH_1):GND    I58 @S9S_MB_2U_LIB.S9S_MB_2U(SCH_1):PAGE145

R2830 Q_RES_0402LF-100K,1%,1/16W,CHIA
     1 P3V3_AUX @S9S_MB_2U_LIB.S9S_MB_2U(SCH_1):P3V3_AUX    I68 @S9S_MB_2U_LIB.S9S_MB_2U(SCH_1):PAGE145
     2 BIC_MONITER @S9S_MB_2U_LIB.S9S_MB_2U(SCH_1):BIC_MONITER    I68 @S9S_MB_2U_LIB.S9S_MB_2U(SCH_1):PAGE145

R2831 Q_RES_0402LF-100K,1%,1/16W,EMPA
     1 BIC_MONITER @S9S_MB_2U_LIB.S9S_MB_2U(SCH_1):BIC_MONITER    I56 @S9S_MB_2U_LIB.S9S_MB_2U(SCH_1):PAGE145
     2    GND @S9S_MB_2U_LIB.S9S_MB_2U(SCH_1):GND    I56 @S9S_MB_2U_LIB.S9S_MB_2U(SCH_1):PAGE145

R2832 Q_RES_0402LF-100K,1%,1/16W,CHIA
     1 P3V3_AUX @S9S_MB_2U_LIB.S9S_MB_2U(SCH_1):P3V3_AUX    I67 @S9S_MB_2U_LIB.S9S_MB_2U(SCH_1):PAGE145
     2 FM_SWB_BIC_READY_N @S9S_MB_2U_LIB.S9S_MB_2U(SCH_1):FM_SWB_BIC_READY_N    I67 @S9S_MB_2U_LIB.S9S_MB_2U(SCH_1):PAGE145

R2833 Q_RES_0402LF-100K,1%,1/16W,EMPA
     1 FM_SWB_BIC_READY_N @S9S_MB_2U_LIB.S9S_MB_2U(SCH_1):FM_SWB_BIC_READY_N    I60 @S9S_MB_2U_LIB.S9S_MB_2U(SCH_1):PAGE145
     2    GND @S9S_MB_2U_LIB.S9S_MB_2U(SCH_1):GND    I60 @S9S_MB_2U_LIB.S9S_MB_2U(SCH_1):PAGE145

R2834 Q_RES_0402LF-4.7K,5%,1/16W,CHIA
     1 P3V3_AUX @S9S_MB_2U_LIB.S9S_MB_2U(SCH_1):P3V3_AUX    I18 @S9S_MB_2U_LIB.S9S_MB_2U(SCH_1):PAGE145
     2 RST_BMC_FROM_SWB @S9S_MB_2U_LIB.S9S_MB_2U(SCH_1):RST_BMC_FROM_SWB    I18 @S9S_MB_2U_LIB.S9S_MB_2U(SCH_1):PAGE145

R2835 Q_RES_0402LF-4.7K,5%,1/16W,CHIA
     1 P3V3_AUX @S9S_MB_2U_LIB.S9S_MB_2U(SCH_1):P3V3_AUX    I14 @S9S_MB_2U_LIB.S9S_MB_2U(SCH_1):PAGE145
     2 BIC_MONITER_N @S9S_MB_2U_LIB.S9S_MB_2U(SCH_1):BIC_MONITER_N    I14 @S9S_MB_2U_LIB.S9S_MB_2U(SCH_1):PAGE145

R2836 Q_RES_0402LF-4.7K,5%,1/16W,CHIA
     1 P3V3_AUX @S9S_MB_2U_LIB.S9S_MB_2U(SCH_1):P3V3_AUX    I19 @S9S_MB_2U_LIB.S9S_MB_2U(SCH_1):PAGE145
     2 FM_SWB_BIC_READY @S9S_MB_2U_LIB.S9S_MB_2U(SCH_1):FM_SWB_BIC_READY    I19 @S9S_MB_2U_LIB.S9S_MB_2U(SCH_1):PAGE145

R2837 Q_RES_0402LF-100K,1%,1/16W,EMPA
     1 P3V3_AUX @S9S_MB_2U_LIB.S9S_MB_2U(SCH_1):P3V3_AUX    I80 @S9S_MB_2U_LIB.S9S_MB_2U(SCH_1):PAGE145
     2 FM_SWB_PWRGD @S9S_MB_2U_LIB.S9S_MB_2U(SCH_1):FM_SWB_PWRGD    I80 @S9S_MB_2U_LIB.S9S_MB_2U(SCH_1):PAGE145

R2838 Q_RES_0402LF-100K,1%,1/16W,CHIA
     1 FM_SWB_PWRGD @S9S_MB_2U_LIB.S9S_MB_2U(SCH_1):FM_SWB_PWRGD    I62 @S9S_MB_2U_LIB.S9S_MB_2U(SCH_1):PAGE145
     2    GND @S9S_MB_2U_LIB.S9S_MB_2U(SCH_1):GND    I62 @S9S_MB_2U_LIB.S9S_MB_2U(SCH_1):PAGE145

R2841 Q_RES_0402LF-4.7K,5%,1/16W,CHIA
     1 P3V3_AUX @S9S_MB_2U_LIB.S9S_MB_2U(SCH_1):P3V3_AUX    I24 @S9S_MB_2U_LIB.S9S_MB_2U(SCH_1):PAGE145
     2 FM_SWB_PWRGD_N @S9S_MB_2U_LIB.S9S_MB_2U(SCH_1):FM_SWB_PWRGD_N    I24 @S9S_MB_2U_LIB.S9S_MB_2U(SCH_1):PAGE145

R2842 Q_RES_0402LF-4.7K,5%,1/16W,CHIA
     1 P3V3_AUX @S9S_MB_2U_LIB.S9S_MB_2U(SCH_1):P3V3_AUX    I30 @S9S_MB_2U_LIB.S9S_MB_2U(SCH_1):PAGE145
     2 FM_GPU_PWRGD_N @S9S_MB_2U_LIB.S9S_MB_2U(SCH_1):FM_GPU_PWRGD_N    I30 @S9S_MB_2U_LIB.S9S_MB_2U(SCH_1):PAGE145

R2843 Q_RES_0402LF-4.7K,1%,1/16W,CHIA
     1 P3V3_ADC @S9S_MB_2U_LIB.S9S_MB_2U(SCH_1):P3V3_ADC   I162 @S9S_MB_2U_LIB.S9S_MB_2U(SCH_1):PAGE239
     2    GND @S9S_MB_2U_LIB.S9S_MB_2U(SCH_1):GND   I162 @S9S_MB_2U_LIB.S9S_MB_2U(SCH_1):PAGE239

R2844 Q_RES_0402LF-33.2,1%,1/16W,CHIA
     1 FM_SWB_BIC_READY_ISO_N @S9S_MB_2U_LIB.S9S_MB_2U(SCH_1):FM_SWB_BIC_READY_ISO_N   I112 @S9S_MB_2U_LIB.S9S_MB_2U(SCH_1):PAGE314
     2 FM_SWB_BIC_READY_ISO_R_N @S9S_MB_2U_LIB.S9S_MB_2U(SCH_1):FM_SWB_BIC_READY_ISO_R_N   I112 @S9S_MB_2U_LIB.S9S_MB_2U(SCH_1):PAGE314

R2845 Q_RES_0402LF-33.2,1%,1/16W,CHIA
     1 BMC_MONITER @S9S_MB_2U_LIB.S9S_MB_2U(SCH_1):BMC_MONITER   I136 @S9S_MB_2U_LIB.S9S_MB_2U(SCH_1):PAGE314
     2 BMC_MONITER_R @S9S_MB_2U_LIB.S9S_MB_2U(SCH_1):BMC_MONITER_R   I136 @S9S_MB_2U_LIB.S9S_MB_2U(SCH_1):PAGE314

R2846 Q_RES_0402LF-33.2,1%,1/16W,CHIA
     1 BIC_MONITER_ISO @S9S_MB_2U_LIB.S9S_MB_2U(SCH_1):BIC_MONITER_ISO   I134 @S9S_MB_2U_LIB.S9S_MB_2U(SCH_1):PAGE314
     2 BIC_MONITER_ISO_R @S9S_MB_2U_LIB.S9S_MB_2U(SCH_1):BIC_MONITER_ISO_R   I134 @S9S_MB_2U_LIB.S9S_MB_2U(SCH_1):PAGE314

R2847 Q_RES_0402LF-33.2,1%,1/16W,CHIA
     1 RST_BMC_FROM_SWB_ISO_N @S9S_MB_2U_LIB.S9S_MB_2U(SCH_1):RST_BMC_FROM_SWB_ISO_N   I107 @S9S_MB_2U_LIB.S9S_MB_2U(SCH_1):PAGE314
     2 RST_BMC_FROM_SWB_ISO_R_N @S9S_MB_2U_LIB.S9S_MB_2U(SCH_1):RST_BMC_FROM_SWB_ISO_R_N   I107 @S9S_MB_2U_LIB.S9S_MB_2U(SCH_1):PAGE314

R2848 Q_RES_0402LF-0,5%,1/16W,CHIP,CA
     1 RST_SWB_BIC_N @S9S_MB_2U_LIB.S9S_MB_2U(SCH_1):RST_SWB_BIC_N    I34 @S9S_MB_2U_LIB.S9S_MB_2U(SCH_1):PAGE214
     2 RST_SWB_BIC_R_N @S9S_MB_2U_LIB.S9S_MB_2U(SCH_1):RST_SWB_BIC_R_N    I34 @S9S_MB_2U_LIB.S9S_MB_2U(SCH_1):PAGE214

R2893 Q_RES_0402LF-0,5%,1/16W,EMPTY,A
     1 SMB_1_BMC_GPU_R_SCL @S9S_MB_2U_LIB.S9S_MB_2U(SCH_1):SMB_1_BMC_GPU_R_SCL    I38 @S9S_MB_2U_LIB.S9S_MB_2U(SCH_1):PAGE222
     2 SMB_1_BMC_GPU_BUF_R_SCL @S9S_MB_2U_LIB.S9S_MB_2U(SCH_1):SMB_1_BMC_GPU_BUF_R_SCL    I38 @S9S_MB_2U_LIB.S9S_MB_2U(SCH_1):PAGE222

R2894 Q_RES_0402LF-0,5%,1/16W,EMPTY,A
     1 SMB_1_BMC_GPU_R_SDA @S9S_MB_2U_LIB.S9S_MB_2U(SCH_1):SMB_1_BMC_GPU_R_SDA    I33 @S9S_MB_2U_LIB.S9S_MB_2U(SCH_1):PAGE222
     2 SMB_1_BMC_GPU_BUF_R_SDA @S9S_MB_2U_LIB.S9S_MB_2U(SCH_1):SMB_1_BMC_GPU_BUF_R_SDA    I33 @S9S_MB_2U_LIB.S9S_MB_2U(SCH_1):PAGE222

R2897 Q_RES_0402LF-33.2,1%,1/16W,CHIA
     1 SMB_1_BMC_GPU_BUF_R_SCL @S9S_MB_2U_LIB.S9S_MB_2U(SCH_1):SMB_1_BMC_GPU_BUF_R_SCL    I78 @S9S_MB_2U_LIB.S9S_MB_2U(SCH_1):PAGE222
     2 SMB_1_BMC_GPU_BUF_SCL @S9S_MB_2U_LIB.S9S_MB_2U(SCH_1):SMB_1_BMC_GPU_BUF_SCL    I78 @S9S_MB_2U_LIB.S9S_MB_2U(SCH_1):PAGE222

R2898 Q_RES_0402LF-33.2,1%,1/16W,CHIA
     1 SMB_1_BMC_GPU_BUF_R_SDA @S9S_MB_2U_LIB.S9S_MB_2U(SCH_1):SMB_1_BMC_GPU_BUF_R_SDA    I79 @S9S_MB_2U_LIB.S9S_MB_2U(SCH_1):PAGE222
     2 SMB_1_BMC_GPU_BUF_SDA @S9S_MB_2U_LIB.S9S_MB_2U(SCH_1):SMB_1_BMC_GPU_BUF_SDA    I79 @S9S_MB_2U_LIB.S9S_MB_2U(SCH_1):PAGE222

R2899 Q_RES_0402LF-0,5%,1/16W,CHIP,CA
     1 SMB_BMC_GPU_EN @S9S_MB_2U_LIB.S9S_MB_2U(SCH_1):SMB_BMC_GPU_EN    I53 @S9S_MB_2U_LIB.S9S_MB_2U(SCH_1):PAGE222
     2 SMB_BMC_GPU_EN_R1 @S9S_MB_2U_LIB.S9S_MB_2U(SCH_1):SMB_BMC_GPU_EN_R1    I53 @S9S_MB_2U_LIB.S9S_MB_2U(SCH_1):PAGE222

R2900 Q_RES_0402LF-2K,1%,1/16W,EMPTYA
     1 MAX11617_VREF @S9S_MB_2U_LIB.S9S_MB_2U(SCH_1):MAX11617_VREF    I72 @S9S_MB_2U_LIB.S9S_MB_2U(SCH_1):PAGE239
     2 MAX11617_VREF_R @S9S_MB_2U_LIB.S9S_MB_2U(SCH_1):MAX11617_VREF_R    I72 @S9S_MB_2U_LIB.S9S_MB_2U(SCH_1):PAGE239

R2905 Q_RES_0402LF-0,5%,1/16W,CHIP,CA
     1 RST_SMB_SWITCH_N @S9S_MB_2U_LIB.S9S_MB_2U(SCH_1):RST_SMB_SWITCH_N    I34 @S9S_MB_2U_LIB.S9S_MB_2U(SCH_1):PAGE233
     2 RST_SMB_SWITCH_R_N @S9S_MB_2U_LIB.S9S_MB_2U(SCH_1):RST_SMB_SWITCH_R_N    I34 @S9S_MB_2U_LIB.S9S_MB_2U(SCH_1):PAGE233

R2906 Q_RES_0402LF-0,5%,1/16W,CHIP,CA
     1 FM_GPU_HSC_EN_BUF_R1 @S9S_MB_2U_LIB.S9S_MB_2U(SCH_1):FM_GPU_HSC_EN_BUF_R1    I37 @S9S_MB_2U_LIB.S9S_MB_2U(SCH_1):PAGE233
     2 FM_GPU_HSC_EN_BUF @S9S_MB_2U_LIB.S9S_MB_2U(SCH_1):FM_GPU_HSC_EN_BUF    I37 @S9S_MB_2U_LIB.S9S_MB_2U(SCH_1):PAGE233

R2907 Q_RES_0402LF-5.11K,1%,1/16W,CHA
     1 P3V3_AUX @S9S_MB_2U_LIB.S9S_MB_2U(SCH_1):P3V3_AUX   I141 @S9S_MB_2U_LIB.S9S_MB_2U(SCH_1):PAGE239
     2 P3V3_AUX_ADC @S9S_MB_2U_LIB.S9S_MB_2U(SCH_1):P3V3_AUX_ADC   I141 @S9S_MB_2U_LIB.S9S_MB_2U(SCH_1):PAGE239

R2908 Q_RES_0402LF-5.11K,1%,1/16W,CHA
     1   P3V3 @S9S_MB_2U_LIB.S9S_MB_2U(SCH_1):P3V3   I161 @S9S_MB_2U_LIB.S9S_MB_2U(SCH_1):PAGE239
     2 P3V3_ADC @S9S_MB_2U_LIB.S9S_MB_2U(SCH_1):P3V3_ADC   I161 @S9S_MB_2U_LIB.S9S_MB_2U(SCH_1):PAGE239

R2909 Q_RES_0402LF-4.7K,5%,1/16W,CHIA
     1 P3V3_AUX @S9S_MB_2U_LIB.S9S_MB_2U(SCH_1):P3V3_AUX   I198 @S9S_MB_2U_LIB.S9S_MB_2U(SCH_1):PAGE140
     2 RST_SWB_BIC_R_N @S9S_MB_2U_LIB.S9S_MB_2U(SCH_1):RST_SWB_BIC_R_N   I198 @S9S_MB_2U_LIB.S9S_MB_2U(SCH_1):PAGE140

R2910 Q_RES_0402LF-100K,1%,1/16W,EMPA
     1 P3V3_AUX @S9S_MB_2U_LIB.S9S_MB_2U(SCH_1):P3V3_AUX   I187 @S9S_MB_2U_LIB.S9S_MB_2U(SCH_1):PAGE160
     2 FM_SWB_PWR_EN_R @S9S_MB_2U_LIB.S9S_MB_2U(SCH_1):FM_SWB_PWR_EN_R   I187 @S9S_MB_2U_LIB.S9S_MB_2U(SCH_1):PAGE160

R2911 Q_RES_0402LF-4.7K,5%,1/16W,EMPA
     1 P3V3_AUX @S9S_MB_2U_LIB.S9S_MB_2U(SCH_1):P3V3_AUX   I153 @S9S_MB_2U_LIB.S9S_MB_2U(SCH_1):PAGE140
     2 RST_SWB_BIC_BUF_R_N @S9S_MB_2U_LIB.S9S_MB_2U(SCH_1):RST_SWB_BIC_BUF_R_N   I153 @S9S_MB_2U_LIB.S9S_MB_2U(SCH_1):PAGE140

R2912 Q_RES_0402LF-4.7K,5%,1/16W,EMPA
     1 P3V3_AUX @S9S_MB_2U_LIB.S9S_MB_2U(SCH_1):P3V3_AUX   I147 @S9S_MB_2U_LIB.S9S_MB_2U(SCH_1):PAGE140
     2 FM_GPU_PWR_EN_R1 @S9S_MB_2U_LIB.S9S_MB_2U(SCH_1):FM_GPU_PWR_EN_R1   I147 @S9S_MB_2U_LIB.S9S_MB_2U(SCH_1):PAGE140

R2914 Q_RES_0402LF-4.7K,5%,1/16W,EMPA
     1 P3V3_AUX @S9S_MB_2U_LIB.S9S_MB_2U(SCH_1):P3V3_AUX   I192 @S9S_MB_2U_LIB.S9S_MB_2U(SCH_1):PAGE160
     2 FM_SWB_PWR_EN_R1_BUF @S9S_MB_2U_LIB.S9S_MB_2U(SCH_1):FM_SWB_PWR_EN_R1_BUF   I192 @S9S_MB_2U_LIB.S9S_MB_2U(SCH_1):PAGE160

R2915 Q_RES_0402LF-4.7K,5%,1/16W,CHIA
     1 BMC_MONITER_R @S9S_MB_2U_LIB.S9S_MB_2U(SCH_1):BMC_MONITER_R    I92 @S9S_MB_2U_LIB.S9S_MB_2U(SCH_1):PAGE140
     2    GND @S9S_MB_2U_LIB.S9S_MB_2U(SCH_1):GND    I92 @S9S_MB_2U_LIB.S9S_MB_2U(SCH_1):PAGE140

R2916 Q_RES_0402LF-4.7K,5%,1/16W,EMPA
     1 RST_SWB_BIC_R_N @S9S_MB_2U_LIB.S9S_MB_2U(SCH_1):RST_SWB_BIC_R_N    I93 @S9S_MB_2U_LIB.S9S_MB_2U(SCH_1):PAGE140
     2    GND @S9S_MB_2U_LIB.S9S_MB_2U(SCH_1):GND    I93 @S9S_MB_2U_LIB.S9S_MB_2U(SCH_1):PAGE140

R2917 Q_RES_0402LF-49.9,1%,1/16W,CHIA
     1 BMC_MONITER_BUF_R @S9S_MB_2U_LIB.S9S_MB_2U(SCH_1):BMC_MONITER_BUF_R   I206 @S9S_MB_2U_LIB.S9S_MB_2U(SCH_1):PAGE140
     2 BMC_MONITER_BUF @S9S_MB_2U_LIB.S9S_MB_2U(SCH_1):BMC_MONITER_BUF   I206 @S9S_MB_2U_LIB.S9S_MB_2U(SCH_1):PAGE140

R2918 Q_RES_0402LF-4.7K,5%,1/16W,CHIA
     1 FM_SWB_PWR_EN_R @S9S_MB_2U_LIB.S9S_MB_2U(SCH_1):FM_SWB_PWR_EN_R   I188 @S9S_MB_2U_LIB.S9S_MB_2U(SCH_1):PAGE160
     2    GND @S9S_MB_2U_LIB.S9S_MB_2U(SCH_1):GND   I188 @S9S_MB_2U_LIB.S9S_MB_2U(SCH_1):PAGE160

R2919 Q_RES_0402LF-4.7K,5%,1/16W,CHIA
     1 P3V3_AUX @S9S_MB_2U_LIB.S9S_MB_2U(SCH_1):P3V3_AUX    I91 @S9S_MB_2U_LIB.S9S_MB_2U(SCH_1):PAGE145
     2 RST_BMC_FROM_SWB_ISO_N @S9S_MB_2U_LIB.S9S_MB_2U(SCH_1):RST_BMC_FROM_SWB_ISO_N    I91 @S9S_MB_2U_LIB.S9S_MB_2U(SCH_1):PAGE145

R2920 Q_RES_0402LF-4.7K,5%,1/16W,CHIA
     1 P3V3_AUX @S9S_MB_2U_LIB.S9S_MB_2U(SCH_1):P3V3_AUX    I84 @S9S_MB_2U_LIB.S9S_MB_2U(SCH_1):PAGE145
     2 BIC_MONITER_ISO @S9S_MB_2U_LIB.S9S_MB_2U(SCH_1):BIC_MONITER_ISO    I84 @S9S_MB_2U_LIB.S9S_MB_2U(SCH_1):PAGE145

R2921 Q_RES_0402LF-10K,1%,1/16W,EMPTA
     1 P3V3_AUX @S9S_MB_2U_LIB.S9S_MB_2U(SCH_1):P3V3_AUX    I93 @S9S_MB_2U_LIB.S9S_MB_2U(SCH_1):PAGE214
     2 RST_SMB_SWITCH_N @S9S_MB_2U_LIB.S9S_MB_2U(SCH_1):RST_SMB_SWITCH_N    I93 @S9S_MB_2U_LIB.S9S_MB_2U(SCH_1):PAGE214

R2922 Q_RES_0402LF-0,5%,1/16W,CHIP,CA
     1 RST_SMB_SWITCH_N @S9S_MB_2U_LIB.S9S_MB_2U(SCH_1):RST_SMB_SWITCH_N    I95 @S9S_MB_2U_LIB.S9S_MB_2U(SCH_1):PAGE214
     2 PU_RST_SMB_U181_N @S9S_MB_2U_LIB.S9S_MB_2U(SCH_1):PU_RST_SMB_U181_N    I95 @S9S_MB_2U_LIB.S9S_MB_2U(SCH_1):PAGE214

R2923 Q_RES_0402LF-4.7K,5%,1/16W,EMPA
     1 P3V3_AUX @S9S_MB_2U_LIB.S9S_MB_2U(SCH_1):P3V3_AUX    I90 @S9S_MB_2U_LIB.S9S_MB_2U(SCH_1):PAGE214
     2 PU_U181_INT @S9S_MB_2U_LIB.S9S_MB_2U(SCH_1):PU_U181_INT    I90 @S9S_MB_2U_LIB.S9S_MB_2U(SCH_1):PAGE214

R2924 Q_RES_0402LF-49.9,1%,1/16W,CHIA
     1 RST_SWB_BIC_BUF_R_N @S9S_MB_2U_LIB.S9S_MB_2U(SCH_1):RST_SWB_BIC_BUF_R_N   I207 @S9S_MB_2U_LIB.S9S_MB_2U(SCH_1):PAGE140
     2 RST_SWB_BIC_BUF_N @S9S_MB_2U_LIB.S9S_MB_2U(SCH_1):RST_SWB_BIC_BUF_N   I207 @S9S_MB_2U_LIB.S9S_MB_2U(SCH_1):PAGE140

R2925 Q_RES_0402LF-49.9,1%,1/16W,CHIA
     1 FM_GPU_PWR_EN_R1 @S9S_MB_2U_LIB.S9S_MB_2U(SCH_1):FM_GPU_PWR_EN_R1   I204 @S9S_MB_2U_LIB.S9S_MB_2U(SCH_1):PAGE140
     2 FM_GPU_PWR_EN_R_BUF @S9S_MB_2U_LIB.S9S_MB_2U(SCH_1):FM_GPU_PWR_EN_R_BUF   I204 @S9S_MB_2U_LIB.S9S_MB_2U(SCH_1):PAGE140

R2926 Q_RES_0402LF-4.7K,5%,1/16W,CHIA
     1 BMC_MONITER_BUF_R @S9S_MB_2U_LIB.S9S_MB_2U(SCH_1):BMC_MONITER_BUF_R   I121 @S9S_MB_2U_LIB.S9S_MB_2U(SCH_1):PAGE140
     2    GND @S9S_MB_2U_LIB.S9S_MB_2U(SCH_1):GND   I121 @S9S_MB_2U_LIB.S9S_MB_2U(SCH_1):PAGE140

R2927 Q_RES_0402LF-100K,1%,1/16W,CHIA
     1 RST_SWB_BIC_BUF_R_N @S9S_MB_2U_LIB.S9S_MB_2U(SCH_1):RST_SWB_BIC_BUF_R_N   I203 @S9S_MB_2U_LIB.S9S_MB_2U(SCH_1):PAGE140
     2    GND @S9S_MB_2U_LIB.S9S_MB_2U(SCH_1):GND   I203 @S9S_MB_2U_LIB.S9S_MB_2U(SCH_1):PAGE140

R2932 Q_RES_0402LF-4.7K,5%,1/16W,CHIA
     1 FM_SWB_PWR_EN_R1_BUF @S9S_MB_2U_LIB.S9S_MB_2U(SCH_1):FM_SWB_PWR_EN_R1_BUF   I195 @S9S_MB_2U_LIB.S9S_MB_2U(SCH_1):PAGE160
     2    GND @S9S_MB_2U_LIB.S9S_MB_2U(SCH_1):GND   I195 @S9S_MB_2U_LIB.S9S_MB_2U(SCH_1):PAGE160

R2933 Q_RES_0402LF-4.7K,5%,1/16W,CHIA
     1 P3V3_AUX @S9S_MB_2U_LIB.S9S_MB_2U(SCH_1):P3V3_AUX    I97 @S9S_MB_2U_LIB.S9S_MB_2U(SCH_1):PAGE145
     2 FM_SWB_BIC_READY_ISO_N @S9S_MB_2U_LIB.S9S_MB_2U(SCH_1):FM_SWB_BIC_READY_ISO_N    I97 @S9S_MB_2U_LIB.S9S_MB_2U(SCH_1):PAGE145

R2934 Q_RES_0402LF-4.7K,5%,1/16W,CHIA
     1 P3V3_AUX @S9S_MB_2U_LIB.S9S_MB_2U(SCH_1):P3V3_AUX   I101 @S9S_MB_2U_LIB.S9S_MB_2U(SCH_1):PAGE145
     2 FM_SWB_PWRGD_ISO @S9S_MB_2U_LIB.S9S_MB_2U(SCH_1):FM_SWB_PWRGD_ISO   I101 @S9S_MB_2U_LIB.S9S_MB_2U(SCH_1):PAGE145

R2935 Q_RES_0402LF-4.7K,5%,1/16W,CHIA
     1 P3V3_AUX @S9S_MB_2U_LIB.S9S_MB_2U(SCH_1):P3V3_AUX   I109 @S9S_MB_2U_LIB.S9S_MB_2U(SCH_1):PAGE145
     2 FM_GPU_PWRGD_ISO @S9S_MB_2U_LIB.S9S_MB_2U(SCH_1):FM_GPU_PWRGD_ISO   I109 @S9S_MB_2U_LIB.S9S_MB_2U(SCH_1):PAGE145

R2936 Q_RES_0402LF-100K,1%,1/16W,EMPA
     1 P3V3_AUX @S9S_MB_2U_LIB.S9S_MB_2U(SCH_1):P3V3_AUX   I162 @S9S_MB_2U_LIB.S9S_MB_2U(SCH_1):PAGE140
     2 FM_GPU_PWR_EN_R @S9S_MB_2U_LIB.S9S_MB_2U(SCH_1):FM_GPU_PWR_EN_R   I162 @S9S_MB_2U_LIB.S9S_MB_2U(SCH_1):PAGE140

R2937 Q_RES_0402LF-4.7K,5%,1/16W,CHIA
     1 FM_GPU_PWR_EN_R @S9S_MB_2U_LIB.S9S_MB_2U(SCH_1):FM_GPU_PWR_EN_R   I160 @S9S_MB_2U_LIB.S9S_MB_2U(SCH_1):PAGE140
     2    GND @S9S_MB_2U_LIB.S9S_MB_2U(SCH_1):GND   I160 @S9S_MB_2U_LIB.S9S_MB_2U(SCH_1):PAGE140

R2939 Q_RES_0402LF-33.2,1%,1/16W,CHIA
     1 FM_GPU_HSC_EN_R @S9S_MB_2U_LIB.S9S_MB_2U(SCH_1):FM_GPU_HSC_EN_R   I106 @S9S_MB_2U_LIB.S9S_MB_2U(SCH_1):PAGE314
     2 FM_GPU_HSC_EN @S9S_MB_2U_LIB.S9S_MB_2U(SCH_1):FM_GPU_HSC_EN   I106 @S9S_MB_2U_LIB.S9S_MB_2U(SCH_1):PAGE314

R2940 Q_RES_0402LF-4.7K,5%,1/16W,EMPA
     1 P3V3_AUX @S9S_MB_2U_LIB.S9S_MB_2U(SCH_1):P3V3_AUX    I28 @S9S_MB_2U_LIB.S9S_MB_2U(SCH_1):PAGE230
     2 FM_GPU_HSC_EN @S9S_MB_2U_LIB.S9S_MB_2U(SCH_1):FM_GPU_HSC_EN    I28 @S9S_MB_2U_LIB.S9S_MB_2U(SCH_1):PAGE230

R2941 Q_RES_0402LF-100K,1%,1/16W,CHIA
     1 FM_GPU_HSC_EN @S9S_MB_2U_LIB.S9S_MB_2U(SCH_1):FM_GPU_HSC_EN    I29 @S9S_MB_2U_LIB.S9S_MB_2U(SCH_1):PAGE230
     2    GND @S9S_MB_2U_LIB.S9S_MB_2U(SCH_1):GND    I29 @S9S_MB_2U_LIB.S9S_MB_2U(SCH_1):PAGE230

R2944 Q_RES_0402LF-33.2,1%,1/16W,CHIA
     1 FM_GPU_HSC_EN_BUF_R @S9S_MB_2U_LIB.S9S_MB_2U(SCH_1):FM_GPU_HSC_EN_BUF_R    I24 @S9S_MB_2U_LIB.S9S_MB_2U(SCH_1):PAGE230
     2 FM_GPU_HSC_EN_BUF @S9S_MB_2U_LIB.S9S_MB_2U(SCH_1):FM_GPU_HSC_EN_BUF    I24 @S9S_MB_2U_LIB.S9S_MB_2U(SCH_1):PAGE230

R2946 Q_RES_0402LF-4.7K,5%,1/16W,EMPA
     1 P3V3_AUX @S9S_MB_2U_LIB.S9S_MB_2U(SCH_1):P3V3_AUX    I25 @S9S_MB_2U_LIB.S9S_MB_2U(SCH_1):PAGE230
     2 FM_GPU_HSC_EN_BUF_R @S9S_MB_2U_LIB.S9S_MB_2U(SCH_1):FM_GPU_HSC_EN_BUF_R    I25 @S9S_MB_2U_LIB.S9S_MB_2U(SCH_1):PAGE230

R2948 Q_RES_0402LF-4.7K,5%,1/16W,EMPA
     1 FM_GPU_HSC_EN_BUF_R @S9S_MB_2U_LIB.S9S_MB_2U(SCH_1):FM_GPU_HSC_EN_BUF_R    I30 @S9S_MB_2U_LIB.S9S_MB_2U(SCH_1):PAGE230
     2    GND @S9S_MB_2U_LIB.S9S_MB_2U(SCH_1):GND    I30 @S9S_MB_2U_LIB.S9S_MB_2U(SCH_1):PAGE230

R2950 Q_RES_0402LF-4.7K,5%,1/16W,EMPA
     1 P3V3_AUX @S9S_MB_2U_LIB.S9S_MB_2U(SCH_1):P3V3_AUX     I4 @S9S_MB_2U_LIB.S9S_MB_2U(SCH_1):PAGE233
     2 FM_PDB_BUF_EN_R @S9S_MB_2U_LIB.S9S_MB_2U(SCH_1):FM_PDB_BUF_EN_R     I4 @S9S_MB_2U_LIB.S9S_MB_2U(SCH_1):PAGE233

R2966 Q_RES_0402LF-1M,1%,1/16W,CHIP,A
     1 P3V3_RTC_AUX @S9S_MB_2U_LIB.S9S_MB_2U(SCH_1):P3V3_RTC_AUX    I96 @S9S_MB_2U_LIB.S9S_MB_2U(SCH_1):PAGE174
     2 FM_INTRUDER_HDR_PCH_N @S9S_MB_2U_LIB.S9S_MB_2U(SCH_1):FM_INTRUDER_HDR_PCH_N    I96 @S9S_MB_2U_LIB.S9S_MB_2U(SCH_1):PAGE174

R2967 Q_RES_0402LF-0,5%,1/16W,CHIP,CA
     1 SMB_PCIE0_3V3AUX_SCL_R3 @S9S_MB_2U_LIB.S9S_MB_2U(SCH_1):SMB_PCIE0_3V3AUX_SCL_R3    I36 @S9S_MB_2U_LIB.S9S_MB_2U(SCH_1):PAGE219
     2 SMB_SENSOR_M2_P0_3V3AUX_SCL @S9S_MB_2U_LIB.S9S_MB_2U(SCH_1):SMB_SENSOR_M2_P0_3V3AUX_SCL    I36 @S9S_MB_2U_LIB.S9S_MB_2U(SCH_1):PAGE219

R2968 Q_RES_0402LF-0,5%,1/16W,CHIP,CA
     1 SMB_PCIE0_3V3AUX_SDA_R3 @S9S_MB_2U_LIB.S9S_MB_2U(SCH_1):SMB_PCIE0_3V3AUX_SDA_R3    I39 @S9S_MB_2U_LIB.S9S_MB_2U(SCH_1):PAGE219
     2 SMB_SENSOR_M2_P0_3V3AUX_SDA @S9S_MB_2U_LIB.S9S_MB_2U(SCH_1):SMB_SENSOR_M2_P0_3V3AUX_SDA    I39 @S9S_MB_2U_LIB.S9S_MB_2U(SCH_1):PAGE219

R2969 Q_RES_0402LF-0,5%,1/16W,CHIP,CA
     1 RST_CPU1_DRAM_GH_N @S9S_MB_2U_LIB.S9S_MB_2U(SCH_1):RST_CPU1_DRAM_GH_N    I49 @S9S_MB_2U_LIB.S9S_MB_2U(SCH_1):PAGE128
     2 RST_CPU1_DRAM_GH_PLD_N @S9S_MB_2U_LIB.S9S_MB_2U(SCH_1):RST_CPU1_DRAM_GH_PLD_N    I49 @S9S_MB_2U_LIB.S9S_MB_2U(SCH_1):PAGE128

R2971 Q_RES_0402LF-0,5%,1/16W,CHIP,CA
     1 FM_BIOS_DEBUG_EN_N @S9S_MB_2U_LIB.S9S_MB_2U(SCH_1):FM_BIOS_DEBUG_EN_N   I253 @S9S_MB_2U_LIB.S9S_MB_2U(SCH_1):PAGE175
     2 FM_BIOS_DEBUG_EN_R_N @S9S_MB_2U_LIB.S9S_MB_2U(SCH_1):FM_BIOS_DEBUG_EN_R_N   I253 @S9S_MB_2U_LIB.S9S_MB_2U(SCH_1):PAGE175

R2972 Q_RES_0402LF-10K,1%,1/16W,CHIPA
     1 P1V05_PCH_AUX @S9S_MB_2U_LIB.S9S_MB_2U(SCH_1):P1V05_PCH_AUX    I71 @S9S_MB_2U_LIB.S9S_MB_2U(SCH_1):PAGE184
     2 FAB_REV_ID2 @S9S_MB_2U_LIB.S9S_MB_2U(SCH_1):FAB_REV_ID2    I71 @S9S_MB_2U_LIB.S9S_MB_2U(SCH_1):PAGE184

R2973 Q_RES_0402LF-1K,1%,1/16W,EMPTYA
     1 FAB_REV_ID2 @S9S_MB_2U_LIB.S9S_MB_2U(SCH_1):FAB_REV_ID2    I69 @S9S_MB_2U_LIB.S9S_MB_2U(SCH_1):PAGE184
     2    GND @S9S_MB_2U_LIB.S9S_MB_2U(SCH_1):GND    I69 @S9S_MB_2U_LIB.S9S_MB_2U(SCH_1):PAGE184

R2974 Q_RES_0402LF-10K,1%,1/16W,CHIPA
     1 P1V05_PCH_AUX @S9S_MB_2U_LIB.S9S_MB_2U(SCH_1):P1V05_PCH_AUX    I72 @S9S_MB_2U_LIB.S9S_MB_2U(SCH_1):PAGE184
     2 FAB_REV_ID1 @S9S_MB_2U_LIB.S9S_MB_2U(SCH_1):FAB_REV_ID1    I72 @S9S_MB_2U_LIB.S9S_MB_2U(SCH_1):PAGE184

R2975 Q_RES_0402LF-1K,1%,1/16W,EMPTYA
     1 FAB_REV_ID1 @S9S_MB_2U_LIB.S9S_MB_2U(SCH_1):FAB_REV_ID1    I70 @S9S_MB_2U_LIB.S9S_MB_2U(SCH_1):PAGE184
     2    GND @S9S_MB_2U_LIB.S9S_MB_2U(SCH_1):GND    I70 @S9S_MB_2U_LIB.S9S_MB_2U(SCH_1):PAGE184

R2976 Q_RES_0402LF-10K,1%,1/16W,EMPTA
     1 P1V05_PCH_AUX @S9S_MB_2U_LIB.S9S_MB_2U(SCH_1):P1V05_PCH_AUX    I13 @S9S_MB_2U_LIB.S9S_MB_2U(SCH_1):PAGE184
     2 FM_BOARD_SKU_ID3 @S9S_MB_2U_LIB.S9S_MB_2U(SCH_1):FM_BOARD_SKU_ID3    I13 @S9S_MB_2U_LIB.S9S_MB_2U(SCH_1):PAGE184

R2977 Q_RES_0402LF-1K,1%,1/16W,CHIP,A
     1 FM_BOARD_SKU_ID3 @S9S_MB_2U_LIB.S9S_MB_2U(SCH_1):FM_BOARD_SKU_ID3    I11 @S9S_MB_2U_LIB.S9S_MB_2U(SCH_1):PAGE184
     2    GND @S9S_MB_2U_LIB.S9S_MB_2U(SCH_1):GND    I11 @S9S_MB_2U_LIB.S9S_MB_2U(SCH_1):PAGE184

R2978 Q_RES_0402LF-1K,1%,1/16W,EMPTYA
     1 FAB_REV_ID0 @S9S_MB_2U_LIB.S9S_MB_2U(SCH_1):FAB_REV_ID0    I74 @S9S_MB_2U_LIB.S9S_MB_2U(SCH_1):PAGE184
     2    GND @S9S_MB_2U_LIB.S9S_MB_2U(SCH_1):GND    I74 @S9S_MB_2U_LIB.S9S_MB_2U(SCH_1):PAGE184

R2979 Q_RES_0402LF-10K,1%,1/16W,EMPTA
     1 P1V05_PCH_AUX @S9S_MB_2U_LIB.S9S_MB_2U(SCH_1):P1V05_PCH_AUX    I48 @S9S_MB_2U_LIB.S9S_MB_2U(SCH_1):PAGE184
     2 FM_BOARD_SKU_ID2 @S9S_MB_2U_LIB.S9S_MB_2U(SCH_1):FM_BOARD_SKU_ID2    I48 @S9S_MB_2U_LIB.S9S_MB_2U(SCH_1):PAGE184

R2980 Q_RES_0402LF-1K,1%,1/16W,CHIP,A
     1 FM_BOARD_SKU_ID2 @S9S_MB_2U_LIB.S9S_MB_2U(SCH_1):FM_BOARD_SKU_ID2    I26 @S9S_MB_2U_LIB.S9S_MB_2U(SCH_1):PAGE184
     2    GND @S9S_MB_2U_LIB.S9S_MB_2U(SCH_1):GND    I26 @S9S_MB_2U_LIB.S9S_MB_2U(SCH_1):PAGE184

R2982 Q_RES_0402LF-0,5%,1/16W,CHIP,CA
     1 SMB_IOEXP_3V3AUX_SCL @S9S_MB_2U_LIB.S9S_MB_2U(SCH_1):SMB_IOEXP_3V3AUX_SCL    I96 @S9S_MB_2U_LIB.S9S_MB_2U(SCH_1):PAGE214
     2 SMB_IOEXP_3V3AUX_SCL_R1 @S9S_MB_2U_LIB.S9S_MB_2U(SCH_1):SMB_IOEXP_3V3AUX_SCL_R1    I96 @S9S_MB_2U_LIB.S9S_MB_2U(SCH_1):PAGE214

R2983 Q_RES_0402LF-0,5%,1/16W,CHIP,CA
     1 SMB_IOEXP_3V3AUX_SDA @S9S_MB_2U_LIB.S9S_MB_2U(SCH_1):SMB_IOEXP_3V3AUX_SDA   I101 @S9S_MB_2U_LIB.S9S_MB_2U(SCH_1):PAGE214
     2 SMB_IOEXP_3V3AUX_SDA_R1 @S9S_MB_2U_LIB.S9S_MB_2U(SCH_1):SMB_IOEXP_3V3AUX_SDA_R1   I101 @S9S_MB_2U_LIB.S9S_MB_2U(SCH_1):PAGE214

R2984 Q_RES_0402LF-10K,1%,1/16W,CHIPA
     1 P3V3_AUX @S9S_MB_2U_LIB.S9S_MB_2U(SCH_1):P3V3_AUX    I25 @S9S_MB_2U_LIB.S9S_MB_2U(SCH_1):PAGE219
     2 SMB_BMC_SWB_SCL @S9S_MB_2U_LIB.S9S_MB_2U(SCH_1):SMB_BMC_SWB_SCL    I25 @S9S_MB_2U_LIB.S9S_MB_2U(SCH_1):PAGE219

R2985 Q_RES_0402LF-10K,1%,1/16W,CHIPA
     1 P3V3_AUX @S9S_MB_2U_LIB.S9S_MB_2U(SCH_1):P3V3_AUX    I24 @S9S_MB_2U_LIB.S9S_MB_2U(SCH_1):PAGE219
     2 SMB_BMC_SWB_SDA @S9S_MB_2U_LIB.S9S_MB_2U(SCH_1):SMB_BMC_SWB_SDA    I24 @S9S_MB_2U_LIB.S9S_MB_2U(SCH_1):PAGE219

R2986 Q_RES_0402LF-0,5%,1/16W,EMPTY,A
     1 SMB_2_BMC_GPU_R_SCL @S9S_MB_2U_LIB.S9S_MB_2U(SCH_1):SMB_2_BMC_GPU_R_SCL    I13 @S9S_MB_2U_LIB.S9S_MB_2U(SCH_1):PAGE222
     2 SMB_2_BMC_GPU_BUF_R_SCL @S9S_MB_2U_LIB.S9S_MB_2U(SCH_1):SMB_2_BMC_GPU_BUF_R_SCL    I13 @S9S_MB_2U_LIB.S9S_MB_2U(SCH_1):PAGE222

R2987 Q_RES_0402LF-0,5%,1/16W,EMPTY,A
     1 SMB_2_BMC_GPU_R_SDA @S9S_MB_2U_LIB.S9S_MB_2U(SCH_1):SMB_2_BMC_GPU_R_SDA    I12 @S9S_MB_2U_LIB.S9S_MB_2U(SCH_1):PAGE222
     2 SMB_2_BMC_GPU_BUF_R_SDA @S9S_MB_2U_LIB.S9S_MB_2U(SCH_1):SMB_2_BMC_GPU_BUF_R_SDA    I12 @S9S_MB_2U_LIB.S9S_MB_2U(SCH_1):PAGE222

R2990 Q_RES_0402LF-33.2,1%,1/16W,CHIA
     1 SMB_2_BMC_GPU_BUF_R_SCL @S9S_MB_2U_LIB.S9S_MB_2U(SCH_1):SMB_2_BMC_GPU_BUF_R_SCL    I26 @S9S_MB_2U_LIB.S9S_MB_2U(SCH_1):PAGE222
     2 SMB_2_BMC_GPU_BUF_SCL @S9S_MB_2U_LIB.S9S_MB_2U(SCH_1):SMB_2_BMC_GPU_BUF_SCL    I26 @S9S_MB_2U_LIB.S9S_MB_2U(SCH_1):PAGE222

R2991 Q_RES_0402LF-33.2,1%,1/16W,CHIA
     1 SMB_2_BMC_GPU_BUF_R_SDA @S9S_MB_2U_LIB.S9S_MB_2U(SCH_1):SMB_2_BMC_GPU_BUF_R_SDA    I27 @S9S_MB_2U_LIB.S9S_MB_2U(SCH_1):PAGE222
     2 SMB_2_BMC_GPU_BUF_SDA @S9S_MB_2U_LIB.S9S_MB_2U(SCH_1):SMB_2_BMC_GPU_BUF_SDA    I27 @S9S_MB_2U_LIB.S9S_MB_2U(SCH_1):PAGE222

R2992 Q_RES_0402LF-0,5%,1/16W,CHIP,CA
     1 SMB_BMC_GPU_EN @S9S_MB_2U_LIB.S9S_MB_2U(SCH_1):SMB_BMC_GPU_EN     I9 @S9S_MB_2U_LIB.S9S_MB_2U(SCH_1):PAGE222
     2 SMB_BMC_GPU_EN_R3 @S9S_MB_2U_LIB.S9S_MB_2U(SCH_1):SMB_BMC_GPU_EN_R3     I9 @S9S_MB_2U_LIB.S9S_MB_2U(SCH_1):PAGE222

R2994 Q_RES_0402LF-0,5%,1/16W,CHIP,CA
     1 P3V_BAT_R1 @S9S_MB_2U_LIB.S9S_MB_2U(SCH_1):P3V_BAT_R1    I58 @S9S_MB_2U_LIB.S9S_MB_2U(SCH_1):PAGE227
     2 P3V_BAT_R @S9S_MB_2U_LIB.S9S_MB_2U(SCH_1):P3V_BAT_R    I58 @S9S_MB_2U_LIB.S9S_MB_2U(SCH_1):PAGE227

R2995 Q_RES_0402LF-33.2,1%,1/16W,CHIA
     1 SMB_SML1_PMBUS_3V3AUX_PCH_SCL @S9S_MB_2U_LIB.S9S_MB_2U(SCH_1):SMB_SML1_PMBUS_3V3AUX_PCH_SCL   I228 @S9S_MB_2U_LIB.S9S_MB_2U(SCH_1):PAGE228
     2 SMB_SML1_PMBUS_HSC_SCL_R3 @S9S_MB_2U_LIB.S9S_MB_2U(SCH_1):SMB_SML1_PMBUS_HSC_SCL_R3   I228 @S9S_MB_2U_LIB.S9S_MB_2U(SCH_1):PAGE228

R2996 Q_RES_0402LF-33.2,1%,1/16W,CHIA
     1 SMB_SML1_PMBUS_3V3AUX_PCH_SDA @S9S_MB_2U_LIB.S9S_MB_2U(SCH_1):SMB_SML1_PMBUS_3V3AUX_PCH_SDA   I229 @S9S_MB_2U_LIB.S9S_MB_2U(SCH_1):PAGE228
     2 SMB_SML1_PMBUS_HSC_SDA_R3 @S9S_MB_2U_LIB.S9S_MB_2U(SCH_1):SMB_SML1_PMBUS_HSC_SDA_R3   I229 @S9S_MB_2U_LIB.S9S_MB_2U(SCH_1):PAGE228

R2999 Q_RES_0402LF-2.2K,5%,1/16W,EMPA
     1 SMB_2_BMC_GPU_SCL @S9S_MB_2U_LIB.S9S_MB_2U(SCH_1):SMB_2_BMC_GPU_SCL   I231 @S9S_MB_2U_LIB.S9S_MB_2U(SCH_1):PAGE228
     2 P3V3_AUX @S9S_MB_2U_LIB.S9S_MB_2U(SCH_1):P3V3_AUX   I231 @S9S_MB_2U_LIB.S9S_MB_2U(SCH_1):PAGE228

R3004 Q_RES_0402LF-2.2K,5%,1/16W,EMPA
     1 SMB_2_BMC_GPU_SDA @S9S_MB_2U_LIB.S9S_MB_2U(SCH_1):SMB_2_BMC_GPU_SDA   I230 @S9S_MB_2U_LIB.S9S_MB_2U(SCH_1):PAGE228
     2 P3V3_AUX @S9S_MB_2U_LIB.S9S_MB_2U(SCH_1):P3V3_AUX   I230 @S9S_MB_2U_LIB.S9S_MB_2U(SCH_1):PAGE228

R3005 Q_RES_0402LF-18K,1%,1/16W,CHIPA
     1    P5V @S9S_MB_2U_LIB.S9S_MB_2U(SCH_1):P5V   I168 @S9S_MB_2U_LIB.S9S_MB_2U(SCH_1):PAGE239
     2 P5V_ADC @S9S_MB_2U_LIB.S9S_MB_2U(SCH_1):P5V_ADC   I168 @S9S_MB_2U_LIB.S9S_MB_2U(SCH_1):PAGE239

R3023 Q_RES_0402LF-0,5%,1/16W,CHIP,CA
     1 H_CPU_PM_FAST_WAKE_N @S9S_MB_2U_LIB.S9S_MB_2U(SCH_1):H_CPU_PM_FAST_WAKE_N    I10 @S9S_MB_2U_LIB.S9S_MB_2U(SCH_1):PAGE117
     2 H_CPU1_PM_FAST_WAKE_N @S9S_MB_2U_LIB.S9S_MB_2U(SCH_1):H_CPU1_PM_FAST_WAKE_N    I10 @S9S_MB_2U_LIB.S9S_MB_2U(SCH_1):PAGE117

R3024 Q_RES_0402LF-240,1%,1/16W,EMPTA
     1    GND @S9S_MB_2U_LIB.S9S_MB_2U(SCH_1):GND   I172 @S9S_MB_2U_LIB.S9S_MB_2U(SCH_1):PAGE119
     2 PD_EXT_CLK_SEL_CPU1 @S9S_MB_2U_LIB.S9S_MB_2U(SCH_1):PD_EXT_CLK_SEL_CPU1   I172 @S9S_MB_2U_LIB.S9S_MB_2U(SCH_1):PAGE119

R3025 Q_RES_0402LF-1K,1%,1/16W,EMPTYA
     1 FM_REMOTE_DEBUG_DET_R @S9S_MB_2U_LIB.S9S_MB_2U(SCH_1):FM_REMOTE_DEBUG_DET_R   I102 @S9S_MB_2U_LIB.S9S_MB_2U(SCH_1):PAGE137
     2    GND @S9S_MB_2U_LIB.S9S_MB_2U(SCH_1):GND   I102 @S9S_MB_2U_LIB.S9S_MB_2U(SCH_1):PAGE137

R3026 Q_RES_0402LF-1K,1%,1/16W,CHIP,A
     1 JTAG_BMC_PCH_TCK @S9S_MB_2U_LIB.S9S_MB_2U(SCH_1):JTAG_BMC_PCH_TCK   I106 @S9S_MB_2U_LIB.S9S_MB_2U(SCH_1):PAGE137
     2    GND @S9S_MB_2U_LIB.S9S_MB_2U(SCH_1):GND   I106 @S9S_MB_2U_LIB.S9S_MB_2U(SCH_1):PAGE137

R3027 Q_RES_0402LF-1K,1%,1/16W,CHIP,A
     1 JTAG_BMC_CPU_TCK @S9S_MB_2U_LIB.S9S_MB_2U(SCH_1):JTAG_BMC_CPU_TCK   I105 @S9S_MB_2U_LIB.S9S_MB_2U(SCH_1):PAGE137
     2    GND @S9S_MB_2U_LIB.S9S_MB_2U(SCH_1):GND   I105 @S9S_MB_2U_LIB.S9S_MB_2U(SCH_1):PAGE137

R3028 Q_RES_0402LF-100K,1%,1/16W,EMPA
     1 FM_SMB_1_ALERT_GPU_N @S9S_MB_2U_LIB.S9S_MB_2U(SCH_1):FM_SMB_1_ALERT_GPU_N   I139 @S9S_MB_2U_LIB.S9S_MB_2U(SCH_1):PAGE145
     2    GND @S9S_MB_2U_LIB.S9S_MB_2U(SCH_1):GND   I139 @S9S_MB_2U_LIB.S9S_MB_2U(SCH_1):PAGE145

R3029 Q_RES_0402LF-4.7K,5%,1/16W,CHIA
     1 P3V3_AUX @S9S_MB_2U_LIB.S9S_MB_2U(SCH_1):P3V3_AUX   I144 @S9S_MB_2U_LIB.S9S_MB_2U(SCH_1):PAGE145
     2 FM_SMB_1_ALERT_GPU @S9S_MB_2U_LIB.S9S_MB_2U(SCH_1):FM_SMB_1_ALERT_GPU   I144 @S9S_MB_2U_LIB.S9S_MB_2U(SCH_1):PAGE145

R3030 Q_RES_0402LF-4.7K,5%,1/16W,CHIA
     1 P3V3_AUX @S9S_MB_2U_LIB.S9S_MB_2U(SCH_1):P3V3_AUX   I146 @S9S_MB_2U_LIB.S9S_MB_2U(SCH_1):PAGE145
     2 FM_SMB_1_ALERT_GPU_ISO_N @S9S_MB_2U_LIB.S9S_MB_2U(SCH_1):FM_SMB_1_ALERT_GPU_ISO_N   I146 @S9S_MB_2U_LIB.S9S_MB_2U(SCH_1):PAGE145

R3032 Q_RES_0402LF-100K,1%,1/16W,EMPA
     1 FM_SMB_2_ALERT_GPU_N @S9S_MB_2U_LIB.S9S_MB_2U(SCH_1):FM_SMB_2_ALERT_GPU_N   I134 @S9S_MB_2U_LIB.S9S_MB_2U(SCH_1):PAGE145
     2    GND @S9S_MB_2U_LIB.S9S_MB_2U(SCH_1):GND   I134 @S9S_MB_2U_LIB.S9S_MB_2U(SCH_1):PAGE145

R3033 Q_RES_0402LF-0,5%,1/16W,CHIP,CA
     1 UART_BMC_BIC_RX @S9S_MB_2U_LIB.S9S_MB_2U(SCH_1):UART_BMC_BIC_RX   I170 @S9S_MB_2U_LIB.S9S_MB_2U(SCH_1):PAGE140
     2 UART_BMC_BIC_R_RX @S9S_MB_2U_LIB.S9S_MB_2U(SCH_1):UART_BMC_BIC_R_RX   I170 @S9S_MB_2U_LIB.S9S_MB_2U(SCH_1):PAGE140

R3034 Q_RES_0402LF-4.7K,5%,1/16W,CHIA
     1 P3V3_AUX @S9S_MB_2U_LIB.S9S_MB_2U(SCH_1):P3V3_AUX   I129 @S9S_MB_2U_LIB.S9S_MB_2U(SCH_1):PAGE145
     2 FM_SMB_2_ALERT_GPU @S9S_MB_2U_LIB.S9S_MB_2U(SCH_1):FM_SMB_2_ALERT_GPU   I129 @S9S_MB_2U_LIB.S9S_MB_2U(SCH_1):PAGE145

R3035 Q_RES_0402LF-4.7K,5%,1/16W,CHIA
     1 P3V3_AUX @S9S_MB_2U_LIB.S9S_MB_2U(SCH_1):P3V3_AUX   I127 @S9S_MB_2U_LIB.S9S_MB_2U(SCH_1):PAGE145
     2 FM_SMB_2_ALERT_GPU_ISO_N @S9S_MB_2U_LIB.S9S_MB_2U(SCH_1):FM_SMB_2_ALERT_GPU_ISO_N   I127 @S9S_MB_2U_LIB.S9S_MB_2U(SCH_1):PAGE145

R3036 Q_RES_0402LF-33.2,1%,1/16W,CHIA
     1 UART_BMC_BIC_R_BUF_RX @S9S_MB_2U_LIB.S9S_MB_2U(SCH_1):UART_BMC_BIC_R_BUF_RX   I197 @S9S_MB_2U_LIB.S9S_MB_2U(SCH_1):PAGE140
     2 UART_BMC_BIC_BUF_RX @S9S_MB_2U_LIB.S9S_MB_2U(SCH_1):UART_BMC_BIC_BUF_RX   I197 @S9S_MB_2U_LIB.S9S_MB_2U(SCH_1):PAGE140

R3037 Q_RES_0402LF-1K,1%,1/16W,EMPTYA
     1 P3V3_AUX @S9S_MB_2U_LIB.S9S_MB_2U(SCH_1):P3V3_AUX   I134 @S9S_MB_2U_LIB.S9S_MB_2U(SCH_1):PAGE154
     2 PD_SMB_OCP1_HP_ADD1 @S9S_MB_2U_LIB.S9S_MB_2U(SCH_1):PD_SMB_OCP1_HP_ADD1   I134 @S9S_MB_2U_LIB.S9S_MB_2U(SCH_1):PAGE154

R3038 Q_RES_0402LF-5.11K,1%,1/16W,CHA
     1 P3V3_AUX @S9S_MB_2U_LIB.S9S_MB_2U(SCH_1):P3V3_AUX    I57 @S9S_MB_2U_LIB.S9S_MB_2U(SCH_1):PAGE188
     2 FM_PCH_SPARE0 @S9S_MB_2U_LIB.S9S_MB_2U(SCH_1):FM_PCH_SPARE0    I57 @S9S_MB_2U_LIB.S9S_MB_2U(SCH_1):PAGE188

R3039 Q_RES_0402LF-1K,1%,1/16W,CHIP,A
     1    GND @S9S_MB_2U_LIB.S9S_MB_2U(SCH_1):GND   I132 @S9S_MB_2U_LIB.S9S_MB_2U(SCH_1):PAGE189
     2 PD_ME_RCVR_N @S9S_MB_2U_LIB.S9S_MB_2U(SCH_1):PD_ME_RCVR_N   I132 @S9S_MB_2U_LIB.S9S_MB_2U(SCH_1):PAGE189

R3040 Q_RES_0402LF-1K,1%,1/16W,CHIP,A
     1 P3V3_AUX @S9S_MB_2U_LIB.S9S_MB_2U(SCH_1):P3V3_AUX     I1 @S9S_MB_2U_LIB.S9S_MB_2U(SCH_1):PAGE192
     2 IRQ_PCH_SCI_WHEA_N @S9S_MB_2U_LIB.S9S_MB_2U(SCH_1):IRQ_PCH_SCI_WHEA_N     I1 @S9S_MB_2U_LIB.S9S_MB_2U(SCH_1):PAGE192

R3041 Q_RES_0402LF-10K,1%,1/16W,CHIPA
     1 P3V3_AUX @S9S_MB_2U_LIB.S9S_MB_2U(SCH_1):P3V3_AUX     I6 @S9S_MB_2U_LIB.S9S_MB_2U(SCH_1):PAGE192
     2 FM_PCH_GLB_RST_WARN_N @S9S_MB_2U_LIB.S9S_MB_2U(SCH_1):FM_PCH_GLB_RST_WARN_N     I6 @S9S_MB_2U_LIB.S9S_MB_2U(SCH_1):PAGE192

R3042 Q_RES_0402LF-10K,1%,1/16W,EMPTA
     1 P1V05_PCH_AUX @S9S_MB_2U_LIB.S9S_MB_2U(SCH_1):P1V05_PCH_AUX    I18 @S9S_MB_2U_LIB.S9S_MB_2U(SCH_1):PAGE192
     2 H_CPU_ERR1_PCH_R_N @S9S_MB_2U_LIB.S9S_MB_2U(SCH_1):H_CPU_ERR1_PCH_R_N    I18 @S9S_MB_2U_LIB.S9S_MB_2U(SCH_1):PAGE192

R3043 Q_RES_0402LF-33.2,1%,1/16W,CHIA
     1 IRQ_HSC_FAULT_N @S9S_MB_2U_LIB.S9S_MB_2U(SCH_1):IRQ_HSC_FAULT_N   I111 @S9S_MB_2U_LIB.S9S_MB_2U(SCH_1):PAGE314
     2 IRQ_HSC_FAULT_R1_N @S9S_MB_2U_LIB.S9S_MB_2U(SCH_1):IRQ_HSC_FAULT_R1_N   I111 @S9S_MB_2U_LIB.S9S_MB_2U(SCH_1):PAGE314

R3045 Q_RES_0402LF-0,5%,1/16W,CHIP,CA
     1 IRQ_UV_DETECT_N @S9S_MB_2U_LIB.S9S_MB_2U(SCH_1):IRQ_UV_DETECT_N   I164 @S9S_MB_2U_LIB.S9S_MB_2U(SCH_1):PAGE312
     2 IRQ_UV_DETECT_R_N @S9S_MB_2U_LIB.S9S_MB_2U(SCH_1):IRQ_UV_DETECT_R_N   I164 @S9S_MB_2U_LIB.S9S_MB_2U(SCH_1):PAGE312

R3046 Q_RES_0402LF-0,5%,1/16W,CHIP,CA
     1 FM_UV_ADR_TRIGGER_N @S9S_MB_2U_LIB.S9S_MB_2U(SCH_1):FM_UV_ADR_TRIGGER_N   I165 @S9S_MB_2U_LIB.S9S_MB_2U(SCH_1):PAGE312
     2 FM_UV_ADR_TRIGGER_R_N @S9S_MB_2U_LIB.S9S_MB_2U(SCH_1):FM_UV_ADR_TRIGGER_R_N   I165 @S9S_MB_2U_LIB.S9S_MB_2U(SCH_1):PAGE312

R3047 Q_RES_0402LF-0,5%,1/16W,CHIP,CA
     1 MB0_P12V_STBY_PWRGD @S9S_MB_2U_LIB.S9S_MB_2U(SCH_1):MB0_P12V_STBY_PWRGD    I85 @S9S_MB_2U_LIB.S9S_MB_2U(SCH_1):PAGE313
     2 PWRGD_PS_PWROK_PLD @S9S_MB_2U_LIB.S9S_MB_2U(SCH_1):PWRGD_PS_PWROK_PLD    I85 @S9S_MB_2U_LIB.S9S_MB_2U(SCH_1):PAGE313

R3048 Q_RES_0402LF-0,5%,1/16W,CHIP,CA
     1 MB0_P12V_STBY_PWRGD @S9S_MB_2U_LIB.S9S_MB_2U(SCH_1):MB0_P12V_STBY_PWRGD    I86 @S9S_MB_2U_LIB.S9S_MB_2U(SCH_1):PAGE313
     2 PWRGD_PS_PWROK @S9S_MB_2U_LIB.S9S_MB_2U(SCH_1):PWRGD_PS_PWROK    I86 @S9S_MB_2U_LIB.S9S_MB_2U(SCH_1):PAGE313

R3049 Q_RES_0402LF-0,5%,1/16W,CHIP,CA
     1 IRQ_SML1_PMBUS_ALERT_N @S9S_MB_2U_LIB.S9S_MB_2U(SCH_1):IRQ_SML1_PMBUS_ALERT_N   I176 @S9S_MB_2U_LIB.S9S_MB_2U(SCH_1):PAGE312
     2 IRQ_PSU_ALERT_R_N @S9S_MB_2U_LIB.S9S_MB_2U(SCH_1):IRQ_PSU_ALERT_R_N   I176 @S9S_MB_2U_LIB.S9S_MB_2U(SCH_1):PAGE312

R3050 Q_RES_0402LF-33.2,1%,1/16W,CHIA
     1 RST_RSMRST_PLD_R_N @S9S_MB_2U_LIB.S9S_MB_2U(SCH_1):RST_RSMRST_PLD_R_N   I129 @S9S_MB_2U_LIB.S9S_MB_2U(SCH_1):PAGE212
     2 RST_RSMRST_NM_HDR_N @S9S_MB_2U_LIB.S9S_MB_2U(SCH_1):RST_RSMRST_NM_HDR_N   I129 @S9S_MB_2U_LIB.S9S_MB_2U(SCH_1):PAGE212

R3051 Q_RES_0402LF-0,5%,1/16W,CHIP,CA
     1 IRQ_SML1_PMBUS_ALERT_R_N @S9S_MB_2U_LIB.S9S_MB_2U(SCH_1):IRQ_SML1_PMBUS_ALERT_R_N     I2 @S9S_MB_2U_LIB.S9S_MB_2U(SCH_1):PAGE215
     2 IRQ_SML1_PMBUS_ALERT_N @S9S_MB_2U_LIB.S9S_MB_2U(SCH_1):IRQ_SML1_PMBUS_ALERT_N     I2 @S9S_MB_2U_LIB.S9S_MB_2U(SCH_1):PAGE215

R3052 Q_RES_0402LF-33.2,1%,1/16W,CHIA
     1 SMB_HOST_3V3AUX_SCL_R5 @S9S_MB_2U_LIB.S9S_MB_2U(SCH_1):SMB_HOST_3V3AUX_SCL_R5    I13 @S9S_MB_2U_LIB.S9S_MB_2U(SCH_1):PAGE215
     2 SMB_HOST_ME_SCL @S9S_MB_2U_LIB.S9S_MB_2U(SCH_1):SMB_HOST_ME_SCL    I13 @S9S_MB_2U_LIB.S9S_MB_2U(SCH_1):PAGE215

R3053 Q_RES_0402LF-33.2,1%,1/16W,CHIA
     1 SMB_HOST_3V3AUX_SDA_R5 @S9S_MB_2U_LIB.S9S_MB_2U(SCH_1):SMB_HOST_3V3AUX_SDA_R5    I12 @S9S_MB_2U_LIB.S9S_MB_2U(SCH_1):PAGE215
     2 SMB_HOST_ME_SDA @S9S_MB_2U_LIB.S9S_MB_2U(SCH_1):SMB_HOST_ME_SDA    I12 @S9S_MB_2U_LIB.S9S_MB_2U(SCH_1):PAGE215

R3054 Q_RES_0402LF-33.2,1%,1/16W,CHIA
     1 PWRGD_PS_PWROK_ME_CONN @S9S_MB_2U_LIB.S9S_MB_2U(SCH_1):PWRGD_PS_PWROK_ME_CONN    I23 @S9S_MB_2U_LIB.S9S_MB_2U(SCH_1):PAGE215
     2 PWRGD_PS_PWROK @S9S_MB_2U_LIB.S9S_MB_2U(SCH_1):PWRGD_PS_PWROK    I23 @S9S_MB_2U_LIB.S9S_MB_2U(SCH_1):PAGE215

R3055 Q_RES_0402LF-1K,1%,1/16W,CHIP,A
     1 P3V3_AUX @S9S_MB_2U_LIB.S9S_MB_2U(SCH_1):P3V3_AUX    I11 @S9S_MB_2U_LIB.S9S_MB_2U(SCH_1):PAGE226
     2 PU_GTL2014_BMC_JTAG_DIR_1 @S9S_MB_2U_LIB.S9S_MB_2U(SCH_1):PU_GTL2014_BMC_JTAG_DIR_1    I11 @S9S_MB_2U_LIB.S9S_MB_2U(SCH_1):PAGE226

R3056 Q_RES_0402LF-33.2,1%,1/16W,CHIA
     1 JTAG_DBP_BMC_PRDY_R1_N @S9S_MB_2U_LIB.S9S_MB_2U(SCH_1):JTAG_DBP_BMC_PRDY_R1_N    I36 @S9S_MB_2U_LIB.S9S_MB_2U(SCH_1):PAGE226
     2 JTAG_DBP_BMC_PRDY_N @S9S_MB_2U_LIB.S9S_MB_2U(SCH_1):JTAG_DBP_BMC_PRDY_N    I36 @S9S_MB_2U_LIB.S9S_MB_2U(SCH_1):PAGE226

R3057 Q_RES_0402LF-33.2,1%,1/16W,CHIA
     1 JTAG_DBP_BMC_PREQ_R1_N @S9S_MB_2U_LIB.S9S_MB_2U(SCH_1):JTAG_DBP_BMC_PREQ_R1_N    I12 @S9S_MB_2U_LIB.S9S_MB_2U(SCH_1):PAGE226
     2 JTAG_BMC_DBP_PREQ_N @S9S_MB_2U_LIB.S9S_MB_2U(SCH_1):JTAG_BMC_DBP_PREQ_N    I12 @S9S_MB_2U_LIB.S9S_MB_2U(SCH_1):PAGE226

R3058 Q_RES_0402LF-33.2,1%,1/16W,CHIA
     1 SMB_SML0_3V3AUX_SCL @S9S_MB_2U_LIB.S9S_MB_2U(SCH_1):SMB_SML0_3V3AUX_SCL   I242 @S9S_MB_2U_LIB.S9S_MB_2U(SCH_1):PAGE228
     2 SMB_SML0_ME_SCL @S9S_MB_2U_LIB.S9S_MB_2U(SCH_1):SMB_SML0_ME_SCL   I242 @S9S_MB_2U_LIB.S9S_MB_2U(SCH_1):PAGE228

R3059 Q_RES_0402LF-33.2,1%,1/16W,CHIA
     1 SMB_SML0_3V3AUX_SDA @S9S_MB_2U_LIB.S9S_MB_2U(SCH_1):SMB_SML0_3V3AUX_SDA   I243 @S9S_MB_2U_LIB.S9S_MB_2U(SCH_1):PAGE228
     2 SMB_SML0_ME_SDA @S9S_MB_2U_LIB.S9S_MB_2U(SCH_1):SMB_SML0_ME_SDA   I243 @S9S_MB_2U_LIB.S9S_MB_2U(SCH_1):PAGE228

R3060 Q_RES_0402LF-33.2,1%,1/16W,CHIA
     1 SMB_SML1_PMBUS_3V3AUX_PCH_SCL @S9S_MB_2U_LIB.S9S_MB_2U(SCH_1):SMB_SML1_PMBUS_3V3AUX_PCH_SCL   I237 @S9S_MB_2U_LIB.S9S_MB_2U(SCH_1):PAGE228
     2 SMB_PMBUS_SML1_ME_SCL @S9S_MB_2U_LIB.S9S_MB_2U(SCH_1):SMB_PMBUS_SML1_ME_SCL   I237 @S9S_MB_2U_LIB.S9S_MB_2U(SCH_1):PAGE228

R3061 Q_RES_0402LF-33.2,1%,1/16W,CHIA
     1 SMB_SML1_PMBUS_3V3AUX_PCH_SDA @S9S_MB_2U_LIB.S9S_MB_2U(SCH_1):SMB_SML1_PMBUS_3V3AUX_PCH_SDA   I234 @S9S_MB_2U_LIB.S9S_MB_2U(SCH_1):PAGE228
     2 SMB_PMBUS_SML1_ME_SDA @S9S_MB_2U_LIB.S9S_MB_2U(SCH_1):SMB_PMBUS_SML1_ME_SDA   I234 @S9S_MB_2U_LIB.S9S_MB_2U(SCH_1):PAGE228

R3062 Q_RES_0402LF-2K,1%,1/16W,EMPTYA
     1 SMB_HOST_3V3AUX_SDA @S9S_MB_2U_LIB.S9S_MB_2U(SCH_1):SMB_HOST_3V3AUX_SDA     I3 @S9S_MB_2U_LIB.S9S_MB_2U(SCH_1):PAGE228
     2 P3V3_AUX @S9S_MB_2U_LIB.S9S_MB_2U(SCH_1):P3V3_AUX     I3 @S9S_MB_2U_LIB.S9S_MB_2U(SCH_1):PAGE228

R3063 Q_RES_0402LF-33.2,1%,1/16W,CHIA
     1 FM_PDB_BUF_EN_R @S9S_MB_2U_LIB.S9S_MB_2U(SCH_1):FM_PDB_BUF_EN_R   I208 @S9S_MB_2U_LIB.S9S_MB_2U(SCH_1):PAGE140
     2 FM_UART_EN @S9S_MB_2U_LIB.S9S_MB_2U(SCH_1):FM_UART_EN   I208 @S9S_MB_2U_LIB.S9S_MB_2U(SCH_1):PAGE140

R3064 Q_RES_0402LF-0,5%,1/16W,EMPTY,A
     1 PECI_CPU_GTL @S9S_MB_2U_LIB.S9S_MB_2U(SCH_1):PECI_CPU_GTL    I45 @S9S_MB_2U_LIB.S9S_MB_2U(SCH_1):PAGE185
     2 PECI_BMC_ME @S9S_MB_2U_LIB.S9S_MB_2U(SCH_1):PECI_BMC_ME    I45 @S9S_MB_2U_LIB.S9S_MB_2U(SCH_1):PAGE185

R3065 Q_RES_0402LF-33.2,1%,1/16W,CHIA
     1 FM_BIOS_POST_CMPLT_N @S9S_MB_2U_LIB.S9S_MB_2U(SCH_1):FM_BIOS_POST_CMPLT_N    I40 @S9S_MB_2U_LIB.S9S_MB_2U(SCH_1):PAGE193
     2 FM_BIOS_POST_CMPLT_HDR_N @S9S_MB_2U_LIB.S9S_MB_2U(SCH_1):FM_BIOS_POST_CMPLT_HDR_N    I40 @S9S_MB_2U_LIB.S9S_MB_2U(SCH_1):PAGE193

R3066 Q_RES_0402LF-0,5%,1/16W,CHIP,CA
     1 FM_SMB_1_ALERT_GPU_ISO_N @S9S_MB_2U_LIB.S9S_MB_2U(SCH_1):FM_SMB_1_ALERT_GPU_ISO_N   I175 @S9S_MB_2U_LIB.S9S_MB_2U(SCH_1):PAGE313
     2 FM_SMB_1_ALERT_GPU_ISO_R_N @S9S_MB_2U_LIB.S9S_MB_2U(SCH_1):FM_SMB_1_ALERT_GPU_ISO_R_N   I175 @S9S_MB_2U_LIB.S9S_MB_2U(SCH_1):PAGE313

R3067 Q_RES_0402LF-0,5%,1/16W,CHIP,CA
     1 FM_SMB_2_ALERT_GPU_ISO_N @S9S_MB_2U_LIB.S9S_MB_2U(SCH_1):FM_SMB_2_ALERT_GPU_ISO_N   I176 @S9S_MB_2U_LIB.S9S_MB_2U(SCH_1):PAGE313
     2 FM_SMB_2_ALERT_GPU_ISO_R_N @S9S_MB_2U_LIB.S9S_MB_2U(SCH_1):FM_SMB_2_ALERT_GPU_ISO_R_N   I176 @S9S_MB_2U_LIB.S9S_MB_2U(SCH_1):PAGE313

R3068 Q_RES_0402LF-130,1%,1/16W,CHIPA
     1 LED_PWRGD_PCH_PWROK_R @S9S_MB_2U_LIB.S9S_MB_2U(SCH_1):LED_PWRGD_PCH_PWROK_R    I38 @S9S_MB_2U_LIB.S9S_MB_2U(SCH_1):PAGE241
     2 P3V3_AUX @S9S_MB_2U_LIB.S9S_MB_2U(SCH_1):P3V3_AUX    I38 @S9S_MB_2U_LIB.S9S_MB_2U(SCH_1):PAGE241

R3069 Q_RES_0402LF-130,1%,1/16W,CHIPA
     1 LED_PWRGD_SYS_PWROK_R @S9S_MB_2U_LIB.S9S_MB_2U(SCH_1):LED_PWRGD_SYS_PWROK_R    I39 @S9S_MB_2U_LIB.S9S_MB_2U(SCH_1):PAGE241
     2 P3V3_AUX @S9S_MB_2U_LIB.S9S_MB_2U(SCH_1):P3V3_AUX    I39 @S9S_MB_2U_LIB.S9S_MB_2U(SCH_1):PAGE241

R3070 Q_RES_0402LF-130,1%,1/16W,CHIPA
     1 LED_RST_PLTRST_N @S9S_MB_2U_LIB.S9S_MB_2U(SCH_1):LED_RST_PLTRST_N    I41 @S9S_MB_2U_LIB.S9S_MB_2U(SCH_1):PAGE241
     2 P3V3_AUX @S9S_MB_2U_LIB.S9S_MB_2U(SCH_1):P3V3_AUX    I41 @S9S_MB_2U_LIB.S9S_MB_2U(SCH_1):PAGE241

R3071 Q_RES_0402LF-130,1%,1/16W,CHIPA
     1 LED_PWRGD_P1V8_PCH_AUX @S9S_MB_2U_LIB.S9S_MB_2U(SCH_1):LED_PWRGD_P1V8_PCH_AUX    I19 @S9S_MB_2U_LIB.S9S_MB_2U(SCH_1):PAGE242
     2 P3V3_AUX @S9S_MB_2U_LIB.S9S_MB_2U(SCH_1):P3V3_AUX    I19 @S9S_MB_2U_LIB.S9S_MB_2U(SCH_1):PAGE242

R3072 Q_RES_0402LF-130,1%,1/16W,CHIPA
     1 LED_PWRGD_P1V05_PCH_AUX @S9S_MB_2U_LIB.S9S_MB_2U(SCH_1):LED_PWRGD_P1V05_PCH_AUX    I15 @S9S_MB_2U_LIB.S9S_MB_2U(SCH_1):PAGE242
     2 P3V3_AUX @S9S_MB_2U_LIB.S9S_MB_2U(SCH_1):P3V3_AUX    I15 @S9S_MB_2U_LIB.S9S_MB_2U(SCH_1):PAGE242

R3073 Q_RES_0402LF-130,1%,1/16W,CHIPA
     1 LED_FM_PCH_SLP_S4_N @S9S_MB_2U_LIB.S9S_MB_2U(SCH_1):LED_FM_PCH_SLP_S4_N    I12 @S9S_MB_2U_LIB.S9S_MB_2U(SCH_1):PAGE242
     2 P3V3_AUX @S9S_MB_2U_LIB.S9S_MB_2U(SCH_1):P3V3_AUX    I12 @S9S_MB_2U_LIB.S9S_MB_2U(SCH_1):PAGE242

R3074 Q_RES_0402LF-130,1%,1/16W,CHIPA
     1 LED_RST_RSMRST_PLD_R_N @S9S_MB_2U_LIB.S9S_MB_2U(SCH_1):LED_RST_RSMRST_PLD_R_N    I14 @S9S_MB_2U_LIB.S9S_MB_2U(SCH_1):PAGE242
     2 P3V3_AUX @S9S_MB_2U_LIB.S9S_MB_2U(SCH_1):P3V3_AUX    I14 @S9S_MB_2U_LIB.S9S_MB_2U(SCH_1):PAGE242

R3075 Q_RES_0402LF-130,1%,1/16W,CHIPA
     1 LED_PWRGD_PS_PWROK_PLD @S9S_MB_2U_LIB.S9S_MB_2U(SCH_1):LED_PWRGD_PS_PWROK_PLD    I37 @S9S_MB_2U_LIB.S9S_MB_2U(SCH_1):PAGE242
     2 P3V3_AUX @S9S_MB_2U_LIB.S9S_MB_2U(SCH_1):P3V3_AUX    I37 @S9S_MB_2U_LIB.S9S_MB_2U(SCH_1):PAGE242

R3078 Q_RES_0402LF-130,1%,1/16W,CHIPA
     1 LED_FM_PCH_SLP_S3_N @S9S_MB_2U_LIB.S9S_MB_2U(SCH_1):LED_FM_PCH_SLP_S3_N    I41 @S9S_MB_2U_LIB.S9S_MB_2U(SCH_1):PAGE242
     2 P3V3_AUX @S9S_MB_2U_LIB.S9S_MB_2U(SCH_1):P3V3_AUX    I41 @S9S_MB_2U_LIB.S9S_MB_2U(SCH_1):PAGE242

R3079 Q_RES_0402LF-130,1%,1/16W,CHIPA
     1 LED_RST_PLD_CPU0_DRAM_EF_N @S9S_MB_2U_LIB.S9S_MB_2U(SCH_1):LED_RST_PLD_CPU0_DRAM_EF_N    I51 @S9S_MB_2U_LIB.S9S_MB_2U(SCH_1):PAGE304
     2 P3V3_AUX @S9S_MB_2U_LIB.S9S_MB_2U(SCH_1):P3V3_AUX    I51 @S9S_MB_2U_LIB.S9S_MB_2U(SCH_1):PAGE304

R3080 Q_RES_0402LF-130,1%,1/16W,CHIPA
     1 LED_RST_PLD_CPU0_DRAM_CD_N @S9S_MB_2U_LIB.S9S_MB_2U(SCH_1):LED_RST_PLD_CPU0_DRAM_CD_N    I50 @S9S_MB_2U_LIB.S9S_MB_2U(SCH_1):PAGE304
     2 P3V3_AUX @S9S_MB_2U_LIB.S9S_MB_2U(SCH_1):P3V3_AUX    I50 @S9S_MB_2U_LIB.S9S_MB_2U(SCH_1):PAGE304

R3081 Q_RES_0402LF-130,1%,1/16W,CHIPA
     1 LED_RST_PLD_CPU0_DRAM_GH_N @S9S_MB_2U_LIB.S9S_MB_2U(SCH_1):LED_RST_PLD_CPU0_DRAM_GH_N    I52 @S9S_MB_2U_LIB.S9S_MB_2U(SCH_1):PAGE304
     2 P3V3_AUX @S9S_MB_2U_LIB.S9S_MB_2U(SCH_1):P3V3_AUX    I52 @S9S_MB_2U_LIB.S9S_MB_2U(SCH_1):PAGE304

R3082 Q_RES_0402LF-130,1%,1/16W,CHIPA
     1 LED_RST_PLD_CPU1_DRAM_AB_N @S9S_MB_2U_LIB.S9S_MB_2U(SCH_1):LED_RST_PLD_CPU1_DRAM_AB_N    I54 @S9S_MB_2U_LIB.S9S_MB_2U(SCH_1):PAGE304
     2 P3V3_AUX @S9S_MB_2U_LIB.S9S_MB_2U(SCH_1):P3V3_AUX    I54 @S9S_MB_2U_LIB.S9S_MB_2U(SCH_1):PAGE304

R3083 Q_RES_0402LF-130,1%,1/16W,CHIPA
     1 LED_RST_PLD_CPU1_DRAM_EF_N @S9S_MB_2U_LIB.S9S_MB_2U(SCH_1):LED_RST_PLD_CPU1_DRAM_EF_N    I57 @S9S_MB_2U_LIB.S9S_MB_2U(SCH_1):PAGE304
     2 P3V3_AUX @S9S_MB_2U_LIB.S9S_MB_2U(SCH_1):P3V3_AUX    I57 @S9S_MB_2U_LIB.S9S_MB_2U(SCH_1):PAGE304

R3084 Q_RES_0402LF-130,1%,1/16W,CHIPA
     1 LED_RST_PLD_CPU1_DRAM_CD_N @S9S_MB_2U_LIB.S9S_MB_2U(SCH_1):LED_RST_PLD_CPU1_DRAM_CD_N    I53 @S9S_MB_2U_LIB.S9S_MB_2U(SCH_1):PAGE304
     2 P3V3_AUX @S9S_MB_2U_LIB.S9S_MB_2U(SCH_1):P3V3_AUX    I53 @S9S_MB_2U_LIB.S9S_MB_2U(SCH_1):PAGE304

R3085 Q_RES_0402LF-130,1%,1/16W,CHIPA
     1 LED_RST_PLD_CPU1_DRAM_GH_N @S9S_MB_2U_LIB.S9S_MB_2U(SCH_1):LED_RST_PLD_CPU1_DRAM_GH_N    I62 @S9S_MB_2U_LIB.S9S_MB_2U(SCH_1):PAGE304
     2 P3V3_AUX @S9S_MB_2U_LIB.S9S_MB_2U(SCH_1):P3V3_AUX    I62 @S9S_MB_2U_LIB.S9S_MB_2U(SCH_1):PAGE304

R3086 Q_RES_0402LF-130,1%,1/16W,CHIPA
     1 LED_PWRGD_PVCCD_HV_CPU0 @S9S_MB_2U_LIB.S9S_MB_2U(SCH_1):LED_PWRGD_PVCCD_HV_CPU0    I49 @S9S_MB_2U_LIB.S9S_MB_2U(SCH_1):PAGE305
     2 P3V3_AUX @S9S_MB_2U_LIB.S9S_MB_2U(SCH_1):P3V3_AUX    I49 @S9S_MB_2U_LIB.S9S_MB_2U(SCH_1):PAGE305

R3087 Q_RES_0402LF-130,1%,1/16W,CHIPA
     1 LED_PWRGD_PVPP_HBM_CPU0 @S9S_MB_2U_LIB.S9S_MB_2U(SCH_1):LED_PWRGD_PVPP_HBM_CPU0    I50 @S9S_MB_2U_LIB.S9S_MB_2U(SCH_1):PAGE305
     2 P3V3_AUX @S9S_MB_2U_LIB.S9S_MB_2U(SCH_1):P3V3_AUX    I50 @S9S_MB_2U_LIB.S9S_MB_2U(SCH_1):PAGE305

R3088 Q_RES_0402LF-130,1%,1/16W,CHIPA
     1 LED_PWRGD_PVCCFA_EHV_FIVRA_CPU0 @S9S_MB_2U_LIB.S9S_MB_2U(SCH_1):LED_PWRGD_PVCCFA_EHV_FIVRA_CPU0    I52 @S9S_MB_2U_LIB.S9S_MB_2U(SCH_1):PAGE305
     2 P3V3_AUX @S9S_MB_2U_LIB.S9S_MB_2U(SCH_1):P3V3_AUX    I52 @S9S_MB_2U_LIB.S9S_MB_2U(SCH_1):PAGE305

R3089 Q_RES_0402LF-130,1%,1/16W,CHIPA
     1 LED_PWRGD_PVCCFA_EHV_CPU0 @S9S_MB_2U_LIB.S9S_MB_2U(SCH_1):LED_PWRGD_PVCCFA_EHV_CPU0    I51 @S9S_MB_2U_LIB.S9S_MB_2U(SCH_1):PAGE305
     2 P3V3_AUX @S9S_MB_2U_LIB.S9S_MB_2U(SCH_1):P3V3_AUX    I51 @S9S_MB_2U_LIB.S9S_MB_2U(SCH_1):PAGE305

R3090 Q_RES_0402LF-130,1%,1/16W,CHIPA
     1 LED_PWRGD_PVNN_MAIN_CPU0 @S9S_MB_2U_LIB.S9S_MB_2U(SCH_1):LED_PWRGD_PVNN_MAIN_CPU0    I54 @S9S_MB_2U_LIB.S9S_MB_2U(SCH_1):PAGE305
     2 P3V3_AUX @S9S_MB_2U_LIB.S9S_MB_2U(SCH_1):P3V3_AUX    I54 @S9S_MB_2U_LIB.S9S_MB_2U(SCH_1):PAGE305

R3091 Q_RES_0402LF-130,1%,1/16W,CHIPA
     1 LED_PWRGD_PVCCIN_CPU0 @S9S_MB_2U_LIB.S9S_MB_2U(SCH_1):LED_PWRGD_PVCCIN_CPU0    I53 @S9S_MB_2U_LIB.S9S_MB_2U(SCH_1):PAGE305
     2 P3V3_AUX @S9S_MB_2U_LIB.S9S_MB_2U(SCH_1):P3V3_AUX    I53 @S9S_MB_2U_LIB.S9S_MB_2U(SCH_1):PAGE305

R3092 Q_RES_0402LF-130,1%,1/16W,CHIPA
     1 LED_PWRGD_PVCCINFAON_CPU0 @S9S_MB_2U_LIB.S9S_MB_2U(SCH_1):LED_PWRGD_PVCCINFAON_CPU0    I55 @S9S_MB_2U_LIB.S9S_MB_2U(SCH_1):PAGE305
     2 P3V3_AUX @S9S_MB_2U_LIB.S9S_MB_2U(SCH_1):P3V3_AUX    I55 @S9S_MB_2U_LIB.S9S_MB_2U(SCH_1):PAGE305

R3093 Q_RES_0402LF-130,1%,1/16W,CHIPA
     1 LED_PWRGD_PVCCD_HV_CPU1 @S9S_MB_2U_LIB.S9S_MB_2U(SCH_1):LED_PWRGD_PVCCD_HV_CPU1    I20 @S9S_MB_2U_LIB.S9S_MB_2U(SCH_1):PAGE306
     2 P3V3_AUX @S9S_MB_2U_LIB.S9S_MB_2U(SCH_1):P3V3_AUX    I20 @S9S_MB_2U_LIB.S9S_MB_2U(SCH_1):PAGE306

R3094 Q_RES_0402LF-130,1%,1/16W,CHIPA
     1 LED_PWRGD_PVPP_HBM_CPU1 @S9S_MB_2U_LIB.S9S_MB_2U(SCH_1):LED_PWRGD_PVPP_HBM_CPU1    I16 @S9S_MB_2U_LIB.S9S_MB_2U(SCH_1):PAGE306
     2 P3V3_AUX @S9S_MB_2U_LIB.S9S_MB_2U(SCH_1):P3V3_AUX    I16 @S9S_MB_2U_LIB.S9S_MB_2U(SCH_1):PAGE306

R3095 Q_RES_0402LF-130,1%,1/16W,CHIPA
     1 LED_PWRGD_PVCCFA_EHV_FIVRA_CPU1 @S9S_MB_2U_LIB.S9S_MB_2U(SCH_1):LED_PWRGD_PVCCFA_EHV_FIVRA_CPU1    I12 @S9S_MB_2U_LIB.S9S_MB_2U(SCH_1):PAGE306
     2 P3V3_AUX @S9S_MB_2U_LIB.S9S_MB_2U(SCH_1):P3V3_AUX    I12 @S9S_MB_2U_LIB.S9S_MB_2U(SCH_1):PAGE306

R3096 Q_RES_0402LF-130,1%,1/16W,CHIPA
     1 LED_PWRGD_PVCCFA_EHV_CPU1 @S9S_MB_2U_LIB.S9S_MB_2U(SCH_1):LED_PWRGD_PVCCFA_EHV_CPU1    I15 @S9S_MB_2U_LIB.S9S_MB_2U(SCH_1):PAGE306
     2 P3V3_AUX @S9S_MB_2U_LIB.S9S_MB_2U(SCH_1):P3V3_AUX    I15 @S9S_MB_2U_LIB.S9S_MB_2U(SCH_1):PAGE306

R3097 Q_RES_0402LF-130,1%,1/16W,CHIPA
     1 LED_PWRGD_PVNN_MAIN_CPU1 @S9S_MB_2U_LIB.S9S_MB_2U(SCH_1):LED_PWRGD_PVNN_MAIN_CPU1    I38 @S9S_MB_2U_LIB.S9S_MB_2U(SCH_1):PAGE306
     2 P3V3_AUX @S9S_MB_2U_LIB.S9S_MB_2U(SCH_1):P3V3_AUX    I38 @S9S_MB_2U_LIB.S9S_MB_2U(SCH_1):PAGE306

R3098 Q_RES_0402LF-130,1%,1/16W,CHIPA
     1 LED_PWRGD_PVCCIN_CPU1 @S9S_MB_2U_LIB.S9S_MB_2U(SCH_1):LED_PWRGD_PVCCIN_CPU1    I37 @S9S_MB_2U_LIB.S9S_MB_2U(SCH_1):PAGE306
     2 P3V3_AUX @S9S_MB_2U_LIB.S9S_MB_2U(SCH_1):P3V3_AUX    I37 @S9S_MB_2U_LIB.S9S_MB_2U(SCH_1):PAGE306

R3099 Q_RES_0402LF-130,1%,1/16W,CHIPA
     1 LED_PWRGD_PVCCINFAON_CPU1 @S9S_MB_2U_LIB.S9S_MB_2U(SCH_1):LED_PWRGD_PVCCINFAON_CPU1    I41 @S9S_MB_2U_LIB.S9S_MB_2U(SCH_1):PAGE306
     2 P3V3_AUX @S9S_MB_2U_LIB.S9S_MB_2U(SCH_1):P3V3_AUX    I41 @S9S_MB_2U_LIB.S9S_MB_2U(SCH_1):PAGE306

R3100 Q_RES_0402LF-130,1%,1/16W,CHIPA
     1 LED_P3V3 @S9S_MB_2U_LIB.S9S_MB_2U(SCH_1):LED_P3V3    I64 @S9S_MB_2U_LIB.S9S_MB_2U(SCH_1):PAGE242
     2   P3V3 @S9S_MB_2U_LIB.S9S_MB_2U(SCH_1):P3V3    I64 @S9S_MB_2U_LIB.S9S_MB_2U(SCH_1):PAGE242

R3101 Q_RES_0402LF-470,1%,1/16W,CHIPA
     1 LED_P5V_AUX @S9S_MB_2U_LIB.S9S_MB_2U(SCH_1):LED_P5V_AUX    I62 @S9S_MB_2U_LIB.S9S_MB_2U(SCH_1):PAGE242
     2 P5V_AUX @S9S_MB_2U_LIB.S9S_MB_2U(SCH_1):P5V_AUX    I62 @S9S_MB_2U_LIB.S9S_MB_2U(SCH_1):PAGE242

R3102 Q_RES_0402LF-470,1%,1/16W,CHIPA
     1 LED_P5V @S9S_MB_2U_LIB.S9S_MB_2U(SCH_1):LED_P5V    I61 @S9S_MB_2U_LIB.S9S_MB_2U(SCH_1):PAGE242
     2    P5V @S9S_MB_2U_LIB.S9S_MB_2U(SCH_1):P5V    I61 @S9S_MB_2U_LIB.S9S_MB_2U(SCH_1):PAGE242

R3103 Q_RES_0402LF-0,5%,1/16W,CHIP,CA
     1 IRQ_SML0_ALERT_R_N @S9S_MB_2U_LIB.S9S_MB_2U(SCH_1):IRQ_SML0_ALERT_R_N    I28 @S9S_MB_2U_LIB.S9S_MB_2U(SCH_1):PAGE215
     2 IRQ_SML0_ALERT_R1_N @S9S_MB_2U_LIB.S9S_MB_2U(SCH_1):IRQ_SML0_ALERT_R1_N    I28 @S9S_MB_2U_LIB.S9S_MB_2U(SCH_1):PAGE215

R3105 Q_RES_0402LF-0,5%,1/16W,CHIP,CA
     1 SMB_BMC_SWB_SCL @S9S_MB_2U_LIB.S9S_MB_2U(SCH_1):SMB_BMC_SWB_SCL    I43 @S9S_MB_2U_LIB.S9S_MB_2U(SCH_1):PAGE222
     2 SMB_BMC_SWB_R_SCL @S9S_MB_2U_LIB.S9S_MB_2U(SCH_1):SMB_BMC_SWB_R_SCL    I43 @S9S_MB_2U_LIB.S9S_MB_2U(SCH_1):PAGE222

R3106 Q_RES_0402LF-0,5%,1/16W,CHIP,CA
     1 SMB_BMC_SWB_SDA @S9S_MB_2U_LIB.S9S_MB_2U(SCH_1):SMB_BMC_SWB_SDA    I42 @S9S_MB_2U_LIB.S9S_MB_2U(SCH_1):PAGE222
     2 SMB_BMC_SWB_R_SDA @S9S_MB_2U_LIB.S9S_MB_2U(SCH_1):SMB_BMC_SWB_R_SDA    I42 @S9S_MB_2U_LIB.S9S_MB_2U(SCH_1):PAGE222

R3107 Q_RES_0402LF-0,5%,1/16W,CHIP,CA
     1 SMB_2_BMC_GPU_SCL @S9S_MB_2U_LIB.S9S_MB_2U(SCH_1):SMB_2_BMC_GPU_SCL     I8 @S9S_MB_2U_LIB.S9S_MB_2U(SCH_1):PAGE222
     2 SMB_2_BMC_GPU_R_SCL @S9S_MB_2U_LIB.S9S_MB_2U(SCH_1):SMB_2_BMC_GPU_R_SCL     I8 @S9S_MB_2U_LIB.S9S_MB_2U(SCH_1):PAGE222

R3108 Q_RES_0402LF-0,5%,1/16W,CHIP,CA
     1 SMB_2_BMC_GPU_SDA @S9S_MB_2U_LIB.S9S_MB_2U(SCH_1):SMB_2_BMC_GPU_SDA     I7 @S9S_MB_2U_LIB.S9S_MB_2U(SCH_1):PAGE222
     2 SMB_2_BMC_GPU_R_SDA @S9S_MB_2U_LIB.S9S_MB_2U(SCH_1):SMB_2_BMC_GPU_R_SDA     I7 @S9S_MB_2U_LIB.S9S_MB_2U(SCH_1):PAGE222

R3109 Q_RES_0402LF-0,5%,1/16W,CHIP,CA
     1 SMB_1_BMC_GPU_SCL @S9S_MB_2U_LIB.S9S_MB_2U(SCH_1):SMB_1_BMC_GPU_SCL    I51 @S9S_MB_2U_LIB.S9S_MB_2U(SCH_1):PAGE222
     2 SMB_1_BMC_GPU_R_SCL @S9S_MB_2U_LIB.S9S_MB_2U(SCH_1):SMB_1_BMC_GPU_R_SCL    I51 @S9S_MB_2U_LIB.S9S_MB_2U(SCH_1):PAGE222

R3110 Q_RES_0402LF-0,5%,1/16W,CHIP,CA
     1 SMB_1_BMC_GPU_SDA @S9S_MB_2U_LIB.S9S_MB_2U(SCH_1):SMB_1_BMC_GPU_SDA    I52 @S9S_MB_2U_LIB.S9S_MB_2U(SCH_1):PAGE222
     2 SMB_1_BMC_GPU_R_SDA @S9S_MB_2U_LIB.S9S_MB_2U(SCH_1):SMB_1_BMC_GPU_R_SDA    I52 @S9S_MB_2U_LIB.S9S_MB_2U(SCH_1):PAGE222

R3111 Q_RES_0402LF-0,5%,1/16W,CHIP,CA
     1 I3C_BMC_SWB_SDA @S9S_MB_2U_LIB.S9S_MB_2U(SCH_1):I3C_BMC_SWB_SDA    I17 @S9S_MB_2U_LIB.S9S_MB_2U(SCH_1):PAGE222
     2 I3C_BMC_SWB_R_SDA @S9S_MB_2U_LIB.S9S_MB_2U(SCH_1):I3C_BMC_SWB_R_SDA    I17 @S9S_MB_2U_LIB.S9S_MB_2U(SCH_1):PAGE222

R3112 Q_RES_0402LF-33.2,1%,1/16W,CHIA
     1 I3C_BMC_SWB_SCL @S9S_MB_2U_LIB.S9S_MB_2U(SCH_1):I3C_BMC_SWB_SCL    I18 @S9S_MB_2U_LIB.S9S_MB_2U(SCH_1):PAGE222
     2 I3C_BMC_SWB_R_SCL @S9S_MB_2U_LIB.S9S_MB_2U(SCH_1):I3C_BMC_SWB_R_SCL    I18 @S9S_MB_2U_LIB.S9S_MB_2U(SCH_1):PAGE222

R3113 Q_RES_0402LF-33.2,1%,1/16W,CHIA
     1 SMB_FAN_3V3AUX_SCL @S9S_MB_2U_LIB.S9S_MB_2U(SCH_1):SMB_FAN_3V3AUX_SCL     I9 @S9S_MB_2U_LIB.S9S_MB_2U(SCH_1):PAGE233
     2 SMB_FAN_3V3AUX_R_SCL @S9S_MB_2U_LIB.S9S_MB_2U(SCH_1):SMB_FAN_3V3AUX_R_SCL     I9 @S9S_MB_2U_LIB.S9S_MB_2U(SCH_1):PAGE233

R3114 Q_RES_0402LF-33.2,1%,1/16W,CHIA
     1 SMB_FAN_3V3AUX_SDA @S9S_MB_2U_LIB.S9S_MB_2U(SCH_1):SMB_FAN_3V3AUX_SDA     I8 @S9S_MB_2U_LIB.S9S_MB_2U(SCH_1):PAGE233
     2 SMB_FAN_3V3AUX_R_SDA @S9S_MB_2U_LIB.S9S_MB_2U(SCH_1):SMB_FAN_3V3AUX_R_SDA     I8 @S9S_MB_2U_LIB.S9S_MB_2U(SCH_1):PAGE233

R3117 Q_RES_0402LF-510K,5%,1/16W,EMPA
     1 P12V_AUX @S9S_MB_2U_LIB.S9S_MB_2U(SCH_1):P12V_AUX    I78 @S9S_MB_2U_LIB.S9S_MB_2U(SCH_1):PAGE245
     2 P3V3_AUX_EN @S9S_MB_2U_LIB.S9S_MB_2U(SCH_1):P3V3_AUX_EN    I78 @S9S_MB_2U_LIB.S9S_MB_2U(SCH_1):PAGE245

R3118 Q_RES_0402LF-86.6K,1%,1/16W,EMA
     1 P3V3_AUX_EN @S9S_MB_2U_LIB.S9S_MB_2U(SCH_1):P3V3_AUX_EN    I76 @S9S_MB_2U_LIB.S9S_MB_2U(SCH_1):PAGE245
     2    GND @S9S_MB_2U_LIB.S9S_MB_2U(SCH_1):GND    I76 @S9S_MB_2U_LIB.S9S_MB_2U(SCH_1):PAGE245

R3123 Q_RES_0402LF-0,5%,1/16W,CHIP,CA
     1 SMB_S3M_CPU0_PIROM_3V3AUX_SCL_R @S9S_MB_2U_LIB.S9S_MB_2U(SCH_1):SMB_S3M_CPU0_PIROM_3V3AUX_SCL_R   I115 @S9S_MB_2U_LIB.S9S_MB_2U(SCH_1):PAGE224
     2 SMB_S3M_CPU0_PIROM_3V3AUX_SCL @S9S_MB_2U_LIB.S9S_MB_2U(SCH_1):SMB_S3M_CPU0_PIROM_3V3AUX_SCL   I115 @S9S_MB_2U_LIB.S9S_MB_2U(SCH_1):PAGE224

R3124 Q_RES_0402LF-0,5%,1/16W,CHIP,CA
     1 SMB_S3M_CPU0_PIROM_3V3AUX_SDA_R @S9S_MB_2U_LIB.S9S_MB_2U(SCH_1):SMB_S3M_CPU0_PIROM_3V3AUX_SDA_R   I114 @S9S_MB_2U_LIB.S9S_MB_2U(SCH_1):PAGE224
     2 SMB_S3M_CPU0_PIROM_3V3AUX_SDA @S9S_MB_2U_LIB.S9S_MB_2U(SCH_1):SMB_S3M_CPU0_PIROM_3V3AUX_SDA   I114 @S9S_MB_2U_LIB.S9S_MB_2U(SCH_1):PAGE224

R3125 Q_RES_0402LF-0,5%,1/16W,CHIP,CA
     1 SMB_S3M_CPU1_PIROM_3V3AUX_SCL_R @S9S_MB_2U_LIB.S9S_MB_2U(SCH_1):SMB_S3M_CPU1_PIROM_3V3AUX_SCL_R   I116 @S9S_MB_2U_LIB.S9S_MB_2U(SCH_1):PAGE224
     2 SMB_S3M_CPU1_PIROM_3V3AUX_SCL @S9S_MB_2U_LIB.S9S_MB_2U(SCH_1):SMB_S3M_CPU1_PIROM_3V3AUX_SCL   I116 @S9S_MB_2U_LIB.S9S_MB_2U(SCH_1):PAGE224

R3126 Q_RES_0402LF-0,5%,1/16W,CHIP,CA
     1 SMB_S3M_CPU1_PIROM_3V3AUX_SDA_R @S9S_MB_2U_LIB.S9S_MB_2U(SCH_1):SMB_S3M_CPU1_PIROM_3V3AUX_SDA_R   I117 @S9S_MB_2U_LIB.S9S_MB_2U(SCH_1):PAGE224
     2 SMB_S3M_CPU1_PIROM_3V3AUX_SDA @S9S_MB_2U_LIB.S9S_MB_2U(SCH_1):SMB_S3M_CPU1_PIROM_3V3AUX_SDA   I117 @S9S_MB_2U_LIB.S9S_MB_2U(SCH_1):PAGE224

R3127 Q_RES_0402LF-10K,1%,1/16W,CHIPA
     1 P3V3_AUX @S9S_MB_2U_LIB.S9S_MB_2U(SCH_1):P3V3_AUX   I109 @S9S_MB_2U_LIB.S9S_MB_2U(SCH_1):PAGE224
     2 PCA9543_S3M_INT1_N @S9S_MB_2U_LIB.S9S_MB_2U(SCH_1):PCA9543_S3M_INT1_N   I109 @S9S_MB_2U_LIB.S9S_MB_2U(SCH_1):PAGE224

R3130 Q_RES_0402LF-10K,1%,1/16W,CHIPA
     1 P3V3_AUX @S9S_MB_2U_LIB.S9S_MB_2U(SCH_1):P3V3_AUX   I110 @S9S_MB_2U_LIB.S9S_MB_2U(SCH_1):PAGE224
     2 PCA9543_S3M_INT2_N @S9S_MB_2U_LIB.S9S_MB_2U(SCH_1):PCA9543_S3M_INT2_N   I110 @S9S_MB_2U_LIB.S9S_MB_2U(SCH_1):PAGE224

R3131 Q_RES_0402LF-10K,1%,1/16W,CHIPA
     1 P3V3_AUX @S9S_MB_2U_LIB.S9S_MB_2U(SCH_1):P3V3_AUX   I111 @S9S_MB_2U_LIB.S9S_MB_2U(SCH_1):PAGE224
     2 PCA9543_S3M_INT3_N @S9S_MB_2U_LIB.S9S_MB_2U(SCH_1):PCA9543_S3M_INT3_N   I111 @S9S_MB_2U_LIB.S9S_MB_2U(SCH_1):PAGE224

R3132 Q_RES_0402LF-100K,1%,1/16W,CHIA
     1    GND @S9S_MB_2U_LIB.S9S_MB_2U(SCH_1):GND    I35 @S9S_MB_2U_LIB.S9S_MB_2U(SCH_1):PAGE150
     2 FM_OCP_SFF_PWR_GOOD @S9S_MB_2U_LIB.S9S_MB_2U(SCH_1):FM_OCP_SFF_PWR_GOOD    I35 @S9S_MB_2U_LIB.S9S_MB_2U(SCH_1):PAGE150

R3133 Q_RES_0402LF-1K,1%,1/16W,CHIP,A
     1 P3V3_AUX @S9S_MB_2U_LIB.S9S_MB_2U(SCH_1):P3V3_AUX    I11 @S9S_MB_2U_LIB.S9S_MB_2U(SCH_1):PAGE131
     2 OCP_V3_2_PRSNT0_R_N @S9S_MB_2U_LIB.S9S_MB_2U(SCH_1):OCP_V3_2_PRSNT0_R_N    I11 @S9S_MB_2U_LIB.S9S_MB_2U(SCH_1):PAGE131

R3134 Q_RES_0402LF-1K,1%,1/16W,CHIP,A
     1 P3V3_AUX @S9S_MB_2U_LIB.S9S_MB_2U(SCH_1):P3V3_AUX     I3 @S9S_MB_2U_LIB.S9S_MB_2U(SCH_1):PAGE131
     2 OCP_V3_2_PRSNT2_R_N @S9S_MB_2U_LIB.S9S_MB_2U(SCH_1):OCP_V3_2_PRSNT2_R_N     I3 @S9S_MB_2U_LIB.S9S_MB_2U(SCH_1):PAGE131

R3135 Q_RES_0402LF-1K,1%,1/16W,CHIP,A
     1 P3V3_AUX @S9S_MB_2U_LIB.S9S_MB_2U(SCH_1):P3V3_AUX    I13 @S9S_MB_2U_LIB.S9S_MB_2U(SCH_1):PAGE131
     2 OCP_V3_2_PRSNT1_R_N @S9S_MB_2U_LIB.S9S_MB_2U(SCH_1):OCP_V3_2_PRSNT1_R_N    I13 @S9S_MB_2U_LIB.S9S_MB_2U(SCH_1):PAGE131

R3136 Q_RES_0402LF-1K,1%,1/16W,CHIP,A
     1 P3V3_AUX @S9S_MB_2U_LIB.S9S_MB_2U(SCH_1):P3V3_AUX     I5 @S9S_MB_2U_LIB.S9S_MB_2U(SCH_1):PAGE131
     2 OCP_V3_2_PRSNT3_R_N @S9S_MB_2U_LIB.S9S_MB_2U(SCH_1):OCP_V3_2_PRSNT3_R_N     I5 @S9S_MB_2U_LIB.S9S_MB_2U(SCH_1):PAGE131

R3142 Q_RES_0402LF-0,5%,1/16W,CHIP,CA
     1 HP_LVC3_OCP_V3_2_PRSNT2_N_R @S9S_MB_2U_LIB.S9S_MB_2U(SCH_1):HP_LVC3_OCP_V3_2_PRSNT2_N_R    I57 @S9S_MB_2U_LIB.S9S_MB_2U(SCH_1):PAGE131
     2 HP_LVC3_OCP_V3_2_PRSNT2_N @S9S_MB_2U_LIB.S9S_MB_2U(SCH_1):HP_LVC3_OCP_V3_2_PRSNT2_N    I57 @S9S_MB_2U_LIB.S9S_MB_2U(SCH_1):PAGE131

R3143 Q_RES_0402LF-0,5%,1/16W,CHIP,CA
     1 HP_LVC3_OCP_V3_2_PRSNT2_N_R @S9S_MB_2U_LIB.S9S_MB_2U(SCH_1):HP_LVC3_OCP_V3_2_PRSNT2_N_R    I56 @S9S_MB_2U_LIB.S9S_MB_2U(SCH_1):PAGE131
     2 HP_LVC3_OCP_V3_2_ATTN_OUT_SW_N @S9S_MB_2U_LIB.S9S_MB_2U(SCH_1):HP_LVC3_OCP_V3_2_ATTN_OUT_SW_N    I56 @S9S_MB_2U_LIB.S9S_MB_2U(SCH_1):PAGE131

R3144 Q_RES_0402LF-0,5%,1/16W,EMPTY,A
     1 P12V_OCP_PWRGD_1 @S9S_MB_2U_LIB.S9S_MB_2U(SCH_1):P12V_OCP_PWRGD_1    I82 @S9S_MB_2U_LIB.S9S_MB_2U(SCH_1):PAGE153
     2 HP_LVC3_OCP_V3_1_P12V_PWRGD @S9S_MB_2U_LIB.S9S_MB_2U(SCH_1):HP_LVC3_OCP_V3_1_P12V_PWRGD    I82 @S9S_MB_2U_LIB.S9S_MB_2U(SCH_1):PAGE153

R3145 Q_RES_0402LF-10K,1%,1/16W,CHIPA
     1 P3V3_AUX @S9S_MB_2U_LIB.S9S_MB_2U(SCH_1):P3V3_AUX    I64 @S9S_MB_2U_LIB.S9S_MB_2U(SCH_1):PAGE131
     2 HP_LVC3_OCP_V3_2_ATTN_OUT_SW_N @S9S_MB_2U_LIB.S9S_MB_2U(SCH_1):HP_LVC3_OCP_V3_2_ATTN_OUT_SW_N    I64 @S9S_MB_2U_LIB.S9S_MB_2U(SCH_1):PAGE131

R3147 Q_RES_0402LF-10K,1%,1/16W,CHIPA
     1 P3V3_AUX @S9S_MB_2U_LIB.S9S_MB_2U(SCH_1):P3V3_AUX    I66 @S9S_MB_2U_LIB.S9S_MB_2U(SCH_1):PAGE131
     2 HP_LVC3_OCP_V3_2_PRSNT2_N @S9S_MB_2U_LIB.S9S_MB_2U(SCH_1):HP_LVC3_OCP_V3_2_PRSNT2_N    I66 @S9S_MB_2U_LIB.S9S_MB_2U(SCH_1):PAGE131

R3149 Q_RES_0402LF-1K,1%,1/16W,EMPTYA
     1 P3V3_AUX @S9S_MB_2U_LIB.S9S_MB_2U(SCH_1):P3V3_AUX    I29 @S9S_MB_2U_LIB.S9S_MB_2U(SCH_1):PAGE132
     2 PD_SMB_OCP2_HP_ADD2 @S9S_MB_2U_LIB.S9S_MB_2U(SCH_1):PD_SMB_OCP2_HP_ADD2    I29 @S9S_MB_2U_LIB.S9S_MB_2U(SCH_1):PAGE132

R3150 Q_RES_0402LF-1K,1%,1/16W,CHIP,A
     1 PD_SMB_OCP2_HP_ADD2 @S9S_MB_2U_LIB.S9S_MB_2U(SCH_1):PD_SMB_OCP2_HP_ADD2    I25 @S9S_MB_2U_LIB.S9S_MB_2U(SCH_1):PAGE132
     2    GND @S9S_MB_2U_LIB.S9S_MB_2U(SCH_1):GND    I25 @S9S_MB_2U_LIB.S9S_MB_2U(SCH_1):PAGE132

R3151 Q_RES_0402LF-1K,1%,1/16W,EMPTYA
     1 P3V3_AUX @S9S_MB_2U_LIB.S9S_MB_2U(SCH_1):P3V3_AUX    I31 @S9S_MB_2U_LIB.S9S_MB_2U(SCH_1):PAGE132
     2 PD_SMB_OCP2_HP_ADD1 @S9S_MB_2U_LIB.S9S_MB_2U(SCH_1):PD_SMB_OCP2_HP_ADD1    I31 @S9S_MB_2U_LIB.S9S_MB_2U(SCH_1):PAGE132

R3152 Q_RES_0402LF-1K,1%,1/16W,CHIP,A
     1 PD_SMB_OCP2_HP_ADD1 @S9S_MB_2U_LIB.S9S_MB_2U(SCH_1):PD_SMB_OCP2_HP_ADD1    I27 @S9S_MB_2U_LIB.S9S_MB_2U(SCH_1):PAGE132
     2    GND @S9S_MB_2U_LIB.S9S_MB_2U(SCH_1):GND    I27 @S9S_MB_2U_LIB.S9S_MB_2U(SCH_1):PAGE132

R3153 Q_RES_0402LF-1K,1%,1/16W,EMPTYA
     1 P3V3_AUX @S9S_MB_2U_LIB.S9S_MB_2U(SCH_1):P3V3_AUX    I32 @S9S_MB_2U_LIB.S9S_MB_2U(SCH_1):PAGE132
     2 PD_SMB_OCP2_HP_ADD0 @S9S_MB_2U_LIB.S9S_MB_2U(SCH_1):PD_SMB_OCP2_HP_ADD0    I32 @S9S_MB_2U_LIB.S9S_MB_2U(SCH_1):PAGE132

R3154 Q_RES_0402LF-1K,1%,1/16W,CHIP,A
     1 PD_SMB_OCP2_HP_ADD0 @S9S_MB_2U_LIB.S9S_MB_2U(SCH_1):PD_SMB_OCP2_HP_ADD0    I65 @S9S_MB_2U_LIB.S9S_MB_2U(SCH_1):PAGE132
     2    GND @S9S_MB_2U_LIB.S9S_MB_2U(SCH_1):GND    I65 @S9S_MB_2U_LIB.S9S_MB_2U(SCH_1):PAGE132

R3155 Q_RES_0402LF-1K,1%,1/16W,CHIP,A
     1 P3V3_AUX @S9S_MB_2U_LIB.S9S_MB_2U(SCH_1):P3V3_AUX     I7 @S9S_MB_2U_LIB.S9S_MB_2U(SCH_1):PAGE132
     2 HP_LVC3_OCP_V3_2_PRSNT2 @S9S_MB_2U_LIB.S9S_MB_2U(SCH_1):HP_LVC3_OCP_V3_2_PRSNT2     I7 @S9S_MB_2U_LIB.S9S_MB_2U(SCH_1):PAGE132

R3156 Q_RES_0402LF-33.2,1%,1/16W,CHIA
     1 SMB_PEHPCPU1_LVC3_SCL @S9S_MB_2U_LIB.S9S_MB_2U(SCH_1):SMB_PEHPCPU1_LVC3_SCL    I34 @S9S_MB_2U_LIB.S9S_MB_2U(SCH_1):PAGE132
     2 SMB_PEHPCPU1_LVC3_R3_SCL @S9S_MB_2U_LIB.S9S_MB_2U(SCH_1):SMB_PEHPCPU1_LVC3_R3_SCL    I34 @S9S_MB_2U_LIB.S9S_MB_2U(SCH_1):PAGE132

R3157 Q_RES_0402LF-33.2,1%,1/16W,CHIA
     1 SMB_PEHPCPU1_LVC3_SDA @S9S_MB_2U_LIB.S9S_MB_2U(SCH_1):SMB_PEHPCPU1_LVC3_SDA    I33 @S9S_MB_2U_LIB.S9S_MB_2U(SCH_1):PAGE132
     2 SMB_PEHPCPU1_LVC3_R3_SDA @S9S_MB_2U_LIB.S9S_MB_2U(SCH_1):SMB_PEHPCPU1_LVC3_R3_SDA    I33 @S9S_MB_2U_LIB.S9S_MB_2U(SCH_1):PAGE132

R3158 Q_RES_0402LF-33.2,1%,1/16W,CHIA
     1 FM_SMB_CPU1_ALERT @S9S_MB_2U_LIB.S9S_MB_2U(SCH_1):FM_SMB_CPU1_ALERT    I23 @S9S_MB_2U_LIB.S9S_MB_2U(SCH_1):PAGE132
     2 FM_SMB_PEHPCPU1_PCIE_ALERT_N @S9S_MB_2U_LIB.S9S_MB_2U(SCH_1):FM_SMB_PEHPCPU1_PCIE_ALERT_N    I23 @S9S_MB_2U_LIB.S9S_MB_2U(SCH_1):PAGE132

R3160 Q_RES_0402LF-1K,1%,1/16W,EMPTYA
     1 P3V3_AUX @S9S_MB_2U_LIB.S9S_MB_2U(SCH_1):P3V3_AUX   I235 @S9S_MB_2U_LIB.S9S_MB_2U(SCH_1):PAGE154
     2 HP_OCP_V3_1_RST_R @S9S_MB_2U_LIB.S9S_MB_2U(SCH_1):HP_OCP_V3_1_RST_R   I235 @S9S_MB_2U_LIB.S9S_MB_2U(SCH_1):PAGE154

R3162 Q_RES_0402LF-4.7K,1%,1/16W,CHIA
     1 P3V3_OCP_V3_2 @S9S_MB_2U_LIB.S9S_MB_2U(SCH_1):P3V3_OCP_V3_2    I26 @S9S_MB_2U_LIB.S9S_MB_2U(SCH_1):PAGE146
     2 OCP_V3_2_ID0 @S9S_MB_2U_LIB.S9S_MB_2U(SCH_1):OCP_V3_2_ID0    I26 @S9S_MB_2U_LIB.S9S_MB_2U(SCH_1):PAGE146

R3163 Q_RES_0402LF-4.7K,1%,1/16W,EMPA
     1 OCP_V3_2_ID0 @S9S_MB_2U_LIB.S9S_MB_2U(SCH_1):OCP_V3_2_ID0    I25 @S9S_MB_2U_LIB.S9S_MB_2U(SCH_1):PAGE146
     2    GND @S9S_MB_2U_LIB.S9S_MB_2U(SCH_1):GND    I25 @S9S_MB_2U_LIB.S9S_MB_2U(SCH_1):PAGE146

R3164 Q_RES_0402LF-10K,1%,1/16W,CHIPA
     1    GND @S9S_MB_2U_LIB.S9S_MB_2U(SCH_1):GND    I38 @S9S_MB_2U_LIB.S9S_MB_2U(SCH_1):PAGE146
     2 OCP_V3_2_AUX_PWR_EN @S9S_MB_2U_LIB.S9S_MB_2U(SCH_1):OCP_V3_2_AUX_PWR_EN    I38 @S9S_MB_2U_LIB.S9S_MB_2U(SCH_1):PAGE146

R3165 Q_RES_0402LF-10K,1%,1/16W,CHIPA
     1    GND @S9S_MB_2U_LIB.S9S_MB_2U(SCH_1):GND    I37 @S9S_MB_2U_LIB.S9S_MB_2U(SCH_1):PAGE146
     2 OCP_V3_2_MAIN_PWR_EN @S9S_MB_2U_LIB.S9S_MB_2U(SCH_1):OCP_V3_2_MAIN_PWR_EN    I37 @S9S_MB_2U_LIB.S9S_MB_2U(SCH_1):PAGE146

R3166 Q_RES_0402LF-4.7K,1%,1/16W,EMPA
     1 P3V3_OCP_V3_2 @S9S_MB_2U_LIB.S9S_MB_2U(SCH_1):P3V3_OCP_V3_2    I23 @S9S_MB_2U_LIB.S9S_MB_2U(SCH_1):PAGE146
     2 OCP_V3_2_ID1 @S9S_MB_2U_LIB.S9S_MB_2U(SCH_1):OCP_V3_2_ID1    I23 @S9S_MB_2U_LIB.S9S_MB_2U(SCH_1):PAGE146

R3167 Q_RES_0402LF-4.7K,1%,1/16W,CHIA
     1 OCP_V3_2_ID1 @S9S_MB_2U_LIB.S9S_MB_2U(SCH_1):OCP_V3_2_ID1    I20 @S9S_MB_2U_LIB.S9S_MB_2U(SCH_1):PAGE146
     2    GND @S9S_MB_2U_LIB.S9S_MB_2U(SCH_1):GND    I20 @S9S_MB_2U_LIB.S9S_MB_2U(SCH_1):PAGE146

R3168 Q_RES_0402LF-0,5%,1/16W,CHIP,CA
     1 OCP_V3_2_MAIN_PWR_EN @S9S_MB_2U_LIB.S9S_MB_2U(SCH_1):OCP_V3_2_MAIN_PWR_EN     I5 @S9S_MB_2U_LIB.S9S_MB_2U(SCH_1):PAGE146
     2 OCP_V3_2_MAIN_PWR_EN_R @S9S_MB_2U_LIB.S9S_MB_2U(SCH_1):OCP_V3_2_MAIN_PWR_EN_R     I5 @S9S_MB_2U_LIB.S9S_MB_2U(SCH_1):PAGE146

R3169 Q_RES_0402LF-0,5%,1/16W,CHIP,CA
     1 OCP_V3_2_ISO_BIF0_EN @S9S_MB_2U_LIB.S9S_MB_2U(SCH_1):OCP_V3_2_ISO_BIF0_EN    I33 @S9S_MB_2U_LIB.S9S_MB_2U(SCH_1):PAGE146
     2 OCP_V3_2_BIF0_R_N @S9S_MB_2U_LIB.S9S_MB_2U(SCH_1):OCP_V3_2_BIF0_R_N    I33 @S9S_MB_2U_LIB.S9S_MB_2U(SCH_1):PAGE146

R3170 Q_RES_0402LF-0,5%,1/16W,CHIP,CA
     1 OCP_V3_2_ISO_BIF1_EN @S9S_MB_2U_LIB.S9S_MB_2U(SCH_1):OCP_V3_2_ISO_BIF1_EN    I32 @S9S_MB_2U_LIB.S9S_MB_2U(SCH_1):PAGE146
     2 OCP_V3_2_BIF1_R_N @S9S_MB_2U_LIB.S9S_MB_2U(SCH_1):OCP_V3_2_BIF1_R_N    I32 @S9S_MB_2U_LIB.S9S_MB_2U(SCH_1):PAGE146

R3171 Q_RES_0402LF-0,5%,1/16W,CHIP,CA
     1 OCP_V3_2_ISO_BIF2_EN @S9S_MB_2U_LIB.S9S_MB_2U(SCH_1):OCP_V3_2_ISO_BIF2_EN    I31 @S9S_MB_2U_LIB.S9S_MB_2U(SCH_1):PAGE146
     2 OCP_V3_2_BIF2_R_N @S9S_MB_2U_LIB.S9S_MB_2U(SCH_1):OCP_V3_2_BIF2_R_N    I31 @S9S_MB_2U_LIB.S9S_MB_2U(SCH_1):PAGE146

R3172 Q_RES_0402LF-0,5%,1/16W,CHIP,CA
     1 OCP_V3_2_AUX_PWR_EN @S9S_MB_2U_LIB.S9S_MB_2U(SCH_1):OCP_V3_2_AUX_PWR_EN    I36 @S9S_MB_2U_LIB.S9S_MB_2U(SCH_1):PAGE146
     2 OCP_V3_2_AUX_PWR_EN_R @S9S_MB_2U_LIB.S9S_MB_2U(SCH_1):OCP_V3_2_AUX_PWR_EN_R    I36 @S9S_MB_2U_LIB.S9S_MB_2U(SCH_1):PAGE146

R3173 Q_RES_0402LF-1K,1%,1/16W,CHIP,A
     1 SGPIO_OCP_V3_2_LD_N @S9S_MB_2U_LIB.S9S_MB_2U(SCH_1):SGPIO_OCP_V3_2_LD_N   I165 @S9S_MB_2U_LIB.S9S_MB_2U(SCH_1):PAGE146
     2 P3V3_OCP_V3_2 @S9S_MB_2U_LIB.S9S_MB_2U(SCH_1):P3V3_OCP_V3_2   I165 @S9S_MB_2U_LIB.S9S_MB_2U(SCH_1):PAGE146

R3174 Q_RES_0402LF-10K,1%,1/16W,CHIPA
     1 SGPIO_OCP_V3_2_DATAIN @S9S_MB_2U_LIB.S9S_MB_2U(SCH_1):SGPIO_OCP_V3_2_DATAIN   I333 @S9S_MB_2U_LIB.S9S_MB_2U(SCH_1):PAGE146
     2 P3V3_OCP_V3_2 @S9S_MB_2U_LIB.S9S_MB_2U(SCH_1):P3V3_OCP_V3_2   I333 @S9S_MB_2U_LIB.S9S_MB_2U(SCH_1):PAGE146

R3175 Q_RES_0402LF-10K,1%,1/16W,CHIPA
     1 SGPIO_OCP_V3_2_DATAOUT @S9S_MB_2U_LIB.S9S_MB_2U(SCH_1):SGPIO_OCP_V3_2_DATAOUT   I334 @S9S_MB_2U_LIB.S9S_MB_2U(SCH_1):PAGE146
     2    GND @S9S_MB_2U_LIB.S9S_MB_2U(SCH_1):GND   I334 @S9S_MB_2U_LIB.S9S_MB_2U(SCH_1):PAGE146

R3176 Q_RES_0402LF-1K,1%,1/16W,CHIP,A
     1 SGPIO_OCP_V3_2_CLK @S9S_MB_2U_LIB.S9S_MB_2U(SCH_1):SGPIO_OCP_V3_2_CLK   I336 @S9S_MB_2U_LIB.S9S_MB_2U(SCH_1):PAGE146
     2 P3V3_OCP_V3_2 @S9S_MB_2U_LIB.S9S_MB_2U(SCH_1):P3V3_OCP_V3_2   I336 @S9S_MB_2U_LIB.S9S_MB_2U(SCH_1):PAGE146

R3177 Q_RES_0402LF-0,5%,1/16W,CHIP,CA
     1 USB2_5_R1_DN @S9S_MB_2U_LIB.S9S_MB_2U(SCH_1):USB2_5_R1_DN   I148 @S9S_MB_2U_LIB.S9S_MB_2U(SCH_1):PAGE146
     2 USB2_5_DN @S9S_MB_2U_LIB.S9S_MB_2U(SCH_1):USB2_5_DN   I148 @S9S_MB_2U_LIB.S9S_MB_2U(SCH_1):PAGE146

R3178 Q_RES_0402LF-0,5%,1/16W,CHIP,CA
     1 USB2_5_R1_DP @S9S_MB_2U_LIB.S9S_MB_2U(SCH_1):USB2_5_R1_DP   I147 @S9S_MB_2U_LIB.S9S_MB_2U(SCH_1):PAGE146
     2 USB2_5_DP @S9S_MB_2U_LIB.S9S_MB_2U(SCH_1):USB2_5_DP   I147 @S9S_MB_2U_LIB.S9S_MB_2U(SCH_1):PAGE146

R3180 Q_RES_0402LF-100,1%,1/16W,CHIPA
     1 OCP_V3_1_PRSNTA_R_N @S9S_MB_2U_LIB.S9S_MB_2U(SCH_1):OCP_V3_1_PRSNTA_R_N   I152 @S9S_MB_2U_LIB.S9S_MB_2U(SCH_1):PAGE146
     2    GND @S9S_MB_2U_LIB.S9S_MB_2U(SCH_1):GND   I152 @S9S_MB_2U_LIB.S9S_MB_2U(SCH_1):PAGE146

R3181 Q_RES_0402LF-27.4,1%,1/16W,CHIA
     1 CLK_50M_NCSI_OCP_2 @S9S_MB_2U_LIB.S9S_MB_2U(SCH_1):CLK_50M_NCSI_OCP_2    I78 @S9S_MB_2U_LIB.S9S_MB_2U(SCH_1):PAGE152
     2 CLK_50M_NCSI_OCP_V3_2 @S9S_MB_2U_LIB.S9S_MB_2U(SCH_1):CLK_50M_NCSI_OCP_V3_2    I78 @S9S_MB_2U_LIB.S9S_MB_2U(SCH_1):PAGE152

R3182 Q_RES_0402LF-10K,1%,1/16W,CHIPA
     1 P3V3_OCP_V3_2 @S9S_MB_2U_LIB.S9S_MB_2U(SCH_1):P3V3_OCP_V3_2     I6 @S9S_MB_2U_LIB.S9S_MB_2U(SCH_1):PAGE156
     2 IRQ_LVC3_OCP_V3_2_WAKE_N @S9S_MB_2U_LIB.S9S_MB_2U(SCH_1):IRQ_LVC3_OCP_V3_2_WAKE_N     I6 @S9S_MB_2U_LIB.S9S_MB_2U(SCH_1):PAGE156

R3183 Q_RES_0402LF-10K,1%,1/16W,CHIPA
     1 P3V3_OCP_V3_2 @S9S_MB_2U_LIB.S9S_MB_2U(SCH_1):P3V3_OCP_V3_2     I7 @S9S_MB_2U_LIB.S9S_MB_2U(SCH_1):PAGE156
     2 PU_OCP_V3_2_WAKE_OE @S9S_MB_2U_LIB.S9S_MB_2U(SCH_1):PU_OCP_V3_2_WAKE_OE     I7 @S9S_MB_2U_LIB.S9S_MB_2U(SCH_1):PAGE156

R3184 Q_RES_0402LF-4.7K,1%,1/16W,CHIA
     1 P3V3_AUX @S9S_MB_2U_LIB.S9S_MB_2U(SCH_1):P3V3_AUX    I28 @S9S_MB_2U_LIB.S9S_MB_2U(SCH_1):PAGE156
     2 OCP_V3_2_WAKE_BUFF_N @S9S_MB_2U_LIB.S9S_MB_2U(SCH_1):OCP_V3_2_WAKE_BUFF_N    I28 @S9S_MB_2U_LIB.S9S_MB_2U(SCH_1):PAGE156

R3185 Q_RES_0402LF-33.2,1%,1/16W,CHIA
     1 OCP_V3_2_WAKE_BUFF_N @S9S_MB_2U_LIB.S9S_MB_2U(SCH_1):OCP_V3_2_WAKE_BUFF_N    I24 @S9S_MB_2U_LIB.S9S_MB_2U(SCH_1):PAGE156
     2 OCP_V3_2_WAKE_BUFF_R_N @S9S_MB_2U_LIB.S9S_MB_2U(SCH_1):OCP_V3_2_WAKE_BUFF_R_N    I24 @S9S_MB_2U_LIB.S9S_MB_2U(SCH_1):PAGE156

R3186 Q_RES_0402LF-33.2,1%,1/16W,CHIA
     1 RST_OCP_V3_2_BUF_N @S9S_MB_2U_LIB.S9S_MB_2U(SCH_1):RST_OCP_V3_2_BUF_N    I41 @S9S_MB_2U_LIB.S9S_MB_2U(SCH_1):PAGE156
     2 RST_PERST0_OCP_V3_2_N @S9S_MB_2U_LIB.S9S_MB_2U(SCH_1):RST_PERST0_OCP_V3_2_N    I41 @S9S_MB_2U_LIB.S9S_MB_2U(SCH_1):PAGE156

R3187 Q_RES_0402LF-33.2,1%,1/16W,CHIA
     1 RST_OCP_V3_2_BUF_N @S9S_MB_2U_LIB.S9S_MB_2U(SCH_1):RST_OCP_V3_2_BUF_N    I40 @S9S_MB_2U_LIB.S9S_MB_2U(SCH_1):PAGE156
     2 RST_PERST1_OCP_V3_2_N @S9S_MB_2U_LIB.S9S_MB_2U(SCH_1):RST_PERST1_OCP_V3_2_N    I40 @S9S_MB_2U_LIB.S9S_MB_2U(SCH_1):PAGE156

R3188 Q_RES_0402LF-33.2,1%,1/16W,CHIA
     1 RST_OCP_V3_2_BUF_N @S9S_MB_2U_LIB.S9S_MB_2U(SCH_1):RST_OCP_V3_2_BUF_N    I39 @S9S_MB_2U_LIB.S9S_MB_2U(SCH_1):PAGE156
     2 RST_PERST2_OCP_V3_2_N @S9S_MB_2U_LIB.S9S_MB_2U(SCH_1):RST_PERST2_OCP_V3_2_N    I39 @S9S_MB_2U_LIB.S9S_MB_2U(SCH_1):PAGE156

R3189 Q_RES_0402LF-33.2,1%,1/16W,CHIA
     1 RST_OCP_V3_2_BUF_N @S9S_MB_2U_LIB.S9S_MB_2U(SCH_1):RST_OCP_V3_2_BUF_N    I38 @S9S_MB_2U_LIB.S9S_MB_2U(SCH_1):PAGE156
     2 RST_PERST3_OCP_V3_2_N @S9S_MB_2U_LIB.S9S_MB_2U(SCH_1):RST_PERST3_OCP_V3_2_N    I38 @S9S_MB_2U_LIB.S9S_MB_2U(SCH_1):PAGE156

R3190 Q_RES_0402LF-4.7K,1%,1/16W,CHIA
     1 P3V3_AUX @S9S_MB_2U_LIB.S9S_MB_2U(SCH_1):P3V3_AUX    I42 @S9S_MB_2U_LIB.S9S_MB_2U(SCH_1):PAGE156
     2 OCP_V3_2_PWRBRK_BUFF_N @S9S_MB_2U_LIB.S9S_MB_2U(SCH_1):OCP_V3_2_PWRBRK_BUFF_N    I42 @S9S_MB_2U_LIB.S9S_MB_2U(SCH_1):PAGE156

R3191 Q_RES_0402LF-33.2,1%,1/16W,CHIA
     1 OCP_V3_2_PWRBRK_BUFF_N @S9S_MB_2U_LIB.S9S_MB_2U(SCH_1):OCP_V3_2_PWRBRK_BUFF_N    I44 @S9S_MB_2U_LIB.S9S_MB_2U(SCH_1):PAGE156
     2 OCP_V3_2_PWRBRK_N @S9S_MB_2U_LIB.S9S_MB_2U(SCH_1):OCP_V3_2_PWRBRK_N    I44 @S9S_MB_2U_LIB.S9S_MB_2U(SCH_1):PAGE156

R3192 Q_RES_0402LF-4.7K,1%,1/16W,EMPA
     1 P3V3_AUX @S9S_MB_2U_LIB.S9S_MB_2U(SCH_1):P3V3_AUX    I59 @S9S_MB_2U_LIB.S9S_MB_2U(SCH_1):PAGE156
     2 IRQ_LVC3_V3_2_WAKE_BUF_N @S9S_MB_2U_LIB.S9S_MB_2U(SCH_1):IRQ_LVC3_V3_2_WAKE_BUF_N    I59 @S9S_MB_2U_LIB.S9S_MB_2U(SCH_1):PAGE156

R3193 Q_RES_0402LF-33.2,1%,1/16W,CHIA
     1 IRQ_LVC3_V3_2_WAKE_BUF_N @S9S_MB_2U_LIB.S9S_MB_2U(SCH_1):IRQ_LVC3_V3_2_WAKE_BUF_N    I55 @S9S_MB_2U_LIB.S9S_MB_2U(SCH_1):PAGE156
     2 IRQ_LVC3_WAKE_N @S9S_MB_2U_LIB.S9S_MB_2U(SCH_1):IRQ_LVC3_WAKE_N    I55 @S9S_MB_2U_LIB.S9S_MB_2U(SCH_1):PAGE156

R3194 Q_RES_0402LF-22,1%,1/16W,CHIP,A
     1 CLK_100M_OCP_V3_2_A_R_DP @S9S_MB_2U_LIB.S9S_MB_2U(SCH_1):CLK_100M_OCP_V3_2_A_R_DP    I17 @S9S_MB_2U_LIB.S9S_MB_2U(SCH_1):PAGE196
     2 CLK_100M_OCP_V3_2_A_DP @S9S_MB_2U_LIB.S9S_MB_2U(SCH_1):CLK_100M_OCP_V3_2_A_DP    I17 @S9S_MB_2U_LIB.S9S_MB_2U(SCH_1):PAGE196

R3195 Q_RES_0402LF-22,1%,1/16W,CHIP,A
     1 CLK_100M_OCP_V3_2_A_R_DN @S9S_MB_2U_LIB.S9S_MB_2U(SCH_1):CLK_100M_OCP_V3_2_A_R_DN    I16 @S9S_MB_2U_LIB.S9S_MB_2U(SCH_1):PAGE196
     2 CLK_100M_OCP_V3_2_A_DN @S9S_MB_2U_LIB.S9S_MB_2U(SCH_1):CLK_100M_OCP_V3_2_A_DN    I16 @S9S_MB_2U_LIB.S9S_MB_2U(SCH_1):PAGE196

R3196 Q_RES_0402LF-22,1%,1/16W,CHIP,A
     1 CLK_100M_OCP_V3_2_B_R_DP @S9S_MB_2U_LIB.S9S_MB_2U(SCH_1):CLK_100M_OCP_V3_2_B_R_DP    I15 @S9S_MB_2U_LIB.S9S_MB_2U(SCH_1):PAGE196
     2 CLK_100M_OCP_V3_2_B_DP @S9S_MB_2U_LIB.S9S_MB_2U(SCH_1):CLK_100M_OCP_V3_2_B_DP    I15 @S9S_MB_2U_LIB.S9S_MB_2U(SCH_1):PAGE196

R3197 Q_RES_0402LF-22,1%,1/16W,CHIP,A
     1 CLK_100M_OCP_V3_2_B_R_DN @S9S_MB_2U_LIB.S9S_MB_2U(SCH_1):CLK_100M_OCP_V3_2_B_R_DN    I14 @S9S_MB_2U_LIB.S9S_MB_2U(SCH_1):PAGE196
     2 CLK_100M_OCP_V3_2_B_DN @S9S_MB_2U_LIB.S9S_MB_2U(SCH_1):CLK_100M_OCP_V3_2_B_DN    I14 @S9S_MB_2U_LIB.S9S_MB_2U(SCH_1):PAGE196

R3198 Q_RES_0402LF-22,1%,1/16W,CHIP,A
     1 CLK_100M_OCP_V3_2_C_R_DP @S9S_MB_2U_LIB.S9S_MB_2U(SCH_1):CLK_100M_OCP_V3_2_C_R_DP    I13 @S9S_MB_2U_LIB.S9S_MB_2U(SCH_1):PAGE196
     2 CLK_100M_OCP_V3_2_C_DP @S9S_MB_2U_LIB.S9S_MB_2U(SCH_1):CLK_100M_OCP_V3_2_C_DP    I13 @S9S_MB_2U_LIB.S9S_MB_2U(SCH_1):PAGE196

R3199 Q_RES_0402LF-22,1%,1/16W,CHIP,A
     1 CLK_100M_OCP_V3_2_C_R_DN @S9S_MB_2U_LIB.S9S_MB_2U(SCH_1):CLK_100M_OCP_V3_2_C_R_DN    I12 @S9S_MB_2U_LIB.S9S_MB_2U(SCH_1):PAGE196
     2 CLK_100M_OCP_V3_2_C_DN @S9S_MB_2U_LIB.S9S_MB_2U(SCH_1):CLK_100M_OCP_V3_2_C_DN    I12 @S9S_MB_2U_LIB.S9S_MB_2U(SCH_1):PAGE196

R3200 Q_RES_0402LF-22,1%,1/16W,CHIP,A
     1 CLK_100M_OCP_V3_2_D_R_DP @S9S_MB_2U_LIB.S9S_MB_2U(SCH_1):CLK_100M_OCP_V3_2_D_R_DP    I11 @S9S_MB_2U_LIB.S9S_MB_2U(SCH_1):PAGE196
     2 CLK_100M_OCP_V3_2_D_DP @S9S_MB_2U_LIB.S9S_MB_2U(SCH_1):CLK_100M_OCP_V3_2_D_DP    I11 @S9S_MB_2U_LIB.S9S_MB_2U(SCH_1):PAGE196

R3201 Q_RES_0402LF-22,1%,1/16W,CHIP,A
     1 CLK_100M_OCP_V3_2_D_R_DN @S9S_MB_2U_LIB.S9S_MB_2U(SCH_1):CLK_100M_OCP_V3_2_D_R_DN    I10 @S9S_MB_2U_LIB.S9S_MB_2U(SCH_1):PAGE196
     2 CLK_100M_OCP_V3_2_D_DN @S9S_MB_2U_LIB.S9S_MB_2U(SCH_1):CLK_100M_OCP_V3_2_D_DN    I10 @S9S_MB_2U_LIB.S9S_MB_2U(SCH_1):PAGE196

R3203 Q_RES_0402LF-33.2,1%,1/16W,CHIA
     1 OCP_V3_2_AUX_PWR_EN @S9S_MB_2U_LIB.S9S_MB_2U(SCH_1):OCP_V3_2_AUX_PWR_EN    I81 @S9S_MB_2U_LIB.S9S_MB_2U(SCH_1):PAGE307
     2 OCP_V3_2_AUX_PWR_EN_R1 @S9S_MB_2U_LIB.S9S_MB_2U(SCH_1):OCP_V3_2_AUX_PWR_EN_R1    I81 @S9S_MB_2U_LIB.S9S_MB_2U(SCH_1):PAGE307

R3205 Q_RES_0402LF-49.9,1%,1/16W,CHIA
     1 FB_BMC_ISOLATE_R2 @S9S_MB_2U_LIB.S9S_MB_2U(SCH_1):FB_BMC_ISOLATE_R2    I85 @S9S_MB_2U_LIB.S9S_MB_2U(SCH_1):PAGE307
     2 FB_BMC_ISOLATE1 @S9S_MB_2U_LIB.S9S_MB_2U(SCH_1):FB_BMC_ISOLATE1    I85 @S9S_MB_2U_LIB.S9S_MB_2U(SCH_1):PAGE307

R3206 Q_RES_0402LF-0,5%,1/16W,EMPTY,A
     1 FM_NCSI_OCP_V3_2_R_OE @S9S_MB_2U_LIB.S9S_MB_2U(SCH_1):FM_NCSI_OCP_V3_2_R_OE    I12 @S9S_MB_2U_LIB.S9S_MB_2U(SCH_1):PAGE307
     2 FB_BMC_ISOLATE1 @S9S_MB_2U_LIB.S9S_MB_2U(SCH_1):FB_BMC_ISOLATE1    I12 @S9S_MB_2U_LIB.S9S_MB_2U(SCH_1):PAGE307

R3207 Q_RES_0402LF-100K,1%,1/16W,CHIA
     1 FB_BMC_ISOLATE1 @S9S_MB_2U_LIB.S9S_MB_2U(SCH_1):FB_BMC_ISOLATE1    I15 @S9S_MB_2U_LIB.S9S_MB_2U(SCH_1):PAGE307
     2    GND @S9S_MB_2U_LIB.S9S_MB_2U(SCH_1):GND    I15 @S9S_MB_2U_LIB.S9S_MB_2U(SCH_1):PAGE307

R3208 Q_RES_0402LF-100,1%,1/16W,CHIPA
     1 OCP_V3_2_ISO_BIF0_EN @S9S_MB_2U_LIB.S9S_MB_2U(SCH_1):OCP_V3_2_ISO_BIF0_EN    I37 @S9S_MB_2U_LIB.S9S_MB_2U(SCH_1):PAGE307
     2    GND @S9S_MB_2U_LIB.S9S_MB_2U(SCH_1):GND    I37 @S9S_MB_2U_LIB.S9S_MB_2U(SCH_1):PAGE307

R3209 Q_RES_0402LF-22,1%,1/16W,EMPTYA
     1 OCP_V3_2_RBT_ARB_IN_R @S9S_MB_2U_LIB.S9S_MB_2U(SCH_1):OCP_V3_2_RBT_ARB_IN_R    I64 @S9S_MB_2U_LIB.S9S_MB_2U(SCH_1):PAGE307
     2 OCP_V3_2_RBT_ARB_IN @S9S_MB_2U_LIB.S9S_MB_2U(SCH_1):OCP_V3_2_RBT_ARB_IN    I64 @S9S_MB_2U_LIB.S9S_MB_2U(SCH_1):PAGE307

R3210 Q_RES_0402LF-22,1%,1/16W,EMPTYA
     1 NCSI_BMC_CRS_DV_R1 @S9S_MB_2U_LIB.S9S_MB_2U(SCH_1):NCSI_BMC_CRS_DV_R1    I65 @S9S_MB_2U_LIB.S9S_MB_2U(SCH_1):PAGE307
     2 RMII_OCP_BMC_CRSDV @S9S_MB_2U_LIB.S9S_MB_2U(SCH_1):RMII_OCP_BMC_CRSDV    I65 @S9S_MB_2U_LIB.S9S_MB_2U(SCH_1):PAGE307

R3211 Q_RES_0402LF-22,1%,1/16W,EMPTYA
     1 NCSI_BMC_RXD0_R1 @S9S_MB_2U_LIB.S9S_MB_2U(SCH_1):NCSI_BMC_RXD0_R1    I63 @S9S_MB_2U_LIB.S9S_MB_2U(SCH_1):PAGE307
     2 RMII_OCP_BMC_RXD_0 @S9S_MB_2U_LIB.S9S_MB_2U(SCH_1):RMII_OCP_BMC_RXD_0    I63 @S9S_MB_2U_LIB.S9S_MB_2U(SCH_1):PAGE307

R3212 Q_RES_0402LF-22,1%,1/16W,EMPTYA
     1 NCSI_BMC_RXD1_R1 @S9S_MB_2U_LIB.S9S_MB_2U(SCH_1):NCSI_BMC_RXD1_R1    I62 @S9S_MB_2U_LIB.S9S_MB_2U(SCH_1):PAGE307
     2 RMII_OCP_BMC_RXD_1 @S9S_MB_2U_LIB.S9S_MB_2U(SCH_1):RMII_OCP_BMC_RXD_1    I62 @S9S_MB_2U_LIB.S9S_MB_2U(SCH_1):PAGE307

R3213 Q_RES_0402LF-0,5%,1/16W,EMPTY,A
     1 NCSI_BMC_TX_EN_R1 @S9S_MB_2U_LIB.S9S_MB_2U(SCH_1):NCSI_BMC_TX_EN_R1    I61 @S9S_MB_2U_LIB.S9S_MB_2U(SCH_1):PAGE307
     2 RMII_BMC_OCP_TX_EN @S9S_MB_2U_LIB.S9S_MB_2U(SCH_1):RMII_BMC_OCP_TX_EN    I61 @S9S_MB_2U_LIB.S9S_MB_2U(SCH_1):PAGE307

R3214 Q_RES_0402LF-0,5%,1/16W,EMPTY,A
     1 NCSI_BMC_TXD0_R1 @S9S_MB_2U_LIB.S9S_MB_2U(SCH_1):NCSI_BMC_TXD0_R1    I60 @S9S_MB_2U_LIB.S9S_MB_2U(SCH_1):PAGE307
     2 RMII_BMC_OCP_TXD_0 @S9S_MB_2U_LIB.S9S_MB_2U(SCH_1):RMII_BMC_OCP_TXD_0    I60 @S9S_MB_2U_LIB.S9S_MB_2U(SCH_1):PAGE307

R3215 Q_RES_0402LF-0,5%,1/16W,EMPTY,A
     1 NCSI_BMC_TXD1_R1 @S9S_MB_2U_LIB.S9S_MB_2U(SCH_1):NCSI_BMC_TXD1_R1    I56 @S9S_MB_2U_LIB.S9S_MB_2U(SCH_1):PAGE307
     2 RMII_BMC_OCP_TXD_1 @S9S_MB_2U_LIB.S9S_MB_2U(SCH_1):RMII_BMC_OCP_TXD_1    I56 @S9S_MB_2U_LIB.S9S_MB_2U(SCH_1):PAGE307

R3216 Q_RES_0402LF-100,1%,1/16W,CHIPA
     1 OCP_V3_2_ISO_BIF1_EN @S9S_MB_2U_LIB.S9S_MB_2U(SCH_1):OCP_V3_2_ISO_BIF1_EN    I38 @S9S_MB_2U_LIB.S9S_MB_2U(SCH_1):PAGE307
     2    GND @S9S_MB_2U_LIB.S9S_MB_2U(SCH_1):GND    I38 @S9S_MB_2U_LIB.S9S_MB_2U(SCH_1):PAGE307

R3217 Q_RES_0402LF-100,1%,1/16W,CHIPA
     1 OCP_V3_2_ISO_BIF2_EN @S9S_MB_2U_LIB.S9S_MB_2U(SCH_1):OCP_V3_2_ISO_BIF2_EN    I40 @S9S_MB_2U_LIB.S9S_MB_2U(SCH_1):PAGE307
     2    GND @S9S_MB_2U_LIB.S9S_MB_2U(SCH_1):GND    I40 @S9S_MB_2U_LIB.S9S_MB_2U(SCH_1):PAGE307

R3222 Q_RES_0402LF-2K,1%,1/16W,CHIP,A
     1 SMB_S3M_CPU0_PIROM_3V3AUX_SCL @S9S_MB_2U_LIB.S9S_MB_2U(SCH_1):SMB_S3M_CPU0_PIROM_3V3AUX_SCL   I132 @S9S_MB_2U_LIB.S9S_MB_2U(SCH_1):PAGE224
     2 P3V3_AUX @S9S_MB_2U_LIB.S9S_MB_2U(SCH_1):P3V3_AUX   I132 @S9S_MB_2U_LIB.S9S_MB_2U(SCH_1):PAGE224

R3223 Q_RES_0402LF-2K,1%,1/16W,CHIP,A
     1 SMB_S3M_CPU0_PIROM_3V3AUX_SDA @S9S_MB_2U_LIB.S9S_MB_2U(SCH_1):SMB_S3M_CPU0_PIROM_3V3AUX_SDA   I133 @S9S_MB_2U_LIB.S9S_MB_2U(SCH_1):PAGE224
     2 P3V3_AUX @S9S_MB_2U_LIB.S9S_MB_2U(SCH_1):P3V3_AUX   I133 @S9S_MB_2U_LIB.S9S_MB_2U(SCH_1):PAGE224

R3224 Q_RES_0402LF-2K,1%,1/16W,CHIP,A
     1 SMB_S3M_CPU1_PIROM_3V3AUX_SCL @S9S_MB_2U_LIB.S9S_MB_2U(SCH_1):SMB_S3M_CPU1_PIROM_3V3AUX_SCL   I131 @S9S_MB_2U_LIB.S9S_MB_2U(SCH_1):PAGE224
     2 P3V3_AUX @S9S_MB_2U_LIB.S9S_MB_2U(SCH_1):P3V3_AUX   I131 @S9S_MB_2U_LIB.S9S_MB_2U(SCH_1):PAGE224

R3225 Q_RES_0402LF-2K,1%,1/16W,CHIP,A
     1 SMB_S3M_CPU1_PIROM_3V3AUX_SDA @S9S_MB_2U_LIB.S9S_MB_2U(SCH_1):SMB_S3M_CPU1_PIROM_3V3AUX_SDA   I130 @S9S_MB_2U_LIB.S9S_MB_2U(SCH_1):PAGE224
     2 P3V3_AUX @S9S_MB_2U_LIB.S9S_MB_2U(SCH_1):P3V3_AUX   I130 @S9S_MB_2U_LIB.S9S_MB_2U(SCH_1):PAGE224

R3226 Q_RES_0402LF-2.2K,5%,1/16W,EMPA
     1 SMB_1_BMC_GPU_SCL @S9S_MB_2U_LIB.S9S_MB_2U(SCH_1):SMB_1_BMC_GPU_SCL   I251 @S9S_MB_2U_LIB.S9S_MB_2U(SCH_1):PAGE228
     2 P3V3_AUX @S9S_MB_2U_LIB.S9S_MB_2U(SCH_1):P3V3_AUX   I251 @S9S_MB_2U_LIB.S9S_MB_2U(SCH_1):PAGE228

R3227 Q_RES_0402LF-2.2K,5%,1/16W,EMPA
     1 SMB_1_BMC_GPU_SDA @S9S_MB_2U_LIB.S9S_MB_2U(SCH_1):SMB_1_BMC_GPU_SDA   I250 @S9S_MB_2U_LIB.S9S_MB_2U(SCH_1):PAGE228
     2 P3V3_AUX @S9S_MB_2U_LIB.S9S_MB_2U(SCH_1):P3V3_AUX   I250 @S9S_MB_2U_LIB.S9S_MB_2U(SCH_1):PAGE228

R3228 Q_RES_0402LF-200,1%,1/16W,CHIPA
     1 SMB_OCP_V3_2_3V3AUX_BUF_R_SCL @S9S_MB_2U_LIB.S9S_MB_2U(SCH_1):SMB_OCP_V3_2_3V3AUX_BUF_R_SCL   I339 @S9S_MB_2U_LIB.S9S_MB_2U(SCH_1):PAGE146
     2 SMB_OCP_V3_2_3V3AUX_BUF_SCL @S9S_MB_2U_LIB.S9S_MB_2U(SCH_1):SMB_OCP_V3_2_3V3AUX_BUF_SCL   I339 @S9S_MB_2U_LIB.S9S_MB_2U(SCH_1):PAGE146

R3229 Q_RES_0402LF-200,1%,1/16W,CHIPA
     1 SMB_OCP_V3_2_3V3AUX_BUF_R_SDA @S9S_MB_2U_LIB.S9S_MB_2U(SCH_1):SMB_OCP_V3_2_3V3AUX_BUF_R_SDA   I338 @S9S_MB_2U_LIB.S9S_MB_2U(SCH_1):PAGE146
     2 SMB_OCP_V3_2_3V3AUX_BUF_SDA @S9S_MB_2U_LIB.S9S_MB_2U(SCH_1):SMB_OCP_V3_2_3V3AUX_BUF_SDA   I338 @S9S_MB_2U_LIB.S9S_MB_2U(SCH_1):PAGE146

R3230 Q_RES_0402LF-33.2,1%,1/16W,CHIA
     1 FM_OCP_V3_2_PWR_GOOD @S9S_MB_2U_LIB.S9S_MB_2U(SCH_1):FM_OCP_V3_2_PWR_GOOD   I110 @S9S_MB_2U_LIB.S9S_MB_2U(SCH_1):PAGE314
     2 FM_OCP_V3_2_PWR_GOOD_R @S9S_MB_2U_LIB.S9S_MB_2U(SCH_1):FM_OCP_V3_2_PWR_GOOD_R   I110 @S9S_MB_2U_LIB.S9S_MB_2U(SCH_1):PAGE314

R3231 Q_RES_0402LF-33.2,1%,1/16W,CHIA
     1 OCP_SFF_AUX_PWR_EN @S9S_MB_2U_LIB.S9S_MB_2U(SCH_1):OCP_SFF_AUX_PWR_EN     I3 @S9S_MB_2U_LIB.S9S_MB_2U(SCH_1):PAGE151
     2 OCP_SFF_AUX_PWR_EN_R4 @S9S_MB_2U_LIB.S9S_MB_2U(SCH_1):OCP_SFF_AUX_PWR_EN_R4     I3 @S9S_MB_2U_LIB.S9S_MB_2U(SCH_1):PAGE151

R3232 Q_RES_0402LF-100K,1%,1/16W,CHIA
     1 RST_HP_OCP_SFF_R_N @S9S_MB_2U_LIB.S9S_MB_2U(SCH_1):RST_HP_OCP_SFF_R_N    I13 @S9S_MB_2U_LIB.S9S_MB_2U(SCH_1):PAGE151
     2    GND @S9S_MB_2U_LIB.S9S_MB_2U(SCH_1):GND    I13 @S9S_MB_2U_LIB.S9S_MB_2U(SCH_1):PAGE151

R3233 Q_RES_0402LF-0,5%,1/16W,CHIP,CA
     1 RST_HP_OCP_SFF_R_N @S9S_MB_2U_LIB.S9S_MB_2U(SCH_1):RST_HP_OCP_SFF_R_N    I17 @S9S_MB_2U_LIB.S9S_MB_2U(SCH_1):PAGE151
     2 RST_SMB_OCP_SFF_N @S9S_MB_2U_LIB.S9S_MB_2U(SCH_1):RST_SMB_OCP_SFF_N    I17 @S9S_MB_2U_LIB.S9S_MB_2U(SCH_1):PAGE151

R3234 Q_RES_0402LF-33.2,1%,1/16W,CHIA
     1 OCP_V3_2_AUX_PWR_EN @S9S_MB_2U_LIB.S9S_MB_2U(SCH_1):OCP_V3_2_AUX_PWR_EN    I75 @S9S_MB_2U_LIB.S9S_MB_2U(SCH_1):PAGE156
     2 OCP_V3_2_AUX_PWR_EN_R3 @S9S_MB_2U_LIB.S9S_MB_2U(SCH_1):OCP_V3_2_AUX_PWR_EN_R3    I75 @S9S_MB_2U_LIB.S9S_MB_2U(SCH_1):PAGE156

R3235 Q_RES_0402LF-100K,1%,1/16W,CHIA
     1 RST_HP_OCP_V3_2_R_N @S9S_MB_2U_LIB.S9S_MB_2U(SCH_1):RST_HP_OCP_V3_2_R_N    I72 @S9S_MB_2U_LIB.S9S_MB_2U(SCH_1):PAGE156
     2    GND @S9S_MB_2U_LIB.S9S_MB_2U(SCH_1):GND    I72 @S9S_MB_2U_LIB.S9S_MB_2U(SCH_1):PAGE156

R3236 Q_RES_0402LF-0,5%,1/16W,CHIP,CA
     1 RST_HP_OCP_V3_2_R_N @S9S_MB_2U_LIB.S9S_MB_2U(SCH_1):RST_HP_OCP_V3_2_R_N    I70 @S9S_MB_2U_LIB.S9S_MB_2U(SCH_1):PAGE156
     2 RST_SMB_OCP_V3_2_N @S9S_MB_2U_LIB.S9S_MB_2U(SCH_1):RST_SMB_OCP_V3_2_N    I70 @S9S_MB_2U_LIB.S9S_MB_2U(SCH_1):PAGE156

R3237 Q_RES_0402LF-0,5%,1/16W,CHIP,CA
     1 OCP_SFF_RBT_ARB_OUT @S9S_MB_2U_LIB.S9S_MB_2U(SCH_1):OCP_SFF_RBT_ARB_OUT    I80 @S9S_MB_2U_LIB.S9S_MB_2U(SCH_1):PAGE151
     2 OCP_SFF_RBT_ARB_IN_R @S9S_MB_2U_LIB.S9S_MB_2U(SCH_1):OCP_SFF_RBT_ARB_IN_R    I80 @S9S_MB_2U_LIB.S9S_MB_2U(SCH_1):PAGE151

R3238 Q_RES_0402LF-33.2,1%,1/16W,CHIA
     1 SMB_OCP_SFF_3V3AUX_SCL @S9S_MB_2U_LIB.S9S_MB_2U(SCH_1):SMB_OCP_SFF_3V3AUX_SCL   I101 @S9S_MB_2U_LIB.S9S_MB_2U(SCH_1):PAGE227
     2 SMB_OCP_SFF_3V3AUX_SCL_R0 @S9S_MB_2U_LIB.S9S_MB_2U(SCH_1):SMB_OCP_SFF_3V3AUX_SCL_R0   I101 @S9S_MB_2U_LIB.S9S_MB_2U(SCH_1):PAGE227

R3239 Q_RES_0402LF-33.2,1%,1/16W,CHIA
     1 SMB_OCP_SFF_3V3AUX_SDA @S9S_MB_2U_LIB.S9S_MB_2U(SCH_1):SMB_OCP_SFF_3V3AUX_SDA   I102 @S9S_MB_2U_LIB.S9S_MB_2U(SCH_1):PAGE227
     2 SMB_OCP_SFF_3V3AUX_SDA_R0 @S9S_MB_2U_LIB.S9S_MB_2U(SCH_1):SMB_OCP_SFF_3V3AUX_SDA_R0   I102 @S9S_MB_2U_LIB.S9S_MB_2U(SCH_1):PAGE227

R3240 Q_RES_0402LF-2.2K,5%,1/16W,EMPA
     1 SMB_OCP_SFF_3V3AUX_SCL @S9S_MB_2U_LIB.S9S_MB_2U(SCH_1):SMB_OCP_SFF_3V3AUX_SCL   I259 @S9S_MB_2U_LIB.S9S_MB_2U(SCH_1):PAGE228
     2 P3V3_AUX @S9S_MB_2U_LIB.S9S_MB_2U(SCH_1):P3V3_AUX   I259 @S9S_MB_2U_LIB.S9S_MB_2U(SCH_1):PAGE228

R3241 Q_RES_0402LF-2.2K,5%,1/16W,EMPA
     1 SMB_OCP_SFF_3V3AUX_SDA @S9S_MB_2U_LIB.S9S_MB_2U(SCH_1):SMB_OCP_SFF_3V3AUX_SDA   I258 @S9S_MB_2U_LIB.S9S_MB_2U(SCH_1):PAGE228
     2 P3V3_AUX @S9S_MB_2U_LIB.S9S_MB_2U(SCH_1):P3V3_AUX   I258 @S9S_MB_2U_LIB.S9S_MB_2U(SCH_1):PAGE228

R3242 Q_RES_0402LF-2.2K,5%,1/16W,EMPA
     1 SMB_OCP_V3_2_3V3AUX_SCL @S9S_MB_2U_LIB.S9S_MB_2U(SCH_1):SMB_OCP_V3_2_3V3AUX_SCL   I260 @S9S_MB_2U_LIB.S9S_MB_2U(SCH_1):PAGE228
     2 P3V3_AUX @S9S_MB_2U_LIB.S9S_MB_2U(SCH_1):P3V3_AUX   I260 @S9S_MB_2U_LIB.S9S_MB_2U(SCH_1):PAGE228

R3243 Q_RES_0402LF-2.2K,5%,1/16W,EMPA
     1 SMB_OCP_V3_2_3V3AUX_SDA @S9S_MB_2U_LIB.S9S_MB_2U(SCH_1):SMB_OCP_V3_2_3V3AUX_SDA   I261 @S9S_MB_2U_LIB.S9S_MB_2U(SCH_1):PAGE228
     2 P3V3_AUX @S9S_MB_2U_LIB.S9S_MB_2U(SCH_1):P3V3_AUX   I261 @S9S_MB_2U_LIB.S9S_MB_2U(SCH_1):PAGE228

R3244 Q_RES_0402LF-0,5%,1/16W,CHIP,CA
     1 OCP_V3_2_RBT_ARB_OUT @S9S_MB_2U_LIB.S9S_MB_2U(SCH_1):OCP_V3_2_RBT_ARB_OUT    I79 @S9S_MB_2U_LIB.S9S_MB_2U(SCH_1):PAGE307
     2 OCP_V3_2_RBT_ARB_IN_R @S9S_MB_2U_LIB.S9S_MB_2U(SCH_1):OCP_V3_2_RBT_ARB_IN_R    I79 @S9S_MB_2U_LIB.S9S_MB_2U(SCH_1):PAGE307

R3249 Q_RES_0402LF-10K,1%,1/16W,CHIPA
     1 P3V3_AUX @S9S_MB_2U_LIB.S9S_MB_2U(SCH_1):P3V3_AUX    I29 @S9S_MB_2U_LIB.S9S_MB_2U(SCH_1):PAGE311
     2 PU_FPGA_D12_PROGRAMN @S9S_MB_2U_LIB.S9S_MB_2U(SCH_1):PU_FPGA_D12_PROGRAMN    I29 @S9S_MB_2U_LIB.S9S_MB_2U(SCH_1):PAGE311

R3254 Q_RES_0402LF-0,5%,1/16W,EMPTY,A
     1 TP_PCIE_HPM_TXP<3> @S9S_MB_2U_LIB.S9S_MB_2U(SCH_1):TP_PCIE_HPM_TXP(3)    I49 @S9S_MB_2U_LIB.S9S_MB_2U(SCH_1):PAGE227
     2 LED_HDD_ACTIVITY_B_N @S9S_MB_2U_LIB.S9S_MB_2U(SCH_1):LED_HDD_ACTIVITY_B_N    I49 @S9S_MB_2U_LIB.S9S_MB_2U(SCH_1):PAGE227

R3263 Q_RES_0402LF-0,5%,1/16W,CHIP,CA
     1 HP_LVC3_OCP_V3_1_R_EN @S9S_MB_2U_LIB.S9S_MB_2U(SCH_1):HP_LVC3_OCP_V3_1_R_EN    I21 @S9S_MB_2U_LIB.S9S_MB_2U(SCH_1):PAGE216
     2 HP_LVC3_OCP_V3_1_EN @S9S_MB_2U_LIB.S9S_MB_2U(SCH_1):HP_LVC3_OCP_V3_1_EN    I21 @S9S_MB_2U_LIB.S9S_MB_2U(SCH_1):PAGE216

R3264 Q_RES_0402LF-0,5%,1/16W,CHIP,CA
     1 HP_LVC3_OCP_V3_2_R_EN @S9S_MB_2U_LIB.S9S_MB_2U(SCH_1):HP_LVC3_OCP_V3_2_R_EN     I7 @S9S_MB_2U_LIB.S9S_MB_2U(SCH_1):PAGE216
     2 HP_LVC3_OCP_V3_2_EN @S9S_MB_2U_LIB.S9S_MB_2U(SCH_1):HP_LVC3_OCP_V3_2_EN     I7 @S9S_MB_2U_LIB.S9S_MB_2U(SCH_1):PAGE216

R3265 Q_RES_0402LF-4.7K,1%,1/16W,EMPA
     1 CLK_GEN2_GPU_FPGA_OE_OR_N @S9S_MB_2U_LIB.S9S_MB_2U(SCH_1):CLK_GEN2_GPU_FPGA_OE_OR_N    I84 @S9S_MB_2U_LIB.S9S_MB_2U(SCH_1):PAGE136
     2    GND @S9S_MB_2U_LIB.S9S_MB_2U(SCH_1):GND    I84 @S9S_MB_2U_LIB.S9S_MB_2U(SCH_1):PAGE136

R3266 Q_RES_0402LF-4.7K,1%,1/16W,CHIA
     1 P3V3_AUX @S9S_MB_2U_LIB.S9S_MB_2U(SCH_1):P3V3_AUX    I89 @S9S_MB_2U_LIB.S9S_MB_2U(SCH_1):PAGE136
     2 FM_P2E_MODE @S9S_MB_2U_LIB.S9S_MB_2U(SCH_1):FM_P2E_MODE    I89 @S9S_MB_2U_LIB.S9S_MB_2U(SCH_1):PAGE136

R3267 Q_RES_0402LF-68K,1%,1/16W,EMPTA
     1 FM_P2E_FGB @S9S_MB_2U_LIB.S9S_MB_2U(SCH_1):FM_P2E_FGB    I12 @S9S_MB_2U_LIB.S9S_MB_2U(SCH_1):PAGE136
     2    GND @S9S_MB_2U_LIB.S9S_MB_2U(SCH_1):GND    I12 @S9S_MB_2U_LIB.S9S_MB_2U(SCH_1):PAGE136

R3268 Q_RES_0402LF-68K,1%,1/16W,EMPTA
     1 FM_P2E_EQA1 @S9S_MB_2U_LIB.S9S_MB_2U(SCH_1):FM_P2E_EQA1     I2 @S9S_MB_2U_LIB.S9S_MB_2U(SCH_1):PAGE136
     2    GND @S9S_MB_2U_LIB.S9S_MB_2U(SCH_1):GND     I2 @S9S_MB_2U_LIB.S9S_MB_2U(SCH_1):PAGE136

R3269 Q_RES_0402LF-1K,1%,1/16W,EMPTYA
     1 P3V3_AUX @S9S_MB_2U_LIB.S9S_MB_2U(SCH_1):P3V3_AUX    I15 @S9S_MB_2U_LIB.S9S_MB_2U(SCH_1):PAGE136
     2 FM_P2E_FGB @S9S_MB_2U_LIB.S9S_MB_2U(SCH_1):FM_P2E_FGB    I15 @S9S_MB_2U_LIB.S9S_MB_2U(SCH_1):PAGE136

R3270 Q_RES_0402LF-1K,1%,1/16W,EMPTYA
     1 FM_P2E_FGB @S9S_MB_2U_LIB.S9S_MB_2U(SCH_1):FM_P2E_FGB    I14 @S9S_MB_2U_LIB.S9S_MB_2U(SCH_1):PAGE136
     2    GND @S9S_MB_2U_LIB.S9S_MB_2U(SCH_1):GND    I14 @S9S_MB_2U_LIB.S9S_MB_2U(SCH_1):PAGE136

R3271 Q_RES_0402LF-1K,1%,1/16W,EMPTYA
     1 P3V3_AUX @S9S_MB_2U_LIB.S9S_MB_2U(SCH_1):P3V3_AUX     I9 @S9S_MB_2U_LIB.S9S_MB_2U(SCH_1):PAGE136
     2 FM_P2E_EQA1 @S9S_MB_2U_LIB.S9S_MB_2U(SCH_1):FM_P2E_EQA1     I9 @S9S_MB_2U_LIB.S9S_MB_2U(SCH_1):PAGE136

R3272 Q_RES_0402LF-1K,1%,1/16W,EMPTYA
     1 FM_P2E_EQA1 @S9S_MB_2U_LIB.S9S_MB_2U(SCH_1):FM_P2E_EQA1     I4 @S9S_MB_2U_LIB.S9S_MB_2U(SCH_1):PAGE136
     2    GND @S9S_MB_2U_LIB.S9S_MB_2U(SCH_1):GND     I4 @S9S_MB_2U_LIB.S9S_MB_2U(SCH_1):PAGE136

R3273 Q_RES_0402LF-68K,1%,1/16W,EMPTA
     1 FM_P2E_FGA @S9S_MB_2U_LIB.S9S_MB_2U(SCH_1):FM_P2E_FGA    I18 @S9S_MB_2U_LIB.S9S_MB_2U(SCH_1):PAGE136
     2    GND @S9S_MB_2U_LIB.S9S_MB_2U(SCH_1):GND    I18 @S9S_MB_2U_LIB.S9S_MB_2U(SCH_1):PAGE136

R3274 Q_RES_0402LF-68K,1%,1/16W,EMPTA
     1 FM_P2E_EQA0 @S9S_MB_2U_LIB.S9S_MB_2U(SCH_1):FM_P2E_EQA0     I6 @S9S_MB_2U_LIB.S9S_MB_2U(SCH_1):PAGE136
     2    GND @S9S_MB_2U_LIB.S9S_MB_2U(SCH_1):GND     I6 @S9S_MB_2U_LIB.S9S_MB_2U(SCH_1):PAGE136

R3275 Q_RES_0402LF-1K,1%,1/16W,EMPTYA
     1 P3V3_AUX @S9S_MB_2U_LIB.S9S_MB_2U(SCH_1):P3V3_AUX    I21 @S9S_MB_2U_LIB.S9S_MB_2U(SCH_1):PAGE136
     2 FM_P2E_FGA @S9S_MB_2U_LIB.S9S_MB_2U(SCH_1):FM_P2E_FGA    I21 @S9S_MB_2U_LIB.S9S_MB_2U(SCH_1):PAGE136

R3276 Q_RES_0402LF-1K,1%,1/16W,EMPTYA
     1 FM_P2E_FGA @S9S_MB_2U_LIB.S9S_MB_2U(SCH_1):FM_P2E_FGA    I20 @S9S_MB_2U_LIB.S9S_MB_2U(SCH_1):PAGE136
     2    GND @S9S_MB_2U_LIB.S9S_MB_2U(SCH_1):GND    I20 @S9S_MB_2U_LIB.S9S_MB_2U(SCH_1):PAGE136

R3277 Q_RES_0402LF-1K,1%,1/16W,EMPTYA
     1 P3V3_AUX @S9S_MB_2U_LIB.S9S_MB_2U(SCH_1):P3V3_AUX    I16 @S9S_MB_2U_LIB.S9S_MB_2U(SCH_1):PAGE136
     2 FM_P2E_EQA0 @S9S_MB_2U_LIB.S9S_MB_2U(SCH_1):FM_P2E_EQA0    I16 @S9S_MB_2U_LIB.S9S_MB_2U(SCH_1):PAGE136

R3278 Q_RES_0402LF-1K,1%,1/16W,CHIP,A
     1 FM_P2E_EQA0 @S9S_MB_2U_LIB.S9S_MB_2U(SCH_1):FM_P2E_EQA0     I8 @S9S_MB_2U_LIB.S9S_MB_2U(SCH_1):PAGE136
     2    GND @S9S_MB_2U_LIB.S9S_MB_2U(SCH_1):GND     I8 @S9S_MB_2U_LIB.S9S_MB_2U(SCH_1):PAGE136

R3279 Q_RES_0402LF-68K,1%,1/16W,EMPTA
     1 FM_P2E_EQB1 @S9S_MB_2U_LIB.S9S_MB_2U(SCH_1):FM_P2E_EQB1    I23 @S9S_MB_2U_LIB.S9S_MB_2U(SCH_1):PAGE136
     2    GND @S9S_MB_2U_LIB.S9S_MB_2U(SCH_1):GND    I23 @S9S_MB_2U_LIB.S9S_MB_2U(SCH_1):PAGE136

R3280 Q_RES_0402LF-1K,1%,1/16W,EMPTYA
     1 P3V3_AUX @S9S_MB_2U_LIB.S9S_MB_2U(SCH_1):P3V3_AUX    I32 @S9S_MB_2U_LIB.S9S_MB_2U(SCH_1):PAGE136
     2 FM_P2E_EQB1 @S9S_MB_2U_LIB.S9S_MB_2U(SCH_1):FM_P2E_EQB1    I32 @S9S_MB_2U_LIB.S9S_MB_2U(SCH_1):PAGE136

R3281 Q_RES_0402LF-1K,1%,1/16W,EMPTYA
     1 FM_P2E_EQB1 @S9S_MB_2U_LIB.S9S_MB_2U(SCH_1):FM_P2E_EQB1    I25 @S9S_MB_2U_LIB.S9S_MB_2U(SCH_1):PAGE136
     2    GND @S9S_MB_2U_LIB.S9S_MB_2U(SCH_1):GND    I25 @S9S_MB_2U_LIB.S9S_MB_2U(SCH_1):PAGE136

R3282 Q_RES_0402LF-68K,1%,1/16W,EMPTA
     1 FM_P2E_EQB0 @S9S_MB_2U_LIB.S9S_MB_2U(SCH_1):FM_P2E_EQB0    I27 @S9S_MB_2U_LIB.S9S_MB_2U(SCH_1):PAGE136
     2    GND @S9S_MB_2U_LIB.S9S_MB_2U(SCH_1):GND    I27 @S9S_MB_2U_LIB.S9S_MB_2U(SCH_1):PAGE136

R3283 Q_RES_0402LF-1K,1%,1/16W,EMPTYA
     1 P3V3_AUX @S9S_MB_2U_LIB.S9S_MB_2U(SCH_1):P3V3_AUX    I57 @S9S_MB_2U_LIB.S9S_MB_2U(SCH_1):PAGE136
     2 FM_P2E_EQB0 @S9S_MB_2U_LIB.S9S_MB_2U(SCH_1):FM_P2E_EQB0    I57 @S9S_MB_2U_LIB.S9S_MB_2U(SCH_1):PAGE136

R3284 Q_RES_0402LF-1K,1%,1/16W,CHIP,A
     1 FM_P2E_EQB0 @S9S_MB_2U_LIB.S9S_MB_2U(SCH_1):FM_P2E_EQB0    I56 @S9S_MB_2U_LIB.S9S_MB_2U(SCH_1):PAGE136
     2    GND @S9S_MB_2U_LIB.S9S_MB_2U(SCH_1):GND    I56 @S9S_MB_2U_LIB.S9S_MB_2U(SCH_1):PAGE136

R3285 Q_RES_0402LF-68K,1%,1/16W,EMPTA
     1 FM_P2E_SWB @S9S_MB_2U_LIB.S9S_MB_2U(SCH_1):FM_P2E_SWB    I61 @S9S_MB_2U_LIB.S9S_MB_2U(SCH_1):PAGE136
     2    GND @S9S_MB_2U_LIB.S9S_MB_2U(SCH_1):GND    I61 @S9S_MB_2U_LIB.S9S_MB_2U(SCH_1):PAGE136

R3286 Q_RES_0402LF-1K,1%,1/16W,EMPTYA
     1 P3V3_AUX @S9S_MB_2U_LIB.S9S_MB_2U(SCH_1):P3V3_AUX    I64 @S9S_MB_2U_LIB.S9S_MB_2U(SCH_1):PAGE136
     2 FM_P2E_SWB @S9S_MB_2U_LIB.S9S_MB_2U(SCH_1):FM_P2E_SWB    I64 @S9S_MB_2U_LIB.S9S_MB_2U(SCH_1):PAGE136

R3287 Q_RES_0402LF-1K,1%,1/16W,EMPTYA
     1 FM_P2E_SWB @S9S_MB_2U_LIB.S9S_MB_2U(SCH_1):FM_P2E_SWB    I63 @S9S_MB_2U_LIB.S9S_MB_2U(SCH_1):PAGE136
     2    GND @S9S_MB_2U_LIB.S9S_MB_2U(SCH_1):GND    I63 @S9S_MB_2U_LIB.S9S_MB_2U(SCH_1):PAGE136

R3288 Q_RES_0402LF-68K,1%,1/16W,EMPTA
     1 FM_P2E_SWA @S9S_MB_2U_LIB.S9S_MB_2U(SCH_1):FM_P2E_SWA    I66 @S9S_MB_2U_LIB.S9S_MB_2U(SCH_1):PAGE136
     2    GND @S9S_MB_2U_LIB.S9S_MB_2U(SCH_1):GND    I66 @S9S_MB_2U_LIB.S9S_MB_2U(SCH_1):PAGE136

R3289 Q_RES_0402LF-1K,1%,1/16W,EMPTYA
     1 P3V3_AUX @S9S_MB_2U_LIB.S9S_MB_2U(SCH_1):P3V3_AUX    I69 @S9S_MB_2U_LIB.S9S_MB_2U(SCH_1):PAGE136
     2 FM_P2E_SWA @S9S_MB_2U_LIB.S9S_MB_2U(SCH_1):FM_P2E_SWA    I69 @S9S_MB_2U_LIB.S9S_MB_2U(SCH_1):PAGE136

R3290 Q_RES_0402LF-1K,1%,1/16W,EMPTYA
     1 FM_P2E_SWA @S9S_MB_2U_LIB.S9S_MB_2U(SCH_1):FM_P2E_SWA    I68 @S9S_MB_2U_LIB.S9S_MB_2U(SCH_1):PAGE136
     2    GND @S9S_MB_2U_LIB.S9S_MB_2U(SCH_1):GND    I68 @S9S_MB_2U_LIB.S9S_MB_2U(SCH_1):PAGE136

R3291 Q_RES_0402LF-4.7K,1%,1/16W,EMPA
     1 PU_TEST @S9S_MB_2U_LIB.S9S_MB_2U(SCH_1):PU_TEST    I82 @S9S_MB_2U_LIB.S9S_MB_2U(SCH_1):PAGE136
     2    GND @S9S_MB_2U_LIB.S9S_MB_2U(SCH_1):GND    I82 @S9S_MB_2U_LIB.S9S_MB_2U(SCH_1):PAGE136

R3292 Q_RES_0402LF-4.7K,1%,1/16W,CHIA
     1 P3V3_AUX @S9S_MB_2U_LIB.S9S_MB_2U(SCH_1):P3V3_AUX    I85 @S9S_MB_2U_LIB.S9S_MB_2U(SCH_1):PAGE136
     2 CLK_GEN2_GPU_FPGA_OE_OR_N @S9S_MB_2U_LIB.S9S_MB_2U(SCH_1):CLK_GEN2_GPU_FPGA_OE_OR_N    I85 @S9S_MB_2U_LIB.S9S_MB_2U(SCH_1):PAGE136

R3293 Q_RES_0402LF-4.7K,1%,1/16W,EMPA
     1 FM_P2E_MODE @S9S_MB_2U_LIB.S9S_MB_2U(SCH_1):FM_P2E_MODE    I88 @S9S_MB_2U_LIB.S9S_MB_2U(SCH_1):PAGE136
     2    GND @S9S_MB_2U_LIB.S9S_MB_2U(SCH_1):GND    I88 @S9S_MB_2U_LIB.S9S_MB_2U(SCH_1):PAGE136

R3294 Q_RES_0402LF-0,5%,1/16W,CHIP,CA
     1 LED_M2_SSD_0_ACT_N @S9S_MB_2U_LIB.S9S_MB_2U(SCH_1):LED_M2_SSD_0_ACT_N   I320 @S9S_MB_2U_LIB.S9S_MB_2U(SCH_1):PAGE182
     2 LED_HDD_ACTIVITY_N @S9S_MB_2U_LIB.S9S_MB_2U(SCH_1):LED_HDD_ACTIVITY_N   I320 @S9S_MB_2U_LIB.S9S_MB_2U(SCH_1):PAGE182

R3295 Q_RES_0402LF-4.7K,1%,1/16W,CHIA
     1 P3V3_M2_0 @S9S_MB_2U_LIB.S9S_MB_2U(SCH_1):P3V3_M2_0   I317 @S9S_MB_2U_LIB.S9S_MB_2U(SCH_1):PAGE182
     2 LED_HDD_ACTIVITY_N @S9S_MB_2U_LIB.S9S_MB_2U(SCH_1):LED_HDD_ACTIVITY_N   I317 @S9S_MB_2U_LIB.S9S_MB_2U(SCH_1):PAGE182

R3296 Q_RES_0402LF-4.7K,1%,1/16W,CHIA
     1 P3V3_AUX @S9S_MB_2U_LIB.S9S_MB_2U(SCH_1):P3V3_AUX   I324 @S9S_MB_2U_LIB.S9S_MB_2U(SCH_1):PAGE182
     2 HDD_ACTIVITY_BUF @S9S_MB_2U_LIB.S9S_MB_2U(SCH_1):HDD_ACTIVITY_BUF   I324 @S9S_MB_2U_LIB.S9S_MB_2U(SCH_1):PAGE182

R3297 Q_RES_0402LF-10K,1%,1/16W,CHIPA
     1 LED_HDD_ACTIVITY_B_N @S9S_MB_2U_LIB.S9S_MB_2U(SCH_1):LED_HDD_ACTIVITY_B_N   I303 @S9S_MB_2U_LIB.S9S_MB_2U(SCH_1):PAGE182
     2    GND @S9S_MB_2U_LIB.S9S_MB_2U(SCH_1):GND   I303 @S9S_MB_2U_LIB.S9S_MB_2U(SCH_1):PAGE182

R3298 Q_RES_0402LF-10K,1%,1/16W,CHIPA
     1 P3V3_AUX @S9S_MB_2U_LIB.S9S_MB_2U(SCH_1):P3V3_AUX   I306 @S9S_MB_2U_LIB.S9S_MB_2U(SCH_1):PAGE182
     2 HDD_ACTIVITY_BUF_N @S9S_MB_2U_LIB.S9S_MB_2U(SCH_1):HDD_ACTIVITY_BUF_N   I306 @S9S_MB_2U_LIB.S9S_MB_2U(SCH_1):PAGE182

R3301 Q_RES_0402LF-33.2,1%,1/16W,CHIA
     1 IRQ_LVC3_WAKE_N @S9S_MB_2U_LIB.S9S_MB_2U(SCH_1):IRQ_LVC3_WAKE_N   I299 @S9S_MB_2U_LIB.S9S_MB_2U(SCH_1):PAGE182
     2 M2_0_PEWAKE_N @S9S_MB_2U_LIB.S9S_MB_2U(SCH_1):M2_0_PEWAKE_N   I299 @S9S_MB_2U_LIB.S9S_MB_2U(SCH_1):PAGE182

R3302 Q_RES_0402LF-0,5%,1/16W,EMPTY,A
     1 TP_PCIE_HPM_TXN<3> @S9S_MB_2U_LIB.S9S_MB_2U(SCH_1):TP_PCIE_HPM_TXN(3)    I48 @S9S_MB_2U_LIB.S9S_MB_2U(SCH_1):PAGE227
     2 FM_PCH_SPKR @S9S_MB_2U_LIB.S9S_MB_2U(SCH_1):FM_PCH_SPKR    I48 @S9S_MB_2U_LIB.S9S_MB_2U(SCH_1):PAGE227

R3303 Q_RES_0402LF-0,5%,1/16W,CHIP,CA
     1 OCP_SFF_PRSNT_ALL_R_N @S9S_MB_2U_LIB.S9S_MB_2U(SCH_1):OCP_SFF_PRSNT_ALL_R_N    I44 @S9S_MB_2U_LIB.S9S_MB_2U(SCH_1):PAGE170
     2 OCP_SFF_PRSNT_ALL_R1_N @S9S_MB_2U_LIB.S9S_MB_2U(SCH_1):OCP_SFF_PRSNT_ALL_R1_N    I44 @S9S_MB_2U_LIB.S9S_MB_2U(SCH_1):PAGE170

R3304 Q_RES_0402LF-0,5%,1/16W,CHIP,CA
     1 OCP_SFF_PRSNT_ALL_R_N @S9S_MB_2U_LIB.S9S_MB_2U(SCH_1):OCP_SFF_PRSNT_ALL_R_N    I45 @S9S_MB_2U_LIB.S9S_MB_2U(SCH_1):PAGE170
     2 OCP_SFF_PRSNT_ALL_R3_N @S9S_MB_2U_LIB.S9S_MB_2U(SCH_1):OCP_SFF_PRSNT_ALL_R3_N    I45 @S9S_MB_2U_LIB.S9S_MB_2U(SCH_1):PAGE170

R3305 Q_RES_0402LF-0,5%,1/16W,CHIP,CA
     1 OCP_SFF_RBT_ARB_IN_MUX1 @S9S_MB_2U_LIB.S9S_MB_2U(SCH_1):OCP_SFF_RBT_ARB_IN_MUX1    I50 @S9S_MB_2U_LIB.S9S_MB_2U(SCH_1):PAGE170
     2 OCP_SFF_RBT_ARB_IN_MUX1_R @S9S_MB_2U_LIB.S9S_MB_2U(SCH_1):OCP_SFF_RBT_ARB_IN_MUX1_R    I50 @S9S_MB_2U_LIB.S9S_MB_2U(SCH_1):PAGE170

R3306 Q_RES_0402LF-0,5%,1/16W,CHIP,CA
     1 OCP_V3_2_PRSNT_ALL_R_N @S9S_MB_2U_LIB.S9S_MB_2U(SCH_1):OCP_V3_2_PRSNT_ALL_R_N    I47 @S9S_MB_2U_LIB.S9S_MB_2U(SCH_1):PAGE170
     2 OCP_V3_2_PRSNT_ALL_R3_N @S9S_MB_2U_LIB.S9S_MB_2U(SCH_1):OCP_V3_2_PRSNT_ALL_R3_N    I47 @S9S_MB_2U_LIB.S9S_MB_2U(SCH_1):PAGE170

R3307 Q_RES_0402LF-0,5%,1/16W,CHIP,CA
     1 OCP_SFF_RBT_ARB_IN_MUX2 @S9S_MB_2U_LIB.S9S_MB_2U(SCH_1):OCP_SFF_RBT_ARB_IN_MUX2    I52 @S9S_MB_2U_LIB.S9S_MB_2U(SCH_1):PAGE170
     2 OCP_SFF_RBT_ARB_IN_MUX2_R @S9S_MB_2U_LIB.S9S_MB_2U(SCH_1):OCP_SFF_RBT_ARB_IN_MUX2_R    I52 @S9S_MB_2U_LIB.S9S_MB_2U(SCH_1):PAGE170

R3308 Q_RES_0402LF-0,5%,1/16W,CHIP,CA
     1 OCP_V3_2_PRSNT_ALL_R_N @S9S_MB_2U_LIB.S9S_MB_2U(SCH_1):OCP_V3_2_PRSNT_ALL_R_N    I46 @S9S_MB_2U_LIB.S9S_MB_2U(SCH_1):PAGE170
     2 OCP_V3_2_PRSNT_ALL_R1_N @S9S_MB_2U_LIB.S9S_MB_2U(SCH_1):OCP_V3_2_PRSNT_ALL_R1_N    I46 @S9S_MB_2U_LIB.S9S_MB_2U(SCH_1):PAGE170

R3315 Q_RES_0402LF-49.9,1%,1/16W,CHIA
     1 GPU_FPGA_RST_R1_BUF_N @S9S_MB_2U_LIB.S9S_MB_2U(SCH_1):GPU_FPGA_RST_R1_BUF_N   I205 @S9S_MB_2U_LIB.S9S_MB_2U(SCH_1):PAGE140
     2 GPU_FPGA_RST_R_BUF_N @S9S_MB_2U_LIB.S9S_MB_2U(SCH_1):GPU_FPGA_RST_R_BUF_N   I205 @S9S_MB_2U_LIB.S9S_MB_2U(SCH_1):PAGE140

R3317 Q_RES_0402LF-4.7K,5%,1/16W,EMPA
     1 P3V3_AUX @S9S_MB_2U_LIB.S9S_MB_2U(SCH_1):P3V3_AUX   I190 @S9S_MB_2U_LIB.S9S_MB_2U(SCH_1):PAGE140
     2 GPU_FPGA_RST_R1_BUF_N @S9S_MB_2U_LIB.S9S_MB_2U(SCH_1):GPU_FPGA_RST_R1_BUF_N   I190 @S9S_MB_2U_LIB.S9S_MB_2U(SCH_1):PAGE140

R3318 Q_RES_0402LF-100K,1%,1/16W,EMPA
     1 P3V3_AUX @S9S_MB_2U_LIB.S9S_MB_2U(SCH_1):P3V3_AUX   I171 @S9S_MB_2U_LIB.S9S_MB_2U(SCH_1):PAGE145
     2 GPU_FPGA_READY @S9S_MB_2U_LIB.S9S_MB_2U(SCH_1):GPU_FPGA_READY   I171 @S9S_MB_2U_LIB.S9S_MB_2U(SCH_1):PAGE145

R3320 Q_RES_0402LF-4.7K,5%,1/16W,CHIA
     1 P3V3_AUX @S9S_MB_2U_LIB.S9S_MB_2U(SCH_1):P3V3_AUX   I162 @S9S_MB_2U_LIB.S9S_MB_2U(SCH_1):PAGE145
     2 GPU_FPGA_READY_N @S9S_MB_2U_LIB.S9S_MB_2U(SCH_1):GPU_FPGA_READY_N   I162 @S9S_MB_2U_LIB.S9S_MB_2U(SCH_1):PAGE145

R3321 Q_RES_0402LF-4.7K,5%,1/16W,CHIA
     1 P3V3_AUX @S9S_MB_2U_LIB.S9S_MB_2U(SCH_1):P3V3_AUX   I158 @S9S_MB_2U_LIB.S9S_MB_2U(SCH_1):PAGE145
     2 GPU_FPGA_READY_ISO @S9S_MB_2U_LIB.S9S_MB_2U(SCH_1):GPU_FPGA_READY_ISO   I158 @S9S_MB_2U_LIB.S9S_MB_2U(SCH_1):PAGE145

R3322 Q_RES_0402LF-4.7K,1%,1/16W,CHIA
     1 P3V3_AUX @S9S_MB_2U_LIB.S9S_MB_2U(SCH_1):P3V3_AUX   I157 @S9S_MB_2U_LIB.S9S_MB_2U(SCH_1):PAGE201
     2 CLK_GEN2_GPU_FPGA_OE_R2_N @S9S_MB_2U_LIB.S9S_MB_2U(SCH_1):CLK_GEN2_GPU_FPGA_OE_R2_N   I157 @S9S_MB_2U_LIB.S9S_MB_2U(SCH_1):PAGE201

R3324 Q_RES_0402LF-33.2,1%,1/16W,CHIA
     1 GPU_FPGA_READY_ISO @S9S_MB_2U_LIB.S9S_MB_2U(SCH_1):GPU_FPGA_READY_ISO   I108 @S9S_MB_2U_LIB.S9S_MB_2U(SCH_1):PAGE314
     2 GPU_FPGA_READY_ISO_R @S9S_MB_2U_LIB.S9S_MB_2U(SCH_1):GPU_FPGA_READY_ISO_R   I108 @S9S_MB_2U_LIB.S9S_MB_2U(SCH_1):PAGE314

R3325 Q_RES_0402LF-10K,1%,1/16W,CHIPA
     1 FM_PCH_SPKR @S9S_MB_2U_LIB.S9S_MB_2U(SCH_1):FM_PCH_SPKR    I92 @S9S_MB_2U_LIB.S9S_MB_2U(SCH_1):PAGE186
     2    GND @S9S_MB_2U_LIB.S9S_MB_2U(SCH_1):GND    I92 @S9S_MB_2U_LIB.S9S_MB_2U(SCH_1):PAGE186

R3326 Q_RES_0402LF-0,5%,1/16W,CHIP,CA
     1 GPU_FPGA_READY_N @S9S_MB_2U_LIB.S9S_MB_2U(SCH_1):GPU_FPGA_READY_N    I84 @S9S_MB_2U_LIB.S9S_MB_2U(SCH_1):PAGE201
     2 GPU_FPGA_READY_R_N @S9S_MB_2U_LIB.S9S_MB_2U(SCH_1):GPU_FPGA_READY_R_N    I84 @S9S_MB_2U_LIB.S9S_MB_2U(SCH_1):PAGE201

R3327 Q_RES_0402LF-0,5%,1/16W,CHIP,CA
     1 CLK_GEN2_GPU_FPGA_OE_N @S9S_MB_2U_LIB.S9S_MB_2U(SCH_1):CLK_GEN2_GPU_FPGA_OE_N    I85 @S9S_MB_2U_LIB.S9S_MB_2U(SCH_1):PAGE201
     2 CLK_GEN2_GPU_FPGA_OE_R2_N @S9S_MB_2U_LIB.S9S_MB_2U(SCH_1):CLK_GEN2_GPU_FPGA_OE_R2_N    I85 @S9S_MB_2U_LIB.S9S_MB_2U(SCH_1):PAGE201

R3335 Q_RES_0402LF-0,5%,1/16W,CHIP,CA
     1 CLK_100M_BMC_RC_DP_R @S9S_MB_2U_LIB.S9S_MB_2U(SCH_1):CLK_100M_BMC_RC_DP_R    I69 @S9S_MB_2U_LIB.S9S_MB_2U(SCH_1):PAGE201
     2 CLK_100M_BMC_RC_DP @S9S_MB_2U_LIB.S9S_MB_2U(SCH_1):CLK_100M_BMC_RC_DP    I69 @S9S_MB_2U_LIB.S9S_MB_2U(SCH_1):PAGE201

R3336 Q_RES_0402LF-0,5%,1/16W,CHIP,CA
     1 CLK_100M_BMC_RC_DN_R @S9S_MB_2U_LIB.S9S_MB_2U(SCH_1):CLK_100M_BMC_RC_DN_R    I74 @S9S_MB_2U_LIB.S9S_MB_2U(SCH_1):PAGE201
     2 CLK_100M_BMC_RC_DN @S9S_MB_2U_LIB.S9S_MB_2U(SCH_1):CLK_100M_BMC_RC_DN    I74 @S9S_MB_2U_LIB.S9S_MB_2U(SCH_1):PAGE201

R3337 Q_RES_0402LF-0,5%,1/16W,CHIP,CA
     1 CLK_100M_GPU_FPGA_DP_R @S9S_MB_2U_LIB.S9S_MB_2U(SCH_1):CLK_100M_GPU_FPGA_DP_R    I75 @S9S_MB_2U_LIB.S9S_MB_2U(SCH_1):PAGE201
     2 CLK_100M_GPU_FPGA_DP @S9S_MB_2U_LIB.S9S_MB_2U(SCH_1):CLK_100M_GPU_FPGA_DP    I75 @S9S_MB_2U_LIB.S9S_MB_2U(SCH_1):PAGE201

R3338 Q_RES_0402LF-0,5%,1/16W,CHIP,CA
     1 CLK_100M_GPU_FPGA_DN_R @S9S_MB_2U_LIB.S9S_MB_2U(SCH_1):CLK_100M_GPU_FPGA_DN_R    I76 @S9S_MB_2U_LIB.S9S_MB_2U(SCH_1):PAGE201
     2 CLK_100M_GPU_FPGA_DN @S9S_MB_2U_LIB.S9S_MB_2U(SCH_1):CLK_100M_GPU_FPGA_DN    I76 @S9S_MB_2U_LIB.S9S_MB_2U(SCH_1):PAGE201

R3340 Q_RES_0402LF-33.2,1%,1/16W,CHIA
     1 SMB_HOST_CLK_3V3AUX_SCL @S9S_MB_2U_LIB.S9S_MB_2U(SCH_1):SMB_HOST_CLK_3V3AUX_SCL   I268 @S9S_MB_2U_LIB.S9S_MB_2U(SCH_1):PAGE228
     2 SMB_HOST_CLK_GEN2_3V3AUX_SCL @S9S_MB_2U_LIB.S9S_MB_2U(SCH_1):SMB_HOST_CLK_GEN2_3V3AUX_SCL   I268 @S9S_MB_2U_LIB.S9S_MB_2U(SCH_1):PAGE228

R3341 Q_RES_0402LF-33.2,1%,1/16W,CHIA
     1 SMB_HOST_CLK_3V3AUX_SDA @S9S_MB_2U_LIB.S9S_MB_2U(SCH_1):SMB_HOST_CLK_3V3AUX_SDA   I264 @S9S_MB_2U_LIB.S9S_MB_2U(SCH_1):PAGE228
     2 SMB_HOST_CLK_GEN2_3V3AUX_SDA @S9S_MB_2U_LIB.S9S_MB_2U(SCH_1):SMB_HOST_CLK_GEN2_3V3AUX_SDA   I264 @S9S_MB_2U_LIB.S9S_MB_2U(SCH_1):PAGE228

R3344 Q_RES_0603LF-1,1%,1/10W,CHIP,CA
     1 P3V3_AUX @S9S_MB_2U_LIB.S9S_MB_2U(SCH_1):P3V3_AUX   I108 @S9S_MB_2U_LIB.S9S_MB_2U(SCH_1):PAGE202
     2 P3V3_AUX_FPGA_VCCIO3 @S9S_MB_2U_LIB.S9S_MB_2U(SCH_1):P3V3_AUX_FPGA_VCCIO3   I108 @S9S_MB_2U_LIB.S9S_MB_2U(SCH_1):PAGE202

R3345 Q_RES_0603LF-1,1%,1/10W,CHIP,CA
     1 P3V3_AUX @S9S_MB_2U_LIB.S9S_MB_2U(SCH_1):P3V3_AUX    I81 @S9S_MB_2U_LIB.S9S_MB_2U(SCH_1):PAGE202
     2 P3V3_AUX_FPGA_VCCIO4 @S9S_MB_2U_LIB.S9S_MB_2U(SCH_1):P3V3_AUX_FPGA_VCCIO4    I81 @S9S_MB_2U_LIB.S9S_MB_2U(SCH_1):PAGE202

R3346 Q_RES_0603LF-1,1%,1/10W,CHIP,CA
     1 P3V3_AUX @S9S_MB_2U_LIB.S9S_MB_2U(SCH_1):P3V3_AUX    I63 @S9S_MB_2U_LIB.S9S_MB_2U(SCH_1):PAGE202
     2 P3V3_AUX_FPGA_VCCIO0 @S9S_MB_2U_LIB.S9S_MB_2U(SCH_1):P3V3_AUX_FPGA_VCCIO0    I63 @S9S_MB_2U_LIB.S9S_MB_2U(SCH_1):PAGE202

R3347 Q_RES_0603LF-1,1%,1/10W,CHIP,CA
     1 P3V3_AUX @S9S_MB_2U_LIB.S9S_MB_2U(SCH_1):P3V3_AUX    I72 @S9S_MB_2U_LIB.S9S_MB_2U(SCH_1):PAGE202
     2 P3V3_AUX_FPGA_VCCIO2 @S9S_MB_2U_LIB.S9S_MB_2U(SCH_1):P3V3_AUX_FPGA_VCCIO2    I72 @S9S_MB_2U_LIB.S9S_MB_2U(SCH_1):PAGE202

R3348 Q_RES_0603LF-1,1%,1/10W,CHIP,CA
     1 P3V3_AUX @S9S_MB_2U_LIB.S9S_MB_2U(SCH_1):P3V3_AUX    I67 @S9S_MB_2U_LIB.S9S_MB_2U(SCH_1):PAGE202
     2 P3V3_AUX_FPGA_VCCIO1 @S9S_MB_2U_LIB.S9S_MB_2U(SCH_1):P3V3_AUX_FPGA_VCCIO1    I67 @S9S_MB_2U_LIB.S9S_MB_2U(SCH_1):PAGE202

R3349 Q_RES_0603LF-1,1%,1/10W,CHIP,CA
     1 P3V3_AUX @S9S_MB_2U_LIB.S9S_MB_2U(SCH_1):P3V3_AUX    I60 @S9S_MB_2U_LIB.S9S_MB_2U(SCH_1):PAGE202
     2 P3V3_AUX_FPGA_VCCIO5 @S9S_MB_2U_LIB.S9S_MB_2U(SCH_1):P3V3_AUX_FPGA_VCCIO5    I60 @S9S_MB_2U_LIB.S9S_MB_2U(SCH_1):PAGE202

R3352 Q_RES_0402LF-0,5%,1/16W,CHIP,CA
     1 CLK_100M_GPU_1_R_DP @S9S_MB_2U_LIB.S9S_MB_2U(SCH_1):CLK_100M_GPU_1_R_DP    I26 @S9S_MB_2U_LIB.S9S_MB_2U(SCH_1):PAGE196
     2 CLK_100M_GPU_1_DP @S9S_MB_2U_LIB.S9S_MB_2U(SCH_1):CLK_100M_GPU_1_DP    I26 @S9S_MB_2U_LIB.S9S_MB_2U(SCH_1):PAGE196

R3353 Q_RES_0402LF-0,5%,1/16W,CHIP,CA
     1 CLK_100M_GPU_1_R_DN @S9S_MB_2U_LIB.S9S_MB_2U(SCH_1):CLK_100M_GPU_1_R_DN    I25 @S9S_MB_2U_LIB.S9S_MB_2U(SCH_1):PAGE196
     2 CLK_100M_GPU_1_DN @S9S_MB_2U_LIB.S9S_MB_2U(SCH_1):CLK_100M_GPU_1_DN    I25 @S9S_MB_2U_LIB.S9S_MB_2U(SCH_1):PAGE196

R3354 Q_RES_0402LF-0,5%,1/16W,CHIP,CA
     1 CLK_100M_GPU_2_R_DP @S9S_MB_2U_LIB.S9S_MB_2U(SCH_1):CLK_100M_GPU_2_R_DP    I24 @S9S_MB_2U_LIB.S9S_MB_2U(SCH_1):PAGE196
     2 CLK_100M_GPU_2_DP @S9S_MB_2U_LIB.S9S_MB_2U(SCH_1):CLK_100M_GPU_2_DP    I24 @S9S_MB_2U_LIB.S9S_MB_2U(SCH_1):PAGE196

R3355 Q_RES_0402LF-0,5%,1/16W,CHIP,CA
     1 CLK_100M_GPU_2_R_DN @S9S_MB_2U_LIB.S9S_MB_2U(SCH_1):CLK_100M_GPU_2_R_DN    I18 @S9S_MB_2U_LIB.S9S_MB_2U(SCH_1):PAGE196
     2 CLK_100M_GPU_2_DN @S9S_MB_2U_LIB.S9S_MB_2U(SCH_1):CLK_100M_GPU_2_DN    I18 @S9S_MB_2U_LIB.S9S_MB_2U(SCH_1):PAGE196

R3362 Q_RES_0402LF-1K,1%,1/16W,CHIP,A
     1 PD_P2E_BUF2_ENSMB @S9S_MB_2U_LIB.S9S_MB_2U(SCH_1):PD_P2E_BUF2_ENSMB    I53 @S9S_MB_2U_LIB.S9S_MB_2U(SCH_1):PAGE159
     2    GND @S9S_MB_2U_LIB.S9S_MB_2U(SCH_1):GND    I53 @S9S_MB_2U_LIB.S9S_MB_2U(SCH_1):PAGE159

R3381 Q_RES_0402LF-1K,1%,1/16W,EMPTYA
     1 FM_P2E_BUF2_RXDET @S9S_MB_2U_LIB.S9S_MB_2U(SCH_1):FM_P2E_BUF2_RXDET    I61 @S9S_MB_2U_LIB.S9S_MB_2U(SCH_1):PAGE159
     2    GND @S9S_MB_2U_LIB.S9S_MB_2U(SCH_1):GND    I61 @S9S_MB_2U_LIB.S9S_MB_2U(SCH_1):PAGE159

R3386 Q_RES_0402LF-1K,1%,1/16W,CHIP,A
     1 P3V3_AUX @S9S_MB_2U_LIB.S9S_MB_2U(SCH_1):P3V3_AUX    I81 @S9S_MB_2U_LIB.S9S_MB_2U(SCH_1):PAGE159
     2 FM_P2E_BUF2_VOD_SEL @S9S_MB_2U_LIB.S9S_MB_2U(SCH_1):FM_P2E_BUF2_VOD_SEL    I81 @S9S_MB_2U_LIB.S9S_MB_2U(SCH_1):PAGE159

R3390 Q_RES_0402LF-49.9,1%,1/16W,CHIA
     1 GPU_FPGA_BOOT_EN_BUF_R @S9S_MB_2U_LIB.S9S_MB_2U(SCH_1):GPU_FPGA_BOOT_EN_BUF_R   I201 @S9S_MB_2U_LIB.S9S_MB_2U(SCH_1):PAGE160
     2 GPU_FPGA_BOOT_EN_BUF @S9S_MB_2U_LIB.S9S_MB_2U(SCH_1):GPU_FPGA_BOOT_EN_BUF   I201 @S9S_MB_2U_LIB.S9S_MB_2U(SCH_1):PAGE160

R3391 Q_RES_0402LF-49.9,1%,1/16W,CHIA
     1 RST_PERST_1_SWB_BUF_R_N @S9S_MB_2U_LIB.S9S_MB_2U(SCH_1):RST_PERST_1_SWB_BUF_R_N   I200 @S9S_MB_2U_LIB.S9S_MB_2U(SCH_1):PAGE160
     2 RST_PERST_1_SWB_BUF_N @S9S_MB_2U_LIB.S9S_MB_2U(SCH_1):RST_PERST_1_SWB_BUF_N   I200 @S9S_MB_2U_LIB.S9S_MB_2U(SCH_1):PAGE160

R3392 Q_RES_0402LF-49.9,1%,1/16W,CHIA
     1 GPU_BASE_STBY_EN_BUF_R @S9S_MB_2U_LIB.S9S_MB_2U(SCH_1):GPU_BASE_STBY_EN_BUF_R   I202 @S9S_MB_2U_LIB.S9S_MB_2U(SCH_1):PAGE160
     2 GPU_BASE_STBY_EN_BUF @S9S_MB_2U_LIB.S9S_MB_2U(SCH_1):GPU_BASE_STBY_EN_BUF   I202 @S9S_MB_2U_LIB.S9S_MB_2U(SCH_1):PAGE160

R3393 Q_RES_0402LF-0,5%,1/16W,CHIP,CA
     1 SMB_IOEXP_3V3AUX_SCL_R @S9S_MB_2U_LIB.S9S_MB_2U(SCH_1):SMB_IOEXP_3V3AUX_SCL_R    I38 @S9S_MB_2U_LIB.S9S_MB_2U(SCH_1):PAGE219
     2 SMB_IOEXP_3V3AUX_SCL @S9S_MB_2U_LIB.S9S_MB_2U(SCH_1):SMB_IOEXP_3V3AUX_SCL    I38 @S9S_MB_2U_LIB.S9S_MB_2U(SCH_1):PAGE219

R3394 Q_RES_0402LF-0,5%,1/16W,CHIP,CA
     1 SMB_IOEXP_3V3AUX_SDA_R @S9S_MB_2U_LIB.S9S_MB_2U(SCH_1):SMB_IOEXP_3V3AUX_SDA_R    I40 @S9S_MB_2U_LIB.S9S_MB_2U(SCH_1):PAGE219
     2 SMB_IOEXP_3V3AUX_SDA @S9S_MB_2U_LIB.S9S_MB_2U(SCH_1):SMB_IOEXP_3V3AUX_SDA    I40 @S9S_MB_2U_LIB.S9S_MB_2U(SCH_1):PAGE219

R3395 Q_RES_0402LF-2.2K,5%,1/16W,CHIA
     1 P3V3_AUX @S9S_MB_2U_LIB.S9S_MB_2U(SCH_1):P3V3_AUX    I54 @S9S_MB_2U_LIB.S9S_MB_2U(SCH_1):PAGE219
     2 SMB_INA230_3V3AUX_SCL @S9S_MB_2U_LIB.S9S_MB_2U(SCH_1):SMB_INA230_3V3AUX_SCL    I54 @S9S_MB_2U_LIB.S9S_MB_2U(SCH_1):PAGE219

R3396 Q_RES_0402LF-2.2K,5%,1/16W,CHIA
     1 P3V3_AUX @S9S_MB_2U_LIB.S9S_MB_2U(SCH_1):P3V3_AUX    I53 @S9S_MB_2U_LIB.S9S_MB_2U(SCH_1):PAGE219
     2 SMB_INA230_3V3AUX_SDA @S9S_MB_2U_LIB.S9S_MB_2U(SCH_1):SMB_INA230_3V3AUX_SDA    I53 @S9S_MB_2U_LIB.S9S_MB_2U(SCH_1):PAGE219

R3397 Q_RES_0402LF-33.2,1%,1/16W,CHIA
     1 GPU_NVS_PWR_BRAKE_N_R @S9S_MB_2U_LIB.S9S_MB_2U(SCH_1):GPU_NVS_PWR_BRAKE_N_R    I37 @S9S_MB_2U_LIB.S9S_MB_2U(SCH_1):PAGE296
     2 GPU_NVS_PWR_BRAKE_N_BUF @S9S_MB_2U_LIB.S9S_MB_2U(SCH_1):GPU_NVS_PWR_BRAKE_N_BUF    I37 @S9S_MB_2U_LIB.S9S_MB_2U(SCH_1):PAGE296

R3428 Q_RES_0402LF-100K,1%,1/16W,EMPA
     1 GPU_FPGA_THERM_OVERT_N @S9S_MB_2U_LIB.S9S_MB_2U(SCH_1):GPU_FPGA_THERM_OVERT_N    I17 @S9S_MB_2U_LIB.S9S_MB_2U(SCH_1):PAGE299
     2    GND @S9S_MB_2U_LIB.S9S_MB_2U(SCH_1):GND    I17 @S9S_MB_2U_LIB.S9S_MB_2U(SCH_1):PAGE299

R3429 Q_RES_0402LF-100K,1%,1/16W,EMPA
     1 P3V3_AUX @S9S_MB_2U_LIB.S9S_MB_2U(SCH_1):P3V3_AUX   I130 @S9S_MB_2U_LIB.S9S_MB_2U(SCH_1):PAGE299
     2 GPU_BASE_HMC_READY @S9S_MB_2U_LIB.S9S_MB_2U(SCH_1):GPU_BASE_HMC_READY   I130 @S9S_MB_2U_LIB.S9S_MB_2U(SCH_1):PAGE299

R3430 Q_RES_0402LF-100K,1%,1/16W,EMPA
     1 GPU_FPGA_OVERT_N @S9S_MB_2U_LIB.S9S_MB_2U(SCH_1):GPU_FPGA_OVERT_N     I3 @S9S_MB_2U_LIB.S9S_MB_2U(SCH_1):PAGE299
     2    GND @S9S_MB_2U_LIB.S9S_MB_2U(SCH_1):GND     I3 @S9S_MB_2U_LIB.S9S_MB_2U(SCH_1):PAGE299

R3431 Q_RES_0402LF-100K,1%,1/16W,EMPA
     1 GPU_HMC_PRSNT_N @S9S_MB_2U_LIB.S9S_MB_2U(SCH_1):GPU_HMC_PRSNT_N   I133 @S9S_MB_2U_LIB.S9S_MB_2U(SCH_1):PAGE299
     2    GND @S9S_MB_2U_LIB.S9S_MB_2U(SCH_1):GND   I133 @S9S_MB_2U_LIB.S9S_MB_2U(SCH_1):PAGE299

R3432 Q_RES_0402LF-4.7K,5%,1/16W,CHIA
     1 P3V3_AUX @S9S_MB_2U_LIB.S9S_MB_2U(SCH_1):P3V3_AUX    I53 @S9S_MB_2U_LIB.S9S_MB_2U(SCH_1):PAGE299
     2 GPU_FPGA_THERM_OVERT @S9S_MB_2U_LIB.S9S_MB_2U(SCH_1):GPU_FPGA_THERM_OVERT    I53 @S9S_MB_2U_LIB.S9S_MB_2U(SCH_1):PAGE299

R3433 Q_RES_0402LF-4.7K,5%,1/16W,CHIA
     1 P3V3_AUX @S9S_MB_2U_LIB.S9S_MB_2U(SCH_1):P3V3_AUX    I49 @S9S_MB_2U_LIB.S9S_MB_2U(SCH_1):PAGE299
     2 GPU_BASE_HMC_READY_N @S9S_MB_2U_LIB.S9S_MB_2U(SCH_1):GPU_BASE_HMC_READY_N    I49 @S9S_MB_2U_LIB.S9S_MB_2U(SCH_1):PAGE299

R3434 Q_RES_0402LF-4.7K,5%,1/16W,CHIA
     1 P3V3_AUX @S9S_MB_2U_LIB.S9S_MB_2U(SCH_1):P3V3_AUX    I39 @S9S_MB_2U_LIB.S9S_MB_2U(SCH_1):PAGE299
     2 GPU_HMC_PRSNT @S9S_MB_2U_LIB.S9S_MB_2U(SCH_1):GPU_HMC_PRSNT    I39 @S9S_MB_2U_LIB.S9S_MB_2U(SCH_1):PAGE299

R3435 Q_RES_0402LF-4.7K,5%,1/16W,CHIA
     1 P3V3_AUX @S9S_MB_2U_LIB.S9S_MB_2U(SCH_1):P3V3_AUX    I23 @S9S_MB_2U_LIB.S9S_MB_2U(SCH_1):PAGE299
     2 GPU_FPGA_OVERT @S9S_MB_2U_LIB.S9S_MB_2U(SCH_1):GPU_FPGA_OVERT    I23 @S9S_MB_2U_LIB.S9S_MB_2U(SCH_1):PAGE299

R3436 Q_RES_0402LF-4.7K,5%,1/16W,CHIA
     1 P3V3_AUX @S9S_MB_2U_LIB.S9S_MB_2U(SCH_1):P3V3_AUX    I45 @S9S_MB_2U_LIB.S9S_MB_2U(SCH_1):PAGE299
     2 GPU_HMC_PRSNT_ISO_N @S9S_MB_2U_LIB.S9S_MB_2U(SCH_1):GPU_HMC_PRSNT_ISO_N    I45 @S9S_MB_2U_LIB.S9S_MB_2U(SCH_1):PAGE299

R3437 Q_RES_0402LF-4.7K,5%,1/16W,CHIA
     1 P3V3_AUX @S9S_MB_2U_LIB.S9S_MB_2U(SCH_1):P3V3_AUX    I27 @S9S_MB_2U_LIB.S9S_MB_2U(SCH_1):PAGE299
     2 GPU_FPGA_OVERT_ISO_N @S9S_MB_2U_LIB.S9S_MB_2U(SCH_1):GPU_FPGA_OVERT_ISO_N    I27 @S9S_MB_2U_LIB.S9S_MB_2U(SCH_1):PAGE299

R3438 Q_RES_0402LF-4.7K,5%,1/16W,CHIA
     1 P3V3_AUX @S9S_MB_2U_LIB.S9S_MB_2U(SCH_1):P3V3_AUX    I55 @S9S_MB_2U_LIB.S9S_MB_2U(SCH_1):PAGE299
     2 GPU_BASE_HMC_READY_ISO @S9S_MB_2U_LIB.S9S_MB_2U(SCH_1):GPU_BASE_HMC_READY_ISO    I55 @S9S_MB_2U_LIB.S9S_MB_2U(SCH_1):PAGE299

R3439 Q_RES_0402LF-4.7K,5%,1/16W,CHIA
     1 P3V3_AUX @S9S_MB_2U_LIB.S9S_MB_2U(SCH_1):P3V3_AUX    I59 @S9S_MB_2U_LIB.S9S_MB_2U(SCH_1):PAGE299
     2 GPU_FPGA_THERM_OVERT_ISO_N @S9S_MB_2U_LIB.S9S_MB_2U(SCH_1):GPU_FPGA_THERM_OVERT_ISO_N    I59 @S9S_MB_2U_LIB.S9S_MB_2U(SCH_1):PAGE299

R3440 Q_RES_0402LF-0,5%,1/16W,EMPTY,A
     1 GPU_BASE_ID0 @S9S_MB_2U_LIB.S9S_MB_2U(SCH_1):GPU_BASE_ID0     I8 @S9S_MB_2U_LIB.S9S_MB_2U(SCH_1):PAGE147
     2    GND @S9S_MB_2U_LIB.S9S_MB_2U(SCH_1):GND     I8 @S9S_MB_2U_LIB.S9S_MB_2U(SCH_1):PAGE147

R3441 Q_RES_0402LF-0,5%,1/16W,CHIP,CA
     1 GPU_BASE_ID1 @S9S_MB_2U_LIB.S9S_MB_2U(SCH_1):GPU_BASE_ID1     I7 @S9S_MB_2U_LIB.S9S_MB_2U(SCH_1):PAGE147
     2    GND @S9S_MB_2U_LIB.S9S_MB_2U(SCH_1):GND     I7 @S9S_MB_2U_LIB.S9S_MB_2U(SCH_1):PAGE147

R3442 Q_RES_0402LF-0,5%,1/16W,CHIP,CA
     1 GPU_PEX_STRAP0 @S9S_MB_2U_LIB.S9S_MB_2U(SCH_1):GPU_PEX_STRAP0     I6 @S9S_MB_2U_LIB.S9S_MB_2U(SCH_1):PAGE147
     2    GND @S9S_MB_2U_LIB.S9S_MB_2U(SCH_1):GND     I6 @S9S_MB_2U_LIB.S9S_MB_2U(SCH_1):PAGE147

R3443 Q_RES_0402LF-0,5%,1/16W,CHIP,CA
     1 GPU_PEX_STRAP1 @S9S_MB_2U_LIB.S9S_MB_2U(SCH_1):GPU_PEX_STRAP1     I5 @S9S_MB_2U_LIB.S9S_MB_2U(SCH_1):PAGE147
     2    GND @S9S_MB_2U_LIB.S9S_MB_2U(SCH_1):GND     I5 @S9S_MB_2U_LIB.S9S_MB_2U(SCH_1):PAGE147

R3448 Q_RES_0402LF-4.7K,5%,1/16W,EMPA
     1 P3V3_AUX @S9S_MB_2U_LIB.S9S_MB_2U(SCH_1):P3V3_AUX   I168 @S9S_MB_2U_LIB.S9S_MB_2U(SCH_1):PAGE160
     2 GPU_FPGA_BOOT_EN @S9S_MB_2U_LIB.S9S_MB_2U(SCH_1):GPU_FPGA_BOOT_EN   I168 @S9S_MB_2U_LIB.S9S_MB_2U(SCH_1):PAGE160

R3449 Q_RES_0402LF-100K,1%,1/16W,CHIA
     1 GPU_FPGA_BOOT_EN @S9S_MB_2U_LIB.S9S_MB_2U(SCH_1):GPU_FPGA_BOOT_EN   I170 @S9S_MB_2U_LIB.S9S_MB_2U(SCH_1):PAGE160
     2    GND @S9S_MB_2U_LIB.S9S_MB_2U(SCH_1):GND   I170 @S9S_MB_2U_LIB.S9S_MB_2U(SCH_1):PAGE160

R3451 Q_RES_0402LF-4.7K,5%,1/16W,EMPA
     1 P3V3_AUX @S9S_MB_2U_LIB.S9S_MB_2U(SCH_1):P3V3_AUX   I127 @S9S_MB_2U_LIB.S9S_MB_2U(SCH_1):PAGE160
     2 GPU_BASE_STBY_EN @S9S_MB_2U_LIB.S9S_MB_2U(SCH_1):GPU_BASE_STBY_EN   I127 @S9S_MB_2U_LIB.S9S_MB_2U(SCH_1):PAGE160

R3452 Q_RES_0402LF-100K,1%,1/16W,CHIA
     1 GPU_BASE_STBY_EN @S9S_MB_2U_LIB.S9S_MB_2U(SCH_1):GPU_BASE_STBY_EN    I95 @S9S_MB_2U_LIB.S9S_MB_2U(SCH_1):PAGE160
     2    GND @S9S_MB_2U_LIB.S9S_MB_2U(SCH_1):GND    I95 @S9S_MB_2U_LIB.S9S_MB_2U(SCH_1):PAGE160

R3453 Q_RES_0402LF-100K,1%,1/16W,EMPA
     1 P3V3_AUX @S9S_MB_2U_LIB.S9S_MB_2U(SCH_1):P3V3_AUX   I164 @S9S_MB_2U_LIB.S9S_MB_2U(SCH_1):PAGE160
     2 GPU_FPGA_BOOT_EN_BUF_R @S9S_MB_2U_LIB.S9S_MB_2U(SCH_1):GPU_FPGA_BOOT_EN_BUF_R   I164 @S9S_MB_2U_LIB.S9S_MB_2U(SCH_1):PAGE160

R3454 Q_RES_0402LF-1K,1%,1/16W,CHIP,A
     1 GPU_FPGA_BOOT_EN_BUF_R @S9S_MB_2U_LIB.S9S_MB_2U(SCH_1):GPU_FPGA_BOOT_EN_BUF_R   I165 @S9S_MB_2U_LIB.S9S_MB_2U(SCH_1):PAGE160
     2    GND @S9S_MB_2U_LIB.S9S_MB_2U(SCH_1):GND   I165 @S9S_MB_2U_LIB.S9S_MB_2U(SCH_1):PAGE160

R3455 Q_RES_0402LF-10K,1%,1/16W,CHIPA
     1 RST_PERST_1_SWB_BUF_R_N @S9S_MB_2U_LIB.S9S_MB_2U(SCH_1):RST_PERST_1_SWB_BUF_R_N   I139 @S9S_MB_2U_LIB.S9S_MB_2U(SCH_1):PAGE160
     2    GND @S9S_MB_2U_LIB.S9S_MB_2U(SCH_1):GND   I139 @S9S_MB_2U_LIB.S9S_MB_2U(SCH_1):PAGE160

R3456 Q_RES_0402LF-100K,1%,1/16W,EMPA
     1 P3V3_AUX @S9S_MB_2U_LIB.S9S_MB_2U(SCH_1):P3V3_AUX   I124 @S9S_MB_2U_LIB.S9S_MB_2U(SCH_1):PAGE160
     2 GPU_BASE_STBY_EN_BUF_R @S9S_MB_2U_LIB.S9S_MB_2U(SCH_1):GPU_BASE_STBY_EN_BUF_R   I124 @S9S_MB_2U_LIB.S9S_MB_2U(SCH_1):PAGE160

R3457 Q_RES_0402LF-10K,1%,1/16W,CHIPA
     1 GPU_BASE_STBY_EN_BUF_R @S9S_MB_2U_LIB.S9S_MB_2U(SCH_1):GPU_BASE_STBY_EN_BUF_R   I123 @S9S_MB_2U_LIB.S9S_MB_2U(SCH_1):PAGE160
     2    GND @S9S_MB_2U_LIB.S9S_MB_2U(SCH_1):GND   I123 @S9S_MB_2U_LIB.S9S_MB_2U(SCH_1):PAGE160

R3458 Q_RES_0603LF-1,1%,1/10W,CHIP,CA
     1 P3V3_AUX @S9S_MB_2U_LIB.S9S_MB_2U(SCH_1):P3V3_AUX   I119 @S9S_MB_2U_LIB.S9S_MB_2U(SCH_1):PAGE202
     2 VCC_PLD_CORE @S9S_MB_2U_LIB.S9S_MB_2U(SCH_1):VCC_PLD_CORE   I119 @S9S_MB_2U_LIB.S9S_MB_2U(SCH_1):PAGE202

R3459 Q_RES_0402LF-4.7K,5%,1/16W,CHIA
     1 P3V3_AUX @S9S_MB_2U_LIB.S9S_MB_2U(SCH_1):P3V3_AUX    I29 @S9S_MB_2U_LIB.S9S_MB_2U(SCH_1):PAGE296
     2 GPU_NVS_PWR_BRAKE_N @S9S_MB_2U_LIB.S9S_MB_2U(SCH_1):GPU_NVS_PWR_BRAKE_N    I29 @S9S_MB_2U_LIB.S9S_MB_2U(SCH_1):PAGE296

R3460 Q_RES_0402LF-100K,1%,1/16W,EMPA
     1 GPU_NVS_PWR_BRAKE_N @S9S_MB_2U_LIB.S9S_MB_2U(SCH_1):GPU_NVS_PWR_BRAKE_N    I31 @S9S_MB_2U_LIB.S9S_MB_2U(SCH_1):PAGE296
     2    GND @S9S_MB_2U_LIB.S9S_MB_2U(SCH_1):GND    I31 @S9S_MB_2U_LIB.S9S_MB_2U(SCH_1):PAGE296

R3461 Q_RES_0402LF-54.9K,1%,1/16W,CHA
     1 P3V3_AUX @S9S_MB_2U_LIB.S9S_MB_2U(SCH_1):P3V3_AUX    I35 @S9S_MB_2U_LIB.S9S_MB_2U(SCH_1):PAGE296
     2 GPU_NVS_PWR_BRAKE_N_R @S9S_MB_2U_LIB.S9S_MB_2U(SCH_1):GPU_NVS_PWR_BRAKE_N_R    I35 @S9S_MB_2U_LIB.S9S_MB_2U(SCH_1):PAGE296

R3462 Q_RES_0402LF-100K,1%,1/16W,EMPA
     1 GPU_NVS_PWR_BRAKE_N_R @S9S_MB_2U_LIB.S9S_MB_2U(SCH_1):GPU_NVS_PWR_BRAKE_N_R    I33 @S9S_MB_2U_LIB.S9S_MB_2U(SCH_1):PAGE296
     2    GND @S9S_MB_2U_LIB.S9S_MB_2U(SCH_1):GND    I33 @S9S_MB_2U_LIB.S9S_MB_2U(SCH_1):PAGE296

R3463 Q_RES_0402LF-54.9K,1%,1/16W,CHA
     1 GPU_BASE_HMC_READY @S9S_MB_2U_LIB.S9S_MB_2U(SCH_1):GPU_BASE_HMC_READY   I131 @S9S_MB_2U_LIB.S9S_MB_2U(SCH_1):PAGE299
     2    GND @S9S_MB_2U_LIB.S9S_MB_2U(SCH_1):GND   I131 @S9S_MB_2U_LIB.S9S_MB_2U(SCH_1):PAGE299

R3464 Q_RES_0402LF-54.9K,1%,1/16W,CHA
     1 P3V3_AUX @S9S_MB_2U_LIB.S9S_MB_2U(SCH_1):P3V3_AUX   I134 @S9S_MB_2U_LIB.S9S_MB_2U(SCH_1):PAGE299
     2 GPU_FPGA_OVERT_N @S9S_MB_2U_LIB.S9S_MB_2U(SCH_1):GPU_FPGA_OVERT_N   I134 @S9S_MB_2U_LIB.S9S_MB_2U(SCH_1):PAGE299

R3465 Q_RES_0402LF-10K,1%,1/16W,CHIPA
     1 P3V3_AUX @S9S_MB_2U_LIB.S9S_MB_2U(SCH_1):P3V3_AUX   I132 @S9S_MB_2U_LIB.S9S_MB_2U(SCH_1):PAGE299
     2 GPU_HMC_PRSNT_N @S9S_MB_2U_LIB.S9S_MB_2U(SCH_1):GPU_HMC_PRSNT_N   I132 @S9S_MB_2U_LIB.S9S_MB_2U(SCH_1):PAGE299

R3466 Q_RES_0402LF-10K,1%,1/16W,CHIPA
     1 RST_PERST_2_SWB_BUF_R_N @S9S_MB_2U_LIB.S9S_MB_2U(SCH_1):RST_PERST_2_SWB_BUF_R_N   I184 @S9S_MB_2U_LIB.S9S_MB_2U(SCH_1):PAGE160
     2    GND @S9S_MB_2U_LIB.S9S_MB_2U(SCH_1):GND   I184 @S9S_MB_2U_LIB.S9S_MB_2U(SCH_1):PAGE160

R3467 Q_RES_0402LF-10K,1%,1/16W,CHIPA
     1 RST_PERST_0_SWB_BUF_R_N @S9S_MB_2U_LIB.S9S_MB_2U(SCH_1):RST_PERST_0_SWB_BUF_R_N   I181 @S9S_MB_2U_LIB.S9S_MB_2U(SCH_1):PAGE160
     2    GND @S9S_MB_2U_LIB.S9S_MB_2U(SCH_1):GND   I181 @S9S_MB_2U_LIB.S9S_MB_2U(SCH_1):PAGE160

R3468 Q_RES_0402LF-49.9,1%,1/16W,CHIA
     1 RST_PERST_2_SWB_BUF_R_N @S9S_MB_2U_LIB.S9S_MB_2U(SCH_1):RST_PERST_2_SWB_BUF_R_N   I197 @S9S_MB_2U_LIB.S9S_MB_2U(SCH_1):PAGE160
     2 RST_PERST_2_SWB_BUF_N @S9S_MB_2U_LIB.S9S_MB_2U(SCH_1):RST_PERST_2_SWB_BUF_N   I197 @S9S_MB_2U_LIB.S9S_MB_2U(SCH_1):PAGE160

R3469 Q_RES_0402LF-49.9,1%,1/16W,CHIA
     1 RST_PERST_0_SWB_BUF_R_N @S9S_MB_2U_LIB.S9S_MB_2U(SCH_1):RST_PERST_0_SWB_BUF_R_N   I199 @S9S_MB_2U_LIB.S9S_MB_2U(SCH_1):PAGE160
     2 RST_PERST_0_SWB_BUF_N @S9S_MB_2U_LIB.S9S_MB_2U(SCH_1):RST_PERST_0_SWB_BUF_N   I199 @S9S_MB_2U_LIB.S9S_MB_2U(SCH_1):PAGE160

R3470 Q_RES_0402LF-10K,1%,1/16W,EMPTA
     1 P3V3_AUX @S9S_MB_2U_LIB.S9S_MB_2U(SCH_1):P3V3_AUX   I145 @S9S_MB_2U_LIB.S9S_MB_2U(SCH_1):PAGE299
     2 GPU_WP_HW_CTRL_N @S9S_MB_2U_LIB.S9S_MB_2U(SCH_1):GPU_WP_HW_CTRL_N   I145 @S9S_MB_2U_LIB.S9S_MB_2U(SCH_1):PAGE299

R3471 Q_RES_0402LF-10K,1%,1/16W,CHIPA
     1 GPU_WP_HW_CTRL_N @S9S_MB_2U_LIB.S9S_MB_2U(SCH_1):GPU_WP_HW_CTRL_N   I144 @S9S_MB_2U_LIB.S9S_MB_2U(SCH_1):PAGE299
     2    GND @S9S_MB_2U_LIB.S9S_MB_2U(SCH_1):GND   I144 @S9S_MB_2U_LIB.S9S_MB_2U(SCH_1):PAGE299

R3472 Q_RES_0402LF-0,5%,1/16W,EMPTY,A
     1    GND @S9S_MB_2U_LIB.S9S_MB_2U(SCH_1):GND   I147 @S9S_MB_2U_LIB.S9S_MB_2U(SCH_1):PAGE299
     2 GPU_WP_HW_CTRL_ISO @S9S_MB_2U_LIB.S9S_MB_2U(SCH_1):GPU_WP_HW_CTRL_ISO   I147 @S9S_MB_2U_LIB.S9S_MB_2U(SCH_1):PAGE299

R3473 Q_RES_0402LF-100K,1%,1/16W,EMPA
     1 GPU_PRSNT_N @S9S_MB_2U_LIB.S9S_MB_2U(SCH_1):GPU_PRSNT_N   I163 @S9S_MB_2U_LIB.S9S_MB_2U(SCH_1):PAGE299
     2    GND @S9S_MB_2U_LIB.S9S_MB_2U(SCH_1):GND   I163 @S9S_MB_2U_LIB.S9S_MB_2U(SCH_1):PAGE299

R3474 Q_RES_0402LF-4.7K,5%,1/16W,CHIA
     1 P3V3_AUX @S9S_MB_2U_LIB.S9S_MB_2U(SCH_1):P3V3_AUX   I158 @S9S_MB_2U_LIB.S9S_MB_2U(SCH_1):PAGE299
     2 GPU_PRSNT @S9S_MB_2U_LIB.S9S_MB_2U(SCH_1):GPU_PRSNT   I158 @S9S_MB_2U_LIB.S9S_MB_2U(SCH_1):PAGE299

R3475 Q_RES_0402LF-4.7K,5%,1/16W,CHIA
     1 P3V3_AUX @S9S_MB_2U_LIB.S9S_MB_2U(SCH_1):P3V3_AUX   I154 @S9S_MB_2U_LIB.S9S_MB_2U(SCH_1):PAGE299
     2 GPU_PRSNT_N_ISO @S9S_MB_2U_LIB.S9S_MB_2U(SCH_1):GPU_PRSNT_N_ISO   I154 @S9S_MB_2U_LIB.S9S_MB_2U(SCH_1):PAGE299

R3476 Q_RES_0402LF-33.2,1%,1/16W,CHIA
     1 GPU_FPGA_THERM_OVERT_ISO_N @S9S_MB_2U_LIB.S9S_MB_2U(SCH_1):GPU_FPGA_THERM_OVERT_ISO_N    I25 @S9S_MB_2U_LIB.S9S_MB_2U(SCH_1):PAGE314
     2 GPU_FPGA_THERM_OVERT_ISO_R_N @S9S_MB_2U_LIB.S9S_MB_2U(SCH_1):GPU_FPGA_THERM_OVERT_ISO_R_N    I25 @S9S_MB_2U_LIB.S9S_MB_2U(SCH_1):PAGE314

R3477 Q_RES_0402LF-33.2,1%,1/16W,CHIA
     1 GPU_NVS_PWR_BRAKE_N @S9S_MB_2U_LIB.S9S_MB_2U(SCH_1):GPU_NVS_PWR_BRAKE_N    I26 @S9S_MB_2U_LIB.S9S_MB_2U(SCH_1):PAGE314
     2 GPU_NVS_PWR_BRAKE_R_N @S9S_MB_2U_LIB.S9S_MB_2U(SCH_1):GPU_NVS_PWR_BRAKE_R_N    I26 @S9S_MB_2U_LIB.S9S_MB_2U(SCH_1):PAGE314

R3478 Q_RES_0402LF-33.2,1%,1/16W,CHIA
     1 GPU_FPGA_EROT_RST_N @S9S_MB_2U_LIB.S9S_MB_2U(SCH_1):GPU_FPGA_EROT_RST_N    I23 @S9S_MB_2U_LIB.S9S_MB_2U(SCH_1):PAGE314
     2 GPU_FPGA_EROT_RST_R_N @S9S_MB_2U_LIB.S9S_MB_2U(SCH_1):GPU_FPGA_EROT_RST_R_N    I23 @S9S_MB_2U_LIB.S9S_MB_2U(SCH_1):PAGE314

R3479 Q_RES_0402LF-33.2,1%,1/16W,CHIA
     1 GPU_BASE_STBY_EN @S9S_MB_2U_LIB.S9S_MB_2U(SCH_1):GPU_BASE_STBY_EN    I24 @S9S_MB_2U_LIB.S9S_MB_2U(SCH_1):PAGE314
     2 GPU_BASE_STBY_EN_R @S9S_MB_2U_LIB.S9S_MB_2U(SCH_1):GPU_BASE_STBY_EN_R    I24 @S9S_MB_2U_LIB.S9S_MB_2U(SCH_1):PAGE314

R3480 Q_RES_0402LF-33.2,1%,1/16W,CHIA
     1 GPU_BASE_HMC_READY_ISO @S9S_MB_2U_LIB.S9S_MB_2U(SCH_1):GPU_BASE_HMC_READY_ISO    I21 @S9S_MB_2U_LIB.S9S_MB_2U(SCH_1):PAGE314
     2 GPU_BASE_HMC_READY_ISO_R @S9S_MB_2U_LIB.S9S_MB_2U(SCH_1):GPU_BASE_HMC_READY_ISO_R    I21 @S9S_MB_2U_LIB.S9S_MB_2U(SCH_1):PAGE314

R3481 Q_RES_0402LF-33.2,1%,1/16W,CHIA
     1 GPU_HMC_PRSNT_ISO_N @S9S_MB_2U_LIB.S9S_MB_2U(SCH_1):GPU_HMC_PRSNT_ISO_N    I22 @S9S_MB_2U_LIB.S9S_MB_2U(SCH_1):PAGE314
     2 GPU_HMC_PRSNT_ISO_R_N @S9S_MB_2U_LIB.S9S_MB_2U(SCH_1):GPU_HMC_PRSNT_ISO_R_N    I22 @S9S_MB_2U_LIB.S9S_MB_2U(SCH_1):PAGE314

R3482 Q_RES_0402LF-33.2,1%,1/16W,CHIA
     1 GPU_FPGA_BOOT_EN @S9S_MB_2U_LIB.S9S_MB_2U(SCH_1):GPU_FPGA_BOOT_EN    I19 @S9S_MB_2U_LIB.S9S_MB_2U(SCH_1):PAGE314
     2 GPU_FPGA_BOOT_EN_R @S9S_MB_2U_LIB.S9S_MB_2U(SCH_1):GPU_FPGA_BOOT_EN_R    I19 @S9S_MB_2U_LIB.S9S_MB_2U(SCH_1):PAGE314

R3483 Q_RES_0402LF-33.2,1%,1/16W,CHIA
     1 GPU_FPGA_EROT_RECOV_N @S9S_MB_2U_LIB.S9S_MB_2U(SCH_1):GPU_FPGA_EROT_RECOV_N    I20 @S9S_MB_2U_LIB.S9S_MB_2U(SCH_1):PAGE314
     2 GPU_FPGA_EROT_RECOV_R_N @S9S_MB_2U_LIB.S9S_MB_2U(SCH_1):GPU_FPGA_EROT_RECOV_R_N    I20 @S9S_MB_2U_LIB.S9S_MB_2U(SCH_1):PAGE314

R3484 Q_RES_0402LF-33.2,1%,1/16W,CHIA
     1 GPU_FPGA_OVERT_ISO_N @S9S_MB_2U_LIB.S9S_MB_2U(SCH_1):GPU_FPGA_OVERT_ISO_N    I17 @S9S_MB_2U_LIB.S9S_MB_2U(SCH_1):PAGE314
     2 GPU_FPGA_OVERT_ISO_R_N @S9S_MB_2U_LIB.S9S_MB_2U(SCH_1):GPU_FPGA_OVERT_ISO_R_N    I17 @S9S_MB_2U_LIB.S9S_MB_2U(SCH_1):PAGE314

R3485 Q_RES_0402LF-33.2,1%,1/16W,CHIA
     1 GPU_WP_HW_CTRL_N @S9S_MB_2U_LIB.S9S_MB_2U(SCH_1):GPU_WP_HW_CTRL_N    I18 @S9S_MB_2U_LIB.S9S_MB_2U(SCH_1):PAGE314
     2 GPU_WP_HW_CTRL_R_N @S9S_MB_2U_LIB.S9S_MB_2U(SCH_1):GPU_WP_HW_CTRL_R_N    I18 @S9S_MB_2U_LIB.S9S_MB_2U(SCH_1):PAGE314

R3486 Q_RES_0402LF-33.2,1%,1/16W,CHIA
     1 GPU_PRSNT_N_ISO @S9S_MB_2U_LIB.S9S_MB_2U(SCH_1):GPU_PRSNT_N_ISO    I15 @S9S_MB_2U_LIB.S9S_MB_2U(SCH_1):PAGE314
     2 GPU_PRSNT_N_ISO_R @S9S_MB_2U_LIB.S9S_MB_2U(SCH_1):GPU_PRSNT_N_ISO_R    I15 @S9S_MB_2U_LIB.S9S_MB_2U(SCH_1):PAGE314

R3487 Q_RES_0402LF-10K,1%,1/16W,CHIPA
     1 P3V3_AUX @S9S_MB_2U_LIB.S9S_MB_2U(SCH_1):P3V3_AUX   I166 @S9S_MB_2U_LIB.S9S_MB_2U(SCH_1):PAGE299
     2 GPU_PRSNT_N @S9S_MB_2U_LIB.S9S_MB_2U(SCH_1):GPU_PRSNT_N   I166 @S9S_MB_2U_LIB.S9S_MB_2U(SCH_1):PAGE299

R3488 Q_RES_0402LF-4.7K,5%,1/16W,CHIA
     1 P3V3_AUX @S9S_MB_2U_LIB.S9S_MB_2U(SCH_1):P3V3_AUX    I40 @S9S_MB_2U_LIB.S9S_MB_2U(SCH_1):PAGE296
     2 GPU_FPGA_EROT_RST_N @S9S_MB_2U_LIB.S9S_MB_2U(SCH_1):GPU_FPGA_EROT_RST_N    I40 @S9S_MB_2U_LIB.S9S_MB_2U(SCH_1):PAGE296

R3489 Q_RES_0402LF-100K,1%,1/16W,EMPA
     1 GPU_FPGA_EROT_RST_N @S9S_MB_2U_LIB.S9S_MB_2U(SCH_1):GPU_FPGA_EROT_RST_N    I42 @S9S_MB_2U_LIB.S9S_MB_2U(SCH_1):PAGE296
     2    GND @S9S_MB_2U_LIB.S9S_MB_2U(SCH_1):GND    I42 @S9S_MB_2U_LIB.S9S_MB_2U(SCH_1):PAGE296

R3490 Q_RES_0402LF-4.7K,5%,1/16W,CHIA
     1 P3V3_AUX @S9S_MB_2U_LIB.S9S_MB_2U(SCH_1):P3V3_AUX    I57 @S9S_MB_2U_LIB.S9S_MB_2U(SCH_1):PAGE296
     2 GPU_FPGA_EROT_RECOV_N @S9S_MB_2U_LIB.S9S_MB_2U(SCH_1):GPU_FPGA_EROT_RECOV_N    I57 @S9S_MB_2U_LIB.S9S_MB_2U(SCH_1):PAGE296

R3491 Q_RES_0402LF-100K,1%,1/16W,EMPA
     1 GPU_FPGA_EROT_RECOV_N @S9S_MB_2U_LIB.S9S_MB_2U(SCH_1):GPU_FPGA_EROT_RECOV_N    I70 @S9S_MB_2U_LIB.S9S_MB_2U(SCH_1):PAGE296
     2    GND @S9S_MB_2U_LIB.S9S_MB_2U(SCH_1):GND    I70 @S9S_MB_2U_LIB.S9S_MB_2U(SCH_1):PAGE296

R3492 Q_RES_0402LF-54.9K,1%,1/16W,CHA
     1 P3V3_AUX @S9S_MB_2U_LIB.S9S_MB_2U(SCH_1):P3V3_AUX    I47 @S9S_MB_2U_LIB.S9S_MB_2U(SCH_1):PAGE296
     2 GPU_FPGA_EROT_RST_BUF_R_N @S9S_MB_2U_LIB.S9S_MB_2U(SCH_1):GPU_FPGA_EROT_RST_BUF_R_N    I47 @S9S_MB_2U_LIB.S9S_MB_2U(SCH_1):PAGE296

R3493 Q_RES_0402LF-100K,1%,1/16W,EMPA
     1 GPU_FPGA_EROT_RST_BUF_R_N @S9S_MB_2U_LIB.S9S_MB_2U(SCH_1):GPU_FPGA_EROT_RST_BUF_R_N    I48 @S9S_MB_2U_LIB.S9S_MB_2U(SCH_1):PAGE296
     2    GND @S9S_MB_2U_LIB.S9S_MB_2U(SCH_1):GND    I48 @S9S_MB_2U_LIB.S9S_MB_2U(SCH_1):PAGE296

R3494 Q_RES_0402LF-54.9K,1%,1/16W,CHA
     1 P3V3_AUX @S9S_MB_2U_LIB.S9S_MB_2U(SCH_1):P3V3_AUX    I55 @S9S_MB_2U_LIB.S9S_MB_2U(SCH_1):PAGE296
     2 GPU_FPGA_EROT_RECOV_BUF_R_N @S9S_MB_2U_LIB.S9S_MB_2U(SCH_1):GPU_FPGA_EROT_RECOV_BUF_R_N    I55 @S9S_MB_2U_LIB.S9S_MB_2U(SCH_1):PAGE296

R3495 Q_RES_0402LF-100K,1%,1/16W,EMPA
     1 GPU_FPGA_EROT_RECOV_BUF_R_N @S9S_MB_2U_LIB.S9S_MB_2U(SCH_1):GPU_FPGA_EROT_RECOV_BUF_R_N    I62 @S9S_MB_2U_LIB.S9S_MB_2U(SCH_1):PAGE296
     2    GND @S9S_MB_2U_LIB.S9S_MB_2U(SCH_1):GND    I62 @S9S_MB_2U_LIB.S9S_MB_2U(SCH_1):PAGE296

R3496 Q_RES_0402LF-33.2,1%,1/16W,CHIA
     1 GPU_FPGA_EROT_RST_BUF_R_N @S9S_MB_2U_LIB.S9S_MB_2U(SCH_1):GPU_FPGA_EROT_RST_BUF_R_N    I45 @S9S_MB_2U_LIB.S9S_MB_2U(SCH_1):PAGE296
     2 GPU_FPGA_EROT_RST_BUF_N @S9S_MB_2U_LIB.S9S_MB_2U(SCH_1):GPU_FPGA_EROT_RST_BUF_N    I45 @S9S_MB_2U_LIB.S9S_MB_2U(SCH_1):PAGE296

R3497 Q_RES_0402LF-33.2,1%,1/16W,CHIA
     1 GPU_FPGA_EROT_RECOV_BUF_R_N @S9S_MB_2U_LIB.S9S_MB_2U(SCH_1):GPU_FPGA_EROT_RECOV_BUF_R_N    I53 @S9S_MB_2U_LIB.S9S_MB_2U(SCH_1):PAGE296
     2 GPU_FPGA_EROT_RECOV_BUF_N @S9S_MB_2U_LIB.S9S_MB_2U(SCH_1):GPU_FPGA_EROT_RECOV_BUF_N    I53 @S9S_MB_2U_LIB.S9S_MB_2U(SCH_1):PAGE296

R3498 Q_RES_0402LF-54.9K,1%,1/16W,CHA
     1 P3V3_AUX @S9S_MB_2U_LIB.S9S_MB_2U(SCH_1):P3V3_AUX   I167 @S9S_MB_2U_LIB.S9S_MB_2U(SCH_1):PAGE299
     2 GPU_FPGA_THERM_OVERT_N @S9S_MB_2U_LIB.S9S_MB_2U(SCH_1):GPU_FPGA_THERM_OVERT_N   I167 @S9S_MB_2U_LIB.S9S_MB_2U(SCH_1):PAGE299

R3499 Q_RES_0402LF-0,5%,1/16W,CHIP,CA
     1 GPU_BASE_ID1 @S9S_MB_2U_LIB.S9S_MB_2U(SCH_1):GPU_BASE_ID1   I118 @S9S_MB_2U_LIB.S9S_MB_2U(SCH_1):PAGE214
     2 GPU_BASE_ID1_R @S9S_MB_2U_LIB.S9S_MB_2U(SCH_1):GPU_BASE_ID1_R   I118 @S9S_MB_2U_LIB.S9S_MB_2U(SCH_1):PAGE214

R3500 Q_RES_0402LF-4.7K,5%,1/16W,CHIA
     1 P3V3_OCP_SFF @S9S_MB_2U_LIB.S9S_MB_2U(SCH_1):P3V3_OCP_SFF    I31 @S9S_MB_2U_LIB.S9S_MB_2U(SCH_1):PAGE216
     2 SMB_OCP_SFF_3V3AUX_BUF_SCL @S9S_MB_2U_LIB.S9S_MB_2U(SCH_1):SMB_OCP_SFF_3V3AUX_BUF_SCL    I31 @S9S_MB_2U_LIB.S9S_MB_2U(SCH_1):PAGE216

R3501 Q_RES_0402LF-4.7K,5%,1/16W,CHIA
     1 P3V3_OCP_SFF @S9S_MB_2U_LIB.S9S_MB_2U(SCH_1):P3V3_OCP_SFF    I30 @S9S_MB_2U_LIB.S9S_MB_2U(SCH_1):PAGE216
     2 SMB_OCP_SFF_3V3AUX_BUF_SDA @S9S_MB_2U_LIB.S9S_MB_2U(SCH_1):SMB_OCP_SFF_3V3AUX_BUF_SDA    I30 @S9S_MB_2U_LIB.S9S_MB_2U(SCH_1):PAGE216

R3502 Q_RES_0402LF-100K,1%,1/16W,EMPA
     1 GPU_FPGA_EROT_FATALERR_N @S9S_MB_2U_LIB.S9S_MB_2U(SCH_1):GPU_FPGA_EROT_FATALERR_N   I181 @S9S_MB_2U_LIB.S9S_MB_2U(SCH_1):PAGE299
     2    GND @S9S_MB_2U_LIB.S9S_MB_2U(SCH_1):GND   I181 @S9S_MB_2U_LIB.S9S_MB_2U(SCH_1):PAGE299

R3503 Q_RES_0402LF-4.7K,5%,1/16W,CHIA
     1 P3V3_AUX @S9S_MB_2U_LIB.S9S_MB_2U(SCH_1):P3V3_AUX   I177 @S9S_MB_2U_LIB.S9S_MB_2U(SCH_1):PAGE299
     2 GPU_FPGA_EROT_FATALERR @S9S_MB_2U_LIB.S9S_MB_2U(SCH_1):GPU_FPGA_EROT_FATALERR   I177 @S9S_MB_2U_LIB.S9S_MB_2U(SCH_1):PAGE299

R3504 Q_RES_0402LF-4.7K,5%,1/16W,CHIA
     1 P3V3_AUX @S9S_MB_2U_LIB.S9S_MB_2U(SCH_1):P3V3_AUX   I174 @S9S_MB_2U_LIB.S9S_MB_2U(SCH_1):PAGE299
     2 GPU_FPGA_EROT_FATALERR_ISO_N @S9S_MB_2U_LIB.S9S_MB_2U(SCH_1):GPU_FPGA_EROT_FATALERR_ISO_N   I174 @S9S_MB_2U_LIB.S9S_MB_2U(SCH_1):PAGE299

R3505 Q_RES_0402LF-33.2,1%,1/16W,CHIA
     1 GPU_FPGA_EROT_FATALERR_ISO_N @S9S_MB_2U_LIB.S9S_MB_2U(SCH_1):GPU_FPGA_EROT_FATALERR_ISO_N    I16 @S9S_MB_2U_LIB.S9S_MB_2U(SCH_1):PAGE314
     2 GPU_FPGA_EROT_FATALERR_ISO_R_N @S9S_MB_2U_LIB.S9S_MB_2U(SCH_1):GPU_FPGA_EROT_FATALERR_ISO_R_N    I16 @S9S_MB_2U_LIB.S9S_MB_2U(SCH_1):PAGE314

R3506 Q_RES_0402LF-4.7K,5%,1/16W,EMPA
     1 P3V3_AUX @S9S_MB_2U_LIB.S9S_MB_2U(SCH_1):P3V3_AUX   I193 @S9S_MB_2U_LIB.S9S_MB_2U(SCH_1):PAGE140
     2 GPU_FPGA_RST_R_N @S9S_MB_2U_LIB.S9S_MB_2U(SCH_1):GPU_FPGA_RST_R_N   I193 @S9S_MB_2U_LIB.S9S_MB_2U(SCH_1):PAGE140

R3507 Q_RES_0402LF-10K,1%,1/16W,CHIPA
     1 GPU_FPGA_RST_R_N @S9S_MB_2U_LIB.S9S_MB_2U(SCH_1):GPU_FPGA_RST_R_N   I192 @S9S_MB_2U_LIB.S9S_MB_2U(SCH_1):PAGE140
     2    GND @S9S_MB_2U_LIB.S9S_MB_2U(SCH_1):GND   I192 @S9S_MB_2U_LIB.S9S_MB_2U(SCH_1):PAGE140

R3508 Q_RES_0402LF-54.9K,1%,1/16W,CHA
     1 FM_GPU_PWR_EN_R1 @S9S_MB_2U_LIB.S9S_MB_2U(SCH_1):FM_GPU_PWR_EN_R1   I194 @S9S_MB_2U_LIB.S9S_MB_2U(SCH_1):PAGE140
     2    GND @S9S_MB_2U_LIB.S9S_MB_2U(SCH_1):GND   I194 @S9S_MB_2U_LIB.S9S_MB_2U(SCH_1):PAGE140

R3509 Q_RES_0402LF-10K,1%,1/16W,CHIPA
     1 GPU_FPGA_RST_R1_BUF_N @S9S_MB_2U_LIB.S9S_MB_2U(SCH_1):GPU_FPGA_RST_R1_BUF_N   I191 @S9S_MB_2U_LIB.S9S_MB_2U(SCH_1):PAGE140
     2    GND @S9S_MB_2U_LIB.S9S_MB_2U(SCH_1):GND   I191 @S9S_MB_2U_LIB.S9S_MB_2U(SCH_1):PAGE140

R3510 Q_RES_0402LF-54.9K,1%,1/16W,CHA
     1 P3V3_AUX @S9S_MB_2U_LIB.S9S_MB_2U(SCH_1):P3V3_AUX   I176 @S9S_MB_2U_LIB.S9S_MB_2U(SCH_1):PAGE145
     2 FM_SMB_1_ALERT_GPU_N @S9S_MB_2U_LIB.S9S_MB_2U(SCH_1):FM_SMB_1_ALERT_GPU_N   I176 @S9S_MB_2U_LIB.S9S_MB_2U(SCH_1):PAGE145

R3511 Q_RES_0402LF-54.9K,1%,1/16W,CHA
     1 GPU_FPGA_READY @S9S_MB_2U_LIB.S9S_MB_2U(SCH_1):GPU_FPGA_READY   I172 @S9S_MB_2U_LIB.S9S_MB_2U(SCH_1):PAGE145
     2    GND @S9S_MB_2U_LIB.S9S_MB_2U(SCH_1):GND   I172 @S9S_MB_2U_LIB.S9S_MB_2U(SCH_1):PAGE145

R3512 Q_RES_0402LF-100K,1%,1/16W,EMPA
     1 P3V3_AUX @S9S_MB_2U_LIB.S9S_MB_2U(SCH_1):P3V3_AUX   I174 @S9S_MB_2U_LIB.S9S_MB_2U(SCH_1):PAGE145
     2 FM_GPU_PWRGD @S9S_MB_2U_LIB.S9S_MB_2U(SCH_1):FM_GPU_PWRGD   I174 @S9S_MB_2U_LIB.S9S_MB_2U(SCH_1):PAGE145

R3513 Q_RES_0402LF-54.9K,1%,1/16W,CHA
     1 FM_GPU_PWRGD @S9S_MB_2U_LIB.S9S_MB_2U(SCH_1):FM_GPU_PWRGD   I173 @S9S_MB_2U_LIB.S9S_MB_2U(SCH_1):PAGE145
     2    GND @S9S_MB_2U_LIB.S9S_MB_2U(SCH_1):GND   I173 @S9S_MB_2U_LIB.S9S_MB_2U(SCH_1):PAGE145

R3514 Q_RES_0402LF-54.9K,1%,1/16W,CHA
     1 P3V3_AUX @S9S_MB_2U_LIB.S9S_MB_2U(SCH_1):P3V3_AUX   I175 @S9S_MB_2U_LIB.S9S_MB_2U(SCH_1):PAGE145
     2 FM_SMB_2_ALERT_GPU_N @S9S_MB_2U_LIB.S9S_MB_2U(SCH_1):FM_SMB_2_ALERT_GPU_N   I175 @S9S_MB_2U_LIB.S9S_MB_2U(SCH_1):PAGE145

R3515 Q_RES_0402LF-49.9,1%,1/16W,CHIA
     1 FM_SWB_PWR_EN_R1_BUF @S9S_MB_2U_LIB.S9S_MB_2U(SCH_1):FM_SWB_PWR_EN_R1_BUF   I198 @S9S_MB_2U_LIB.S9S_MB_2U(SCH_1):PAGE160
     2 FM_SWB_PWR_EN_R_BUF @S9S_MB_2U_LIB.S9S_MB_2U(SCH_1):FM_SWB_PWR_EN_R_BUF   I198 @S9S_MB_2U_LIB.S9S_MB_2U(SCH_1):PAGE160

R3516 Q_RES_0402LF-0,5%,1/16W,CHIP,CA
     1 GPU_BASE_ID0 @S9S_MB_2U_LIB.S9S_MB_2U(SCH_1):GPU_BASE_ID0   I127 @S9S_MB_2U_LIB.S9S_MB_2U(SCH_1):PAGE214
     2 GPU_BASE_ID0_R @S9S_MB_2U_LIB.S9S_MB_2U(SCH_1):GPU_BASE_ID0_R   I127 @S9S_MB_2U_LIB.S9S_MB_2U(SCH_1):PAGE214

R3517 Q_RES_0402LF-0,5%,1/16W,CHIP,CA
     1 GPU_PEX_STRAP1 @S9S_MB_2U_LIB.S9S_MB_2U(SCH_1):GPU_PEX_STRAP1   I128 @S9S_MB_2U_LIB.S9S_MB_2U(SCH_1):PAGE214
     2 GPU_PEX_STRAP1_R @S9S_MB_2U_LIB.S9S_MB_2U(SCH_1):GPU_PEX_STRAP1_R   I128 @S9S_MB_2U_LIB.S9S_MB_2U(SCH_1):PAGE214

R3518 Q_RES_0402LF-0,5%,1/16W,CHIP,CA
     1 GPU_PEX_STRAP0 @S9S_MB_2U_LIB.S9S_MB_2U(SCH_1):GPU_PEX_STRAP0   I129 @S9S_MB_2U_LIB.S9S_MB_2U(SCH_1):PAGE214
     2 GPU_PEX_STRAP0_R @S9S_MB_2U_LIB.S9S_MB_2U(SCH_1):GPU_PEX_STRAP0_R   I129 @S9S_MB_2U_LIB.S9S_MB_2U(SCH_1):PAGE214

R3519 Q_RES_0402LF-4.7K,5%,1/16W,CHIA
     1 P3V3_OCP_V3_2 @S9S_MB_2U_LIB.S9S_MB_2U(SCH_1):P3V3_OCP_V3_2    I34 @S9S_MB_2U_LIB.S9S_MB_2U(SCH_1):PAGE216
     2 SMB_OCP_V3_2_3V3AUX_BUF_SCL @S9S_MB_2U_LIB.S9S_MB_2U(SCH_1):SMB_OCP_V3_2_3V3AUX_BUF_SCL    I34 @S9S_MB_2U_LIB.S9S_MB_2U(SCH_1):PAGE216

R3520 Q_RES_0402LF-4.7K,5%,1/16W,CHIA
     1 P3V3_OCP_V3_2 @S9S_MB_2U_LIB.S9S_MB_2U(SCH_1):P3V3_OCP_V3_2    I33 @S9S_MB_2U_LIB.S9S_MB_2U(SCH_1):PAGE216
     2 SMB_OCP_V3_2_3V3AUX_BUF_SDA @S9S_MB_2U_LIB.S9S_MB_2U(SCH_1):SMB_OCP_V3_2_3V3AUX_BUF_SDA    I33 @S9S_MB_2U_LIB.S9S_MB_2U(SCH_1):PAGE216

R3521 Q_RES_0402LF-54.9K,1%,1/16W,CHA
     1 P3V3_AUX @S9S_MB_2U_LIB.S9S_MB_2U(SCH_1):P3V3_AUX    I23 @S9S_MB_2U_LIB.S9S_MB_2U(SCH_1):PAGE222
     2 SMB_2_BMC_GPU_BUF_R_SCL @S9S_MB_2U_LIB.S9S_MB_2U(SCH_1):SMB_2_BMC_GPU_BUF_R_SCL    I23 @S9S_MB_2U_LIB.S9S_MB_2U(SCH_1):PAGE222

R3522 Q_RES_0402LF-54.9K,1%,1/16W,CHA
     1 P3V3_AUX @S9S_MB_2U_LIB.S9S_MB_2U(SCH_1):P3V3_AUX    I25 @S9S_MB_2U_LIB.S9S_MB_2U(SCH_1):PAGE222
     2 SMB_2_BMC_GPU_BUF_R_SDA @S9S_MB_2U_LIB.S9S_MB_2U(SCH_1):SMB_2_BMC_GPU_BUF_R_SDA    I25 @S9S_MB_2U_LIB.S9S_MB_2U(SCH_1):PAGE222

R3523 Q_RES_0402LF-54.9K,1%,1/16W,CHA
     1 P3V3_AUX @S9S_MB_2U_LIB.S9S_MB_2U(SCH_1):P3V3_AUX    I80 @S9S_MB_2U_LIB.S9S_MB_2U(SCH_1):PAGE222
     2 SMB_1_BMC_GPU_BUF_R_SCL @S9S_MB_2U_LIB.S9S_MB_2U(SCH_1):SMB_1_BMC_GPU_BUF_R_SCL    I80 @S9S_MB_2U_LIB.S9S_MB_2U(SCH_1):PAGE222

R3524 Q_RES_0402LF-54.9K,1%,1/16W,CHA
     1 P3V3_AUX @S9S_MB_2U_LIB.S9S_MB_2U(SCH_1):P3V3_AUX    I81 @S9S_MB_2U_LIB.S9S_MB_2U(SCH_1):PAGE222
     2 SMB_1_BMC_GPU_BUF_R_SDA @S9S_MB_2U_LIB.S9S_MB_2U(SCH_1):SMB_1_BMC_GPU_BUF_R_SDA    I81 @S9S_MB_2U_LIB.S9S_MB_2U(SCH_1):PAGE222

R3525 Q_RES_0402LF-54.9K,1%,1/16W,CHA
     1 P3V3_AUX @S9S_MB_2U_LIB.S9S_MB_2U(SCH_1):P3V3_AUX   I184 @S9S_MB_2U_LIB.S9S_MB_2U(SCH_1):PAGE299
     2 GPU_FPGA_EROT_FATALERR_N @S9S_MB_2U_LIB.S9S_MB_2U(SCH_1):GPU_FPGA_EROT_FATALERR_N   I184 @S9S_MB_2U_LIB.S9S_MB_2U(SCH_1):PAGE299

R3526 Q_RES_0402LF-0,5%,1/16W,CHIP,CA
     1 SMB_PCIE0_3V3AUX_SCL_R5 @S9S_MB_2U_LIB.S9S_MB_2U(SCH_1):SMB_PCIE0_3V3AUX_SCL_R5    I35 @S9S_MB_2U_LIB.S9S_MB_2U(SCH_1):PAGE219
     2 SMB_SENSOR_E1S_3V3AUX_SCL @S9S_MB_2U_LIB.S9S_MB_2U(SCH_1):SMB_SENSOR_E1S_3V3AUX_SCL    I35 @S9S_MB_2U_LIB.S9S_MB_2U(SCH_1):PAGE219

R3527 Q_RES_0402LF-0,5%,1/16W,CHIP,CA
     1 SMB_PCIE0_3V3AUX_SDA_R5 @S9S_MB_2U_LIB.S9S_MB_2U(SCH_1):SMB_PCIE0_3V3AUX_SDA_R5    I37 @S9S_MB_2U_LIB.S9S_MB_2U(SCH_1):PAGE219
     2 SMB_SENSOR_E1S_3V3AUX_SDA @S9S_MB_2U_LIB.S9S_MB_2U(SCH_1):SMB_SENSOR_E1S_3V3AUX_SDA    I37 @S9S_MB_2U_LIB.S9S_MB_2U(SCH_1):PAGE219

R3529 Q_RES_0402LF-10K,1%,1/16W,CHIPA
     1 P3V3_AUX @S9S_MB_2U_LIB.S9S_MB_2U(SCH_1):P3V3_AUX    I99 @S9S_MB_2U_LIB.S9S_MB_2U(SCH_1):PAGE183
     2 SMB_PCIE_E1S_ISO_EN_R @S9S_MB_2U_LIB.S9S_MB_2U(SCH_1):SMB_PCIE_E1S_ISO_EN_R    I99 @S9S_MB_2U_LIB.S9S_MB_2U(SCH_1):PAGE183

R3530 Q_RES_0402LF-4.7K,5%,1/16W,CHIA
     1 P3V3_E1S_0 @S9S_MB_2U_LIB.S9S_MB_2U(SCH_1):P3V3_E1S_0    I80 @S9S_MB_2U_LIB.S9S_MB_2U(SCH_1):PAGE183
     2 SMB_E1S_3V3AUX_ISO_SCL_R @S9S_MB_2U_LIB.S9S_MB_2U(SCH_1):SMB_E1S_3V3AUX_ISO_SCL_R    I80 @S9S_MB_2U_LIB.S9S_MB_2U(SCH_1):PAGE183

R3531 Q_RES_0402LF-200K,1%,1/16W,EMPA
     1 SMB_PCIE_E1S_ISO_EN @S9S_MB_2U_LIB.S9S_MB_2U(SCH_1):SMB_PCIE_E1S_ISO_EN    I96 @S9S_MB_2U_LIB.S9S_MB_2U(SCH_1):PAGE183
     2 SMB_PCIE_E1S_ISO_EN_R @S9S_MB_2U_LIB.S9S_MB_2U(SCH_1):SMB_PCIE_E1S_ISO_EN_R    I96 @S9S_MB_2U_LIB.S9S_MB_2U(SCH_1):PAGE183

R3532 Q_RES_0402LF-4.7K,5%,1/16W,CHIA
     1 P3V3_E1S_0 @S9S_MB_2U_LIB.S9S_MB_2U(SCH_1):P3V3_E1S_0    I78 @S9S_MB_2U_LIB.S9S_MB_2U(SCH_1):PAGE183
     2 SMB_E1S_3V3AUX_ISO_SDA_R @S9S_MB_2U_LIB.S9S_MB_2U(SCH_1):SMB_E1S_3V3AUX_ISO_SDA_R    I78 @S9S_MB_2U_LIB.S9S_MB_2U(SCH_1):PAGE183

R3533 Q_RES_0402LF-33.2,1%,1/16W,CHIA
     1 SMB_E1S_3V3AUX_ISO_SCL_R @S9S_MB_2U_LIB.S9S_MB_2U(SCH_1):SMB_E1S_3V3AUX_ISO_SCL_R    I76 @S9S_MB_2U_LIB.S9S_MB_2U(SCH_1):PAGE183
     2 SMB_E1S_3V3AUX_ISO_SCL @S9S_MB_2U_LIB.S9S_MB_2U(SCH_1):SMB_E1S_3V3AUX_ISO_SCL    I76 @S9S_MB_2U_LIB.S9S_MB_2U(SCH_1):PAGE183

R3534 Q_RES_0402LF-33.2,1%,1/16W,CHIA
     1 SMB_E1S_3V3AUX_ISO_SDA_R @S9S_MB_2U_LIB.S9S_MB_2U(SCH_1):SMB_E1S_3V3AUX_ISO_SDA_R    I77 @S9S_MB_2U_LIB.S9S_MB_2U(SCH_1):PAGE183
     2 SMB_E1S_3V3AUX_ISO_SDA @S9S_MB_2U_LIB.S9S_MB_2U(SCH_1):SMB_E1S_3V3AUX_ISO_SDA    I77 @S9S_MB_2U_LIB.S9S_MB_2U(SCH_1):PAGE183

R3535 Q_RES_0402LF-2.2K,5%,1/16W,CHIA
     1 P3V3_AUX @S9S_MB_2U_LIB.S9S_MB_2U(SCH_1):P3V3_AUX    I49 @S9S_MB_2U_LIB.S9S_MB_2U(SCH_1):PAGE219
     2 SMB_SENSOR_E1S_3V3AUX_SCL @S9S_MB_2U_LIB.S9S_MB_2U(SCH_1):SMB_SENSOR_E1S_3V3AUX_SCL    I49 @S9S_MB_2U_LIB.S9S_MB_2U(SCH_1):PAGE219

R3536 Q_RES_0402LF-2.2K,5%,1/16W,CHIA
     1 P3V3_AUX @S9S_MB_2U_LIB.S9S_MB_2U(SCH_1):P3V3_AUX    I50 @S9S_MB_2U_LIB.S9S_MB_2U(SCH_1):PAGE219
     2 SMB_SENSOR_E1S_3V3AUX_SDA @S9S_MB_2U_LIB.S9S_MB_2U(SCH_1):SMB_SENSOR_E1S_3V3AUX_SDA    I50 @S9S_MB_2U_LIB.S9S_MB_2U(SCH_1):PAGE219

R3553 Q_RES_0402LF-33.2,1%,1/16W,CHIA
     1 SMB_LM75_3_3V3AUX_SCL @S9S_MB_2U_LIB.S9S_MB_2U(SCH_1):SMB_LM75_3_3V3AUX_SCL   I134 @S9S_MB_2U_LIB.S9S_MB_2U(SCH_1):PAGE161
     2 SMB_LM75_3_3V3AUX_SCL_R1 @S9S_MB_2U_LIB.S9S_MB_2U(SCH_1):SMB_LM75_3_3V3AUX_SCL_R1   I134 @S9S_MB_2U_LIB.S9S_MB_2U(SCH_1):PAGE161

R3554 Q_RES_0402LF-33.2,1%,1/16W,CHIA
     1 SMB_LM75_3_3V3AUX_SDA @S9S_MB_2U_LIB.S9S_MB_2U(SCH_1):SMB_LM75_3_3V3AUX_SDA   I136 @S9S_MB_2U_LIB.S9S_MB_2U(SCH_1):PAGE161
     2 SMB_LM75_3_3V3AUX_SDA_R1 @S9S_MB_2U_LIB.S9S_MB_2U(SCH_1):SMB_LM75_3_3V3AUX_SDA_R1   I136 @S9S_MB_2U_LIB.S9S_MB_2U(SCH_1):PAGE161

R3559 Q_RES_0402LF-0,5%,1/16W,CHIP,CA
     1 OCP_V3_2_P3V3_ADC_ALERT_R @S9S_MB_2U_LIB.S9S_MB_2U(SCH_1):OCP_V3_2_P3V3_ADC_ALERT_R    I96 @S9S_MB_2U_LIB.S9S_MB_2U(SCH_1):PAGE163
     2 OCP_V3_2_P3V3_ADC_ALERT @S9S_MB_2U_LIB.S9S_MB_2U(SCH_1):OCP_V3_2_P3V3_ADC_ALERT    I96 @S9S_MB_2U_LIB.S9S_MB_2U(SCH_1):PAGE163

R3560 Q_RES_0402LF-0,5%,1/16W,CHIP,CA
     1 M2_0_P3V3_ADC_ALERT_R @S9S_MB_2U_LIB.S9S_MB_2U(SCH_1):M2_0_P3V3_ADC_ALERT_R    I41 @S9S_MB_2U_LIB.S9S_MB_2U(SCH_1):PAGE163
     2 M2_0_P3V3_ADC_ALERT @S9S_MB_2U_LIB.S9S_MB_2U(SCH_1):M2_0_P3V3_ADC_ALERT    I41 @S9S_MB_2U_LIB.S9S_MB_2U(SCH_1):PAGE163

R3561 Q_RES_0402LF-0,5%,1/16W,CHIP,CA
     1 P12V_SCM_ADC_ALERT_R @S9S_MB_2U_LIB.S9S_MB_2U(SCH_1):P12V_SCM_ADC_ALERT_R    I64 @S9S_MB_2U_LIB.S9S_MB_2U(SCH_1):PAGE163
     2 P12V_SCM_ADC_ALERT @S9S_MB_2U_LIB.S9S_MB_2U(SCH_1):P12V_SCM_ADC_ALERT    I64 @S9S_MB_2U_LIB.S9S_MB_2U(SCH_1):PAGE163

R3563 Q_RES_0402LF-0,5%,1/16W,CHIP,CA
     1 OCP_SFF_P3V3_ADC_ALERT_R @S9S_MB_2U_LIB.S9S_MB_2U(SCH_1):OCP_SFF_P3V3_ADC_ALERT_R    I35 @S9S_MB_2U_LIB.S9S_MB_2U(SCH_1):PAGE295
     2 OCP_SFF_P3V3_ADC_ALERT @S9S_MB_2U_LIB.S9S_MB_2U(SCH_1):OCP_SFF_P3V3_ADC_ALERT    I35 @S9S_MB_2U_LIB.S9S_MB_2U(SCH_1):PAGE295

R3568 Q_RES_0402LF-33.2,1%,1/16W,CHIA
     1 SMB_INA230_3_3V3AUX_SCL_R @S9S_MB_2U_LIB.S9S_MB_2U(SCH_1):SMB_INA230_3_3V3AUX_SCL_R   I101 @S9S_MB_2U_LIB.S9S_MB_2U(SCH_1):PAGE163
     2 SMB_INA230_3_3V3AUX_SCL_R1 @S9S_MB_2U_LIB.S9S_MB_2U(SCH_1):SMB_INA230_3_3V3AUX_SCL_R1   I101 @S9S_MB_2U_LIB.S9S_MB_2U(SCH_1):PAGE163

R3569 Q_RES_0402LF-33.2,1%,1/16W,CHIA
     1 SMB_INA230_3_3V3AUX_SDA_R @S9S_MB_2U_LIB.S9S_MB_2U(SCH_1):SMB_INA230_3_3V3AUX_SDA_R   I102 @S9S_MB_2U_LIB.S9S_MB_2U(SCH_1):PAGE163
     2 SMB_INA230_3_3V3AUX_SDA_R1 @S9S_MB_2U_LIB.S9S_MB_2U(SCH_1):SMB_INA230_3_3V3AUX_SDA_R1   I102 @S9S_MB_2U_LIB.S9S_MB_2U(SCH_1):PAGE163

R3570 Q_RES_0402LF-10,1%,1/16W,CHIP,A
     1 P3V3_OCP_V3_2_R @S9S_MB_2U_LIB.S9S_MB_2U(SCH_1):P3V3_OCP_V3_2_R   I109 @S9S_MB_2U_LIB.S9S_MB_2U(SCH_1):PAGE163
     2 VSENSE_P12V_INA230_3_INP @S9S_MB_2U_LIB.S9S_MB_2U(SCH_1):VSENSE_P12V_INA230_3_INP   I109 @S9S_MB_2U_LIB.S9S_MB_2U(SCH_1):PAGE163

R3571 Q_RES_0402LF-10,1%,1/16W,CHIP,A
     1 P3V3_OCP_V3_2 @S9S_MB_2U_LIB.S9S_MB_2U(SCH_1):P3V3_OCP_V3_2   I110 @S9S_MB_2U_LIB.S9S_MB_2U(SCH_1):PAGE163
     2 VSENSE_P12V_INA230_3_INN @S9S_MB_2U_LIB.S9S_MB_2U(SCH_1):VSENSE_P12V_INA230_3_INN   I110 @S9S_MB_2U_LIB.S9S_MB_2U(SCH_1):PAGE163

R3572 Q_RES_0402LF-33.2,1%,1/16W,CHIA
     1 SMB_INA230_4_3V3AUX_SCL_R @S9S_MB_2U_LIB.S9S_MB_2U(SCH_1):SMB_INA230_4_3V3AUX_SCL_R    I38 @S9S_MB_2U_LIB.S9S_MB_2U(SCH_1):PAGE163
     2 SMB_INA230_4_3V3AUX_SCL_R1 @S9S_MB_2U_LIB.S9S_MB_2U(SCH_1):SMB_INA230_4_3V3AUX_SCL_R1    I38 @S9S_MB_2U_LIB.S9S_MB_2U(SCH_1):PAGE163

R3573 Q_RES_0402LF-33.2,1%,1/16W,CHIA
     1 SMB_INA230_4_3V3AUX_SDA_R @S9S_MB_2U_LIB.S9S_MB_2U(SCH_1):SMB_INA230_4_3V3AUX_SDA_R    I37 @S9S_MB_2U_LIB.S9S_MB_2U(SCH_1):PAGE163
     2 SMB_INA230_4_3V3AUX_SDA_R1 @S9S_MB_2U_LIB.S9S_MB_2U(SCH_1):SMB_INA230_4_3V3AUX_SDA_R1    I37 @S9S_MB_2U_LIB.S9S_MB_2U(SCH_1):PAGE163

R3574 Q_RES_0402LF-10,1%,1/16W,CHIP,A
     1   P3V3 @S9S_MB_2U_LIB.S9S_MB_2U(SCH_1):P3V3    I35 @S9S_MB_2U_LIB.S9S_MB_2U(SCH_1):PAGE163
     2 VSENSE_P12V_INA230_4_INP @S9S_MB_2U_LIB.S9S_MB_2U(SCH_1):VSENSE_P12V_INA230_4_INP    I35 @S9S_MB_2U_LIB.S9S_MB_2U(SCH_1):PAGE163

R3575 Q_RES_0402LF-10,1%,1/16W,CHIP,A
     1 P3V3_M2_0 @S9S_MB_2U_LIB.S9S_MB_2U(SCH_1):P3V3_M2_0    I33 @S9S_MB_2U_LIB.S9S_MB_2U(SCH_1):PAGE163
     2 VSENSE_P12V_INA230_4_INN @S9S_MB_2U_LIB.S9S_MB_2U(SCH_1):VSENSE_P12V_INA230_4_INN    I33 @S9S_MB_2U_LIB.S9S_MB_2U(SCH_1):PAGE163

R3576 Q_RES_0402LF-33.2,1%,1/16W,CHIA
     1 SMB_INA230_5_3V3AUX_SCL_R @S9S_MB_2U_LIB.S9S_MB_2U(SCH_1):SMB_INA230_5_3V3AUX_SCL_R    I61 @S9S_MB_2U_LIB.S9S_MB_2U(SCH_1):PAGE163
     2 SMB_INA230_5_3V3AUX_SCL_R1 @S9S_MB_2U_LIB.S9S_MB_2U(SCH_1):SMB_INA230_5_3V3AUX_SCL_R1    I61 @S9S_MB_2U_LIB.S9S_MB_2U(SCH_1):PAGE163

R3577 Q_RES_0402LF-33.2,1%,1/16W,CHIA
     1 SMB_INA230_5_3V3AUX_SDA_R @S9S_MB_2U_LIB.S9S_MB_2U(SCH_1):SMB_INA230_5_3V3AUX_SDA_R    I60 @S9S_MB_2U_LIB.S9S_MB_2U(SCH_1):PAGE163
     2 SMB_INA230_5_3V3AUX_SDA_R1 @S9S_MB_2U_LIB.S9S_MB_2U(SCH_1):SMB_INA230_5_3V3AUX_SDA_R1    I60 @S9S_MB_2U_LIB.S9S_MB_2U(SCH_1):PAGE163

R3578 Q_RES_0402LF-10,1%,1/16W,CHIP,A
     1 P12V_SCM_R @S9S_MB_2U_LIB.S9S_MB_2U(SCH_1):P12V_SCM_R    I58 @S9S_MB_2U_LIB.S9S_MB_2U(SCH_1):PAGE163
     2 VSENSE_P12V_INA230_5_INP @S9S_MB_2U_LIB.S9S_MB_2U(SCH_1):VSENSE_P12V_INA230_5_INP    I58 @S9S_MB_2U_LIB.S9S_MB_2U(SCH_1):PAGE163

R3579 Q_RES_0402LF-10,1%,1/16W,CHIP,A
     1 P12V_SCM @S9S_MB_2U_LIB.S9S_MB_2U(SCH_1):P12V_SCM    I56 @S9S_MB_2U_LIB.S9S_MB_2U(SCH_1):PAGE163
     2 VSENSE_P12V_INA230_5_INN @S9S_MB_2U_LIB.S9S_MB_2U(SCH_1):VSENSE_P12V_INA230_5_INN    I56 @S9S_MB_2U_LIB.S9S_MB_2U(SCH_1):PAGE163

R3580 Q_RES_0402LF-0,5%,1/16W,CHIP,CA
     1 SMB_INA230_3V3AUX_SCL_R @S9S_MB_2U_LIB.S9S_MB_2U(SCH_1):SMB_INA230_3V3AUX_SCL_R    I59 @S9S_MB_2U_LIB.S9S_MB_2U(SCH_1):PAGE219
     2 SMB_INA230_3V3AUX_SCL @S9S_MB_2U_LIB.S9S_MB_2U(SCH_1):SMB_INA230_3V3AUX_SCL    I59 @S9S_MB_2U_LIB.S9S_MB_2U(SCH_1):PAGE219

R3581 Q_RES_0402LF-0,5%,1/16W,CHIP,CA
     1 SMB_INA230_3V3AUX_SDA_R @S9S_MB_2U_LIB.S9S_MB_2U(SCH_1):SMB_INA230_3V3AUX_SDA_R    I60 @S9S_MB_2U_LIB.S9S_MB_2U(SCH_1):PAGE219
     2 SMB_INA230_3V3AUX_SDA @S9S_MB_2U_LIB.S9S_MB_2U(SCH_1):SMB_INA230_3V3AUX_SDA    I60 @S9S_MB_2U_LIB.S9S_MB_2U(SCH_1):PAGE219

R3582 Q_RES_0402LF-2.2K,5%,1/16W,CHIA
     1 P3V3_AUX @S9S_MB_2U_LIB.S9S_MB_2U(SCH_1):P3V3_AUX    I52 @S9S_MB_2U_LIB.S9S_MB_2U(SCH_1):PAGE219
     2 SMB_IOEXP_3V3AUX_SCL @S9S_MB_2U_LIB.S9S_MB_2U(SCH_1):SMB_IOEXP_3V3AUX_SCL    I52 @S9S_MB_2U_LIB.S9S_MB_2U(SCH_1):PAGE219

R3583 Q_RES_0402LF-2.2K,5%,1/16W,CHIA
     1 P3V3_AUX @S9S_MB_2U_LIB.S9S_MB_2U(SCH_1):P3V3_AUX    I51 @S9S_MB_2U_LIB.S9S_MB_2U(SCH_1):PAGE219
     2 SMB_IOEXP_3V3AUX_SDA @S9S_MB_2U_LIB.S9S_MB_2U(SCH_1):SMB_IOEXP_3V3AUX_SDA    I51 @S9S_MB_2U_LIB.S9S_MB_2U(SCH_1):PAGE219

R3586 Q_RES_0402LF-33.2,1%,1/16W,CHIA
     1 SMB_INA230_3V3AUX_SCL @S9S_MB_2U_LIB.S9S_MB_2U(SCH_1):SMB_INA230_3V3AUX_SCL     I4 @S9S_MB_2U_LIB.S9S_MB_2U(SCH_1):PAGE220
     2 SMB_INA230_1_3V3AUX_SCL_R @S9S_MB_2U_LIB.S9S_MB_2U(SCH_1):SMB_INA230_1_3V3AUX_SCL_R     I4 @S9S_MB_2U_LIB.S9S_MB_2U(SCH_1):PAGE220

R3587 Q_RES_0402LF-33.2,1%,1/16W,CHIA
     1 SMB_INA230_3V3AUX_SDA @S9S_MB_2U_LIB.S9S_MB_2U(SCH_1):SMB_INA230_3V3AUX_SDA     I3 @S9S_MB_2U_LIB.S9S_MB_2U(SCH_1):PAGE220
     2 SMB_INA230_1_3V3AUX_SDA_R @S9S_MB_2U_LIB.S9S_MB_2U(SCH_1):SMB_INA230_1_3V3AUX_SDA_R     I3 @S9S_MB_2U_LIB.S9S_MB_2U(SCH_1):PAGE220

R3588 Q_RES_0402LF-33.2,1%,1/16W,CHIA
     1 SMB_INA230_3V3AUX_SCL @S9S_MB_2U_LIB.S9S_MB_2U(SCH_1):SMB_INA230_3V3AUX_SCL    I16 @S9S_MB_2U_LIB.S9S_MB_2U(SCH_1):PAGE220
     2 SMB_INA230_2_3V3AUX_SCL_R @S9S_MB_2U_LIB.S9S_MB_2U(SCH_1):SMB_INA230_2_3V3AUX_SCL_R    I16 @S9S_MB_2U_LIB.S9S_MB_2U(SCH_1):PAGE220

R3589 Q_RES_0402LF-33.2,1%,1/16W,CHIA
     1 SMB_INA230_3V3AUX_SDA @S9S_MB_2U_LIB.S9S_MB_2U(SCH_1):SMB_INA230_3V3AUX_SDA    I11 @S9S_MB_2U_LIB.S9S_MB_2U(SCH_1):PAGE220
     2 SMB_INA230_2_3V3AUX_SDA_R @S9S_MB_2U_LIB.S9S_MB_2U(SCH_1):SMB_INA230_2_3V3AUX_SDA_R    I11 @S9S_MB_2U_LIB.S9S_MB_2U(SCH_1):PAGE220

R3590 Q_RES_0402LF-33.2,1%,1/16W,CHIA
     1 SMB_INA230_3V3AUX_SCL @S9S_MB_2U_LIB.S9S_MB_2U(SCH_1):SMB_INA230_3V3AUX_SCL    I17 @S9S_MB_2U_LIB.S9S_MB_2U(SCH_1):PAGE220
     2 SMB_INA230_3_3V3AUX_SCL_R @S9S_MB_2U_LIB.S9S_MB_2U(SCH_1):SMB_INA230_3_3V3AUX_SCL_R    I17 @S9S_MB_2U_LIB.S9S_MB_2U(SCH_1):PAGE220

R3591 Q_RES_0402LF-33.2,1%,1/16W,CHIA
     1 SMB_INA230_3V3AUX_SDA @S9S_MB_2U_LIB.S9S_MB_2U(SCH_1):SMB_INA230_3V3AUX_SDA    I18 @S9S_MB_2U_LIB.S9S_MB_2U(SCH_1):PAGE220
     2 SMB_INA230_3_3V3AUX_SDA_R @S9S_MB_2U_LIB.S9S_MB_2U(SCH_1):SMB_INA230_3_3V3AUX_SDA_R    I18 @S9S_MB_2U_LIB.S9S_MB_2U(SCH_1):PAGE220

R3592 Q_RES_0402LF-33.2,1%,1/16W,CHIA
     1 SMB_INA230_3V3AUX_SCL @S9S_MB_2U_LIB.S9S_MB_2U(SCH_1):SMB_INA230_3V3AUX_SCL    I20 @S9S_MB_2U_LIB.S9S_MB_2U(SCH_1):PAGE220
     2 SMB_INA230_5_3V3AUX_SCL_R @S9S_MB_2U_LIB.S9S_MB_2U(SCH_1):SMB_INA230_5_3V3AUX_SCL_R    I20 @S9S_MB_2U_LIB.S9S_MB_2U(SCH_1):PAGE220

R3593 Q_RES_0402LF-33.2,1%,1/16W,CHIA
     1 SMB_INA230_3V3AUX_SDA @S9S_MB_2U_LIB.S9S_MB_2U(SCH_1):SMB_INA230_3V3AUX_SDA    I19 @S9S_MB_2U_LIB.S9S_MB_2U(SCH_1):PAGE220
     2 SMB_INA230_5_3V3AUX_SDA_R @S9S_MB_2U_LIB.S9S_MB_2U(SCH_1):SMB_INA230_5_3V3AUX_SDA_R    I19 @S9S_MB_2U_LIB.S9S_MB_2U(SCH_1):PAGE220

R3594 Q_RES_0402LF-33.2,1%,1/16W,CHIA
     1 SMB_INA230_3V3AUX_SCL @S9S_MB_2U_LIB.S9S_MB_2U(SCH_1):SMB_INA230_3V3AUX_SCL    I21 @S9S_MB_2U_LIB.S9S_MB_2U(SCH_1):PAGE220
     2 SMB_INA230_4_3V3AUX_SCL_R @S9S_MB_2U_LIB.S9S_MB_2U(SCH_1):SMB_INA230_4_3V3AUX_SCL_R    I21 @S9S_MB_2U_LIB.S9S_MB_2U(SCH_1):PAGE220

R3595 Q_RES_0402LF-33.2,1%,1/16W,CHIA
     1 SMB_INA230_3V3AUX_SDA @S9S_MB_2U_LIB.S9S_MB_2U(SCH_1):SMB_INA230_3V3AUX_SDA    I26 @S9S_MB_2U_LIB.S9S_MB_2U(SCH_1):PAGE220
     2 SMB_INA230_4_3V3AUX_SDA_R @S9S_MB_2U_LIB.S9S_MB_2U(SCH_1):SMB_INA230_4_3V3AUX_SDA_R    I26 @S9S_MB_2U_LIB.S9S_MB_2U(SCH_1):PAGE220

R3600 Q_RES_0402LF-33.2,1%,1/16W,CHIA
     1 SMB_INA230_1_3V3AUX_SCL_R @S9S_MB_2U_LIB.S9S_MB_2U(SCH_1):SMB_INA230_1_3V3AUX_SCL_R    I38 @S9S_MB_2U_LIB.S9S_MB_2U(SCH_1):PAGE295
     2 SMB_INA230_1_3V3AUX_SCL_R1 @S9S_MB_2U_LIB.S9S_MB_2U(SCH_1):SMB_INA230_1_3V3AUX_SCL_R1    I38 @S9S_MB_2U_LIB.S9S_MB_2U(SCH_1):PAGE295

R3601 Q_RES_0402LF-33.2,1%,1/16W,CHIA
     1 SMB_INA230_1_3V3AUX_SDA_R @S9S_MB_2U_LIB.S9S_MB_2U(SCH_1):SMB_INA230_1_3V3AUX_SDA_R    I39 @S9S_MB_2U_LIB.S9S_MB_2U(SCH_1):PAGE295
     2 SMB_INA230_1_3V3AUX_SDA_R1 @S9S_MB_2U_LIB.S9S_MB_2U(SCH_1):SMB_INA230_1_3V3AUX_SDA_R1    I39 @S9S_MB_2U_LIB.S9S_MB_2U(SCH_1):PAGE295

R3602 Q_RES_0402LF-10,1%,1/16W,CHIP,A
     1 P3V3_OCP_SFF_R @S9S_MB_2U_LIB.S9S_MB_2U(SCH_1):P3V3_OCP_SFF_R    I41 @S9S_MB_2U_LIB.S9S_MB_2U(SCH_1):PAGE295
     2 VSENSE_P3V3_INA230_1_INP @S9S_MB_2U_LIB.S9S_MB_2U(SCH_1):VSENSE_P3V3_INA230_1_INP    I41 @S9S_MB_2U_LIB.S9S_MB_2U(SCH_1):PAGE295

R3603 Q_RES_0402LF-10,1%,1/16W,CHIP,A
     1 P3V3_OCP_SFF @S9S_MB_2U_LIB.S9S_MB_2U(SCH_1):P3V3_OCP_SFF    I43 @S9S_MB_2U_LIB.S9S_MB_2U(SCH_1):PAGE295
     2 VSENSE_P3V3_INA230_1_INN @S9S_MB_2U_LIB.S9S_MB_2U(SCH_1):VSENSE_P3V3_INA230_1_INN    I43 @S9S_MB_2U_LIB.S9S_MB_2U(SCH_1):PAGE295

R3608 Q_RES_0402LF-4.7K,1%,1/16W,CHIA
     1    GND @S9S_MB_2U_LIB.S9S_MB_2U(SCH_1):GND   I103 @S9S_MB_2U_LIB.S9S_MB_2U(SCH_1):PAGE163
     2 INA230_3_A1 @S9S_MB_2U_LIB.S9S_MB_2U(SCH_1):INA230_3_A1   I103 @S9S_MB_2U_LIB.S9S_MB_2U(SCH_1):PAGE163

R3609 Q_RES_0402LF-4.7K,1%,1/16W,EMPA
     1    GND @S9S_MB_2U_LIB.S9S_MB_2U(SCH_1):GND   I104 @S9S_MB_2U_LIB.S9S_MB_2U(SCH_1):PAGE163
     2 INA230_3_A0 @S9S_MB_2U_LIB.S9S_MB_2U(SCH_1):INA230_3_A0   I104 @S9S_MB_2U_LIB.S9S_MB_2U(SCH_1):PAGE163

R3610 Q_RES_0402LF-4.7K,1%,1/16W,EMPA
     1    GND @S9S_MB_2U_LIB.S9S_MB_2U(SCH_1):GND    I45 @S9S_MB_2U_LIB.S9S_MB_2U(SCH_1):PAGE163
     2 INA230_4_A1 @S9S_MB_2U_LIB.S9S_MB_2U(SCH_1):INA230_4_A1    I45 @S9S_MB_2U_LIB.S9S_MB_2U(SCH_1):PAGE163

R3611 Q_RES_0402LF-4.7K,1%,1/16W,CHIA
     1    GND @S9S_MB_2U_LIB.S9S_MB_2U(SCH_1):GND    I36 @S9S_MB_2U_LIB.S9S_MB_2U(SCH_1):PAGE163
     2 INA230_4_A0 @S9S_MB_2U_LIB.S9S_MB_2U(SCH_1):INA230_4_A0    I36 @S9S_MB_2U_LIB.S9S_MB_2U(SCH_1):PAGE163

R3612 Q_RES_0402LF-4.7K,1%,1/16W,EMPA
     1    GND @S9S_MB_2U_LIB.S9S_MB_2U(SCH_1):GND    I68 @S9S_MB_2U_LIB.S9S_MB_2U(SCH_1):PAGE163
     2 INA230_5_A1 @S9S_MB_2U_LIB.S9S_MB_2U(SCH_1):INA230_5_A1    I68 @S9S_MB_2U_LIB.S9S_MB_2U(SCH_1):PAGE163

R3613 Q_RES_0402LF-4.7K,1%,1/16W,EMPA
     1    GND @S9S_MB_2U_LIB.S9S_MB_2U(SCH_1):GND    I59 @S9S_MB_2U_LIB.S9S_MB_2U(SCH_1):PAGE163
     2 INA230_5_A0 @S9S_MB_2U_LIB.S9S_MB_2U(SCH_1):INA230_5_A0    I59 @S9S_MB_2U_LIB.S9S_MB_2U(SCH_1):PAGE163

R3616 Q_RES_0402LF-4.7K,1%,1/16W,CHIA
     1    GND @S9S_MB_2U_LIB.S9S_MB_2U(SCH_1):GND    I31 @S9S_MB_2U_LIB.S9S_MB_2U(SCH_1):PAGE295
     2 INA230_1_A1 @S9S_MB_2U_LIB.S9S_MB_2U(SCH_1):INA230_1_A1    I31 @S9S_MB_2U_LIB.S9S_MB_2U(SCH_1):PAGE295

R3617 Q_RES_0402LF-4.7K,1%,1/16W,EMPA
     1    GND @S9S_MB_2U_LIB.S9S_MB_2U(SCH_1):GND    I40 @S9S_MB_2U_LIB.S9S_MB_2U(SCH_1):PAGE295
     2 INA230_1_A0 @S9S_MB_2U_LIB.S9S_MB_2U(SCH_1):INA230_1_A0    I40 @S9S_MB_2U_LIB.S9S_MB_2U(SCH_1):PAGE295

R3620 Q_RES_0402LF-0,5%,1/16W,CHIP,CA
     1 INA230_3_A0 @S9S_MB_2U_LIB.S9S_MB_2U(SCH_1):INA230_3_A0   I100 @S9S_MB_2U_LIB.S9S_MB_2U(SCH_1):PAGE163
     2 SMB_INA230_3_3V3AUX_SCL_R1 @S9S_MB_2U_LIB.S9S_MB_2U(SCH_1):SMB_INA230_3_3V3AUX_SCL_R1   I100 @S9S_MB_2U_LIB.S9S_MB_2U(SCH_1):PAGE163

R3621 Q_RES_0402LF-4.7K,1%,1/16W,EMPA
     1 P3V3_AUX @S9S_MB_2U_LIB.S9S_MB_2U(SCH_1):P3V3_AUX    I87 @S9S_MB_2U_LIB.S9S_MB_2U(SCH_1):PAGE163
     2 INA230_4_A0 @S9S_MB_2U_LIB.S9S_MB_2U(SCH_1):INA230_4_A0    I87 @S9S_MB_2U_LIB.S9S_MB_2U(SCH_1):PAGE163

R3622 Q_RES_0402LF-4.7K,1%,1/16W,CHIA
     1 P3V3_AUX @S9S_MB_2U_LIB.S9S_MB_2U(SCH_1):P3V3_AUX    I90 @S9S_MB_2U_LIB.S9S_MB_2U(SCH_1):PAGE163
     2 INA230_5_A0 @S9S_MB_2U_LIB.S9S_MB_2U(SCH_1):INA230_5_A0    I90 @S9S_MB_2U_LIB.S9S_MB_2U(SCH_1):PAGE163

R3623 Q_RES_0402LF-4.7K,1%,1/16W,CHIA
     1 P3V3_AUX @S9S_MB_2U_LIB.S9S_MB_2U(SCH_1):P3V3_AUX    I86 @S9S_MB_2U_LIB.S9S_MB_2U(SCH_1):PAGE163
     2 INA230_4_A1 @S9S_MB_2U_LIB.S9S_MB_2U(SCH_1):INA230_4_A1    I86 @S9S_MB_2U_LIB.S9S_MB_2U(SCH_1):PAGE163

R3624 Q_RES_0402LF-4.7K,1%,1/16W,CHIA
     1 P3V3_AUX @S9S_MB_2U_LIB.S9S_MB_2U(SCH_1):P3V3_AUX    I89 @S9S_MB_2U_LIB.S9S_MB_2U(SCH_1):PAGE163
     2 INA230_5_A1 @S9S_MB_2U_LIB.S9S_MB_2U(SCH_1):INA230_5_A1    I89 @S9S_MB_2U_LIB.S9S_MB_2U(SCH_1):PAGE163

R3627 Q_RES_0402LF-4.7K,1%,1/16W,CHIA
     1 P3V3_AUX @S9S_MB_2U_LIB.S9S_MB_2U(SCH_1):P3V3_AUX    I89 @S9S_MB_2U_LIB.S9S_MB_2U(SCH_1):PAGE295
     2 INA230_1_A0 @S9S_MB_2U_LIB.S9S_MB_2U(SCH_1):INA230_1_A0    I89 @S9S_MB_2U_LIB.S9S_MB_2U(SCH_1):PAGE295

R3628 Q_RES_0402LF-4.7K,1%,1/16W,EMPA
     1 P3V3_AUX @S9S_MB_2U_LIB.S9S_MB_2U(SCH_1):P3V3_AUX    I88 @S9S_MB_2U_LIB.S9S_MB_2U(SCH_1):PAGE295
     2 INA230_1_A1 @S9S_MB_2U_LIB.S9S_MB_2U(SCH_1):INA230_1_A1    I88 @S9S_MB_2U_LIB.S9S_MB_2U(SCH_1):PAGE295

R3630 Q_RES_0402LF-0,5%,1/16W,CHIP,CA
     1 HP_LVC3_OCP_V3_2_EN @S9S_MB_2U_LIB.S9S_MB_2U(SCH_1):HP_LVC3_OCP_V3_2_EN    I66 @S9S_MB_2U_LIB.S9S_MB_2U(SCH_1):PAGE237
     2 P12V_OCP_V3_2_EN_2_R3 @S9S_MB_2U_LIB.S9S_MB_2U(SCH_1):P12V_OCP_V3_2_EN_2_R3    I66 @S9S_MB_2U_LIB.S9S_MB_2U(SCH_1):PAGE237

R3631 Q_RES_0402LF-0,5%,1/16W,EMPTY,A
     1 HP_LVC3_OCP_V3_2_EN @S9S_MB_2U_LIB.S9S_MB_2U(SCH_1):HP_LVC3_OCP_V3_2_EN    I44 @S9S_MB_2U_LIB.S9S_MB_2U(SCH_1):PAGE237
     2 P3V3_OCP_EN_2 @S9S_MB_2U_LIB.S9S_MB_2U(SCH_1):P3V3_OCP_EN_2    I44 @S9S_MB_2U_LIB.S9S_MB_2U(SCH_1):PAGE237

R3633 Q_RES_2512LF-0.01,1%,1W,CHIP,CA
     1 P3V3_OCP_V3_2 @S9S_MB_2U_LIB.S9S_MB_2U(SCH_1):P3V3_OCP_V3_2   I127 @S9S_MB_2U_LIB.S9S_MB_2U(SCH_1):PAGE163
     2 P3V3_OCP_V3_2_R @S9S_MB_2U_LIB.S9S_MB_2U(SCH_1):P3V3_OCP_V3_2_R   I127 @S9S_MB_2U_LIB.S9S_MB_2U(SCH_1):PAGE163

R3634 Q_RES_2512LF-0.01,1%,1W,CHIP,CA
     1 P3V3_M2_0 @S9S_MB_2U_LIB.S9S_MB_2U(SCH_1):P3V3_M2_0   I128 @S9S_MB_2U_LIB.S9S_MB_2U(SCH_1):PAGE163
     2   P3V3 @S9S_MB_2U_LIB.S9S_MB_2U(SCH_1):P3V3   I128 @S9S_MB_2U_LIB.S9S_MB_2U(SCH_1):PAGE163

R3635 Q_RES_2512LF-0.01,1%,1W,CHIP,CA
     1 P12V_SCM @S9S_MB_2U_LIB.S9S_MB_2U(SCH_1):P12V_SCM   I129 @S9S_MB_2U_LIB.S9S_MB_2U(SCH_1):PAGE163
     2 P12V_SCM_R @S9S_MB_2U_LIB.S9S_MB_2U(SCH_1):P12V_SCM_R   I129 @S9S_MB_2U_LIB.S9S_MB_2U(SCH_1):PAGE163

R3636 Q_RES_0402LF-0,5%,1/16W,CHIP,CA
     1 OCP_SFF_CLK_OE_N @S9S_MB_2U_LIB.S9S_MB_2U(SCH_1):OCP_SFF_CLK_OE_N   I536 @S9S_MB_2U_LIB.S9S_MB_2U(SCH_1):PAGE195
     2 FM_DB2000_11_OE_N @S9S_MB_2U_LIB.S9S_MB_2U(SCH_1):FM_DB2000_11_OE_N   I536 @S9S_MB_2U_LIB.S9S_MB_2U(SCH_1):PAGE195

R3637 Q_RES_0402LF-0,5%,1/16W,CHIP,CA
     1 OCP_SFF_CLK_OE_N @S9S_MB_2U_LIB.S9S_MB_2U(SCH_1):OCP_SFF_CLK_OE_N   I537 @S9S_MB_2U_LIB.S9S_MB_2U(SCH_1):PAGE195
     2 FM_DB2000_12_OE_N @S9S_MB_2U_LIB.S9S_MB_2U(SCH_1):FM_DB2000_12_OE_N   I537 @S9S_MB_2U_LIB.S9S_MB_2U(SCH_1):PAGE195

R3638 Q_RES_0402LF-10K,1%,1/16W,CHIPA
     1 P3V3_AUX @S9S_MB_2U_LIB.S9S_MB_2U(SCH_1):P3V3_AUX   I378 @S9S_MB_2U_LIB.S9S_MB_2U(SCH_1):PAGE197
     2 CK440Q_OE_1 @S9S_MB_2U_LIB.S9S_MB_2U(SCH_1):CK440Q_OE_1   I378 @S9S_MB_2U_LIB.S9S_MB_2U(SCH_1):PAGE197

R3639 Q_RES_0402LF-10K,1%,1/16W,CHIPA
     1 P3V3_AUX @S9S_MB_2U_LIB.S9S_MB_2U(SCH_1):P3V3_AUX   I379 @S9S_MB_2U_LIB.S9S_MB_2U(SCH_1):PAGE197
     2 CK440Q_OE_2 @S9S_MB_2U_LIB.S9S_MB_2U(SCH_1):CK440Q_OE_2   I379 @S9S_MB_2U_LIB.S9S_MB_2U(SCH_1):PAGE197

R3640 Q_RES_0402LF-10K,1%,1/16W,CHIPA
     1 P3V3_AUX @S9S_MB_2U_LIB.S9S_MB_2U(SCH_1):P3V3_AUX   I380 @S9S_MB_2U_LIB.S9S_MB_2U(SCH_1):PAGE197
     2 CK440Q_OE_3 @S9S_MB_2U_LIB.S9S_MB_2U(SCH_1):CK440Q_OE_3   I380 @S9S_MB_2U_LIB.S9S_MB_2U(SCH_1):PAGE197

R3641 Q_RES_0402LF-10K,1%,1/16W,CHIPA
     1 P3V3_AUX @S9S_MB_2U_LIB.S9S_MB_2U(SCH_1):P3V3_AUX   I381 @S9S_MB_2U_LIB.S9S_MB_2U(SCH_1):PAGE197
     2 CK440Q_OE_4 @S9S_MB_2U_LIB.S9S_MB_2U(SCH_1):CK440Q_OE_4   I381 @S9S_MB_2U_LIB.S9S_MB_2U(SCH_1):PAGE197

R3642 Q_RES_0402LF-10K,1%,1/16W,CHIPA
     1 P3V3_AUX @S9S_MB_2U_LIB.S9S_MB_2U(SCH_1):P3V3_AUX   I382 @S9S_MB_2U_LIB.S9S_MB_2U(SCH_1):PAGE197
     2 CK440Q_OE_5 @S9S_MB_2U_LIB.S9S_MB_2U(SCH_1):CK440Q_OE_5   I382 @S9S_MB_2U_LIB.S9S_MB_2U(SCH_1):PAGE197

R3643 Q_RES_0402LF-10K,1%,1/16W,CHIPA
     1 P3V3_AUX @S9S_MB_2U_LIB.S9S_MB_2U(SCH_1):P3V3_AUX   I383 @S9S_MB_2U_LIB.S9S_MB_2U(SCH_1):PAGE197
     2 CK440Q_OE_6 @S9S_MB_2U_LIB.S9S_MB_2U(SCH_1):CK440Q_OE_6   I383 @S9S_MB_2U_LIB.S9S_MB_2U(SCH_1):PAGE197

R3645 Q_RES_2512LF-0.01,1%,1W,CHIP,CA
     1 P3V3_OCP_SFF @S9S_MB_2U_LIB.S9S_MB_2U(SCH_1):P3V3_OCP_SFF   I152 @S9S_MB_2U_LIB.S9S_MB_2U(SCH_1):PAGE295
     2 P3V3_OCP_SFF_R @S9S_MB_2U_LIB.S9S_MB_2U(SCH_1):P3V3_OCP_SFF_R   I152 @S9S_MB_2U_LIB.S9S_MB_2U(SCH_1):PAGE295

R3651 Q_RES_0402LF-0,5%,1/16W,CHIP,CA
     1 USB2_P0_R_DP @S9S_MB_2U_LIB.S9S_MB_2U(SCH_1):USB2_P0_R_DP   I138 @S9S_MB_2U_LIB.S9S_MB_2U(SCH_1):PAGE155
     2 USB2_HOST_BMC_B_DP @S9S_MB_2U_LIB.S9S_MB_2U(SCH_1):USB2_HOST_BMC_B_DP   I138 @S9S_MB_2U_LIB.S9S_MB_2U(SCH_1):PAGE155

R3652 Q_RES_0402LF-0,5%,1/16W,CHIP,CA
     1 USB2_P0_R_DN @S9S_MB_2U_LIB.S9S_MB_2U(SCH_1):USB2_P0_R_DN   I137 @S9S_MB_2U_LIB.S9S_MB_2U(SCH_1):PAGE155
     2 USB2_HOST_BMC_B_DN @S9S_MB_2U_LIB.S9S_MB_2U(SCH_1):USB2_HOST_BMC_B_DN   I137 @S9S_MB_2U_LIB.S9S_MB_2U(SCH_1):PAGE155

R3653 Q_RES_0402LF-680,1%,1/16W,CHIPA
     1 USB_HUB_RREF @S9S_MB_2U_LIB.S9S_MB_2U(SCH_1):USB_HUB_RREF   I139 @S9S_MB_2U_LIB.S9S_MB_2U(SCH_1):PAGE155
     2    GND @S9S_MB_2U_LIB.S9S_MB_2U(SCH_1):GND   I139 @S9S_MB_2U_LIB.S9S_MB_2U(SCH_1):PAGE155

R3654 Q_RES_0402LF-33.2,1%,1/16W,CHIA
     1 RST_USB_HUB_N @S9S_MB_2U_LIB.S9S_MB_2U(SCH_1):RST_USB_HUB_N   I155 @S9S_MB_2U_LIB.S9S_MB_2U(SCH_1):PAGE155
     2 RST_USB_HUB_R_N @S9S_MB_2U_LIB.S9S_MB_2U(SCH_1):RST_USB_HUB_R_N   I155 @S9S_MB_2U_LIB.S9S_MB_2U(SCH_1):PAGE155

R3655 Q_RES_0402LF-0,5%,1/16W,CHIP,CA
     1 P3V3_AUX @S9S_MB_2U_LIB.S9S_MB_2U(SCH_1):P3V3_AUX   I161 @S9S_MB_2U_LIB.S9S_MB_2U(SCH_1):PAGE155
     2 P3V3_AUX_USB_HUB @S9S_MB_2U_LIB.S9S_MB_2U(SCH_1):P3V3_AUX_USB_HUB   I161 @S9S_MB_2U_LIB.S9S_MB_2U(SCH_1):PAGE155

R3656 Q_RES_0402LF-10K,1%,1/16W,EMPTA
     1 P3V3_AUX @S9S_MB_2U_LIB.S9S_MB_2U(SCH_1):P3V3_AUX   I194 @S9S_MB_2U_LIB.S9S_MB_2U(SCH_1):PAGE155
     2 USB_HUB_OVCUR1 @S9S_MB_2U_LIB.S9S_MB_2U(SCH_1):USB_HUB_OVCUR1   I194 @S9S_MB_2U_LIB.S9S_MB_2U(SCH_1):PAGE155

R3657 Q_RES_0402LF-10K,1%,1/16W,EMPTA
     1 P3V3_AUX @S9S_MB_2U_LIB.S9S_MB_2U(SCH_1):P3V3_AUX   I195 @S9S_MB_2U_LIB.S9S_MB_2U(SCH_1):PAGE155
     2 USB_HUB_OVCUR2 @S9S_MB_2U_LIB.S9S_MB_2U(SCH_1):USB_HUB_OVCUR2   I195 @S9S_MB_2U_LIB.S9S_MB_2U(SCH_1):PAGE155

R3658 Q_RES_0402LF-10K,1%,1/16W,EMPTA
     1 P3V3_AUX @S9S_MB_2U_LIB.S9S_MB_2U(SCH_1):P3V3_AUX   I196 @S9S_MB_2U_LIB.S9S_MB_2U(SCH_1):PAGE155
     2 USB_HUB_OVCUR3 @S9S_MB_2U_LIB.S9S_MB_2U(SCH_1):USB_HUB_OVCUR3   I196 @S9S_MB_2U_LIB.S9S_MB_2U(SCH_1):PAGE155

R3659 Q_RES_0402LF-10K,1%,1/16W,EMPTA
     1 P3V3_AUX @S9S_MB_2U_LIB.S9S_MB_2U(SCH_1):P3V3_AUX   I198 @S9S_MB_2U_LIB.S9S_MB_2U(SCH_1):PAGE155
     2 USB_HUB_OVCUR4 @S9S_MB_2U_LIB.S9S_MB_2U(SCH_1):USB_HUB_OVCUR4   I198 @S9S_MB_2U_LIB.S9S_MB_2U(SCH_1):PAGE155

R3660 Q_RES_0402LF-10K,1%,1/16W,CHIPA
     1 P3V3_AUX @S9S_MB_2U_LIB.S9S_MB_2U(SCH_1):P3V3_AUX   I159 @S9S_MB_2U_LIB.S9S_MB_2U(SCH_1):PAGE155
     2 RST_USB_HUB_R_N @S9S_MB_2U_LIB.S9S_MB_2U(SCH_1):RST_USB_HUB_R_N   I159 @S9S_MB_2U_LIB.S9S_MB_2U(SCH_1):PAGE155

R3661 Q_RES_0402LF-47K,0.1%,1/16W,EMA
     1    GND @S9S_MB_2U_LIB.S9S_MB_2U(SCH_1):GND   I201 @S9S_MB_2U_LIB.S9S_MB_2U(SCH_1):PAGE155
     2 RST_USB_HUB_R_N @S9S_MB_2U_LIB.S9S_MB_2U(SCH_1):RST_USB_HUB_R_N   I201 @S9S_MB_2U_LIB.S9S_MB_2U(SCH_1):PAGE155

R3662 Q_RES_0402LF-0,5%,1/16W,CHIP,CA
     1 P3V3_AUX_USB_HUB @S9S_MB_2U_LIB.S9S_MB_2U(SCH_1):P3V3_AUX_USB_HUB   I167 @S9S_MB_2U_LIB.S9S_MB_2U(SCH_1):PAGE155
     2 USB_HUB_DVDD @S9S_MB_2U_LIB.S9S_MB_2U(SCH_1):USB_HUB_DVDD   I167 @S9S_MB_2U_LIB.S9S_MB_2U(SCH_1):PAGE155

R3663 Q_RES_0402LF-10K,1%,1/16W,CHIPA
     1 P3V3_AUX @S9S_MB_2U_LIB.S9S_MB_2U(SCH_1):P3V3_AUX   I186 @S9S_MB_2U_LIB.S9S_MB_2U(SCH_1):PAGE155
     2 USB_HUB_PSELF @S9S_MB_2U_LIB.S9S_MB_2U(SCH_1):USB_HUB_PSELF   I186 @S9S_MB_2U_LIB.S9S_MB_2U(SCH_1):PAGE155

R3664 Q_RES_0402LF-10K,1%,1/16W,EMPTA
     1 USB_HUB_PSELF @S9S_MB_2U_LIB.S9S_MB_2U(SCH_1):USB_HUB_PSELF   I187 @S9S_MB_2U_LIB.S9S_MB_2U(SCH_1):PAGE155
     2    GND @S9S_MB_2U_LIB.S9S_MB_2U(SCH_1):GND   I187 @S9S_MB_2U_LIB.S9S_MB_2U(SCH_1):PAGE155

R3665 Q_RES_0402LF-100K,1%,1/16W,CHIA
     1 USB_HUB_PGANG @S9S_MB_2U_LIB.S9S_MB_2U(SCH_1):USB_HUB_PGANG   I182 @S9S_MB_2U_LIB.S9S_MB_2U(SCH_1):PAGE155
     2    GND @S9S_MB_2U_LIB.S9S_MB_2U(SCH_1):GND   I182 @S9S_MB_2U_LIB.S9S_MB_2U(SCH_1):PAGE155

R3666 Q_RES_0402LF-0,5%,1/16W,CHIP,CA
     1 USB_HUB_TEST @S9S_MB_2U_LIB.S9S_MB_2U(SCH_1):USB_HUB_TEST   I199 @S9S_MB_2U_LIB.S9S_MB_2U(SCH_1):PAGE155
     2    GND @S9S_MB_2U_LIB.S9S_MB_2U(SCH_1):GND   I199 @S9S_MB_2U_LIB.S9S_MB_2U(SCH_1):PAGE155

R3667 Q_RES_0402LF-1K,1%,1/16W,EMPTYA
     1 P3V3_AUX @S9S_MB_2U_LIB.S9S_MB_2U(SCH_1):P3V3_AUX   I224 @S9S_MB_2U_LIB.S9S_MB_2U(SCH_1):PAGE239
     2 ADC128_A1 @S9S_MB_2U_LIB.S9S_MB_2U(SCH_1):ADC128_A1   I224 @S9S_MB_2U_LIB.S9S_MB_2U(SCH_1):PAGE239

R3668 Q_RES_0402LF-1K,1%,1/16W,CHIP,A
     1 ADC128_A1 @S9S_MB_2U_LIB.S9S_MB_2U(SCH_1):ADC128_A1   I223 @S9S_MB_2U_LIB.S9S_MB_2U(SCH_1):PAGE239
     2    GND @S9S_MB_2U_LIB.S9S_MB_2U(SCH_1):GND   I223 @S9S_MB_2U_LIB.S9S_MB_2U(SCH_1):PAGE239

R3669 Q_RES_0402LF-1K,1%,1/16W,EMPTYA
     1 P3V3_AUX @S9S_MB_2U_LIB.S9S_MB_2U(SCH_1):P3V3_AUX   I228 @S9S_MB_2U_LIB.S9S_MB_2U(SCH_1):PAGE239
     2 ADC128_A0 @S9S_MB_2U_LIB.S9S_MB_2U(SCH_1):ADC128_A0   I228 @S9S_MB_2U_LIB.S9S_MB_2U(SCH_1):PAGE239

R3670 Q_RES_0402LF-1K,1%,1/16W,CHIP,A
     1 ADC128_A0 @S9S_MB_2U_LIB.S9S_MB_2U(SCH_1):ADC128_A0   I227 @S9S_MB_2U_LIB.S9S_MB_2U(SCH_1):PAGE239
     2    GND @S9S_MB_2U_LIB.S9S_MB_2U(SCH_1):GND   I227 @S9S_MB_2U_LIB.S9S_MB_2U(SCH_1):PAGE239

R3671 Q_RES_0402LF-0,5%,1/16W,CHIP,CA
     1 SMB_VR_3V3AUX_SDA_R1 @S9S_MB_2U_LIB.S9S_MB_2U(SCH_1):SMB_VR_3V3AUX_SDA_R1   I110 @S9S_MB_2U_LIB.S9S_MB_2U(SCH_1):PAGE239
     2 SMB_SEN_TIC_3V3AUX_SDA @S9S_MB_2U_LIB.S9S_MB_2U(SCH_1):SMB_SEN_TIC_3V3AUX_SDA   I110 @S9S_MB_2U_LIB.S9S_MB_2U(SCH_1):PAGE239

R3672 Q_RES_0402LF-0,5%,1/16W,CHIP,CA
     1 SMB_VR_3V3AUX_SCL_R1 @S9S_MB_2U_LIB.S9S_MB_2U(SCH_1):SMB_VR_3V3AUX_SCL_R1   I111 @S9S_MB_2U_LIB.S9S_MB_2U(SCH_1):PAGE239
     2 SMB_SEN_TIC_3V3AUX_SCL @S9S_MB_2U_LIB.S9S_MB_2U(SCH_1):SMB_SEN_TIC_3V3AUX_SCL   I111 @S9S_MB_2U_LIB.S9S_MB_2U(SCH_1):PAGE239

R3679 Q_RES_0402LF-0,5%,1/16W,EMPTY,A
     1 P12V_AUX_ADC @S9S_MB_2U_LIB.S9S_MB_2U(SCH_1):P12V_AUX_ADC   I209 @S9S_MB_2U_LIB.S9S_MB_2U(SCH_1):PAGE239
     2 P12V_AUX_ADC_MAM @S9S_MB_2U_LIB.S9S_MB_2U(SCH_1):P12V_AUX_ADC_MAM   I209 @S9S_MB_2U_LIB.S9S_MB_2U(SCH_1):PAGE239

R3680 Q_RES_0402LF-0,5%,1/16W,CHIP,CA
     1 P12V_AUX_ADC @S9S_MB_2U_LIB.S9S_MB_2U(SCH_1):P12V_AUX_ADC   I210 @S9S_MB_2U_LIB.S9S_MB_2U(SCH_1):PAGE239
     2 P12V_AUX_ADC_TIC @S9S_MB_2U_LIB.S9S_MB_2U(SCH_1):P12V_AUX_ADC_TIC   I210 @S9S_MB_2U_LIB.S9S_MB_2U(SCH_1):PAGE239

R3681 Q_RES_0402LF-0,5%,1/16W,EMPTY,A
     1 P3V3_AUX_ADC @S9S_MB_2U_LIB.S9S_MB_2U(SCH_1):P3V3_AUX_ADC   I176 @S9S_MB_2U_LIB.S9S_MB_2U(SCH_1):PAGE239
     2 P3V3_AUX_ADC_MAM @S9S_MB_2U_LIB.S9S_MB_2U(SCH_1):P3V3_AUX_ADC_MAM   I176 @S9S_MB_2U_LIB.S9S_MB_2U(SCH_1):PAGE239

R3682 Q_RES_0402LF-0,5%,1/16W,CHIP,CA
     1 P3V3_AUX_ADC @S9S_MB_2U_LIB.S9S_MB_2U(SCH_1):P3V3_AUX_ADC   I179 @S9S_MB_2U_LIB.S9S_MB_2U(SCH_1):PAGE239
     2 P3V3_AUX_ADC_TIC @S9S_MB_2U_LIB.S9S_MB_2U(SCH_1):P3V3_AUX_ADC_TIC   I179 @S9S_MB_2U_LIB.S9S_MB_2U(SCH_1):PAGE239

R3683 Q_RES_0402LF-0,5%,1/16W,EMPTY,A
     1 P3V3_ADC @S9S_MB_2U_LIB.S9S_MB_2U(SCH_1):P3V3_ADC   I199 @S9S_MB_2U_LIB.S9S_MB_2U(SCH_1):PAGE239
     2 P3V3_ADC_MAM @S9S_MB_2U_LIB.S9S_MB_2U(SCH_1):P3V3_ADC_MAM   I199 @S9S_MB_2U_LIB.S9S_MB_2U(SCH_1):PAGE239

R3684 Q_RES_0402LF-0,5%,1/16W,CHIP,CA
     1 P3V3_ADC @S9S_MB_2U_LIB.S9S_MB_2U(SCH_1):P3V3_ADC   I200 @S9S_MB_2U_LIB.S9S_MB_2U(SCH_1):PAGE239
     2 P3V3_ADC_TIC @S9S_MB_2U_LIB.S9S_MB_2U(SCH_1):P3V3_ADC_TIC   I200 @S9S_MB_2U_LIB.S9S_MB_2U(SCH_1):PAGE239

R3685 Q_RES_0402LF-0,5%,1/16W,EMPTY,A
     1 P5V_ADC @S9S_MB_2U_LIB.S9S_MB_2U(SCH_1):P5V_ADC   I190 @S9S_MB_2U_LIB.S9S_MB_2U(SCH_1):PAGE239
     2 P5V_ADC_MAM @S9S_MB_2U_LIB.S9S_MB_2U(SCH_1):P5V_ADC_MAM   I190 @S9S_MB_2U_LIB.S9S_MB_2U(SCH_1):PAGE239

R3686 Q_RES_0402LF-0,5%,1/16W,CHIP,CA
     1 P5V_ADC @S9S_MB_2U_LIB.S9S_MB_2U(SCH_1):P5V_ADC   I191 @S9S_MB_2U_LIB.S9S_MB_2U(SCH_1):PAGE239
     2 P5V_ADC_TIC @S9S_MB_2U_LIB.S9S_MB_2U(SCH_1):P5V_ADC_TIC   I191 @S9S_MB_2U_LIB.S9S_MB_2U(SCH_1):PAGE239

R3687 Q_RES_0402LF-0,5%,1/16W,EMPTY,A
     1 P1V581_PDB_ADC @S9S_MB_2U_LIB.S9S_MB_2U(SCH_1):P1V581_PDB_ADC   I240 @S9S_MB_2U_LIB.S9S_MB_2U(SCH_1):PAGE239
     2 P3V3_PDB_AUX_ADC_MAM @S9S_MB_2U_LIB.S9S_MB_2U(SCH_1):P3V3_PDB_AUX_ADC_MAM   I240 @S9S_MB_2U_LIB.S9S_MB_2U(SCH_1):PAGE239

R3688 Q_RES_0402LF-0,5%,1/16W,CHIP,CA
     1 P1V581_PDB_ADC @S9S_MB_2U_LIB.S9S_MB_2U(SCH_1):P1V581_PDB_ADC   I241 @S9S_MB_2U_LIB.S9S_MB_2U(SCH_1):PAGE239
     2 P3V3_PDB_AUX_ADC_TIC @S9S_MB_2U_LIB.S9S_MB_2U(SCH_1):P3V3_PDB_AUX_ADC_TIC   I241 @S9S_MB_2U_LIB.S9S_MB_2U(SCH_1):PAGE239

R3689 Q_RES_0402LF-4.7K,1%,1/16W,EMPA
     1 P3V3_ADC128_VCC @S9S_MB_2U_LIB.S9S_MB_2U(SCH_1):P3V3_ADC128_VCC   I129 @S9S_MB_2U_LIB.S9S_MB_2U(SCH_1):PAGE239
     2 ADC128_VREF @S9S_MB_2U_LIB.S9S_MB_2U(SCH_1):ADC128_VREF   I129 @S9S_MB_2U_LIB.S9S_MB_2U(SCH_1):PAGE239

R3690 Q_RES_0402LF-4.7K,1%,1/16W,EMPA
     1 ADC128_VREF @S9S_MB_2U_LIB.S9S_MB_2U(SCH_1):ADC128_VREF   I131 @S9S_MB_2U_LIB.S9S_MB_2U(SCH_1):PAGE239
     2    GND @S9S_MB_2U_LIB.S9S_MB_2U(SCH_1):GND   I131 @S9S_MB_2U_LIB.S9S_MB_2U(SCH_1):PAGE239

R3703 Q_RES_0402LF-10K,1%,1/16W,EMPTA
     1 P3V3_AUX @S9S_MB_2U_LIB.S9S_MB_2U(SCH_1):P3V3_AUX     I3 @S9S_MB_2U_LIB.S9S_MB_2U(SCH_1):PAGE221
     2 PCA9548_PCIE0_ADDR2 @S9S_MB_2U_LIB.S9S_MB_2U(SCH_1):PCA9548_PCIE0_ADDR2     I3 @S9S_MB_2U_LIB.S9S_MB_2U(SCH_1):PAGE221

R3704 Q_RES_0402LF-1K,1%,1/16W,CHIP,A
     1 PCA9548_PCIE0_ADDR2 @S9S_MB_2U_LIB.S9S_MB_2U(SCH_1):PCA9548_PCIE0_ADDR2     I2 @S9S_MB_2U_LIB.S9S_MB_2U(SCH_1):PAGE221
     2    GND @S9S_MB_2U_LIB.S9S_MB_2U(SCH_1):GND     I2 @S9S_MB_2U_LIB.S9S_MB_2U(SCH_1):PAGE221

R3705 Q_RES_0402LF-10K,1%,1/16W,EMPTA
     1 P3V3_AUX @S9S_MB_2U_LIB.S9S_MB_2U(SCH_1):P3V3_AUX   I147 @S9S_MB_2U_LIB.S9S_MB_2U(SCH_1):PAGE221
     2 RST_SMB_SWITCH_N @S9S_MB_2U_LIB.S9S_MB_2U(SCH_1):RST_SMB_SWITCH_N   I147 @S9S_MB_2U_LIB.S9S_MB_2U(SCH_1):PAGE221

R3706 Q_RES_0402LF-10K,1%,1/16W,EMPTA
     1 P3V3_AUX @S9S_MB_2U_LIB.S9S_MB_2U(SCH_1):P3V3_AUX     I9 @S9S_MB_2U_LIB.S9S_MB_2U(SCH_1):PAGE221
     2 PCA9548_PCIE0_ADDR1 @S9S_MB_2U_LIB.S9S_MB_2U(SCH_1):PCA9548_PCIE0_ADDR1     I9 @S9S_MB_2U_LIB.S9S_MB_2U(SCH_1):PAGE221

R3707 Q_RES_0402LF-1K,1%,1/16W,CHIP,A
     1 PCA9548_PCIE0_ADDR1 @S9S_MB_2U_LIB.S9S_MB_2U(SCH_1):PCA9548_PCIE0_ADDR1     I6 @S9S_MB_2U_LIB.S9S_MB_2U(SCH_1):PAGE221
     2    GND @S9S_MB_2U_LIB.S9S_MB_2U(SCH_1):GND     I6 @S9S_MB_2U_LIB.S9S_MB_2U(SCH_1):PAGE221

R3708 Q_RES_0402LF-10K,1%,1/16W,EMPTA
     1 P3V3_AUX @S9S_MB_2U_LIB.S9S_MB_2U(SCH_1):P3V3_AUX    I10 @S9S_MB_2U_LIB.S9S_MB_2U(SCH_1):PAGE221
     2 PCA9548_PCIE0_ADDR0 @S9S_MB_2U_LIB.S9S_MB_2U(SCH_1):PCA9548_PCIE0_ADDR0    I10 @S9S_MB_2U_LIB.S9S_MB_2U(SCH_1):PAGE221

R3709 Q_RES_0402LF-1K,1%,1/16W,CHIP,A
     1 PCA9548_PCIE0_ADDR0 @S9S_MB_2U_LIB.S9S_MB_2U(SCH_1):PCA9548_PCIE0_ADDR0     I8 @S9S_MB_2U_LIB.S9S_MB_2U(SCH_1):PAGE221
     2    GND @S9S_MB_2U_LIB.S9S_MB_2U(SCH_1):GND     I8 @S9S_MB_2U_LIB.S9S_MB_2U(SCH_1):PAGE221

R3710 Q_RES_0402LF-0,5%,1/16W,CHIP,CA
     1 RST_SMB_SWITCH_N @S9S_MB_2U_LIB.S9S_MB_2U(SCH_1):RST_SMB_SWITCH_N   I145 @S9S_MB_2U_LIB.S9S_MB_2U(SCH_1):PAGE221
     2 PU_RST_SMB_PCIE2_N @S9S_MB_2U_LIB.S9S_MB_2U(SCH_1):PU_RST_SMB_PCIE2_N   I145 @S9S_MB_2U_LIB.S9S_MB_2U(SCH_1):PAGE221

R3711 Q_RES_0402LF-33.2,1%,1/16W,CHIA
     1 SMB_VR_SENSOR_3V3AUX_SCL @S9S_MB_2U_LIB.S9S_MB_2U(SCH_1):SMB_VR_SENSOR_3V3AUX_SCL   I116 @S9S_MB_2U_LIB.S9S_MB_2U(SCH_1):PAGE221
     2 SMB_VR_SENSOR_3V3AUX_SCL_R @S9S_MB_2U_LIB.S9S_MB_2U(SCH_1):SMB_VR_SENSOR_3V3AUX_SCL_R   I116 @S9S_MB_2U_LIB.S9S_MB_2U(SCH_1):PAGE221

R3712 Q_RES_0402LF-33.2,1%,1/16W,CHIA
     1 SMB_VR_SENSOR_3V3AUX_SDA @S9S_MB_2U_LIB.S9S_MB_2U(SCH_1):SMB_VR_SENSOR_3V3AUX_SDA   I115 @S9S_MB_2U_LIB.S9S_MB_2U(SCH_1):PAGE221
     2 SMB_VR_SENSOR_3V3AUX_SDA_R @S9S_MB_2U_LIB.S9S_MB_2U(SCH_1):SMB_VR_SENSOR_3V3AUX_SDA_R   I115 @S9S_MB_2U_LIB.S9S_MB_2U(SCH_1):PAGE221

R3713 Q_RES_0402LF-0,5%,1/16W,CHIP,CA
     1 SMB_VR_3V3AUX_SCL_R6 @S9S_MB_2U_LIB.S9S_MB_2U(SCH_1):SMB_VR_3V3AUX_SCL_R6   I137 @S9S_MB_2U_LIB.S9S_MB_2U(SCH_1):PAGE221
     2 SMB_VR_3V3AUX_SCL @S9S_MB_2U_LIB.S9S_MB_2U(SCH_1):SMB_VR_3V3AUX_SCL   I137 @S9S_MB_2U_LIB.S9S_MB_2U(SCH_1):PAGE221

R3714 Q_RES_0402LF-0,5%,1/16W,CHIP,CA
     1 SMB_VR_3V3AUX_SDA_R6 @S9S_MB_2U_LIB.S9S_MB_2U(SCH_1):SMB_VR_3V3AUX_SDA_R6   I138 @S9S_MB_2U_LIB.S9S_MB_2U(SCH_1):PAGE221
     2 SMB_VR_3V3AUX_SDA @S9S_MB_2U_LIB.S9S_MB_2U(SCH_1):SMB_VR_3V3AUX_SDA   I138 @S9S_MB_2U_LIB.S9S_MB_2U(SCH_1):PAGE221

R3715 Q_RES_0402LF-0,5%,1/16W,CHIP,CA
     1 SMB_LM75_0_3V3AUX_SCL_R @S9S_MB_2U_LIB.S9S_MB_2U(SCH_1):SMB_LM75_0_3V3AUX_SCL_R   I139 @S9S_MB_2U_LIB.S9S_MB_2U(SCH_1):PAGE221
     2 SMB_LM75_0_3V3AUX_SCL @S9S_MB_2U_LIB.S9S_MB_2U(SCH_1):SMB_LM75_0_3V3AUX_SCL   I139 @S9S_MB_2U_LIB.S9S_MB_2U(SCH_1):PAGE221

R3716 Q_RES_0402LF-0,5%,1/16W,CHIP,CA
     1 SMB_LM75_0_3V3AUX_SDA_R @S9S_MB_2U_LIB.S9S_MB_2U(SCH_1):SMB_LM75_0_3V3AUX_SDA_R   I140 @S9S_MB_2U_LIB.S9S_MB_2U(SCH_1):PAGE221
     2 SMB_LM75_0_3V3AUX_SDA @S9S_MB_2U_LIB.S9S_MB_2U(SCH_1):SMB_LM75_0_3V3AUX_SDA   I140 @S9S_MB_2U_LIB.S9S_MB_2U(SCH_1):PAGE221

R3717 Q_RES_0402LF-0,5%,1/16W,CHIP,CA
     1 SMB_LM75_1_3V3AUX_SCL_R @S9S_MB_2U_LIB.S9S_MB_2U(SCH_1):SMB_LM75_1_3V3AUX_SCL_R   I141 @S9S_MB_2U_LIB.S9S_MB_2U(SCH_1):PAGE221
     2 SMB_LM75_1_3V3AUX_SCL @S9S_MB_2U_LIB.S9S_MB_2U(SCH_1):SMB_LM75_1_3V3AUX_SCL   I141 @S9S_MB_2U_LIB.S9S_MB_2U(SCH_1):PAGE221

R3718 Q_RES_0402LF-0,5%,1/16W,CHIP,CA
     1 SMB_LM75_1_3V3AUX_SDA_R @S9S_MB_2U_LIB.S9S_MB_2U(SCH_1):SMB_LM75_1_3V3AUX_SDA_R   I142 @S9S_MB_2U_LIB.S9S_MB_2U(SCH_1):PAGE221
     2 SMB_LM75_1_3V3AUX_SDA @S9S_MB_2U_LIB.S9S_MB_2U(SCH_1):SMB_LM75_1_3V3AUX_SDA   I142 @S9S_MB_2U_LIB.S9S_MB_2U(SCH_1):PAGE221

R3719 Q_RES_0402LF-0,5%,1/16W,CHIP,CA
     1 SMB_LM75_2_3V3AUX_SCL_R @S9S_MB_2U_LIB.S9S_MB_2U(SCH_1):SMB_LM75_2_3V3AUX_SCL_R   I143 @S9S_MB_2U_LIB.S9S_MB_2U(SCH_1):PAGE221
     2 SMB_LM75_2_3V3AUX_SCL @S9S_MB_2U_LIB.S9S_MB_2U(SCH_1):SMB_LM75_2_3V3AUX_SCL   I143 @S9S_MB_2U_LIB.S9S_MB_2U(SCH_1):PAGE221

R3720 Q_RES_0402LF-0,5%,1/16W,CHIP,CA
     1 SMB_LM75_2_3V3AUX_SDA_R @S9S_MB_2U_LIB.S9S_MB_2U(SCH_1):SMB_LM75_2_3V3AUX_SDA_R   I144 @S9S_MB_2U_LIB.S9S_MB_2U(SCH_1):PAGE221
     2 SMB_LM75_2_3V3AUX_SDA @S9S_MB_2U_LIB.S9S_MB_2U(SCH_1):SMB_LM75_2_3V3AUX_SDA   I144 @S9S_MB_2U_LIB.S9S_MB_2U(SCH_1):PAGE221

R3721 Q_RES_0402LF-0,5%,1/16W,CHIP,CA
     1 SMB_LM75_3_3V3AUX_SCL_R @S9S_MB_2U_LIB.S9S_MB_2U(SCH_1):SMB_LM75_3_3V3AUX_SCL_R   I120 @S9S_MB_2U_LIB.S9S_MB_2U(SCH_1):PAGE221
     2 SMB_LM75_3_3V3AUX_SCL @S9S_MB_2U_LIB.S9S_MB_2U(SCH_1):SMB_LM75_3_3V3AUX_SCL   I120 @S9S_MB_2U_LIB.S9S_MB_2U(SCH_1):PAGE221

R3722 Q_RES_0402LF-0,5%,1/16W,CHIP,CA
     1 SMB_LM75_3_3V3AUX_SDA_R @S9S_MB_2U_LIB.S9S_MB_2U(SCH_1):SMB_LM75_3_3V3AUX_SDA_R   I119 @S9S_MB_2U_LIB.S9S_MB_2U(SCH_1):PAGE221
     2 SMB_LM75_3_3V3AUX_SDA @S9S_MB_2U_LIB.S9S_MB_2U(SCH_1):SMB_LM75_3_3V3AUX_SDA   I119 @S9S_MB_2U_LIB.S9S_MB_2U(SCH_1):PAGE221

R3723 Q_RES_0402LF-2.2K,5%,1/16W,CHIA
     1 P3V3_AUX @S9S_MB_2U_LIB.S9S_MB_2U(SCH_1):P3V3_AUX    I55 @S9S_MB_2U_LIB.S9S_MB_2U(SCH_1):PAGE221
     2 SMB_VR_3V3AUX_SCL @S9S_MB_2U_LIB.S9S_MB_2U(SCH_1):SMB_VR_3V3AUX_SCL    I55 @S9S_MB_2U_LIB.S9S_MB_2U(SCH_1):PAGE221

R3724 Q_RES_0402LF-2.2K,5%,1/16W,CHIA
     1 P3V3_AUX @S9S_MB_2U_LIB.S9S_MB_2U(SCH_1):P3V3_AUX    I56 @S9S_MB_2U_LIB.S9S_MB_2U(SCH_1):PAGE221
     2 SMB_VR_3V3AUX_SDA @S9S_MB_2U_LIB.S9S_MB_2U(SCH_1):SMB_VR_3V3AUX_SDA    I56 @S9S_MB_2U_LIB.S9S_MB_2U(SCH_1):PAGE221

R3725 Q_RES_0402LF-2.2K,5%,1/16W,CHIA
     1 P3V3_AUX @S9S_MB_2U_LIB.S9S_MB_2U(SCH_1):P3V3_AUX    I53 @S9S_MB_2U_LIB.S9S_MB_2U(SCH_1):PAGE221
     2 SMB_LM75_0_3V3AUX_SCL @S9S_MB_2U_LIB.S9S_MB_2U(SCH_1):SMB_LM75_0_3V3AUX_SCL    I53 @S9S_MB_2U_LIB.S9S_MB_2U(SCH_1):PAGE221

R3726 Q_RES_0402LF-2.2K,5%,1/16W,CHIA
     1 P3V3_AUX @S9S_MB_2U_LIB.S9S_MB_2U(SCH_1):P3V3_AUX    I52 @S9S_MB_2U_LIB.S9S_MB_2U(SCH_1):PAGE221
     2 SMB_LM75_0_3V3AUX_SDA @S9S_MB_2U_LIB.S9S_MB_2U(SCH_1):SMB_LM75_0_3V3AUX_SDA    I52 @S9S_MB_2U_LIB.S9S_MB_2U(SCH_1):PAGE221

R3727 Q_RES_0402LF-2.2K,5%,1/16W,CHIA
     1 P3V3_AUX @S9S_MB_2U_LIB.S9S_MB_2U(SCH_1):P3V3_AUX    I51 @S9S_MB_2U_LIB.S9S_MB_2U(SCH_1):PAGE221
     2 SMB_LM75_1_3V3AUX_SCL @S9S_MB_2U_LIB.S9S_MB_2U(SCH_1):SMB_LM75_1_3V3AUX_SCL    I51 @S9S_MB_2U_LIB.S9S_MB_2U(SCH_1):PAGE221

R3728 Q_RES_0402LF-2.2K,5%,1/16W,CHIA
     1 P3V3_AUX @S9S_MB_2U_LIB.S9S_MB_2U(SCH_1):P3V3_AUX    I50 @S9S_MB_2U_LIB.S9S_MB_2U(SCH_1):PAGE221
     2 SMB_LM75_1_3V3AUX_SDA @S9S_MB_2U_LIB.S9S_MB_2U(SCH_1):SMB_LM75_1_3V3AUX_SDA    I50 @S9S_MB_2U_LIB.S9S_MB_2U(SCH_1):PAGE221

R3729 Q_RES_0402LF-2.2K,5%,1/16W,CHIA
     1 P3V3_AUX @S9S_MB_2U_LIB.S9S_MB_2U(SCH_1):P3V3_AUX    I48 @S9S_MB_2U_LIB.S9S_MB_2U(SCH_1):PAGE221
     2 SMB_LM75_2_3V3AUX_SCL @S9S_MB_2U_LIB.S9S_MB_2U(SCH_1):SMB_LM75_2_3V3AUX_SCL    I48 @S9S_MB_2U_LIB.S9S_MB_2U(SCH_1):PAGE221

R3730 Q_RES_0402LF-2.2K,5%,1/16W,CHIA
     1 P3V3_AUX @S9S_MB_2U_LIB.S9S_MB_2U(SCH_1):P3V3_AUX    I49 @S9S_MB_2U_LIB.S9S_MB_2U(SCH_1):PAGE221
     2 SMB_LM75_2_3V3AUX_SDA @S9S_MB_2U_LIB.S9S_MB_2U(SCH_1):SMB_LM75_2_3V3AUX_SDA    I49 @S9S_MB_2U_LIB.S9S_MB_2U(SCH_1):PAGE221

R3731 Q_RES_0402LF-2.2K,5%,1/16W,CHIA
     1 P3V3_AUX @S9S_MB_2U_LIB.S9S_MB_2U(SCH_1):P3V3_AUX    I98 @S9S_MB_2U_LIB.S9S_MB_2U(SCH_1):PAGE221
     2 SMB_LM75_3_3V3AUX_SCL @S9S_MB_2U_LIB.S9S_MB_2U(SCH_1):SMB_LM75_3_3V3AUX_SCL    I98 @S9S_MB_2U_LIB.S9S_MB_2U(SCH_1):PAGE221

R3732 Q_RES_0402LF-2.2K,5%,1/16W,CHIA
     1 P3V3_AUX @S9S_MB_2U_LIB.S9S_MB_2U(SCH_1):P3V3_AUX    I34 @S9S_MB_2U_LIB.S9S_MB_2U(SCH_1):PAGE221
     2 SMB_LM75_3_3V3AUX_SDA @S9S_MB_2U_LIB.S9S_MB_2U(SCH_1):SMB_LM75_3_3V3AUX_SDA    I34 @S9S_MB_2U_LIB.S9S_MB_2U(SCH_1):PAGE221

R3751 Q_RES_0402LF-0,5%,1/16W,CHIP,CA
     1 INA230_2_A0 @S9S_MB_2U_LIB.S9S_MB_2U(SCH_1):INA230_2_A0   I146 @S9S_MB_2U_LIB.S9S_MB_2U(SCH_1):PAGE295
     2 SMB_INA230_2_3V3AUX_SDA_R1 @S9S_MB_2U_LIB.S9S_MB_2U(SCH_1):SMB_INA230_2_3V3AUX_SDA_R1   I146 @S9S_MB_2U_LIB.S9S_MB_2U(SCH_1):PAGE295

R3752 Q_RES_0402LF-0,5%,1/16W,CHIP,CA
     1 E1S_0_P3V3_ADC_ALERT_R @S9S_MB_2U_LIB.S9S_MB_2U(SCH_1):E1S_0_P3V3_ADC_ALERT_R   I122 @S9S_MB_2U_LIB.S9S_MB_2U(SCH_1):PAGE295
     2 E1S_0_P3V3_ADC_ALERT @S9S_MB_2U_LIB.S9S_MB_2U(SCH_1):E1S_0_P3V3_ADC_ALERT   I122 @S9S_MB_2U_LIB.S9S_MB_2U(SCH_1):PAGE295

R3754 Q_RES_0402LF-33.2,1%,1/16W,CHIA
     1 SMB_INA230_2_3V3AUX_SCL_R @S9S_MB_2U_LIB.S9S_MB_2U(SCH_1):SMB_INA230_2_3V3AUX_SCL_R   I130 @S9S_MB_2U_LIB.S9S_MB_2U(SCH_1):PAGE295
     2 SMB_INA230_2_3V3AUX_SCL_R1 @S9S_MB_2U_LIB.S9S_MB_2U(SCH_1):SMB_INA230_2_3V3AUX_SCL_R1   I130 @S9S_MB_2U_LIB.S9S_MB_2U(SCH_1):PAGE295

R3756 Q_RES_0402LF-33.2,1%,1/16W,CHIA
     1 SMB_INA230_2_3V3AUX_SDA_R @S9S_MB_2U_LIB.S9S_MB_2U(SCH_1):SMB_INA230_2_3V3AUX_SDA_R   I131 @S9S_MB_2U_LIB.S9S_MB_2U(SCH_1):PAGE295
     2 SMB_INA230_2_3V3AUX_SDA_R1 @S9S_MB_2U_LIB.S9S_MB_2U(SCH_1):SMB_INA230_2_3V3AUX_SDA_R1   I131 @S9S_MB_2U_LIB.S9S_MB_2U(SCH_1):PAGE295

R3758 Q_RES_0402LF-10,1%,1/16W,CHIP,A
     1 P3V3_E1S_0_R @S9S_MB_2U_LIB.S9S_MB_2U(SCH_1):P3V3_E1S_0_R   I132 @S9S_MB_2U_LIB.S9S_MB_2U(SCH_1):PAGE295
     2 VSENSE_P3V3_INA230_2_INP @S9S_MB_2U_LIB.S9S_MB_2U(SCH_1):VSENSE_P3V3_INA230_2_INP   I132 @S9S_MB_2U_LIB.S9S_MB_2U(SCH_1):PAGE295

R3760 Q_RES_0402LF-10,1%,1/16W,CHIP,A
     1 P3V3_E1S_0 @S9S_MB_2U_LIB.S9S_MB_2U(SCH_1):P3V3_E1S_0   I134 @S9S_MB_2U_LIB.S9S_MB_2U(SCH_1):PAGE295
     2 VSENSE_P3V3_INA230_2_INN @S9S_MB_2U_LIB.S9S_MB_2U(SCH_1):VSENSE_P3V3_INA230_2_INN   I134 @S9S_MB_2U_LIB.S9S_MB_2U(SCH_1):PAGE295

R3763 Q_RES_0402LF-4.7K,1%,1/16W,CHIA
     1    GND @S9S_MB_2U_LIB.S9S_MB_2U(SCH_1):GND   I136 @S9S_MB_2U_LIB.S9S_MB_2U(SCH_1):PAGE295
     2 INA230_2_A1 @S9S_MB_2U_LIB.S9S_MB_2U(SCH_1):INA230_2_A1   I136 @S9S_MB_2U_LIB.S9S_MB_2U(SCH_1):PAGE295

R3764 Q_RES_0402LF-4.7K,1%,1/16W,EMPA
     1    GND @S9S_MB_2U_LIB.S9S_MB_2U(SCH_1):GND   I135 @S9S_MB_2U_LIB.S9S_MB_2U(SCH_1):PAGE295
     2 INA230_2_A0 @S9S_MB_2U_LIB.S9S_MB_2U(SCH_1):INA230_2_A0   I135 @S9S_MB_2U_LIB.S9S_MB_2U(SCH_1):PAGE295

R3767 Q_RES_2512LF-0.01,1%,1W,CHIP,CA
     1 P3V3_E1S_0 @S9S_MB_2U_LIB.S9S_MB_2U(SCH_1):P3V3_E1S_0   I153 @S9S_MB_2U_LIB.S9S_MB_2U(SCH_1):PAGE295
     2 P3V3_E1S_0_R @S9S_MB_2U_LIB.S9S_MB_2U(SCH_1):P3V3_E1S_0_R   I153 @S9S_MB_2U_LIB.S9S_MB_2U(SCH_1):PAGE295

R3770 Q_RES_0402LF-0,5%,1/16W,CHIP,CA
     1 GPU_PRSNT @S9S_MB_2U_LIB.S9S_MB_2U(SCH_1):GPU_PRSNT    I34 @S9S_MB_2U_LIB.S9S_MB_2U(SCH_1):PAGE230
     2 GPU_PRSNT_R @S9S_MB_2U_LIB.S9S_MB_2U(SCH_1):GPU_PRSNT_R    I34 @S9S_MB_2U_LIB.S9S_MB_2U(SCH_1):PAGE230

R3771 Q_RES_0402LF-10K,1%,1/16W,CHIPA
     1 P3V3_AUX @S9S_MB_2U_LIB.S9S_MB_2U(SCH_1):P3V3_AUX   I291 @S9S_MB_2U_LIB.S9S_MB_2U(SCH_1):PAGE297
     2 E1S_0_PWRDIS @S9S_MB_2U_LIB.S9S_MB_2U(SCH_1):E1S_0_PWRDIS   I291 @S9S_MB_2U_LIB.S9S_MB_2U(SCH_1):PAGE297

R3772 Q_RES_0402LF-0,5%,1/16W,CHIP,CA
     1 RST_SMB_BUF_E1S_0_N @S9S_MB_2U_LIB.S9S_MB_2U(SCH_1):RST_SMB_BUF_E1S_0_N   I301 @S9S_MB_2U_LIB.S9S_MB_2U(SCH_1):PAGE297
     2 RST_SMB_E1S_0_N @S9S_MB_2U_LIB.S9S_MB_2U(SCH_1):RST_SMB_E1S_0_N   I301 @S9S_MB_2U_LIB.S9S_MB_2U(SCH_1):PAGE297

R3773 Q_RES_0402LF-4.7K,5%,1/16W,EMPA
     1 P3V3_AUX @S9S_MB_2U_LIB.S9S_MB_2U(SCH_1):P3V3_AUX   I299 @S9S_MB_2U_LIB.S9S_MB_2U(SCH_1):PAGE297
     2 RST_SMB_E1S_0_N @S9S_MB_2U_LIB.S9S_MB_2U(SCH_1):RST_SMB_E1S_0_N   I299 @S9S_MB_2U_LIB.S9S_MB_2U(SCH_1):PAGE297

R3775 Q_RES_0402LF-0,5%,1/16W,CHIP,CA
     1 RST_SMB_SWITCH_N @S9S_MB_2U_LIB.S9S_MB_2U(SCH_1):RST_SMB_SWITCH_N   I307 @S9S_MB_2U_LIB.S9S_MB_2U(SCH_1):PAGE297
     2 RST_SMB_E1S_N @S9S_MB_2U_LIB.S9S_MB_2U(SCH_1):RST_SMB_E1S_N   I307 @S9S_MB_2U_LIB.S9S_MB_2U(SCH_1):PAGE297

R3776 Q_RES_0402LF-0,5%,1/16W,CHIP,CA
     1 FM_UARTSW_MSB_N @S9S_MB_2U_LIB.S9S_MB_2U(SCH_1):FM_UARTSW_MSB_N    I21 @S9S_MB_2U_LIB.S9S_MB_2U(SCH_1):PAGE227
     2 FM_UARTSW_MSB_R @S9S_MB_2U_LIB.S9S_MB_2U(SCH_1):FM_UARTSW_MSB_R    I21 @S9S_MB_2U_LIB.S9S_MB_2U(SCH_1):PAGE227

R3777 Q_RES_0402LF-0,5%,1/16W,CHIP,CA
     1 FM_UARTSW_LSB_N @S9S_MB_2U_LIB.S9S_MB_2U(SCH_1):FM_UARTSW_LSB_N    I19 @S9S_MB_2U_LIB.S9S_MB_2U(SCH_1):PAGE227
     2 FM_UARTSW_LSB_R @S9S_MB_2U_LIB.S9S_MB_2U(SCH_1):FM_UARTSW_LSB_R    I19 @S9S_MB_2U_LIB.S9S_MB_2U(SCH_1):PAGE227

R3778 Q_RES_0402LF-0,5%,1/16W,CHIP,CA
     1 FM_SOL_UART_CH_SEL_R @S9S_MB_2U_LIB.S9S_MB_2U(SCH_1):FM_SOL_UART_CH_SEL_R   I159 @S9S_MB_2U_LIB.S9S_MB_2U(SCH_1):PAGE227
     2 FM_SOL_UART_CH_SEL @S9S_MB_2U_LIB.S9S_MB_2U(SCH_1):FM_SOL_UART_CH_SEL   I159 @S9S_MB_2U_LIB.S9S_MB_2U(SCH_1):PAGE227

R3779 Q_RES_0402LF-0,5%,1/16W,CHIP,CA
     1 RST_PCIE_PCH_DEV_PERST_E1S_R_N @S9S_MB_2U_LIB.S9S_MB_2U(SCH_1):RST_PCIE_PCH_DEV_PERST_E1S_R_N   I309 @S9S_MB_2U_LIB.S9S_MB_2U(SCH_1):PAGE297
     2 RST_PCIE_PCH_E1S_PERST_N @S9S_MB_2U_LIB.S9S_MB_2U(SCH_1):RST_PCIE_PCH_E1S_PERST_N   I309 @S9S_MB_2U_LIB.S9S_MB_2U(SCH_1):PAGE297

R3783 Q_RES_0402LF-100K,1%,1/16W,CHIA
     1 P3V3_AUX @S9S_MB_2U_LIB.S9S_MB_2U(SCH_1):P3V3_AUX   I110 @S9S_MB_2U_LIB.S9S_MB_2U(SCH_1):PAGE153
     2 OCP_V3_1_P3V3_PWRGD @S9S_MB_2U_LIB.S9S_MB_2U(SCH_1):OCP_V3_1_P3V3_PWRGD   I110 @S9S_MB_2U_LIB.S9S_MB_2U(SCH_1):PAGE153

R3784 Q_RES_0402LF-0,5%,1/16W,EMPTY,A
     1 P12V_OCP_UV_1_R @S9S_MB_2U_LIB.S9S_MB_2U(SCH_1):P12V_OCP_UV_1_R    I39 @S9S_MB_2U_LIB.S9S_MB_2U(SCH_1):PAGE153
     2 P12V_OCP_UV_1 @S9S_MB_2U_LIB.S9S_MB_2U(SCH_1):P12V_OCP_UV_1    I39 @S9S_MB_2U_LIB.S9S_MB_2U(SCH_1):PAGE153

R3785 Q_RES_0402LF-0,5%,1/16W,CHIP,CA
     1 P3V3_OCP_UV_1_R1 @S9S_MB_2U_LIB.S9S_MB_2U(SCH_1):P3V3_OCP_UV_1_R1    I64 @S9S_MB_2U_LIB.S9S_MB_2U(SCH_1):PAGE153
     2 P3V3_OCP_UV_1 @S9S_MB_2U_LIB.S9S_MB_2U(SCH_1):P3V3_OCP_UV_1    I64 @S9S_MB_2U_LIB.S9S_MB_2U(SCH_1):PAGE153

R3794 Q_RES_0402LF-0,5%,1/16W,CHIP,CA
     1 P3V3_OCP_PWRGD_1 @S9S_MB_2U_LIB.S9S_MB_2U(SCH_1):P3V3_OCP_PWRGD_1   I105 @S9S_MB_2U_LIB.S9S_MB_2U(SCH_1):PAGE153
     2 OCP_V3_1_P3V3_PWRGD @S9S_MB_2U_LIB.S9S_MB_2U(SCH_1):OCP_V3_1_P3V3_PWRGD   I105 @S9S_MB_2U_LIB.S9S_MB_2U(SCH_1):PAGE153

R3796 Q_RES_0402LF-100K,1%,1/16W,CHIA
     1 P3V3_AUX @S9S_MB_2U_LIB.S9S_MB_2U(SCH_1):P3V3_AUX   I108 @S9S_MB_2U_LIB.S9S_MB_2U(SCH_1):PAGE153
     2 P3V3_OCP_FAULT_1 @S9S_MB_2U_LIB.S9S_MB_2U(SCH_1):P3V3_OCP_FAULT_1   I108 @S9S_MB_2U_LIB.S9S_MB_2U(SCH_1):PAGE153

R3797 Q_RES_0402LF-100K,1%,1/16W,EMPA
     1 P3V3_AUX @S9S_MB_2U_LIB.S9S_MB_2U(SCH_1):P3V3_AUX    I92 @S9S_MB_2U_LIB.S9S_MB_2U(SCH_1):PAGE153
     2 HP_LVC3_OCP_V3_1_P12V_PWRGD @S9S_MB_2U_LIB.S9S_MB_2U(SCH_1):HP_LVC3_OCP_V3_1_P12V_PWRGD    I92 @S9S_MB_2U_LIB.S9S_MB_2U(SCH_1):PAGE153

R3799 Q_RES_0402LF-100K,1%,1/16W,EMPA
     1 P3V3_AUX @S9S_MB_2U_LIB.S9S_MB_2U(SCH_1):P3V3_AUX    I90 @S9S_MB_2U_LIB.S9S_MB_2U(SCH_1):PAGE153
     2 P12V_OCP_FAULT_1 @S9S_MB_2U_LIB.S9S_MB_2U(SCH_1):P12V_OCP_FAULT_1    I90 @S9S_MB_2U_LIB.S9S_MB_2U(SCH_1):PAGE153

R3807 Q_RES_0402LF-0,5%,1/16W,CHIP,CA
     1 P3V3_OCP_UV_2_R1 @S9S_MB_2U_LIB.S9S_MB_2U(SCH_1):P3V3_OCP_UV_2_R1    I47 @S9S_MB_2U_LIB.S9S_MB_2U(SCH_1):PAGE131
     2 P3V3_OCP_UV_2 @S9S_MB_2U_LIB.S9S_MB_2U(SCH_1):P3V3_OCP_UV_2    I47 @S9S_MB_2U_LIB.S9S_MB_2U(SCH_1):PAGE131

R3816 Q_RES_0402LF-100K,1%,1/16W,EMPA
     1 P3V3_AUX @S9S_MB_2U_LIB.S9S_MB_2U(SCH_1):P3V3_AUX    I80 @S9S_MB_2U_LIB.S9S_MB_2U(SCH_1):PAGE131
     2 P12V_OCP_FAULT_2 @S9S_MB_2U_LIB.S9S_MB_2U(SCH_1):P12V_OCP_FAULT_2    I80 @S9S_MB_2U_LIB.S9S_MB_2U(SCH_1):PAGE131

R3825 Q_RES_0402LF-100K,1%,1/16W,EMPA
     1 P3V3_AUX @S9S_MB_2U_LIB.S9S_MB_2U(SCH_1):P3V3_AUX    I81 @S9S_MB_2U_LIB.S9S_MB_2U(SCH_1):PAGE131
     2 HP_LVC3_OCP_V3_2_P12V_PWRGD @S9S_MB_2U_LIB.S9S_MB_2U(SCH_1):HP_LVC3_OCP_V3_2_P12V_PWRGD    I81 @S9S_MB_2U_LIB.S9S_MB_2U(SCH_1):PAGE131

R3826 Q_RES_0402LF-100K,1%,1/16W,CHIA
     1 P3V3_AUX @S9S_MB_2U_LIB.S9S_MB_2U(SCH_1):P3V3_AUX   I110 @S9S_MB_2U_LIB.S9S_MB_2U(SCH_1):PAGE131
     2 OCP_V3_2_P3V3_PWRGD @S9S_MB_2U_LIB.S9S_MB_2U(SCH_1):OCP_V3_2_P3V3_PWRGD   I110 @S9S_MB_2U_LIB.S9S_MB_2U(SCH_1):PAGE131

R3827 Q_RES_0402LF-0,5%,1/16W,EMPTY,A
     1 P12V_OCP_UV_2_R @S9S_MB_2U_LIB.S9S_MB_2U(SCH_1):P12V_OCP_UV_2_R    I30 @S9S_MB_2U_LIB.S9S_MB_2U(SCH_1):PAGE131
     2 P12V_OCP_UV_2 @S9S_MB_2U_LIB.S9S_MB_2U(SCH_1):P12V_OCP_UV_2    I30 @S9S_MB_2U_LIB.S9S_MB_2U(SCH_1):PAGE131

R3831 Q_RES_0402LF-0,5%,1/16W,EMPTY,A
     1 P12V_OCP_PWRGD_2 @S9S_MB_2U_LIB.S9S_MB_2U(SCH_1):P12V_OCP_PWRGD_2    I78 @S9S_MB_2U_LIB.S9S_MB_2U(SCH_1):PAGE131
     2 HP_LVC3_OCP_V3_2_P12V_PWRGD @S9S_MB_2U_LIB.S9S_MB_2U(SCH_1):HP_LVC3_OCP_V3_2_P12V_PWRGD    I78 @S9S_MB_2U_LIB.S9S_MB_2U(SCH_1):PAGE131

R3832 Q_RES_0402LF-0,5%,1/16W,CHIP,CA
     1 P3V3_OCP_PWRGD_2 @S9S_MB_2U_LIB.S9S_MB_2U(SCH_1):P3V3_OCP_PWRGD_2    I97 @S9S_MB_2U_LIB.S9S_MB_2U(SCH_1):PAGE131
     2 OCP_V3_2_P3V3_PWRGD @S9S_MB_2U_LIB.S9S_MB_2U(SCH_1):OCP_V3_2_P3V3_PWRGD    I97 @S9S_MB_2U_LIB.S9S_MB_2U(SCH_1):PAGE131

R3833 Q_RES_0402LF-100K,1%,1/16W,CHIA
     1 P3V3_AUX @S9S_MB_2U_LIB.S9S_MB_2U(SCH_1):P3V3_AUX   I108 @S9S_MB_2U_LIB.S9S_MB_2U(SCH_1):PAGE131
     2 P3V3_OCP_FAULT_2 @S9S_MB_2U_LIB.S9S_MB_2U(SCH_1):P3V3_OCP_FAULT_2   I108 @S9S_MB_2U_LIB.S9S_MB_2U(SCH_1):PAGE131

R3834 Q_RES_0402LF-0,5%,1/16W,CHIP,CA
     1 HP_LVC3_OCP_V3_1_EN @S9S_MB_2U_LIB.S9S_MB_2U(SCH_1):HP_LVC3_OCP_V3_1_EN    I65 @S9S_MB_2U_LIB.S9S_MB_2U(SCH_1):PAGE236
     2 P12V_OCP_EN_1_R2 @S9S_MB_2U_LIB.S9S_MB_2U(SCH_1):P12V_OCP_EN_1_R2    I65 @S9S_MB_2U_LIB.S9S_MB_2U(SCH_1):PAGE236

R3836 Q_RES_0402LF-10K,1%,1/16W,CHIPA
     1 P3V3_AUX @S9S_MB_2U_LIB.S9S_MB_2U(SCH_1):P3V3_AUX    I92 @S9S_MB_2U_LIB.S9S_MB_2U(SCH_1):PAGE229
     2 HP_LVC3_SCM_HSC_PWRGD_R @S9S_MB_2U_LIB.S9S_MB_2U(SCH_1):HP_LVC3_SCM_HSC_PWRGD_R    I92 @S9S_MB_2U_LIB.S9S_MB_2U(SCH_1):PAGE229

R3845 Q_RES_0402LF-0,5%,1/16W,EMPTY,A
     1 HP_LVC3_OCP_V3_1_EN @S9S_MB_2U_LIB.S9S_MB_2U(SCH_1):HP_LVC3_OCP_V3_1_EN    I46 @S9S_MB_2U_LIB.S9S_MB_2U(SCH_1):PAGE236
     2 P3V3_OCP_EN_1_R2 @S9S_MB_2U_LIB.S9S_MB_2U(SCH_1):P3V3_OCP_EN_1_R2    I46 @S9S_MB_2U_LIB.S9S_MB_2U(SCH_1):PAGE236

R3848 Q_RES_0402LF-10K,1%,1/16W,CHIPA
     1 P3V3_AUX @S9S_MB_2U_LIB.S9S_MB_2U(SCH_1):P3V3_AUX    I75 @S9S_MB_2U_LIB.S9S_MB_2U(SCH_1):PAGE237
     2 HP_LVC3_OCP_V3_2_P12V_PWRGD @S9S_MB_2U_LIB.S9S_MB_2U(SCH_1):HP_LVC3_OCP_V3_2_P12V_PWRGD    I75 @S9S_MB_2U_LIB.S9S_MB_2U(SCH_1):PAGE237

R3858 Q_RES_0402LF-33.2,1%,1/16W,CHIA
     1 SMB_OCP_V3_2_3V3AUX_SDA @S9S_MB_2U_LIB.S9S_MB_2U(SCH_1):SMB_OCP_V3_2_3V3AUX_SDA    I94 @S9S_MB_2U_LIB.S9S_MB_2U(SCH_1):PAGE227
     2 SMB_OCP_V3_2_3V3AUX_SDA_R0 @S9S_MB_2U_LIB.S9S_MB_2U(SCH_1):SMB_OCP_V3_2_3V3AUX_SDA_R0    I94 @S9S_MB_2U_LIB.S9S_MB_2U(SCH_1):PAGE227

R3859 Q_RES_0402LF-0,5%,1/16W,EMPTY,A
     1 P12V_OCP_V3_2_ISENSE_MAM_MAM @S9S_MB_2U_LIB.S9S_MB_2U(SCH_1):P12V_OCP_V3_2_ISENSE_MAM_MAM   I321 @S9S_MB_2U_LIB.S9S_MB_2U(SCH_1):PAGE239
     2 P12V_OCP_V3_2_ISENSE_MAM @S9S_MB_2U_LIB.S9S_MB_2U(SCH_1):P12V_OCP_V3_2_ISENSE_MAM   I321 @S9S_MB_2U_LIB.S9S_MB_2U(SCH_1):PAGE239

R3860 Q_RES_0402LF-0,5%,1/16W,EMPTY,A
     1 P12V_OCP_V3_2_ISENSE_MPS_MAM @S9S_MB_2U_LIB.S9S_MB_2U(SCH_1):P12V_OCP_V3_2_ISENSE_MPS_MAM   I322 @S9S_MB_2U_LIB.S9S_MB_2U(SCH_1):PAGE239
     2 P12V_OCP_V3_2_ISENSE_MAM @S9S_MB_2U_LIB.S9S_MB_2U(SCH_1):P12V_OCP_V3_2_ISENSE_MAM   I322 @S9S_MB_2U_LIB.S9S_MB_2U(SCH_1):PAGE239

R3861 Q_RES_0402LF-0,5%,1/16W,EMPTY,A
     1 P12V_OCP_V3_2_ISENSE_MAM_TIC @S9S_MB_2U_LIB.S9S_MB_2U(SCH_1):P12V_OCP_V3_2_ISENSE_MAM_TIC   I323 @S9S_MB_2U_LIB.S9S_MB_2U(SCH_1):PAGE239
     2 P12V_OCP_V3_2_ISENSE_TIC @S9S_MB_2U_LIB.S9S_MB_2U(SCH_1):P12V_OCP_V3_2_ISENSE_TIC   I323 @S9S_MB_2U_LIB.S9S_MB_2U(SCH_1):PAGE239

R3862 Q_RES_0402LF-0,5%,1/16W,CHIP,CA
     1 P12V_OCP_V3_2_ISENSE_MPS_TIC @S9S_MB_2U_LIB.S9S_MB_2U(SCH_1):P12V_OCP_V3_2_ISENSE_MPS_TIC   I324 @S9S_MB_2U_LIB.S9S_MB_2U(SCH_1):PAGE239
     2 P12V_OCP_V3_2_ISENSE_TIC @S9S_MB_2U_LIB.S9S_MB_2U(SCH_1):P12V_OCP_V3_2_ISENSE_TIC   I324 @S9S_MB_2U_LIB.S9S_MB_2U(SCH_1):PAGE239

R3863 Q_RES_0402LF-0,5%,1/16W,EMPTY,A
     1 P12V_OCP_SFF_ISENSE_MAM_MAM @S9S_MB_2U_LIB.S9S_MB_2U(SCH_1):P12V_OCP_SFF_ISENSE_MAM_MAM   I313 @S9S_MB_2U_LIB.S9S_MB_2U(SCH_1):PAGE239
     2 P12V_OCP_SFF_ISENSE_MAM @S9S_MB_2U_LIB.S9S_MB_2U(SCH_1):P12V_OCP_SFF_ISENSE_MAM   I313 @S9S_MB_2U_LIB.S9S_MB_2U(SCH_1):PAGE239

R3864 Q_RES_0402LF-0,5%,1/16W,EMPTY,A
     1 P12V_OCP_SFF_ISENSE_MPS_MAM @S9S_MB_2U_LIB.S9S_MB_2U(SCH_1):P12V_OCP_SFF_ISENSE_MPS_MAM   I314 @S9S_MB_2U_LIB.S9S_MB_2U(SCH_1):PAGE239
     2 P12V_OCP_SFF_ISENSE_MAM @S9S_MB_2U_LIB.S9S_MB_2U(SCH_1):P12V_OCP_SFF_ISENSE_MAM   I314 @S9S_MB_2U_LIB.S9S_MB_2U(SCH_1):PAGE239

R3865 Q_RES_0402LF-0,5%,1/16W,EMPTY,A
     1 P12V_OCP_SFF_ISENSE_MAM_TIC @S9S_MB_2U_LIB.S9S_MB_2U(SCH_1):P12V_OCP_SFF_ISENSE_MAM_TIC   I315 @S9S_MB_2U_LIB.S9S_MB_2U(SCH_1):PAGE239
     2 P12V_OCP_SFF_ISENSE_TIC @S9S_MB_2U_LIB.S9S_MB_2U(SCH_1):P12V_OCP_SFF_ISENSE_TIC   I315 @S9S_MB_2U_LIB.S9S_MB_2U(SCH_1):PAGE239

R3866 Q_RES_0402LF-0,5%,1/16W,CHIP,CA
     1 P12V_OCP_SFF_ISENSE_MPS_TIC @S9S_MB_2U_LIB.S9S_MB_2U(SCH_1):P12V_OCP_SFF_ISENSE_MPS_TIC   I316 @S9S_MB_2U_LIB.S9S_MB_2U(SCH_1):PAGE239
     2 P12V_OCP_SFF_ISENSE_TIC @S9S_MB_2U_LIB.S9S_MB_2U(SCH_1):P12V_OCP_SFF_ISENSE_TIC   I316 @S9S_MB_2U_LIB.S9S_MB_2U(SCH_1):PAGE239

R3867 Q_RES_0402LF-0,5%,1/16W,EMPTY,A
     1 P12V_OCP_SENSE_2 @S9S_MB_2U_LIB.S9S_MB_2U(SCH_1):P12V_OCP_SENSE_2    I75 @S9S_MB_2U_LIB.S9S_MB_2U(SCH_1):PAGE131
     2 P12V_OCP_V3_2_ISENSE_MAM_MAM @S9S_MB_2U_LIB.S9S_MB_2U(SCH_1):P12V_OCP_V3_2_ISENSE_MAM_MAM    I75 @S9S_MB_2U_LIB.S9S_MB_2U(SCH_1):PAGE131

R3868 Q_RES_0402LF-0,5%,1/16W,EMPTY,A
     1 P12V_OCP_SENSE_2 @S9S_MB_2U_LIB.S9S_MB_2U(SCH_1):P12V_OCP_SENSE_2    I74 @S9S_MB_2U_LIB.S9S_MB_2U(SCH_1):PAGE131
     2 P12V_OCP_V3_2_ISENSE_MAM_TIC @S9S_MB_2U_LIB.S9S_MB_2U(SCH_1):P12V_OCP_V3_2_ISENSE_MAM_TIC    I74 @S9S_MB_2U_LIB.S9S_MB_2U(SCH_1):PAGE131

R3869 Q_RES_0402LF-0,5%,1/16W,EMPTY,A
     1 P12V_OCP_SENSE_1 @S9S_MB_2U_LIB.S9S_MB_2U(SCH_1):P12V_OCP_SENSE_1    I87 @S9S_MB_2U_LIB.S9S_MB_2U(SCH_1):PAGE153
     2 P12V_OCP_SFF_ISENSE_MAM_MAM @S9S_MB_2U_LIB.S9S_MB_2U(SCH_1):P12V_OCP_SFF_ISENSE_MAM_MAM    I87 @S9S_MB_2U_LIB.S9S_MB_2U(SCH_1):PAGE153

R3870 Q_RES_0402LF-0,5%,1/16W,EMPTY,A
     1 P12V_OCP_SENSE_1 @S9S_MB_2U_LIB.S9S_MB_2U(SCH_1):P12V_OCP_SENSE_1    I88 @S9S_MB_2U_LIB.S9S_MB_2U(SCH_1):PAGE153
     2 P12V_OCP_SFF_ISENSE_MAM_TIC @S9S_MB_2U_LIB.S9S_MB_2U(SCH_1):P12V_OCP_SFF_ISENSE_MAM_TIC    I88 @S9S_MB_2U_LIB.S9S_MB_2U(SCH_1):PAGE153

R3871 Q_RES_0402LF-0,5%,1/16W,EMPTY,A
     1 P12V_OCP_IMON_1 @S9S_MB_2U_LIB.S9S_MB_2U(SCH_1):P12V_OCP_IMON_1    I82 @S9S_MB_2U_LIB.S9S_MB_2U(SCH_1):PAGE236
     2 P12V_OCP_SFF_ISENSE_MPS_MAM @S9S_MB_2U_LIB.S9S_MB_2U(SCH_1):P12V_OCP_SFF_ISENSE_MPS_MAM    I82 @S9S_MB_2U_LIB.S9S_MB_2U(SCH_1):PAGE236

R3872 Q_RES_0402LF-0,5%,1/16W,CHIP,CA
     1 P12V_OCP_IMON_1 @S9S_MB_2U_LIB.S9S_MB_2U(SCH_1):P12V_OCP_IMON_1    I81 @S9S_MB_2U_LIB.S9S_MB_2U(SCH_1):PAGE236
     2 P12V_OCP_SFF_ISENSE_MPS_TIC @S9S_MB_2U_LIB.S9S_MB_2U(SCH_1):P12V_OCP_SFF_ISENSE_MPS_TIC    I81 @S9S_MB_2U_LIB.S9S_MB_2U(SCH_1):PAGE236

R3873 Q_RES_0402LF-0,5%,1/16W,EMPTY,A
     1 P12V_OCP_IMON_2 @S9S_MB_2U_LIB.S9S_MB_2U(SCH_1):P12V_OCP_IMON_2    I81 @S9S_MB_2U_LIB.S9S_MB_2U(SCH_1):PAGE237
     2 P12V_OCP_V3_2_ISENSE_MPS_MAM @S9S_MB_2U_LIB.S9S_MB_2U(SCH_1):P12V_OCP_V3_2_ISENSE_MPS_MAM    I81 @S9S_MB_2U_LIB.S9S_MB_2U(SCH_1):PAGE237

R3874 Q_RES_0402LF-0,5%,1/16W,CHIP,CA
     1 P12V_OCP_IMON_2 @S9S_MB_2U_LIB.S9S_MB_2U(SCH_1):P12V_OCP_IMON_2    I80 @S9S_MB_2U_LIB.S9S_MB_2U(SCH_1):PAGE237
     2 P12V_OCP_V3_2_ISENSE_MPS_TIC @S9S_MB_2U_LIB.S9S_MB_2U(SCH_1):P12V_OCP_V3_2_ISENSE_MPS_TIC    I80 @S9S_MB_2U_LIB.S9S_MB_2U(SCH_1):PAGE237

R3875 Q_RES_0402LF-49.9,1%,1/16W,CHIA
     1 I3C_SPD_DDRABCD_CPU0_LVC1_SCL_R @S9S_MB_2U_LIB.S9S_MB_2U(SCH_1):I3C_SPD_DDRABCD_CPU0_LVC1_SCL_R1   I204 @S9S_MB_2U_LIB.S9S_MB_2U(SCH_1):PAGE82
     2 I3C_SPD_DDRABCD_CPU0_LVC1_SCL @S9S_MB_2U_LIB.S9S_MB_2U(SCH_1):I3C_SPD_DDRABCD_CPU0_LVC1_SCL   I204 @S9S_MB_2U_LIB.S9S_MB_2U(SCH_1):PAGE82

R3876 Q_RES_0402LF-49.9,1%,1/16W,CHIA
     1 I3C_SPD_DDRABCD_CPU0_LVC1_SCL_1 @S9S_MB_2U_LIB.S9S_MB_2U(SCH_1):I3C_SPD_DDRABCD_CPU0_LVC1_SCL_R2   I182 @S9S_MB_2U_LIB.S9S_MB_2U(SCH_1):PAGE83
     2 I3C_SPD_DDRABCD_CPU0_LVC1_SCL @S9S_MB_2U_LIB.S9S_MB_2U(SCH_1):I3C_SPD_DDRABCD_CPU0_LVC1_SCL   I182 @S9S_MB_2U_LIB.S9S_MB_2U(SCH_1):PAGE83

R3877 Q_RES_0402LF-49.9,1%,1/16W,CHIA
     1 I3C_SPD_DDRABCD_CPU0_LVC1_SCL_2 @S9S_MB_2U_LIB.S9S_MB_2U(SCH_1):I3C_SPD_DDRABCD_CPU0_LVC1_SCL_R3   I182 @S9S_MB_2U_LIB.S9S_MB_2U(SCH_1):PAGE84
     2 I3C_SPD_DDRABCD_CPU0_LVC1_SCL @S9S_MB_2U_LIB.S9S_MB_2U(SCH_1):I3C_SPD_DDRABCD_CPU0_LVC1_SCL   I182 @S9S_MB_2U_LIB.S9S_MB_2U(SCH_1):PAGE84

R3878 Q_RES_0402LF-49.9,1%,1/16W,CHIA
     1 I3C_SPD_DDRABCD_CPU0_LVC1_SCL_3 @S9S_MB_2U_LIB.S9S_MB_2U(SCH_1):I3C_SPD_DDRABCD_CPU0_LVC1_SCL_R4   I180 @S9S_MB_2U_LIB.S9S_MB_2U(SCH_1):PAGE85
     2 I3C_SPD_DDRABCD_CPU0_LVC1_SCL @S9S_MB_2U_LIB.S9S_MB_2U(SCH_1):I3C_SPD_DDRABCD_CPU0_LVC1_SCL   I180 @S9S_MB_2U_LIB.S9S_MB_2U(SCH_1):PAGE85

R3879 Q_RES_0402LF-49.9,1%,1/16W,CHIA
     1 I3C_SPD_DDRABCD_CPU0_LVC1_SCL_4 @S9S_MB_2U_LIB.S9S_MB_2U(SCH_1):I3C_SPD_DDRABCD_CPU0_LVC1_SCL_R5   I180 @S9S_MB_2U_LIB.S9S_MB_2U(SCH_1):PAGE86
     2 I3C_SPD_DDRABCD_CPU0_LVC1_SCL @S9S_MB_2U_LIB.S9S_MB_2U(SCH_1):I3C_SPD_DDRABCD_CPU0_LVC1_SCL   I180 @S9S_MB_2U_LIB.S9S_MB_2U(SCH_1):PAGE86

R3880 Q_RES_0402LF-49.9,1%,1/16W,CHIA
     1 I3C_SPD_DDRABCD_CPU0_LVC1_SCL_5 @S9S_MB_2U_LIB.S9S_MB_2U(SCH_1):I3C_SPD_DDRABCD_CPU0_LVC1_SCL_R6   I180 @S9S_MB_2U_LIB.S9S_MB_2U(SCH_1):PAGE87
     2 I3C_SPD_DDRABCD_CPU0_LVC1_SCL @S9S_MB_2U_LIB.S9S_MB_2U(SCH_1):I3C_SPD_DDRABCD_CPU0_LVC1_SCL   I180 @S9S_MB_2U_LIB.S9S_MB_2U(SCH_1):PAGE87

R3881 Q_RES_0402LF-49.9,1%,1/16W,CHIA
     1 I3C_SPD_DDRABCD_CPU0_LVC1_SCL_6 @S9S_MB_2U_LIB.S9S_MB_2U(SCH_1):I3C_SPD_DDRABCD_CPU0_LVC1_SCL_R7   I180 @S9S_MB_2U_LIB.S9S_MB_2U(SCH_1):PAGE88
     2 I3C_SPD_DDRABCD_CPU0_LVC1_SCL @S9S_MB_2U_LIB.S9S_MB_2U(SCH_1):I3C_SPD_DDRABCD_CPU0_LVC1_SCL   I180 @S9S_MB_2U_LIB.S9S_MB_2U(SCH_1):PAGE88

R3882 Q_RES_0402LF-49.9,1%,1/16W,CHIA
     1 I3C_SPD_DDRABCD_CPU0_LVC1_SCL_7 @S9S_MB_2U_LIB.S9S_MB_2U(SCH_1):I3C_SPD_DDRABCD_CPU0_LVC1_SCL_R8   I180 @S9S_MB_2U_LIB.S9S_MB_2U(SCH_1):PAGE89
     2 I3C_SPD_DDRABCD_CPU0_LVC1_SCL @S9S_MB_2U_LIB.S9S_MB_2U(SCH_1):I3C_SPD_DDRABCD_CPU0_LVC1_SCL   I180 @S9S_MB_2U_LIB.S9S_MB_2U(SCH_1):PAGE89

R3883 Q_RES_0402LF-49.9,1%,1/16W,CHIA
     1 I3C_SPD_DDREFGH_CPU0_LVC1_SCL_R @S9S_MB_2U_LIB.S9S_MB_2U(SCH_1):I3C_SPD_DDREFGH_CPU0_LVC1_SCL_R1   I179 @S9S_MB_2U_LIB.S9S_MB_2U(SCH_1):PAGE90
     2 I3C_SPD_DDREFGH_CPU0_LVC1_SCL @S9S_MB_2U_LIB.S9S_MB_2U(SCH_1):I3C_SPD_DDREFGH_CPU0_LVC1_SCL   I179 @S9S_MB_2U_LIB.S9S_MB_2U(SCH_1):PAGE90

R3884 Q_RES_0402LF-49.9,1%,1/16W,CHIA
     1 I3C_SPD_DDREFGH_CPU0_LVC1_SCL_1 @S9S_MB_2U_LIB.S9S_MB_2U(SCH_1):I3C_SPD_DDREFGH_CPU0_LVC1_SCL_R2   I179 @S9S_MB_2U_LIB.S9S_MB_2U(SCH_1):PAGE91
     2 I3C_SPD_DDREFGH_CPU0_LVC1_SCL @S9S_MB_2U_LIB.S9S_MB_2U(SCH_1):I3C_SPD_DDREFGH_CPU0_LVC1_SCL   I179 @S9S_MB_2U_LIB.S9S_MB_2U(SCH_1):PAGE91

R3885 Q_RES_0402LF-49.9,1%,1/16W,CHIA
     1 I3C_SPD_DDREFGH_CPU0_LVC1_SCL_2 @S9S_MB_2U_LIB.S9S_MB_2U(SCH_1):I3C_SPD_DDREFGH_CPU0_LVC1_SCL_R3   I179 @S9S_MB_2U_LIB.S9S_MB_2U(SCH_1):PAGE92
     2 I3C_SPD_DDREFGH_CPU0_LVC1_SCL @S9S_MB_2U_LIB.S9S_MB_2U(SCH_1):I3C_SPD_DDREFGH_CPU0_LVC1_SCL   I179 @S9S_MB_2U_LIB.S9S_MB_2U(SCH_1):PAGE92

R3886 Q_RES_0402LF-49.9,1%,1/16W,CHIA
     1 I3C_SPD_DDREFGH_CPU0_LVC1_SCL_3 @S9S_MB_2U_LIB.S9S_MB_2U(SCH_1):I3C_SPD_DDREFGH_CPU0_LVC1_SCL_R4   I179 @S9S_MB_2U_LIB.S9S_MB_2U(SCH_1):PAGE93
     2 I3C_SPD_DDREFGH_CPU0_LVC1_SCL @S9S_MB_2U_LIB.S9S_MB_2U(SCH_1):I3C_SPD_DDREFGH_CPU0_LVC1_SCL   I179 @S9S_MB_2U_LIB.S9S_MB_2U(SCH_1):PAGE93

R3887 Q_RES_0402LF-49.9,1%,1/16W,CHIA
     1 I3C_SPD_DDREFGH_CPU0_LVC1_SCL_4 @S9S_MB_2U_LIB.S9S_MB_2U(SCH_1):I3C_SPD_DDREFGH_CPU0_LVC1_SCL_R5   I179 @S9S_MB_2U_LIB.S9S_MB_2U(SCH_1):PAGE94
     2 I3C_SPD_DDREFGH_CPU0_LVC1_SCL @S9S_MB_2U_LIB.S9S_MB_2U(SCH_1):I3C_SPD_DDREFGH_CPU0_LVC1_SCL   I179 @S9S_MB_2U_LIB.S9S_MB_2U(SCH_1):PAGE94

R3888 Q_RES_0402LF-49.9,1%,1/16W,CHIA
     1 I3C_SPD_DDREFGH_CPU0_LVC1_SCL_5 @S9S_MB_2U_LIB.S9S_MB_2U(SCH_1):I3C_SPD_DDREFGH_CPU0_LVC1_SCL_R6   I179 @S9S_MB_2U_LIB.S9S_MB_2U(SCH_1):PAGE95
     2 I3C_SPD_DDREFGH_CPU0_LVC1_SCL @S9S_MB_2U_LIB.S9S_MB_2U(SCH_1):I3C_SPD_DDREFGH_CPU0_LVC1_SCL   I179 @S9S_MB_2U_LIB.S9S_MB_2U(SCH_1):PAGE95

R3889 Q_RES_0402LF-49.9,1%,1/16W,CHIA
     1 I3C_SPD_DDREFGH_CPU0_LVC1_SCL_6 @S9S_MB_2U_LIB.S9S_MB_2U(SCH_1):I3C_SPD_DDREFGH_CPU0_LVC1_SCL_R7   I179 @S9S_MB_2U_LIB.S9S_MB_2U(SCH_1):PAGE96
     2 I3C_SPD_DDREFGH_CPU0_LVC1_SCL @S9S_MB_2U_LIB.S9S_MB_2U(SCH_1):I3C_SPD_DDREFGH_CPU0_LVC1_SCL   I179 @S9S_MB_2U_LIB.S9S_MB_2U(SCH_1):PAGE96

R3890 Q_RES_0402LF-49.9,1%,1/16W,CHIA
     1 I3C_SPD_DDREFGH_CPU0_LVC1_SCL_7 @S9S_MB_2U_LIB.S9S_MB_2U(SCH_1):I3C_SPD_DDREFGH_CPU0_LVC1_SCL_R8   I179 @S9S_MB_2U_LIB.S9S_MB_2U(SCH_1):PAGE97
     2 I3C_SPD_DDREFGH_CPU0_LVC1_SCL @S9S_MB_2U_LIB.S9S_MB_2U(SCH_1):I3C_SPD_DDREFGH_CPU0_LVC1_SCL   I179 @S9S_MB_2U_LIB.S9S_MB_2U(SCH_1):PAGE97

R3891 Q_RES_0402LF-49.9,1%,1/16W,CHIA
     1 I3C_SPD_DDRABCD_CPU1_LVC1_SCL_R @S9S_MB_2U_LIB.S9S_MB_2U(SCH_1):I3C_SPD_DDRABCD_CPU1_LVC1_SCL_R1   I179 @S9S_MB_2U_LIB.S9S_MB_2U(SCH_1):PAGE98
     2 I3C_SPD_DDRABCD_CPU1_LVC1_SCL @S9S_MB_2U_LIB.S9S_MB_2U(SCH_1):I3C_SPD_DDRABCD_CPU1_LVC1_SCL   I179 @S9S_MB_2U_LIB.S9S_MB_2U(SCH_1):PAGE98

R3892 Q_RES_0402LF-49.9,1%,1/16W,CHIA
     1 I3C_SPD_DDRABCD_CPU1_LVC1_SCL_1 @S9S_MB_2U_LIB.S9S_MB_2U(SCH_1):I3C_SPD_DDRABCD_CPU1_LVC1_SCL_R2   I180 @S9S_MB_2U_LIB.S9S_MB_2U(SCH_1):PAGE99
     2 I3C_SPD_DDRABCD_CPU1_LVC1_SCL @S9S_MB_2U_LIB.S9S_MB_2U(SCH_1):I3C_SPD_DDRABCD_CPU1_LVC1_SCL   I180 @S9S_MB_2U_LIB.S9S_MB_2U(SCH_1):PAGE99

R3893 Q_RES_0402LF-49.9,1%,1/16W,CHIA
     1 I3C_SPD_DDRABCD_CPU1_LVC1_SCL_2 @S9S_MB_2U_LIB.S9S_MB_2U(SCH_1):I3C_SPD_DDRABCD_CPU1_LVC1_SCL_R3   I180 @S9S_MB_2U_LIB.S9S_MB_2U(SCH_1):PAGE100
     2 I3C_SPD_DDRABCD_CPU1_LVC1_SCL @S9S_MB_2U_LIB.S9S_MB_2U(SCH_1):I3C_SPD_DDRABCD_CPU1_LVC1_SCL   I180 @S9S_MB_2U_LIB.S9S_MB_2U(SCH_1):PAGE100

R3894 Q_RES_0402LF-49.9,1%,1/16W,CHIA
     1 I3C_SPD_DDRABCD_CPU1_LVC1_SCL_3 @S9S_MB_2U_LIB.S9S_MB_2U(SCH_1):I3C_SPD_DDRABCD_CPU1_LVC1_SCL_R4   I180 @S9S_MB_2U_LIB.S9S_MB_2U(SCH_1):PAGE101
     2 I3C_SPD_DDRABCD_CPU1_LVC1_SCL @S9S_MB_2U_LIB.S9S_MB_2U(SCH_1):I3C_SPD_DDRABCD_CPU1_LVC1_SCL   I180 @S9S_MB_2U_LIB.S9S_MB_2U(SCH_1):PAGE101

R3895 Q_RES_0402LF-49.9,1%,1/16W,CHIA
     1 I3C_SPD_DDRABCD_CPU1_LVC1_SCL_4 @S9S_MB_2U_LIB.S9S_MB_2U(SCH_1):I3C_SPD_DDRABCD_CPU1_LVC1_SCL_R5   I180 @S9S_MB_2U_LIB.S9S_MB_2U(SCH_1):PAGE102
     2 I3C_SPD_DDRABCD_CPU1_LVC1_SCL @S9S_MB_2U_LIB.S9S_MB_2U(SCH_1):I3C_SPD_DDRABCD_CPU1_LVC1_SCL   I180 @S9S_MB_2U_LIB.S9S_MB_2U(SCH_1):PAGE102

R3896 Q_RES_0402LF-49.9,1%,1/16W,CHIA
     1 I3C_SPD_DDRABCD_CPU1_LVC1_SCL_5 @S9S_MB_2U_LIB.S9S_MB_2U(SCH_1):I3C_SPD_DDRABCD_CPU1_LVC1_SCL_R6   I180 @S9S_MB_2U_LIB.S9S_MB_2U(SCH_1):PAGE103
     2 I3C_SPD_DDRABCD_CPU1_LVC1_SCL @S9S_MB_2U_LIB.S9S_MB_2U(SCH_1):I3C_SPD_DDRABCD_CPU1_LVC1_SCL   I180 @S9S_MB_2U_LIB.S9S_MB_2U(SCH_1):PAGE103

R3897 Q_RES_0402LF-49.9,1%,1/16W,CHIA
     1 I3C_SPD_DDRABCD_CPU1_LVC1_SCL_6 @S9S_MB_2U_LIB.S9S_MB_2U(SCH_1):I3C_SPD_DDRABCD_CPU1_LVC1_SCL_R7   I180 @S9S_MB_2U_LIB.S9S_MB_2U(SCH_1):PAGE104
     2 I3C_SPD_DDRABCD_CPU1_LVC1_SCL @S9S_MB_2U_LIB.S9S_MB_2U(SCH_1):I3C_SPD_DDRABCD_CPU1_LVC1_SCL   I180 @S9S_MB_2U_LIB.S9S_MB_2U(SCH_1):PAGE104

R3898 Q_RES_0402LF-49.9,1%,1/16W,CHIA
     1 I3C_SPD_DDRABCD_CPU1_LVC1_SCL_7 @S9S_MB_2U_LIB.S9S_MB_2U(SCH_1):I3C_SPD_DDRABCD_CPU1_LVC1_SCL_R8   I183 @S9S_MB_2U_LIB.S9S_MB_2U(SCH_1):PAGE105
     2 I3C_SPD_DDRABCD_CPU1_LVC1_SCL @S9S_MB_2U_LIB.S9S_MB_2U(SCH_1):I3C_SPD_DDRABCD_CPU1_LVC1_SCL   I183 @S9S_MB_2U_LIB.S9S_MB_2U(SCH_1):PAGE105

R3899 Q_RES_0402LF-49.9,1%,1/16W,CHIA
     1 I3C_SPD_DDREFGH_CPU1_LVC1_SCL_R @S9S_MB_2U_LIB.S9S_MB_2U(SCH_1):I3C_SPD_DDREFGH_CPU1_LVC1_SCL_R1   I183 @S9S_MB_2U_LIB.S9S_MB_2U(SCH_1):PAGE106
     2 I3C_SPD_DDREFGH_CPU1_LVC1_SCL @S9S_MB_2U_LIB.S9S_MB_2U(SCH_1):I3C_SPD_DDREFGH_CPU1_LVC1_SCL   I183 @S9S_MB_2U_LIB.S9S_MB_2U(SCH_1):PAGE106

R3900 Q_RES_0402LF-49.9,1%,1/16W,CHIA
     1 I3C_SPD_DDREFGH_CPU1_LVC1_SCL_1 @S9S_MB_2U_LIB.S9S_MB_2U(SCH_1):I3C_SPD_DDREFGH_CPU1_LVC1_SCL_R2   I183 @S9S_MB_2U_LIB.S9S_MB_2U(SCH_1):PAGE107
     2 I3C_SPD_DDREFGH_CPU1_LVC1_SCL @S9S_MB_2U_LIB.S9S_MB_2U(SCH_1):I3C_SPD_DDREFGH_CPU1_LVC1_SCL   I183 @S9S_MB_2U_LIB.S9S_MB_2U(SCH_1):PAGE107

R3901 Q_RES_0402LF-49.9,1%,1/16W,CHIA
     1 I3C_SPD_DDREFGH_CPU1_LVC1_SCL_2 @S9S_MB_2U_LIB.S9S_MB_2U(SCH_1):I3C_SPD_DDREFGH_CPU1_LVC1_SCL_R3   I182 @S9S_MB_2U_LIB.S9S_MB_2U(SCH_1):PAGE108
     2 I3C_SPD_DDREFGH_CPU1_LVC1_SCL @S9S_MB_2U_LIB.S9S_MB_2U(SCH_1):I3C_SPD_DDREFGH_CPU1_LVC1_SCL   I182 @S9S_MB_2U_LIB.S9S_MB_2U(SCH_1):PAGE108

R3902 Q_RES_0402LF-49.9,1%,1/16W,CHIA
     1 I3C_SPD_DDREFGH_CPU1_LVC1_SCL_3 @S9S_MB_2U_LIB.S9S_MB_2U(SCH_1):I3C_SPD_DDREFGH_CPU1_LVC1_SCL_R4   I180 @S9S_MB_2U_LIB.S9S_MB_2U(SCH_1):PAGE109
     2 I3C_SPD_DDREFGH_CPU1_LVC1_SCL @S9S_MB_2U_LIB.S9S_MB_2U(SCH_1):I3C_SPD_DDREFGH_CPU1_LVC1_SCL   I180 @S9S_MB_2U_LIB.S9S_MB_2U(SCH_1):PAGE109

R3903 Q_RES_0402LF-49.9,1%,1/16W,CHIA
     1 I3C_SPD_DDREFGH_CPU1_LVC1_SCL_4 @S9S_MB_2U_LIB.S9S_MB_2U(SCH_1):I3C_SPD_DDREFGH_CPU1_LVC1_SCL_R5   I182 @S9S_MB_2U_LIB.S9S_MB_2U(SCH_1):PAGE110
     2 I3C_SPD_DDREFGH_CPU1_LVC1_SCL @S9S_MB_2U_LIB.S9S_MB_2U(SCH_1):I3C_SPD_DDREFGH_CPU1_LVC1_SCL   I182 @S9S_MB_2U_LIB.S9S_MB_2U(SCH_1):PAGE110

R3904 Q_RES_0402LF-49.9,1%,1/16W,CHIA
     1 I3C_SPD_DDREFGH_CPU1_LVC1_SCL_5 @S9S_MB_2U_LIB.S9S_MB_2U(SCH_1):I3C_SPD_DDREFGH_CPU1_LVC1_SCL_R6   I182 @S9S_MB_2U_LIB.S9S_MB_2U(SCH_1):PAGE111
     2 I3C_SPD_DDREFGH_CPU1_LVC1_SCL @S9S_MB_2U_LIB.S9S_MB_2U(SCH_1):I3C_SPD_DDREFGH_CPU1_LVC1_SCL   I182 @S9S_MB_2U_LIB.S9S_MB_2U(SCH_1):PAGE111

R3905 Q_RES_0402LF-49.9,1%,1/16W,CHIA
     1 I3C_SPD_DDREFGH_CPU1_LVC1_SCL_6 @S9S_MB_2U_LIB.S9S_MB_2U(SCH_1):I3C_SPD_DDREFGH_CPU1_LVC1_SCL_R7   I183 @S9S_MB_2U_LIB.S9S_MB_2U(SCH_1):PAGE112
     2 I3C_SPD_DDREFGH_CPU1_LVC1_SCL @S9S_MB_2U_LIB.S9S_MB_2U(SCH_1):I3C_SPD_DDREFGH_CPU1_LVC1_SCL   I183 @S9S_MB_2U_LIB.S9S_MB_2U(SCH_1):PAGE112

R3906 Q_RES_0402LF-49.9,1%,1/16W,CHIA
     1 I3C_SPD_DDREFGH_CPU1_LVC1_SCL_7 @S9S_MB_2U_LIB.S9S_MB_2U(SCH_1):I3C_SPD_DDREFGH_CPU1_LVC1_SCL_R8   I182 @S9S_MB_2U_LIB.S9S_MB_2U(SCH_1):PAGE113
     2 I3C_SPD_DDREFGH_CPU1_LVC1_SCL @S9S_MB_2U_LIB.S9S_MB_2U(SCH_1):I3C_SPD_DDREFGH_CPU1_LVC1_SCL   I182 @S9S_MB_2U_LIB.S9S_MB_2U(SCH_1):PAGE113

R3907 Q_RES_0402LF-33K,1%,1/16W,CHIPA
     1 PDB_PRSNT_N @S9S_MB_2U_LIB.S9S_MB_2U(SCH_1):PDB_PRSNT_N     I4 @S9S_MB_2U_LIB.S9S_MB_2U(SCH_1):PAGE303
     2    GND @S9S_MB_2U_LIB.S9S_MB_2U(SCH_1):GND     I4 @S9S_MB_2U_LIB.S9S_MB_2U(SCH_1):PAGE303

R3909 Q_RES_0402LF-33.2,1%,1/16W,CHIA
     1 SMB_SML1_PMBUS_HSC_SCL @S9S_MB_2U_LIB.S9S_MB_2U(SCH_1):SMB_SML1_PMBUS_HSC_SCL    I38 @S9S_MB_2U_LIB.S9S_MB_2U(SCH_1):PAGE303
     2 SMB_SML1_PMBUS_HSC_L_SCL @S9S_MB_2U_LIB.S9S_MB_2U(SCH_1):SMB_SML1_PMBUS_HSC_L_SCL    I38 @S9S_MB_2U_LIB.S9S_MB_2U(SCH_1):PAGE303

R3923 Q_RES_0402LF-63.4K,1%,1/16W,CHA
     1 P12V_PSU_FUSE @S9S_MB_2U_LIB.S9S_MB_2U(SCH_1):P12V_PSU_FUSE    I10 @S9S_MB_2U_LIB.S9S_MB_2U(SCH_1):PAGE303
     2 PDB_PRSNT_N @S9S_MB_2U_LIB.S9S_MB_2U(SCH_1):PDB_PRSNT_N    I10 @S9S_MB_2U_LIB.S9S_MB_2U(SCH_1):PAGE303

R3924 Q_RES_0402LF-0,5%,1/16W,CHIP,CA
     1 IRQ_SML1_PMBUS_ALERT_N @S9S_MB_2U_LIB.S9S_MB_2U(SCH_1):IRQ_SML1_PMBUS_ALERT_N    I17 @S9S_MB_2U_LIB.S9S_MB_2U(SCH_1):PAGE303
     2 IRQ_SML1_PMBUS_ALERT @S9S_MB_2U_LIB.S9S_MB_2U(SCH_1):IRQ_SML1_PMBUS_ALERT    I17 @S9S_MB_2U_LIB.S9S_MB_2U(SCH_1):PAGE303

R3925 Q_RES_0402LF-1K,1%,1/16W,CHIP,A
     1 IRQ_SML1_PMBUS_ALERT @S9S_MB_2U_LIB.S9S_MB_2U(SCH_1):IRQ_SML1_PMBUS_ALERT    I33 @S9S_MB_2U_LIB.S9S_MB_2U(SCH_1):PAGE303
     2 P3V3_AUX @S9S_MB_2U_LIB.S9S_MB_2U(SCH_1):P3V3_AUX    I33 @S9S_MB_2U_LIB.S9S_MB_2U(SCH_1):PAGE303

R3933 Q_RES_0402LF-16.9K,1%,1/16W,CHA
     1 P12V_AUX @S9S_MB_2U_LIB.S9S_MB_2U(SCH_1):P12V_AUX    I62 @S9S_MB_2U_LIB.S9S_MB_2U(SCH_1):PAGE303
     2 MB0_P12V_STBY_PWRGD @S9S_MB_2U_LIB.S9S_MB_2U(SCH_1):MB0_P12V_STBY_PWRGD    I62 @S9S_MB_2U_LIB.S9S_MB_2U(SCH_1):PAGE303

R3934 Q_RES_0402LF-22,1%,1/16W,CHIP,A
     1 HSC_D_OC_R @S9S_MB_2U_LIB.S9S_MB_2U(SCH_1):HSC_D_OC_R    I82 @S9S_MB_2U_LIB.S9S_MB_2U(SCH_1):PAGE303
     2 HSC_D_OC @S9S_MB_2U_LIB.S9S_MB_2U(SCH_1):HSC_D_OC    I82 @S9S_MB_2U_LIB.S9S_MB_2U(SCH_1):PAGE303

R3936 Q_RES_0402LF-4.7K,1%,1/16W,CHIA
     1 HSC_VDD @S9S_MB_2U_LIB.S9S_MB_2U(SCH_1):HSC_VDD    I85 @S9S_MB_2U_LIB.S9S_MB_2U(SCH_1):PAGE303
     2 HSC_D_OC @S9S_MB_2U_LIB.S9S_MB_2U(SCH_1):HSC_D_OC    I85 @S9S_MB_2U_LIB.S9S_MB_2U(SCH_1):PAGE303

R3938 Q_RES_0402LF-10K,1%,1/16W,CHIPA
     1 PU_OC2_USB_N @S9S_MB_2U_LIB.S9S_MB_2U(SCH_1):PU_OC2_USB_N   I272 @S9S_MB_2U_LIB.S9S_MB_2U(SCH_1):PAGE175
     2 P3V3_AUX @S9S_MB_2U_LIB.S9S_MB_2U(SCH_1):P3V3_AUX   I272 @S9S_MB_2U_LIB.S9S_MB_2U(SCH_1):PAGE175

R3939 Q_RES_0402LF-0,5%,1/16W,EMPTY,A
     1 P12V_E1S_0_ISENSE_MAM_MAM @S9S_MB_2U_LIB.S9S_MB_2U(SCH_1):P12V_E1S_0_ISENSE_MAM_MAM   I330 @S9S_MB_2U_LIB.S9S_MB_2U(SCH_1):PAGE239
     2 P12V_E1S_0_ISENSE_MAM @S9S_MB_2U_LIB.S9S_MB_2U(SCH_1):P12V_E1S_0_ISENSE_MAM   I330 @S9S_MB_2U_LIB.S9S_MB_2U(SCH_1):PAGE239

R3940 Q_RES_0402LF-0,5%,1/16W,EMPTY,A
     1 P12V_E1S_0_ISENSE_MPS_MAM @S9S_MB_2U_LIB.S9S_MB_2U(SCH_1):P12V_E1S_0_ISENSE_MPS_MAM   I337 @S9S_MB_2U_LIB.S9S_MB_2U(SCH_1):PAGE239
     2 P12V_E1S_0_ISENSE_MAM @S9S_MB_2U_LIB.S9S_MB_2U(SCH_1):P12V_E1S_0_ISENSE_MAM   I337 @S9S_MB_2U_LIB.S9S_MB_2U(SCH_1):PAGE239

R3941 Q_RES_0402LF-0,5%,1/16W,EMPTY,A
     1 P12V_E1S_0_ISENSE_MAM_TIC @S9S_MB_2U_LIB.S9S_MB_2U(SCH_1):P12V_E1S_0_ISENSE_MAM_TIC   I338 @S9S_MB_2U_LIB.S9S_MB_2U(SCH_1):PAGE239
     2 P12V_E1S_0_ISENSE_TIC @S9S_MB_2U_LIB.S9S_MB_2U(SCH_1):P12V_E1S_0_ISENSE_TIC   I338 @S9S_MB_2U_LIB.S9S_MB_2U(SCH_1):PAGE239

R3942 Q_RES_0402LF-0,5%,1/16W,CHIP,CA
     1 P12V_E1S_0_ISENSE_MPS_TIC @S9S_MB_2U_LIB.S9S_MB_2U(SCH_1):P12V_E1S_0_ISENSE_MPS_TIC   I339 @S9S_MB_2U_LIB.S9S_MB_2U(SCH_1):PAGE239
     2 P12V_E1S_0_ISENSE_TIC @S9S_MB_2U_LIB.S9S_MB_2U(SCH_1):P12V_E1S_0_ISENSE_TIC   I339 @S9S_MB_2U_LIB.S9S_MB_2U(SCH_1):PAGE239

R3943 Q_RES_0402LF-0,5%,1/16W,CHIP,CA
     1 E1S_0_EN @S9S_MB_2U_LIB.S9S_MB_2U(SCH_1):E1S_0_EN    I45 @S9S_MB_2U_LIB.S9S_MB_2U(SCH_1):PAGE323
     2 P12V_E1S_EN_0_R2 @S9S_MB_2U_LIB.S9S_MB_2U(SCH_1):P12V_E1S_EN_0_R2    I45 @S9S_MB_2U_LIB.S9S_MB_2U(SCH_1):PAGE323

R3946 Q_RES_0402LF-0,5%,1/16W,EMPTY,A
     1 E1S_0_EN @S9S_MB_2U_LIB.S9S_MB_2U(SCH_1):E1S_0_EN     I5 @S9S_MB_2U_LIB.S9S_MB_2U(SCH_1):PAGE323
     2 P3V3_E1S_EN_0_R2 @S9S_MB_2U_LIB.S9S_MB_2U(SCH_1):P3V3_E1S_EN_0_R2     I5 @S9S_MB_2U_LIB.S9S_MB_2U(SCH_1):PAGE323

R3948 Q_RES_0402LF-10K,1%,1/16W,CHIPA
     1 P3V3_AUX @S9S_MB_2U_LIB.S9S_MB_2U(SCH_1):P3V3_AUX    I64 @S9S_MB_2U_LIB.S9S_MB_2U(SCH_1):PAGE323
     2 HP_LVC3_E1S_0_HSC_PWRGD @S9S_MB_2U_LIB.S9S_MB_2U(SCH_1):HP_LVC3_E1S_0_HSC_PWRGD    I64 @S9S_MB_2U_LIB.S9S_MB_2U(SCH_1):PAGE323

R3955 Q_RES_0402LF-0,5%,1/16W,EMPTY,A
     1 P12V_E1S_IMON_0 @S9S_MB_2U_LIB.S9S_MB_2U(SCH_1):P12V_E1S_IMON_0    I67 @S9S_MB_2U_LIB.S9S_MB_2U(SCH_1):PAGE323
     2 P12V_E1S_0_ISENSE_MPS_MAM @S9S_MB_2U_LIB.S9S_MB_2U(SCH_1):P12V_E1S_0_ISENSE_MPS_MAM    I67 @S9S_MB_2U_LIB.S9S_MB_2U(SCH_1):PAGE323

R3956 Q_RES_0402LF-0,5%,1/16W,CHIP,CA
     1 P12V_E1S_IMON_0 @S9S_MB_2U_LIB.S9S_MB_2U(SCH_1):P12V_E1S_IMON_0    I66 @S9S_MB_2U_LIB.S9S_MB_2U(SCH_1):PAGE323
     2 P12V_E1S_0_ISENSE_MPS_TIC @S9S_MB_2U_LIB.S9S_MB_2U(SCH_1):P12V_E1S_0_ISENSE_MPS_TIC    I66 @S9S_MB_2U_LIB.S9S_MB_2U(SCH_1):PAGE323

R3958 Q_RES_0402LF-0,5%,1/16W,EMPTY,A
     1 P12V_E1S_UV_0_R @S9S_MB_2U_LIB.S9S_MB_2U(SCH_1):P12V_E1S_UV_0_R    I26 @S9S_MB_2U_LIB.S9S_MB_2U(SCH_1):PAGE324
     2 P12V_E1S_UV_0 @S9S_MB_2U_LIB.S9S_MB_2U(SCH_1):P12V_E1S_UV_0    I26 @S9S_MB_2U_LIB.S9S_MB_2U(SCH_1):PAGE324

R3959 Q_RES_0402LF-0,5%,1/16W,CHIP,CA
     1 P3V3_E1S_UV_0_R @S9S_MB_2U_LIB.S9S_MB_2U(SCH_1):P3V3_E1S_UV_0_R    I15 @S9S_MB_2U_LIB.S9S_MB_2U(SCH_1):PAGE324
     2 P3V3_E1S_UV_0 @S9S_MB_2U_LIB.S9S_MB_2U(SCH_1):P3V3_E1S_UV_0    I15 @S9S_MB_2U_LIB.S9S_MB_2U(SCH_1):PAGE324

R3972 Q_RES_0402LF-0,5%,1/16W,EMPTY,A
     1 P12V_E1S_PWRGD_0 @S9S_MB_2U_LIB.S9S_MB_2U(SCH_1):P12V_E1S_PWRGD_0    I68 @S9S_MB_2U_LIB.S9S_MB_2U(SCH_1):PAGE324
     2 HP_LVC3_E1S_0_HSC_PWRGD @S9S_MB_2U_LIB.S9S_MB_2U(SCH_1):HP_LVC3_E1S_0_HSC_PWRGD    I68 @S9S_MB_2U_LIB.S9S_MB_2U(SCH_1):PAGE324

R3973 Q_RES_0402LF-0,5%,1/16W,CHIP,CA
     1 P3V3_E1S_PWRGD_0 @S9S_MB_2U_LIB.S9S_MB_2U(SCH_1):P3V3_E1S_PWRGD_0    I44 @S9S_MB_2U_LIB.S9S_MB_2U(SCH_1):PAGE324
     2 TP_P3V3_E1S_PWRGD_0 @S9S_MB_2U_LIB.S9S_MB_2U(SCH_1):TP_P3V3_E1S_PWRGD_0    I44 @S9S_MB_2U_LIB.S9S_MB_2U(SCH_1):PAGE324

R3974 Q_RES_0402LF-0,5%,1/16W,EMPTY,A
     1 P12V_E1S_SENSE_0 @S9S_MB_2U_LIB.S9S_MB_2U(SCH_1):P12V_E1S_SENSE_0    I67 @S9S_MB_2U_LIB.S9S_MB_2U(SCH_1):PAGE324
     2 P12V_E1S_0_ISENSE_MAM_MAM @S9S_MB_2U_LIB.S9S_MB_2U(SCH_1):P12V_E1S_0_ISENSE_MAM_MAM    I67 @S9S_MB_2U_LIB.S9S_MB_2U(SCH_1):PAGE324

R3975 Q_RES_0402LF-0,5%,1/16W,EMPTY,A
     1 P12V_E1S_SENSE_0 @S9S_MB_2U_LIB.S9S_MB_2U(SCH_1):P12V_E1S_SENSE_0    I65 @S9S_MB_2U_LIB.S9S_MB_2U(SCH_1):PAGE324
     2 P12V_E1S_0_ISENSE_MAM_TIC @S9S_MB_2U_LIB.S9S_MB_2U(SCH_1):P12V_E1S_0_ISENSE_MAM_TIC    I65 @S9S_MB_2U_LIB.S9S_MB_2U(SCH_1):PAGE324

R3976 Q_RES_0402LF-100K,1%,1/16W,EMPA
     1 P3V3_AUX @S9S_MB_2U_LIB.S9S_MB_2U(SCH_1):P3V3_AUX    I73 @S9S_MB_2U_LIB.S9S_MB_2U(SCH_1):PAGE324
     2 P12V_E1S_FAULT_0 @S9S_MB_2U_LIB.S9S_MB_2U(SCH_1):P12V_E1S_FAULT_0    I73 @S9S_MB_2U_LIB.S9S_MB_2U(SCH_1):PAGE324

R3977 Q_RES_0402LF-100K,1%,1/16W,CHIA
     1 P3V3_AUX @S9S_MB_2U_LIB.S9S_MB_2U(SCH_1):P3V3_AUX    I48 @S9S_MB_2U_LIB.S9S_MB_2U(SCH_1):PAGE324
     2 P3V3_E1S_FAULT_0 @S9S_MB_2U_LIB.S9S_MB_2U(SCH_1):P3V3_E1S_FAULT_0    I48 @S9S_MB_2U_LIB.S9S_MB_2U(SCH_1):PAGE324

R3978 Q_RES_0402LF-100K,1%,1/16W,EMPA
     1 P3V3_AUX @S9S_MB_2U_LIB.S9S_MB_2U(SCH_1):P3V3_AUX    I76 @S9S_MB_2U_LIB.S9S_MB_2U(SCH_1):PAGE324
     2 HP_LVC3_E1S_0_HSC_PWRGD @S9S_MB_2U_LIB.S9S_MB_2U(SCH_1):HP_LVC3_E1S_0_HSC_PWRGD    I76 @S9S_MB_2U_LIB.S9S_MB_2U(SCH_1):PAGE324

R3979 Q_RES_0402LF-100K,1%,1/16W,CHIA
     1 P3V3_AUX @S9S_MB_2U_LIB.S9S_MB_2U(SCH_1):P3V3_AUX    I50 @S9S_MB_2U_LIB.S9S_MB_2U(SCH_1):PAGE324
     2 TP_P3V3_E1S_PWRGD_0 @S9S_MB_2U_LIB.S9S_MB_2U(SCH_1):TP_P3V3_E1S_PWRGD_0    I50 @S9S_MB_2U_LIB.S9S_MB_2U(SCH_1):PAGE324

R3996 Q_RES_0402LF-0,5%,1/16W,CHIP,CA
     1 VIRTUAL_RESEAT_FPGA_N @S9S_MB_2U_LIB.S9S_MB_2U(SCH_1):VIRTUAL_RESEAT_FPGA_N    I17 @S9S_MB_2U_LIB.S9S_MB_2U(SCH_1):PAGE229
     2 P12V_SCM_EN @S9S_MB_2U_LIB.S9S_MB_2U(SCH_1):P12V_SCM_EN    I17 @S9S_MB_2U_LIB.S9S_MB_2U(SCH_1):PAGE229

R3997 Q_RES_0402LF-0,5%,1/16W,EMPTY,A
     1 P12V_SCM_UV_R @S9S_MB_2U_LIB.S9S_MB_2U(SCH_1):P12V_SCM_UV_R    I27 @S9S_MB_2U_LIB.S9S_MB_2U(SCH_1):PAGE229
     2 P12V_SCM_UV @S9S_MB_2U_LIB.S9S_MB_2U(SCH_1):P12V_SCM_UV    I27 @S9S_MB_2U_LIB.S9S_MB_2U(SCH_1):PAGE229

R3998 Q_RES_0402LF-0,5%,1/16W,CHIP,CA
     1 P12V_SCM_EN @S9S_MB_2U_LIB.S9S_MB_2U(SCH_1):P12V_SCM_EN    I14 @S9S_MB_2U_LIB.S9S_MB_2U(SCH_1):PAGE229
     2 P12V_SCM_EN_R2 @S9S_MB_2U_LIB.S9S_MB_2U(SCH_1):P12V_SCM_EN_R2    I14 @S9S_MB_2U_LIB.S9S_MB_2U(SCH_1):PAGE229

R4013 Q_RES_0402LF-100K,1%,1/16W,EMPA
     1 P3V3_AUX @S9S_MB_2U_LIB.S9S_MB_2U(SCH_1):P3V3_AUX    I79 @S9S_MB_2U_LIB.S9S_MB_2U(SCH_1):PAGE229
     2 P12V_SCM_FAULT_R_N @S9S_MB_2U_LIB.S9S_MB_2U(SCH_1):P12V_SCM_FAULT_R_N    I79 @S9S_MB_2U_LIB.S9S_MB_2U(SCH_1):PAGE229

R4015 Q_RES_0402LF-100K,1%,1/16W,EMPA
     1 P3V3_AUX @S9S_MB_2U_LIB.S9S_MB_2U(SCH_1):P3V3_AUX    I81 @S9S_MB_2U_LIB.S9S_MB_2U(SCH_1):PAGE229
     2 HP_LVC3_SCM_HSC_PWRGD @S9S_MB_2U_LIB.S9S_MB_2U(SCH_1):HP_LVC3_SCM_HSC_PWRGD    I81 @S9S_MB_2U_LIB.S9S_MB_2U(SCH_1):PAGE229

R4016 Q_RES_0402LF-4.32K,1%,1/16W,CHA
     1   P3V3 @S9S_MB_2U_LIB.S9S_MB_2U(SCH_1):P3V3    I97 @S9S_MB_2U_LIB.S9S_MB_2U(SCH_1):PAGE321
     2 P0V62_CPU0_ERRS_VREF @S9S_MB_2U_LIB.S9S_MB_2U(SCH_1):P0V62_CPU0_ERRS_VREF    I97 @S9S_MB_2U_LIB.S9S_MB_2U(SCH_1):PAGE321

R4019 Q_RES_0402LF-1K,1%,1/16W,CHIP,A
     1 P0V62_CPU0_ERRS_VREF @S9S_MB_2U_LIB.S9S_MB_2U(SCH_1):P0V62_CPU0_ERRS_VREF    I98 @S9S_MB_2U_LIB.S9S_MB_2U(SCH_1):PAGE321
     2    GND @S9S_MB_2U_LIB.S9S_MB_2U(SCH_1):GND    I98 @S9S_MB_2U_LIB.S9S_MB_2U(SCH_1):PAGE321

R4021 Q_RES_0402LF-33.2,1%,1/16W,CHIA
     1 PWRGD_CPUPWRGD_LVC2_R @S9S_MB_2U_LIB.S9S_MB_2U(SCH_1):PWRGD_CPUPWRGD_LVC2_R    I78 @S9S_MB_2U_LIB.S9S_MB_2U(SCH_1):PAGE321
     2 PWRGD_CPUPWRGD_LVC2_R1 @S9S_MB_2U_LIB.S9S_MB_2U(SCH_1):PWRGD_CPUPWRGD_LVC2_R1    I78 @S9S_MB_2U_LIB.S9S_MB_2U(SCH_1):PAGE321

R4022 Q_RES_0402LF-33.2,1%,1/16W,CHIA
     1 H_CPU_RMCA_LVC2_R1_N @S9S_MB_2U_LIB.S9S_MB_2U(SCH_1):H_CPU_RMCA_LVC2_R1_N    I79 @S9S_MB_2U_LIB.S9S_MB_2U(SCH_1):PAGE321
     2 H_CPU_RMCA_LVC2_R2_N @S9S_MB_2U_LIB.S9S_MB_2U(SCH_1):H_CPU_RMCA_LVC2_R2_N    I79 @S9S_MB_2U_LIB.S9S_MB_2U(SCH_1):PAGE321

R4023 Q_RES_0402LF-33.2,1%,1/16W,CHIA
     1 H_CPU_CATERR_LVC2_R1_N @S9S_MB_2U_LIB.S9S_MB_2U(SCH_1):H_CPU_CATERR_LVC2_R1_N    I80 @S9S_MB_2U_LIB.S9S_MB_2U(SCH_1):PAGE321
     2 H_CPU_CATERR_LVC2_R2_N @S9S_MB_2U_LIB.S9S_MB_2U(SCH_1):H_CPU_CATERR_LVC2_R2_N    I80 @S9S_MB_2U_LIB.S9S_MB_2U(SCH_1):PAGE321

R4029 Q_RES_0402LF-1K,1%,1/16W,CHIP,A
     1 PD_CPU0_ERRS_DIR @S9S_MB_2U_LIB.S9S_MB_2U(SCH_1):PD_CPU0_ERRS_DIR    I77 @S9S_MB_2U_LIB.S9S_MB_2U(SCH_1):PAGE321
     2    GND @S9S_MB_2U_LIB.S9S_MB_2U(SCH_1):GND    I77 @S9S_MB_2U_LIB.S9S_MB_2U(SCH_1):PAGE321

R4036 Q_RES_0402LF-4.32K,1%,1/16W,CHA
     1 P3V3_AUX @S9S_MB_2U_LIB.S9S_MB_2U(SCH_1):P3V3_AUX   I128 @S9S_MB_2U_LIB.S9S_MB_2U(SCH_1):PAGE322
     2 P0V62_CPU0_RST_DDR_VREF @S9S_MB_2U_LIB.S9S_MB_2U(SCH_1):P0V62_CPU0_RST_DDR_VREF   I128 @S9S_MB_2U_LIB.S9S_MB_2U(SCH_1):PAGE322

R4037 Q_RES_0402LF-4.32K,1%,1/16W,CHA
     1 P3V3_AUX @S9S_MB_2U_LIB.S9S_MB_2U(SCH_1):P3V3_AUX   I130 @S9S_MB_2U_LIB.S9S_MB_2U(SCH_1):PAGE322
     2 P0V62_CPU1_RST_DDR_VREF @S9S_MB_2U_LIB.S9S_MB_2U(SCH_1):P0V62_CPU1_RST_DDR_VREF   I130 @S9S_MB_2U_LIB.S9S_MB_2U(SCH_1):PAGE322

R4038 Q_RES_0402LF-4.32K,1%,1/16W,CHA
     1   P3V3 @S9S_MB_2U_LIB.S9S_MB_2U(SCH_1):P3V3   I182 @S9S_MB_2U_LIB.S9S_MB_2U(SCH_1):PAGE322
     2 P0V62_CPU0_ERRS_U306_VREF @S9S_MB_2U_LIB.S9S_MB_2U(SCH_1):P0V62_CPU0_ERRS_U306_VREF   I182 @S9S_MB_2U_LIB.S9S_MB_2U(SCH_1):PAGE322

R4039 Q_RES_0402LF-1K,1%,1/16W,CHIP,A
     1 P0V62_CPU0_RST_DDR_VREF @S9S_MB_2U_LIB.S9S_MB_2U(SCH_1):P0V62_CPU0_RST_DDR_VREF   I129 @S9S_MB_2U_LIB.S9S_MB_2U(SCH_1):PAGE322
     2    GND @S9S_MB_2U_LIB.S9S_MB_2U(SCH_1):GND   I129 @S9S_MB_2U_LIB.S9S_MB_2U(SCH_1):PAGE322

R4040 Q_RES_0402LF-1K,1%,1/16W,CHIP,A
     1 P0V62_CPU1_RST_DDR_VREF @S9S_MB_2U_LIB.S9S_MB_2U(SCH_1):P0V62_CPU1_RST_DDR_VREF   I131 @S9S_MB_2U_LIB.S9S_MB_2U(SCH_1):PAGE322
     2    GND @S9S_MB_2U_LIB.S9S_MB_2U(SCH_1):GND   I131 @S9S_MB_2U_LIB.S9S_MB_2U(SCH_1):PAGE322

R4041 Q_RES_0402LF-1K,1%,1/16W,CHIP,A
     1 P0V62_CPU0_ERRS_U306_VREF @S9S_MB_2U_LIB.S9S_MB_2U(SCH_1):P0V62_CPU0_ERRS_U306_VREF   I181 @S9S_MB_2U_LIB.S9S_MB_2U(SCH_1):PAGE322
     2    GND @S9S_MB_2U_LIB.S9S_MB_2U(SCH_1):GND   I181 @S9S_MB_2U_LIB.S9S_MB_2U(SCH_1):PAGE322

R4042 Q_RES_0402LF-33.2,1%,1/16W,CHIA
     1 RST_CPU0_DRAM_AB_PLD_LVT3_R_N @S9S_MB_2U_LIB.S9S_MB_2U(SCH_1):RST_CPU0_DRAM_AB_PLD_LVT3_R_N    I39 @S9S_MB_2U_LIB.S9S_MB_2U(SCH_1):PAGE322
     2 RST_CPU0_DRAM_AB_PLD_LVT3_N @S9S_MB_2U_LIB.S9S_MB_2U(SCH_1):RST_CPU0_DRAM_AB_PLD_LVT3_N    I39 @S9S_MB_2U_LIB.S9S_MB_2U(SCH_1):PAGE322

R4043 Q_RES_0402LF-33.2,1%,1/16W,CHIA
     1 RST_CPU0_DRAM_CD_PLD_LVT3_R_N @S9S_MB_2U_LIB.S9S_MB_2U(SCH_1):RST_CPU0_DRAM_CD_PLD_LVT3_R_N    I38 @S9S_MB_2U_LIB.S9S_MB_2U(SCH_1):PAGE322
     2 RST_CPU0_DRAM_CD_PLD_LVT3_N @S9S_MB_2U_LIB.S9S_MB_2U(SCH_1):RST_CPU0_DRAM_CD_PLD_LVT3_N    I38 @S9S_MB_2U_LIB.S9S_MB_2U(SCH_1):PAGE322

R4044 Q_RES_0402LF-33.2,1%,1/16W,CHIA
     1 RST_CPU0_DRAM_EF_PLD_LVT3_R_N @S9S_MB_2U_LIB.S9S_MB_2U(SCH_1):RST_CPU0_DRAM_EF_PLD_LVT3_R_N    I37 @S9S_MB_2U_LIB.S9S_MB_2U(SCH_1):PAGE322
     2 RST_CPU0_DRAM_EF_PLD_LVT3_N @S9S_MB_2U_LIB.S9S_MB_2U(SCH_1):RST_CPU0_DRAM_EF_PLD_LVT3_N    I37 @S9S_MB_2U_LIB.S9S_MB_2U(SCH_1):PAGE322

R4045 Q_RES_0402LF-33.2,1%,1/16W,CHIA
     1 RST_CPU0_DRAM_GH_PLD_LVT3_R_N @S9S_MB_2U_LIB.S9S_MB_2U(SCH_1):RST_CPU0_DRAM_GH_PLD_LVT3_R_N    I36 @S9S_MB_2U_LIB.S9S_MB_2U(SCH_1):PAGE322
     2 RST_CPU0_DRAM_GH_PLD_LVT3_N @S9S_MB_2U_LIB.S9S_MB_2U(SCH_1):RST_CPU0_DRAM_GH_PLD_LVT3_N    I36 @S9S_MB_2U_LIB.S9S_MB_2U(SCH_1):PAGE322

R4046 Q_RES_0402LF-33.2,1%,1/16W,CHIA
     1 RST_CPU1_DRAM_AB_PLD_LVT3_R_N @S9S_MB_2U_LIB.S9S_MB_2U(SCH_1):RST_CPU1_DRAM_AB_PLD_LVT3_R_N    I52 @S9S_MB_2U_LIB.S9S_MB_2U(SCH_1):PAGE322
     2 RST_CPU1_DRAM_AB_PLD_LVT3_N @S9S_MB_2U_LIB.S9S_MB_2U(SCH_1):RST_CPU1_DRAM_AB_PLD_LVT3_N    I52 @S9S_MB_2U_LIB.S9S_MB_2U(SCH_1):PAGE322

R4047 Q_RES_0402LF-33.2,1%,1/16W,CHIA
     1 RST_CPU1_DRAM_CD_PLD_LVT3_R_N @S9S_MB_2U_LIB.S9S_MB_2U(SCH_1):RST_CPU1_DRAM_CD_PLD_LVT3_R_N    I53 @S9S_MB_2U_LIB.S9S_MB_2U(SCH_1):PAGE322
     2 RST_CPU1_DRAM_CD_PLD_LVT3_N @S9S_MB_2U_LIB.S9S_MB_2U(SCH_1):RST_CPU1_DRAM_CD_PLD_LVT3_N    I53 @S9S_MB_2U_LIB.S9S_MB_2U(SCH_1):PAGE322

R4048 Q_RES_0402LF-33.2,1%,1/16W,CHIA
     1 RST_CPU1_DRAM_EF_PLD_LVT3_R_N @S9S_MB_2U_LIB.S9S_MB_2U(SCH_1):RST_CPU1_DRAM_EF_PLD_LVT3_R_N    I55 @S9S_MB_2U_LIB.S9S_MB_2U(SCH_1):PAGE322
     2 RST_CPU1_DRAM_EF_PLD_LVT3_N @S9S_MB_2U_LIB.S9S_MB_2U(SCH_1):RST_CPU1_DRAM_EF_PLD_LVT3_N    I55 @S9S_MB_2U_LIB.S9S_MB_2U(SCH_1):PAGE322

R4049 Q_RES_0402LF-33.2,1%,1/16W,CHIA
     1 RST_CPU1_DRAM_GH_PLD_LVT3_R_N @S9S_MB_2U_LIB.S9S_MB_2U(SCH_1):RST_CPU1_DRAM_GH_PLD_LVT3_R_N    I54 @S9S_MB_2U_LIB.S9S_MB_2U(SCH_1):PAGE322
     2 RST_CPU1_DRAM_GH_PLD_LVT3_N @S9S_MB_2U_LIB.S9S_MB_2U(SCH_1):RST_CPU1_DRAM_GH_PLD_LVT3_N    I54 @S9S_MB_2U_LIB.S9S_MB_2U(SCH_1):PAGE322

R4050 Q_RES_0402LF-33.2,1%,1/16W,CHIA
     1 H_CPU_ERR0_LVC2_R_N @S9S_MB_2U_LIB.S9S_MB_2U(SCH_1):H_CPU_ERR0_LVC2_R_N   I184 @S9S_MB_2U_LIB.S9S_MB_2U(SCH_1):PAGE322
     2 H_CPU_ERR0_LVC2_N @S9S_MB_2U_LIB.S9S_MB_2U(SCH_1):H_CPU_ERR0_LVC2_N   I184 @S9S_MB_2U_LIB.S9S_MB_2U(SCH_1):PAGE322

R4051 Q_RES_0402LF-33.2,1%,1/16W,CHIA
     1 H_CPU_ERR1_LVC2_R_N @S9S_MB_2U_LIB.S9S_MB_2U(SCH_1):H_CPU_ERR1_LVC2_R_N    I94 @S9S_MB_2U_LIB.S9S_MB_2U(SCH_1):PAGE322
     2 H_CPU_ERR1_LVC2_N @S9S_MB_2U_LIB.S9S_MB_2U(SCH_1):H_CPU_ERR1_LVC2_N    I94 @S9S_MB_2U_LIB.S9S_MB_2U(SCH_1):PAGE322

R4052 Q_RES_0402LF-33.2,1%,1/16W,CHIA
     1 H_CPU_ERR2_LVC2_R_N @S9S_MB_2U_LIB.S9S_MB_2U(SCH_1):H_CPU_ERR2_LVC2_R_N   I187 @S9S_MB_2U_LIB.S9S_MB_2U(SCH_1):PAGE322
     2 H_CPU_ERR2_LVC2_N @S9S_MB_2U_LIB.S9S_MB_2U(SCH_1):H_CPU_ERR2_LVC2_N   I187 @S9S_MB_2U_LIB.S9S_MB_2U(SCH_1):PAGE322

R4053 Q_RES_0402LF-1K,1%,1/16W,CHIP,A
     1 PD_GTL2014_BMC_JTAG_DIR_0 @S9S_MB_2U_LIB.S9S_MB_2U(SCH_1):PD_GTL2014_BMC_JTAG_DIR_0    I66 @S9S_MB_2U_LIB.S9S_MB_2U(SCH_1):PAGE322
     2    GND @S9S_MB_2U_LIB.S9S_MB_2U(SCH_1):GND    I66 @S9S_MB_2U_LIB.S9S_MB_2U(SCH_1):PAGE322

R4054 Q_RES_0402LF-1K,1%,1/16W,CHIP,A
     1 PD_GTL2014_BMC_JTAG_DIR_1 @S9S_MB_2U_LIB.S9S_MB_2U(SCH_1):PD_GTL2014_BMC_JTAG_DIR_1    I67 @S9S_MB_2U_LIB.S9S_MB_2U(SCH_1):PAGE322
     2    GND @S9S_MB_2U_LIB.S9S_MB_2U(SCH_1):GND    I67 @S9S_MB_2U_LIB.S9S_MB_2U(SCH_1):PAGE322

R4055 Q_RES_0402LF-1K,1%,1/16W,CHIP,A
     1 PD_CPU1_ERRS_U306_DIR @S9S_MB_2U_LIB.S9S_MB_2U(SCH_1):PD_CPU1_ERRS_U306_DIR    I91 @S9S_MB_2U_LIB.S9S_MB_2U(SCH_1):PAGE322
     2    GND @S9S_MB_2U_LIB.S9S_MB_2U(SCH_1):GND    I91 @S9S_MB_2U_LIB.S9S_MB_2U(SCH_1):PAGE322

R4056 Q_RES_0402LF-0,5%,1/16W,CHIP,CA
     1 HSC_D_OC @S9S_MB_2U_LIB.S9S_MB_2U(SCH_1):HSC_D_OC    I80 @S9S_MB_2U_LIB.S9S_MB_2U(SCH_1):PAGE312
     2 HSC_D_OC_R1 @S9S_MB_2U_LIB.S9S_MB_2U(SCH_1):HSC_D_OC_R1    I80 @S9S_MB_2U_LIB.S9S_MB_2U(SCH_1):PAGE312

R4057 Q_RES_0402LF-33.2,1%,1/16W,CHIA
     1 PRSNT_SWB_ISO_N @S9S_MB_2U_LIB.S9S_MB_2U(SCH_1):PRSNT_SWB_ISO_N   I217 @S9S_MB_2U_LIB.S9S_MB_2U(SCH_1):PAGE312
     2 PRSNT_SWB_ISO_R_N @S9S_MB_2U_LIB.S9S_MB_2U(SCH_1):PRSNT_SWB_ISO_R_N   I217 @S9S_MB_2U_LIB.S9S_MB_2U(SCH_1):PAGE312

R4059 Q_RES_0402LF-0,5%,1/16W,EMPTY,A
     1 HP_LVC3_OCP_V3_2_EN @S9S_MB_2U_LIB.S9S_MB_2U(SCH_1):HP_LVC3_OCP_V3_2_EN     I6 @S9S_MB_2U_LIB.S9S_MB_2U(SCH_1):PAGE131
     2 P12V_OCP_EN_2_R @S9S_MB_2U_LIB.S9S_MB_2U(SCH_1):P12V_OCP_EN_2_R     I6 @S9S_MB_2U_LIB.S9S_MB_2U(SCH_1):PAGE131

R4060 Q_RES_0402LF-0,5%,1/16W,CHIP,CA
     1 HP_LVC3_OCP_V3_2_EN @S9S_MB_2U_LIB.S9S_MB_2U(SCH_1):HP_LVC3_OCP_V3_2_EN    I35 @S9S_MB_2U_LIB.S9S_MB_2U(SCH_1):PAGE131
     2 P3V3_OCP_EN_2_R @S9S_MB_2U_LIB.S9S_MB_2U(SCH_1):P3V3_OCP_EN_2_R    I35 @S9S_MB_2U_LIB.S9S_MB_2U(SCH_1):PAGE131

R4061 Q_RES_0402LF-0,5%,1/16W,EMPTY,A
     1 HP_LVC3_OCP_V3_1_EN @S9S_MB_2U_LIB.S9S_MB_2U(SCH_1):HP_LVC3_OCP_V3_1_EN     I4 @S9S_MB_2U_LIB.S9S_MB_2U(SCH_1):PAGE153
     2 P12V_OCP_EN_1_R @S9S_MB_2U_LIB.S9S_MB_2U(SCH_1):P12V_OCP_EN_1_R     I4 @S9S_MB_2U_LIB.S9S_MB_2U(SCH_1):PAGE153

R4062 Q_RES_0402LF-0,5%,1/16W,EMPTY,A
     1 P12V_SCM_EN @S9S_MB_2U_LIB.S9S_MB_2U(SCH_1):P12V_SCM_EN    I20 @S9S_MB_2U_LIB.S9S_MB_2U(SCH_1):PAGE229
     2 P12V_SCM_EN_R @S9S_MB_2U_LIB.S9S_MB_2U(SCH_1):P12V_SCM_EN_R    I20 @S9S_MB_2U_LIB.S9S_MB_2U(SCH_1):PAGE229

R4063 Q_RES_0402LF-0,5%,1/16W,CHIP,CA
     1 E1S_0_EN @S9S_MB_2U_LIB.S9S_MB_2U(SCH_1):E1S_0_EN     I1 @S9S_MB_2U_LIB.S9S_MB_2U(SCH_1):PAGE324
     2 P3V3_E1S_EN_1_R @S9S_MB_2U_LIB.S9S_MB_2U(SCH_1):P3V3_E1S_EN_1_R     I1 @S9S_MB_2U_LIB.S9S_MB_2U(SCH_1):PAGE324

R4064 Q_RES_0402LF-0,5%,1/16W,CHIP,CA
     1 E1S_0_EN @S9S_MB_2U_LIB.S9S_MB_2U(SCH_1):E1S_0_EN    I21 @S9S_MB_2U_LIB.S9S_MB_2U(SCH_1):PAGE324
     2 P12V_E1S_EN_0_R @S9S_MB_2U_LIB.S9S_MB_2U(SCH_1):P12V_E1S_EN_0_R    I21 @S9S_MB_2U_LIB.S9S_MB_2U(SCH_1):PAGE324

R4065 Q_RES_0402LF-10K,1%,1/16W,EMPTA
     1 P12V_AUX @S9S_MB_2U_LIB.S9S_MB_2U(SCH_1):P12V_AUX    I14 @S9S_MB_2U_LIB.S9S_MB_2U(SCH_1):PAGE131
     2 P12V_OCP_2_EN_G @S9S_MB_2U_LIB.S9S_MB_2U(SCH_1):P12V_OCP_2_EN_G    I14 @S9S_MB_2U_LIB.S9S_MB_2U(SCH_1):PAGE131

R4066 Q_RES_0402LF-4.7K,5%,1/16W,CHIA
     1 P3V3_OCP_EN_2_R @S9S_MB_2U_LIB.S9S_MB_2U(SCH_1):P3V3_OCP_EN_2_R    I37 @S9S_MB_2U_LIB.S9S_MB_2U(SCH_1):PAGE131
     2    GND @S9S_MB_2U_LIB.S9S_MB_2U(SCH_1):GND    I37 @S9S_MB_2U_LIB.S9S_MB_2U(SCH_1):PAGE131

R4067 Q_RES_0402LF-10K,1%,1/16W,CHIPA
     1 P12V_AUX @S9S_MB_2U_LIB.S9S_MB_2U(SCH_1):P12V_AUX    I40 @S9S_MB_2U_LIB.S9S_MB_2U(SCH_1):PAGE131
     2 P3V3_OCP_2_EN_G @S9S_MB_2U_LIB.S9S_MB_2U(SCH_1):P3V3_OCP_2_EN_G    I40 @S9S_MB_2U_LIB.S9S_MB_2U(SCH_1):PAGE131

R4068 Q_RES_0402LF-10K,1%,1/16W,EMPTA
     1 P12V_AUX @S9S_MB_2U_LIB.S9S_MB_2U(SCH_1):P12V_AUX    I15 @S9S_MB_2U_LIB.S9S_MB_2U(SCH_1):PAGE153
     2 P12V_OCP_1_EN_G @S9S_MB_2U_LIB.S9S_MB_2U(SCH_1):P12V_OCP_1_EN_G    I15 @S9S_MB_2U_LIB.S9S_MB_2U(SCH_1):PAGE153

R4069 Q_RES_0402LF-4.7K,5%,1/16W,CHIA
     1 P3V3_OCP_EN_1_R @S9S_MB_2U_LIB.S9S_MB_2U(SCH_1):P3V3_OCP_EN_1_R    I20 @S9S_MB_2U_LIB.S9S_MB_2U(SCH_1):PAGE153
     2    GND @S9S_MB_2U_LIB.S9S_MB_2U(SCH_1):GND    I20 @S9S_MB_2U_LIB.S9S_MB_2U(SCH_1):PAGE153

R4070 Q_RES_0402LF-10K,1%,1/16W,CHIPA
     1 P12V_AUX @S9S_MB_2U_LIB.S9S_MB_2U(SCH_1):P12V_AUX    I62 @S9S_MB_2U_LIB.S9S_MB_2U(SCH_1):PAGE153
     2 P3V3_OCP_1_EN_G @S9S_MB_2U_LIB.S9S_MB_2U(SCH_1):P3V3_OCP_1_EN_G    I62 @S9S_MB_2U_LIB.S9S_MB_2U(SCH_1):PAGE153

R4071 Q_RES_0402LF-10K,1%,1/16W,EMPTA
     1 P12V_AUX @S9S_MB_2U_LIB.S9S_MB_2U(SCH_1):P12V_AUX    I24 @S9S_MB_2U_LIB.S9S_MB_2U(SCH_1):PAGE229
     2 P12V_SCM_EN_G @S9S_MB_2U_LIB.S9S_MB_2U(SCH_1):P12V_SCM_EN_G    I24 @S9S_MB_2U_LIB.S9S_MB_2U(SCH_1):PAGE229

R4072 Q_RES_0402LF-10K,1%,1/16W,CHIPA
     1 P12V_AUX @S9S_MB_2U_LIB.S9S_MB_2U(SCH_1):P12V_AUX     I6 @S9S_MB_2U_LIB.S9S_MB_2U(SCH_1):PAGE324
     2 P3V3_E1S_0_EN_G @S9S_MB_2U_LIB.S9S_MB_2U(SCH_1):P3V3_E1S_0_EN_G     I6 @S9S_MB_2U_LIB.S9S_MB_2U(SCH_1):PAGE324

R4073 Q_RES_0402LF-4.7K,5%,1/16W,CHIA
     1 P12V_E1S_EN_0_R @S9S_MB_2U_LIB.S9S_MB_2U(SCH_1):P12V_E1S_EN_0_R     I9 @S9S_MB_2U_LIB.S9S_MB_2U(SCH_1):PAGE324
     2    GND @S9S_MB_2U_LIB.S9S_MB_2U(SCH_1):GND     I9 @S9S_MB_2U_LIB.S9S_MB_2U(SCH_1):PAGE324

R4074 Q_RES_0402LF-10K,1%,1/16W,EMPTA
     1 P12V_AUX @S9S_MB_2U_LIB.S9S_MB_2U(SCH_1):P12V_AUX    I22 @S9S_MB_2U_LIB.S9S_MB_2U(SCH_1):PAGE324
     2 P12V_E1S_0_EN_G @S9S_MB_2U_LIB.S9S_MB_2U(SCH_1):P12V_E1S_0_EN_G    I22 @S9S_MB_2U_LIB.S9S_MB_2U(SCH_1):PAGE324

R4075 Q_RES_0402LF-0,5%,1/16W,CHIP,CA
     1 CLK_GEN2_BMC_RC_OE_N @S9S_MB_2U_LIB.S9S_MB_2U(SCH_1):CLK_GEN2_BMC_RC_OE_N   I147 @S9S_MB_2U_LIB.S9S_MB_2U(SCH_1):PAGE201
     2 CLK_GEN2_BMC_RC_OE_R3_N @S9S_MB_2U_LIB.S9S_MB_2U(SCH_1):CLK_GEN2_BMC_RC_OE_R3_N   I147 @S9S_MB_2U_LIB.S9S_MB_2U(SCH_1):PAGE201

R4076 Q_RES_0402LF-0,5%,1/16W,CHIP,CA
     1 CLK_GEN2_GPU_FPGA_OE_OR_N @S9S_MB_2U_LIB.S9S_MB_2U(SCH_1):CLK_GEN2_GPU_FPGA_OE_OR_N   I146 @S9S_MB_2U_LIB.S9S_MB_2U(SCH_1):PAGE201
     2 CLK_GEN2_GPU_OE_N @S9S_MB_2U_LIB.S9S_MB_2U(SCH_1):CLK_GEN2_GPU_OE_N   I146 @S9S_MB_2U_LIB.S9S_MB_2U(SCH_1):PAGE201

R4077 Q_RES_0402LF-1,1%,1/16W,CHIP,CA
     1 VFG3P3_CLK_GEN @S9S_MB_2U_LIB.S9S_MB_2U(SCH_1):VFG3P3_CLK_GEN   I102 @S9S_MB_2U_LIB.S9S_MB_2U(SCH_1):PAGE201
     2 VFG_3P3A_CLK_GEN @S9S_MB_2U_LIB.S9S_MB_2U(SCH_1):VFG_3P3A_CLK_GEN   I102 @S9S_MB_2U_LIB.S9S_MB_2U(SCH_1):PAGE201

R4078 Q_RES_0402LF-10K,1%,1/16W,EMPTA
     1 P3V3_AUX @S9S_MB_2U_LIB.S9S_MB_2U(SCH_1):P3V3_AUX   I127 @S9S_MB_2U_LIB.S9S_MB_2U(SCH_1):PAGE201
     2 FG_SS_EN @S9S_MB_2U_LIB.S9S_MB_2U(SCH_1):FG_SS_EN   I127 @S9S_MB_2U_LIB.S9S_MB_2U(SCH_1):PAGE201

R4079 Q_RES_0402LF-10K,1%,1/16W,CHIPA
     1 FG_SS_EN @S9S_MB_2U_LIB.S9S_MB_2U(SCH_1):FG_SS_EN   I128 @S9S_MB_2U_LIB.S9S_MB_2U(SCH_1):PAGE201
     2    GND @S9S_MB_2U_LIB.S9S_MB_2U(SCH_1):GND   I128 @S9S_MB_2U_LIB.S9S_MB_2U(SCH_1):PAGE201

R4080 Q_RES_0402LF-10K,1%,1/16W,CHIPA
     1 P3V3_AUX @S9S_MB_2U_LIB.S9S_MB_2U(SCH_1):P3V3_AUX   I142 @S9S_MB_2U_LIB.S9S_MB_2U(SCH_1):PAGE201
     2 P3V3_PWRGD_CLKGEN @S9S_MB_2U_LIB.S9S_MB_2U(SCH_1):P3V3_PWRGD_CLKGEN   I142 @S9S_MB_2U_LIB.S9S_MB_2U(SCH_1):PAGE201

R4081 Q_RES_0402LF-10K,1%,1/16W,CHIPA
     1 P3V3_AUX @S9S_MB_2U_LIB.S9S_MB_2U(SCH_1):P3V3_AUX   I135 @S9S_MB_2U_LIB.S9S_MB_2U(SCH_1):PAGE201
     2 CLK_GEN2_SMB_SADR @S9S_MB_2U_LIB.S9S_MB_2U(SCH_1):CLK_GEN2_SMB_SADR   I135 @S9S_MB_2U_LIB.S9S_MB_2U(SCH_1):PAGE201

R4082 Q_RES_0402LF-10K,1%,1/16W,EMPTA
     1 CLK_GEN2_SMB_SADR @S9S_MB_2U_LIB.S9S_MB_2U(SCH_1):CLK_GEN2_SMB_SADR   I134 @S9S_MB_2U_LIB.S9S_MB_2U(SCH_1):PAGE201
     2    GND @S9S_MB_2U_LIB.S9S_MB_2U(SCH_1):GND   I134 @S9S_MB_2U_LIB.S9S_MB_2U(SCH_1):PAGE201

R4083 Q_RES_0402LF-0,5%,1/16W,EMPTY,A
     1 E1S_0_PERST1_CLKREQ_N @S9S_MB_2U_LIB.S9S_MB_2U(SCH_1):E1S_0_PERST1_CLKREQ_N   I274 @S9S_MB_2U_LIB.S9S_MB_2U(SCH_1):PAGE175
     2 E1S_0_CLKREQ_N @S9S_MB_2U_LIB.S9S_MB_2U(SCH_1):E1S_0_CLKREQ_N   I274 @S9S_MB_2U_LIB.S9S_MB_2U(SCH_1):PAGE175

R4084 Q_RES_0402LF-0,5%,1/16W,EMPTY,A
     1 E1S_0_PRSNT_N @S9S_MB_2U_LIB.S9S_MB_2U(SCH_1):E1S_0_PRSNT_N   I275 @S9S_MB_2U_LIB.S9S_MB_2U(SCH_1):PAGE175
     2 E1S_0_CLKREQ_N @S9S_MB_2U_LIB.S9S_MB_2U(SCH_1):E1S_0_CLKREQ_N   I275 @S9S_MB_2U_LIB.S9S_MB_2U(SCH_1):PAGE175

R4086 Q_RES_0402LF-10K,1%,1/16W,CHIPA
     1 P3V3_AUX_FPGA_VCCIO2 @S9S_MB_2U_LIB.S9S_MB_2U(SCH_1):P3V3_AUX_FPGA_VCCIO2    I86 @S9S_MB_2U_LIB.S9S_MB_2U(SCH_1):PAGE312
     2 PULL_FPGA_PB46A @S9S_MB_2U_LIB.S9S_MB_2U(SCH_1):PULL_FPGA_PB46A    I86 @S9S_MB_2U_LIB.S9S_MB_2U(SCH_1):PAGE312

R4087 Q_RES_0402LF-33.2,1%,1/16W,CHIA
     1 FM_JTAG_BMC_MUX_SEL_FROM_BMC_R @S9S_MB_2U_LIB.S9S_MB_2U(SCH_1):FM_JTAG_BMC_MUX_SEL_FROM_BMC_R    I28 @S9S_MB_2U_LIB.S9S_MB_2U(SCH_1):PAGE227
     2 FM_JTAG_BMC_MUX_SEL_FROM_BMC_R2 @S9S_MB_2U_LIB.S9S_MB_2U(SCH_1):FM_JTAG_BMC_MUX_SEL_FROM_BMC_R2    I28 @S9S_MB_2U_LIB.S9S_MB_2U(SCH_1):PAGE227

R4088 Q_RES_0402LF-0,5%,1/16W,CHIP,CA
     1 FM_JTAG_BMC_MUX_SEL_FROM_BMC_R @S9S_MB_2U_LIB.S9S_MB_2U(SCH_1):FM_JTAG_BMC_MUX_SEL_FROM_BMC_R   I166 @S9S_MB_2U_LIB.S9S_MB_2U(SCH_1):PAGE313
     2 FM_JTAG_BMC_MUX_SEL @S9S_MB_2U_LIB.S9S_MB_2U(SCH_1):FM_JTAG_BMC_MUX_SEL   I166 @S9S_MB_2U_LIB.S9S_MB_2U(SCH_1):PAGE313

R4089 Q_RES_0402LF-33.2,1%,1/16W,CHIA
     1 H_CPU0_PMSYNC_CPU1_R1 @S9S_MB_2U_LIB.S9S_MB_2U(SCH_1):H_CPU0_PMSYNC_CPU1_R1   I128 @S9S_MB_2U_LIB.S9S_MB_2U(SCH_1):PAGE14
     2 H_CPU0_PMSYNC_CPU1 @S9S_MB_2U_LIB.S9S_MB_2U(SCH_1):H_CPU0_PMSYNC_CPU1   I128 @S9S_MB_2U_LIB.S9S_MB_2U(SCH_1):PAGE14

R4090 Q_RES_0402LF-4.7K,1%,1/16W,CHIA
     1 P3V3_AUX @S9S_MB_2U_LIB.S9S_MB_2U(SCH_1):P3V3_AUX   I124 @S9S_MB_2U_LIB.S9S_MB_2U(SCH_1):PAGE163
     2 M2_0_P3V3_ADC_ALERT_R @S9S_MB_2U_LIB.S9S_MB_2U(SCH_1):M2_0_P3V3_ADC_ALERT_R   I124 @S9S_MB_2U_LIB.S9S_MB_2U(SCH_1):PAGE163

R4091 Q_RES_0402LF-4.7K,1%,1/16W,CHIA
     1 P3V3_AUX @S9S_MB_2U_LIB.S9S_MB_2U(SCH_1):P3V3_AUX   I122 @S9S_MB_2U_LIB.S9S_MB_2U(SCH_1):PAGE163
     2 P12V_SCM_ADC_ALERT_R @S9S_MB_2U_LIB.S9S_MB_2U(SCH_1):P12V_SCM_ADC_ALERT_R   I122 @S9S_MB_2U_LIB.S9S_MB_2U(SCH_1):PAGE163

R4092 Q_RES_0402LF-4.7K,1%,1/16W,CHIA
     1 P3V3_AUX @S9S_MB_2U_LIB.S9S_MB_2U(SCH_1):P3V3_AUX   I126 @S9S_MB_2U_LIB.S9S_MB_2U(SCH_1):PAGE163
     2 OCP_V3_2_P3V3_ADC_ALERT_R @S9S_MB_2U_LIB.S9S_MB_2U(SCH_1):OCP_V3_2_P3V3_ADC_ALERT_R   I126 @S9S_MB_2U_LIB.S9S_MB_2U(SCH_1):PAGE163

R4093 Q_RES_0402LF-4.7K,1%,1/16W,CHIA
     1 P3V3_AUX @S9S_MB_2U_LIB.S9S_MB_2U(SCH_1):P3V3_AUX   I149 @S9S_MB_2U_LIB.S9S_MB_2U(SCH_1):PAGE295
     2 E1S_0_P3V3_ADC_ALERT_R @S9S_MB_2U_LIB.S9S_MB_2U(SCH_1):E1S_0_P3V3_ADC_ALERT_R   I149 @S9S_MB_2U_LIB.S9S_MB_2U(SCH_1):PAGE295

R4094 Q_RES_0402LF-4.7K,1%,1/16W,CHIA
     1 P3V3_AUX @S9S_MB_2U_LIB.S9S_MB_2U(SCH_1):P3V3_AUX   I151 @S9S_MB_2U_LIB.S9S_MB_2U(SCH_1):PAGE295
     2 OCP_SFF_P3V3_ADC_ALERT_R @S9S_MB_2U_LIB.S9S_MB_2U(SCH_1):OCP_SFF_P3V3_ADC_ALERT_R   I151 @S9S_MB_2U_LIB.S9S_MB_2U(SCH_1):PAGE295

R4095 Q_RES_0402LF-10K,1%,1/16W,CHIPA
     1 PD_PCH_GPPC_A_19 @S9S_MB_2U_LIB.S9S_MB_2U(SCH_1):PD_PCH_GPPC_A_19   I284 @S9S_MB_2U_LIB.S9S_MB_2U(SCH_1):PAGE175
     2    GND @S9S_MB_2U_LIB.S9S_MB_2U(SCH_1):GND   I284 @S9S_MB_2U_LIB.S9S_MB_2U(SCH_1):PAGE175

R4096 Q_RES_0402LF-10K,1%,1/16W,CHIPA
     1 PD_PCH_GPPC_A_18 @S9S_MB_2U_LIB.S9S_MB_2U(SCH_1):PD_PCH_GPPC_A_18   I285 @S9S_MB_2U_LIB.S9S_MB_2U(SCH_1):PAGE175
     2    GND @S9S_MB_2U_LIB.S9S_MB_2U(SCH_1):GND   I285 @S9S_MB_2U_LIB.S9S_MB_2U(SCH_1):PAGE175

R4097 Q_RES_0402LF-10K,1%,1/16W,CHIPA
     1 PD_PCH_GPPC_A_15 @S9S_MB_2U_LIB.S9S_MB_2U(SCH_1):PD_PCH_GPPC_A_15   I286 @S9S_MB_2U_LIB.S9S_MB_2U(SCH_1):PAGE175
     2    GND @S9S_MB_2U_LIB.S9S_MB_2U(SCH_1):GND   I286 @S9S_MB_2U_LIB.S9S_MB_2U(SCH_1):PAGE175

R4098 Q_RES_0402LF-10K,1%,1/16W,CHIPA
     1 PD_PCH_GPPC_A_14 @S9S_MB_2U_LIB.S9S_MB_2U(SCH_1):PD_PCH_GPPC_A_14   I287 @S9S_MB_2U_LIB.S9S_MB_2U(SCH_1):PAGE175
     2    GND @S9S_MB_2U_LIB.S9S_MB_2U(SCH_1):GND   I287 @S9S_MB_2U_LIB.S9S_MB_2U(SCH_1):PAGE175

R4099 Q_RES_0402LF-10K,1%,1/16W,CHIPA
     1 PD_PCH_GPPC_A_10 @S9S_MB_2U_LIB.S9S_MB_2U(SCH_1):PD_PCH_GPPC_A_10   I288 @S9S_MB_2U_LIB.S9S_MB_2U(SCH_1):PAGE175
     2    GND @S9S_MB_2U_LIB.S9S_MB_2U(SCH_1):GND   I288 @S9S_MB_2U_LIB.S9S_MB_2U(SCH_1):PAGE175

R4100 Q_RES_0402LF-10K,1%,1/16W,CHIPA
     1 PD_PCH_GPPC_C10 @S9S_MB_2U_LIB.S9S_MB_2U(SCH_1):PD_PCH_GPPC_C10   I300 @S9S_MB_2U_LIB.S9S_MB_2U(SCH_1):PAGE175
     2    GND @S9S_MB_2U_LIB.S9S_MB_2U(SCH_1):GND   I300 @S9S_MB_2U_LIB.S9S_MB_2U(SCH_1):PAGE175

R4101 Q_RES_0402LF-10K,1%,1/16W,CHIPA
     1 PD_PCH_GPPC_C9 @S9S_MB_2U_LIB.S9S_MB_2U(SCH_1):PD_PCH_GPPC_C9   I299 @S9S_MB_2U_LIB.S9S_MB_2U(SCH_1):PAGE175
     2    GND @S9S_MB_2U_LIB.S9S_MB_2U(SCH_1):GND   I299 @S9S_MB_2U_LIB.S9S_MB_2U(SCH_1):PAGE175

R4102 Q_RES_0402LF-10K,1%,1/16W,CHIPA
     1 PD_PCH_GPPC_C5 @S9S_MB_2U_LIB.S9S_MB_2U(SCH_1):PD_PCH_GPPC_C5   I298 @S9S_MB_2U_LIB.S9S_MB_2U(SCH_1):PAGE175
     2    GND @S9S_MB_2U_LIB.S9S_MB_2U(SCH_1):GND   I298 @S9S_MB_2U_LIB.S9S_MB_2U(SCH_1):PAGE175

R4103 Q_RES_0402LF-10K,1%,1/16W,CHIPA
     1 PD_GPP_M_17 @S9S_MB_2U_LIB.S9S_MB_2U(SCH_1):PD_GPP_M_17   I186 @S9S_MB_2U_LIB.S9S_MB_2U(SCH_1):PAGE176
     2    GND @S9S_MB_2U_LIB.S9S_MB_2U(SCH_1):GND   I186 @S9S_MB_2U_LIB.S9S_MB_2U(SCH_1):PAGE176

R4104 Q_RES_0402LF-10K,1%,1/16W,CHIPA
     1 PD_GPP_M_16 @S9S_MB_2U_LIB.S9S_MB_2U(SCH_1):PD_GPP_M_16   I185 @S9S_MB_2U_LIB.S9S_MB_2U(SCH_1):PAGE176
     2    GND @S9S_MB_2U_LIB.S9S_MB_2U(SCH_1):GND   I185 @S9S_MB_2U_LIB.S9S_MB_2U(SCH_1):PAGE176

R4105 Q_RES_0402LF-10K,1%,1/16W,CHIPA
     1 PD_GPP_M_15 @S9S_MB_2U_LIB.S9S_MB_2U(SCH_1):PD_GPP_M_15   I183 @S9S_MB_2U_LIB.S9S_MB_2U(SCH_1):PAGE176
     2    GND @S9S_MB_2U_LIB.S9S_MB_2U(SCH_1):GND   I183 @S9S_MB_2U_LIB.S9S_MB_2U(SCH_1):PAGE176

R4106 Q_RES_0402LF-10K,1%,1/16W,CHIPA
     1 PD_GPP_M_8 @S9S_MB_2U_LIB.S9S_MB_2U(SCH_1):PD_GPP_M_8   I184 @S9S_MB_2U_LIB.S9S_MB_2U(SCH_1):PAGE176
     2    GND @S9S_MB_2U_LIB.S9S_MB_2U(SCH_1):GND   I184 @S9S_MB_2U_LIB.S9S_MB_2U(SCH_1):PAGE176

R4107 Q_RES_0402LF-10K,1%,1/16W,CHIPA
     1 PD_GPP_I_17 @S9S_MB_2U_LIB.S9S_MB_2U(SCH_1):PD_GPP_I_17   I197 @S9S_MB_2U_LIB.S9S_MB_2U(SCH_1):PAGE176
     2    GND @S9S_MB_2U_LIB.S9S_MB_2U(SCH_1):GND   I197 @S9S_MB_2U_LIB.S9S_MB_2U(SCH_1):PAGE176

R4108 Q_RES_0402LF-10K,1%,1/16W,CHIPA
     1 PD_GPP_I_16 @S9S_MB_2U_LIB.S9S_MB_2U(SCH_1):PD_GPP_I_16   I196 @S9S_MB_2U_LIB.S9S_MB_2U(SCH_1):PAGE176
     2    GND @S9S_MB_2U_LIB.S9S_MB_2U(SCH_1):GND   I196 @S9S_MB_2U_LIB.S9S_MB_2U(SCH_1):PAGE176

R4109 Q_RES_0402LF-10K,1%,1/16W,CHIPA
     1 PD_GPP_I_15 @S9S_MB_2U_LIB.S9S_MB_2U(SCH_1):PD_GPP_I_15   I195 @S9S_MB_2U_LIB.S9S_MB_2U(SCH_1):PAGE176
     2    GND @S9S_MB_2U_LIB.S9S_MB_2U(SCH_1):GND   I195 @S9S_MB_2U_LIB.S9S_MB_2U(SCH_1):PAGE176

R4110 Q_RES_0402LF-10K,1%,1/16W,CHIPA
     1 PD_PCH_GPP_E_14 @S9S_MB_2U_LIB.S9S_MB_2U(SCH_1):PD_PCH_GPP_E_14   I202 @S9S_MB_2U_LIB.S9S_MB_2U(SCH_1):PAGE176
     2    GND @S9S_MB_2U_LIB.S9S_MB_2U(SCH_1):GND   I202 @S9S_MB_2U_LIB.S9S_MB_2U(SCH_1):PAGE176

R4111 Q_RES_0402LF-10K,1%,1/16W,CHIPA
     1 PD_PCH_GPP_E_13 @S9S_MB_2U_LIB.S9S_MB_2U(SCH_1):PD_PCH_GPP_E_13   I204 @S9S_MB_2U_LIB.S9S_MB_2U(SCH_1):PAGE176
     2    GND @S9S_MB_2U_LIB.S9S_MB_2U(SCH_1):GND   I204 @S9S_MB_2U_LIB.S9S_MB_2U(SCH_1):PAGE176

R4112 Q_RES_0402LF-10K,1%,1/16W,CHIPA
     1 PD_PCH_GPP_E_12 @S9S_MB_2U_LIB.S9S_MB_2U(SCH_1):PD_PCH_GPP_E_12   I203 @S9S_MB_2U_LIB.S9S_MB_2U(SCH_1):PAGE176
     2    GND @S9S_MB_2U_LIB.S9S_MB_2U(SCH_1):GND   I203 @S9S_MB_2U_LIB.S9S_MB_2U(SCH_1):PAGE176

R4113 Q_RES_0402LF-10K,1%,1/16W,CHIPA
     1 PD_PCH_GPP_E_11 @S9S_MB_2U_LIB.S9S_MB_2U(SCH_1):PD_PCH_GPP_E_11   I206 @S9S_MB_2U_LIB.S9S_MB_2U(SCH_1):PAGE176
     2    GND @S9S_MB_2U_LIB.S9S_MB_2U(SCH_1):GND   I206 @S9S_MB_2U_LIB.S9S_MB_2U(SCH_1):PAGE176

R4114 Q_RES_0402LF-10K,1%,1/16W,CHIPA
     1 PD_PCH_GPP_E_10 @S9S_MB_2U_LIB.S9S_MB_2U(SCH_1):PD_PCH_GPP_E_10   I205 @S9S_MB_2U_LIB.S9S_MB_2U(SCH_1):PAGE176
     2    GND @S9S_MB_2U_LIB.S9S_MB_2U(SCH_1):GND   I205 @S9S_MB_2U_LIB.S9S_MB_2U(SCH_1):PAGE176

R4115 Q_RES_0402LF-10K,1%,1/16W,CHIPA
     1 PD_PCH_GPP_E_9 @S9S_MB_2U_LIB.S9S_MB_2U(SCH_1):PD_PCH_GPP_E_9   I201 @S9S_MB_2U_LIB.S9S_MB_2U(SCH_1):PAGE176
     2    GND @S9S_MB_2U_LIB.S9S_MB_2U(SCH_1):GND   I201 @S9S_MB_2U_LIB.S9S_MB_2U(SCH_1):PAGE176

R4116 Q_RES_0402LF-10K,1%,1/16W,CHIPA
     1 PD_PCH_GPP_E_8 @S9S_MB_2U_LIB.S9S_MB_2U(SCH_1):PD_PCH_GPP_E_8   I207 @S9S_MB_2U_LIB.S9S_MB_2U(SCH_1):PAGE176
     2    GND @S9S_MB_2U_LIB.S9S_MB_2U(SCH_1):GND   I207 @S9S_MB_2U_LIB.S9S_MB_2U(SCH_1):PAGE176

R4117 Q_RES_0402LF-10K,1%,1/16W,CHIPA
     1 PD_PCH_GPP_E_3 @S9S_MB_2U_LIB.S9S_MB_2U(SCH_1):PD_PCH_GPP_E_3   I209 @S9S_MB_2U_LIB.S9S_MB_2U(SCH_1):PAGE176
     2    GND @S9S_MB_2U_LIB.S9S_MB_2U(SCH_1):GND   I209 @S9S_MB_2U_LIB.S9S_MB_2U(SCH_1):PAGE176

R4118 Q_RES_0402LF-10,1%,1/16W,CHIP,A
     1 IRQ_LPC_SERIRQ_ESPI_CS1_N @S9S_MB_2U_LIB.S9S_MB_2U(SCH_1):IRQ_LPC_SERIRQ_ESPI_CS1_N   I105 @S9S_MB_2U_LIB.S9S_MB_2U(SCH_1):PAGE190
     2 IRQ_LPC_SERIRQ_ESPI_CS1_R_N @S9S_MB_2U_LIB.S9S_MB_2U(SCH_1):IRQ_LPC_SERIRQ_ESPI_CS1_R_N   I105 @S9S_MB_2U_LIB.S9S_MB_2U(SCH_1):PAGE190

R4119 Q_RES_0402LF-54.9K,1%,1/16W,EMA
     1 P3V3_AUX @S9S_MB_2U_LIB.S9S_MB_2U(SCH_1):P3V3_AUX    I13 @S9S_MB_2U_LIB.S9S_MB_2U(SCH_1):PAGE143
     2 GPU_3V3IO_RSVD0_FFU @S9S_MB_2U_LIB.S9S_MB_2U(SCH_1):GPU_3V3IO_RSVD0_FFU    I13 @S9S_MB_2U_LIB.S9S_MB_2U(SCH_1):PAGE143

R4120 Q_RES_0402LF-100K,1%,1/16W,EMPA
     1 GPU_3V3IO_RSVD0_FFU @S9S_MB_2U_LIB.S9S_MB_2U(SCH_1):GPU_3V3IO_RSVD0_FFU    I14 @S9S_MB_2U_LIB.S9S_MB_2U(SCH_1):PAGE143
     2    GND @S9S_MB_2U_LIB.S9S_MB_2U(SCH_1):GND    I14 @S9S_MB_2U_LIB.S9S_MB_2U(SCH_1):PAGE143

R4121 Q_RES_0402LF-10K,1%,1/16W,CHIPA
     1 P3V3_AUX @S9S_MB_2U_LIB.S9S_MB_2U(SCH_1):P3V3_AUX   I143 @S9S_MB_2U_LIB.S9S_MB_2U(SCH_1):PAGE143
     2 PRSNT_CABLE_GPU_B3_N @S9S_MB_2U_LIB.S9S_MB_2U(SCH_1):PRSNT_CABLE_GPU_B3_N   I143 @S9S_MB_2U_LIB.S9S_MB_2U(SCH_1):PAGE143

R4122 Q_RES_0402LF-100K,1%,1/16W,EMPA
     1 PRSNT_CABLE_GPU_B3_N @S9S_MB_2U_LIB.S9S_MB_2U(SCH_1):PRSNT_CABLE_GPU_B3_N    I49 @S9S_MB_2U_LIB.S9S_MB_2U(SCH_1):PAGE143
     2    GND @S9S_MB_2U_LIB.S9S_MB_2U(SCH_1):GND    I49 @S9S_MB_2U_LIB.S9S_MB_2U(SCH_1):PAGE143

R4123 Q_RES_0402LF-54.9K,1%,1/16W,EMA
     1 P3V3_AUX @S9S_MB_2U_LIB.S9S_MB_2U(SCH_1):P3V3_AUX    I31 @S9S_MB_2U_LIB.S9S_MB_2U(SCH_1):PAGE143
     2 GPU_3V3IO_RSVD1_FFU @S9S_MB_2U_LIB.S9S_MB_2U(SCH_1):GPU_3V3IO_RSVD1_FFU    I31 @S9S_MB_2U_LIB.S9S_MB_2U(SCH_1):PAGE143

R4124 Q_RES_0402LF-100K,1%,1/16W,EMPA
     1 GPU_3V3IO_RSVD1_FFU @S9S_MB_2U_LIB.S9S_MB_2U(SCH_1):GPU_3V3IO_RSVD1_FFU    I32 @S9S_MB_2U_LIB.S9S_MB_2U(SCH_1):PAGE143
     2    GND @S9S_MB_2U_LIB.S9S_MB_2U(SCH_1):GND    I32 @S9S_MB_2U_LIB.S9S_MB_2U(SCH_1):PAGE143

R4125 Q_RES_0402LF-4.7K,5%,1/16W,CHIA
     1 P3V3_AUX @S9S_MB_2U_LIB.S9S_MB_2U(SCH_1):P3V3_AUX     I9 @S9S_MB_2U_LIB.S9S_MB_2U(SCH_1):PAGE143
     2 GPU_3V3IO_RSVD0_FFU_N @S9S_MB_2U_LIB.S9S_MB_2U(SCH_1):GPU_3V3IO_RSVD0_FFU_N     I9 @S9S_MB_2U_LIB.S9S_MB_2U(SCH_1):PAGE143

R4126 Q_RES_0402LF-4.7K,5%,1/16W,CHIA
     1 P3V3_AUX @S9S_MB_2U_LIB.S9S_MB_2U(SCH_1):P3V3_AUX    I43 @S9S_MB_2U_LIB.S9S_MB_2U(SCH_1):PAGE143
     2 PRSNT_CABLE_GPU_B3 @S9S_MB_2U_LIB.S9S_MB_2U(SCH_1):PRSNT_CABLE_GPU_B3    I43 @S9S_MB_2U_LIB.S9S_MB_2U(SCH_1):PAGE143

R4127 Q_RES_0402LF-4.7K,5%,1/16W,CHIA
     1 P3V3_AUX @S9S_MB_2U_LIB.S9S_MB_2U(SCH_1):P3V3_AUX    I27 @S9S_MB_2U_LIB.S9S_MB_2U(SCH_1):PAGE143
     2 GPU_3V3IO_RSVD1_FFU_N @S9S_MB_2U_LIB.S9S_MB_2U(SCH_1):GPU_3V3IO_RSVD1_FFU_N    I27 @S9S_MB_2U_LIB.S9S_MB_2U(SCH_1):PAGE143

R4128 Q_RES_0402LF-4.7K,5%,1/16W,CHIA
     1 P3V3_AUX @S9S_MB_2U_LIB.S9S_MB_2U(SCH_1):P3V3_AUX     I5 @S9S_MB_2U_LIB.S9S_MB_2U(SCH_1):PAGE143
     2 GPU_3V3IO_RSVD0_FFU_ISO @S9S_MB_2U_LIB.S9S_MB_2U(SCH_1):GPU_3V3IO_RSVD0_FFU_ISO     I5 @S9S_MB_2U_LIB.S9S_MB_2U(SCH_1):PAGE143

R4129 Q_RES_0402LF-4.7K,5%,1/16W,CHIA
     1 P3V3_AUX @S9S_MB_2U_LIB.S9S_MB_2U(SCH_1):P3V3_AUX    I36 @S9S_MB_2U_LIB.S9S_MB_2U(SCH_1):PAGE143
     2 PRSNT_CABLE_GPU_B3_ISO_N @S9S_MB_2U_LIB.S9S_MB_2U(SCH_1):PRSNT_CABLE_GPU_B3_ISO_N    I36 @S9S_MB_2U_LIB.S9S_MB_2U(SCH_1):PAGE143

R4130 Q_RES_0402LF-4.7K,5%,1/16W,CHIA
     1 P3V3_AUX @S9S_MB_2U_LIB.S9S_MB_2U(SCH_1):P3V3_AUX    I21 @S9S_MB_2U_LIB.S9S_MB_2U(SCH_1):PAGE143
     2 GPU_3V3IO_RSVD1_FFU_ISO @S9S_MB_2U_LIB.S9S_MB_2U(SCH_1):GPU_3V3IO_RSVD1_FFU_ISO    I21 @S9S_MB_2U_LIB.S9S_MB_2U(SCH_1):PAGE143

R4131 Q_RES_0402LF-54.9K,1%,1/16W,EMA
     1 P3V3_AUX @S9S_MB_2U_LIB.S9S_MB_2U(SCH_1):P3V3_AUX    I85 @S9S_MB_2U_LIB.S9S_MB_2U(SCH_1):PAGE143
     2 GPU_3V3IO_RSVD3_FFU @S9S_MB_2U_LIB.S9S_MB_2U(SCH_1):GPU_3V3IO_RSVD3_FFU    I85 @S9S_MB_2U_LIB.S9S_MB_2U(SCH_1):PAGE143

R4132 Q_RES_0402LF-100K,1%,1/16W,EMPA
     1 GPU_3V3IO_RSVD3_FFU @S9S_MB_2U_LIB.S9S_MB_2U(SCH_1):GPU_3V3IO_RSVD3_FFU    I86 @S9S_MB_2U_LIB.S9S_MB_2U(SCH_1):PAGE143
     2    GND @S9S_MB_2U_LIB.S9S_MB_2U(SCH_1):GND    I86 @S9S_MB_2U_LIB.S9S_MB_2U(SCH_1):PAGE143

R4133 Q_RES_0402LF-54.9K,1%,1/16W,EMA
     1 P3V3_AUX @S9S_MB_2U_LIB.S9S_MB_2U(SCH_1):P3V3_AUX    I95 @S9S_MB_2U_LIB.S9S_MB_2U(SCH_1):PAGE143
     2 GPU_3V3IO_RSVD5_FFU @S9S_MB_2U_LIB.S9S_MB_2U(SCH_1):GPU_3V3IO_RSVD5_FFU    I95 @S9S_MB_2U_LIB.S9S_MB_2U(SCH_1):PAGE143

R4134 Q_RES_0402LF-100K,1%,1/16W,EMPA
     1 GPU_3V3IO_RSVD5_FFU @S9S_MB_2U_LIB.S9S_MB_2U(SCH_1):GPU_3V3IO_RSVD5_FFU    I96 @S9S_MB_2U_LIB.S9S_MB_2U(SCH_1):PAGE143
     2    GND @S9S_MB_2U_LIB.S9S_MB_2U(SCH_1):GND    I96 @S9S_MB_2U_LIB.S9S_MB_2U(SCH_1):PAGE143

R4135 Q_RES_0402LF-10K,1%,1/16W,CHIPA
     1 P3V3_AUX @S9S_MB_2U_LIB.S9S_MB_2U(SCH_1):P3V3_AUX   I144 @S9S_MB_2U_LIB.S9S_MB_2U(SCH_1):PAGE143
     2 PRSNT_CABLE_GPU_A2_N @S9S_MB_2U_LIB.S9S_MB_2U(SCH_1):PRSNT_CABLE_GPU_A2_N   I144 @S9S_MB_2U_LIB.S9S_MB_2U(SCH_1):PAGE143

R4136 Q_RES_0402LF-100K,1%,1/16W,EMPA
     1 PRSNT_CABLE_GPU_A2_N @S9S_MB_2U_LIB.S9S_MB_2U(SCH_1):PRSNT_CABLE_GPU_A2_N    I91 @S9S_MB_2U_LIB.S9S_MB_2U(SCH_1):PAGE143
     2    GND @S9S_MB_2U_LIB.S9S_MB_2U(SCH_1):GND    I91 @S9S_MB_2U_LIB.S9S_MB_2U(SCH_1):PAGE143

R4137 Q_RES_0402LF-4.7K,5%,1/16W,CHIA
     1 P3V3_AUX @S9S_MB_2U_LIB.S9S_MB_2U(SCH_1):P3V3_AUX    I72 @S9S_MB_2U_LIB.S9S_MB_2U(SCH_1):PAGE143
     2 GPU_3V3IO_RSVD3_FFU_N @S9S_MB_2U_LIB.S9S_MB_2U(SCH_1):GPU_3V3IO_RSVD3_FFU_N    I72 @S9S_MB_2U_LIB.S9S_MB_2U(SCH_1):PAGE143

R4138 Q_RES_0402LF-4.7K,5%,1/16W,CHIA
     1 P3V3_AUX @S9S_MB_2U_LIB.S9S_MB_2U(SCH_1):P3V3_AUX    I81 @S9S_MB_2U_LIB.S9S_MB_2U(SCH_1):PAGE143
     2 GPU_3V3IO_RSVD5_FFU_N @S9S_MB_2U_LIB.S9S_MB_2U(SCH_1):GPU_3V3IO_RSVD5_FFU_N    I81 @S9S_MB_2U_LIB.S9S_MB_2U(SCH_1):PAGE143

R4139 Q_RES_0402LF-4.7K,5%,1/16W,CHIA
     1 P3V3_AUX @S9S_MB_2U_LIB.S9S_MB_2U(SCH_1):P3V3_AUX    I76 @S9S_MB_2U_LIB.S9S_MB_2U(SCH_1):PAGE143
     2 PRSNT_CABLE_GPU_A2 @S9S_MB_2U_LIB.S9S_MB_2U(SCH_1):PRSNT_CABLE_GPU_A2    I76 @S9S_MB_2U_LIB.S9S_MB_2U(SCH_1):PAGE143

R4140 Q_RES_0402LF-4.7K,5%,1/16W,CHIA
     1 P3V3_AUX @S9S_MB_2U_LIB.S9S_MB_2U(SCH_1):P3V3_AUX    I52 @S9S_MB_2U_LIB.S9S_MB_2U(SCH_1):PAGE143
     2 GPU_3V3IO_RSVD3_FFU_ISO @S9S_MB_2U_LIB.S9S_MB_2U(SCH_1):GPU_3V3IO_RSVD3_FFU_ISO    I52 @S9S_MB_2U_LIB.S9S_MB_2U(SCH_1):PAGE143

R4141 Q_RES_0402LF-4.7K,5%,1/16W,CHIA
     1 P3V3_AUX @S9S_MB_2U_LIB.S9S_MB_2U(SCH_1):P3V3_AUX    I64 @S9S_MB_2U_LIB.S9S_MB_2U(SCH_1):PAGE143
     2 GPU_3V3IO_RSVD5_FFU_ISO @S9S_MB_2U_LIB.S9S_MB_2U(SCH_1):GPU_3V3IO_RSVD5_FFU_ISO    I64 @S9S_MB_2U_LIB.S9S_MB_2U(SCH_1):PAGE143

R4142 Q_RES_0402LF-4.7K,5%,1/16W,CHIA
     1 P3V3_AUX @S9S_MB_2U_LIB.S9S_MB_2U(SCH_1):P3V3_AUX    I60 @S9S_MB_2U_LIB.S9S_MB_2U(SCH_1):PAGE143
     2 PRSNT_CABLE_GPU_A2_ISO_N @S9S_MB_2U_LIB.S9S_MB_2U(SCH_1):PRSNT_CABLE_GPU_A2_ISO_N    I60 @S9S_MB_2U_LIB.S9S_MB_2U(SCH_1):PAGE143

R4143 Q_RES_0402LF-33.2,1%,1/16W,CHIA
     1 GPU_3V3IO_RSVD0_FFU_ISO @S9S_MB_2U_LIB.S9S_MB_2U(SCH_1):GPU_3V3IO_RSVD0_FFU_ISO    I89 @S9S_MB_2U_LIB.S9S_MB_2U(SCH_1):PAGE312
     2 GPU_3V3IO_RSVD0_FFU_ISO_R @S9S_MB_2U_LIB.S9S_MB_2U(SCH_1):GPU_3V3IO_RSVD0_FFU_ISO_R    I89 @S9S_MB_2U_LIB.S9S_MB_2U(SCH_1):PAGE312

R4144 Q_RES_0402LF-33.2,1%,1/16W,CHIA
     1 GPU_3V3IO_RSVD1_FFU_ISO @S9S_MB_2U_LIB.S9S_MB_2U(SCH_1):GPU_3V3IO_RSVD1_FFU_ISO    I93 @S9S_MB_2U_LIB.S9S_MB_2U(SCH_1):PAGE312
     2 GPU_3V3IO_RSVD1_FFU_ISO_R @S9S_MB_2U_LIB.S9S_MB_2U(SCH_1):GPU_3V3IO_RSVD1_FFU_ISO_R    I93 @S9S_MB_2U_LIB.S9S_MB_2U(SCH_1):PAGE312

R4145 Q_RES_0402LF-33.2,1%,1/16W,CHIA
     1 PRSNT_CABLE_GPU_B3_ISO_N @S9S_MB_2U_LIB.S9S_MB_2U(SCH_1):PRSNT_CABLE_GPU_B3_ISO_N    I97 @S9S_MB_2U_LIB.S9S_MB_2U(SCH_1):PAGE312
     2 PRSNT_CABLE_GPU_B3_ISO_R_N @S9S_MB_2U_LIB.S9S_MB_2U(SCH_1):PRSNT_CABLE_GPU_B3_ISO_R_N    I97 @S9S_MB_2U_LIB.S9S_MB_2U(SCH_1):PAGE312

R4146 Q_RES_0402LF-33.2,1%,1/16W,CHIA
     1 GPU_3V3IO_RSVD3_FFU_ISO @S9S_MB_2U_LIB.S9S_MB_2U(SCH_1):GPU_3V3IO_RSVD3_FFU_ISO    I98 @S9S_MB_2U_LIB.S9S_MB_2U(SCH_1):PAGE312
     2 GPU_3V3IO_RSVD3_FFU_ISO_R @S9S_MB_2U_LIB.S9S_MB_2U(SCH_1):GPU_3V3IO_RSVD3_FFU_ISO_R    I98 @S9S_MB_2U_LIB.S9S_MB_2U(SCH_1):PAGE312

R4147 Q_RES_0402LF-33.2,1%,1/16W,CHIA
     1 PRSNT_CABLE_GPU_A2_ISO_N @S9S_MB_2U_LIB.S9S_MB_2U(SCH_1):PRSNT_CABLE_GPU_A2_ISO_N   I104 @S9S_MB_2U_LIB.S9S_MB_2U(SCH_1):PAGE312
     2 PRSNT_CABLE_GPU_A2_ISO_R_N @S9S_MB_2U_LIB.S9S_MB_2U(SCH_1):PRSNT_CABLE_GPU_A2_ISO_R_N   I104 @S9S_MB_2U_LIB.S9S_MB_2U(SCH_1):PAGE312

R4148 Q_RES_0402LF-33.2,1%,1/16W,CHIA
     1 GPU_3V3IO_RSVD5_FFU_ISO @S9S_MB_2U_LIB.S9S_MB_2U(SCH_1):GPU_3V3IO_RSVD5_FFU_ISO   I103 @S9S_MB_2U_LIB.S9S_MB_2U(SCH_1):PAGE312
     2 GPU_3V3IO_RSVD5_FFU_ISO_R @S9S_MB_2U_LIB.S9S_MB_2U(SCH_1):GPU_3V3IO_RSVD5_FFU_ISO_R   I103 @S9S_MB_2U_LIB.S9S_MB_2U(SCH_1):PAGE312

R4149 Q_RES_0402LF-33.2,1%,1/16W,CHIA
     1 SMB_1_PLD_3V3AUX_SCL @S9S_MB_2U_LIB.S9S_MB_2U(SCH_1):SMB_1_PLD_3V3AUX_SCL   I272 @S9S_MB_2U_LIB.S9S_MB_2U(SCH_1):PAGE228
     2 SMB_1_PLD_3V3AUX_SCL_R1 @S9S_MB_2U_LIB.S9S_MB_2U(SCH_1):SMB_1_PLD_3V3AUX_SCL_R1   I272 @S9S_MB_2U_LIB.S9S_MB_2U(SCH_1):PAGE228

R4150 Q_RES_0402LF-33.2,1%,1/16W,CHIA
     1 SMB_1_PLD_3V3AUX_SDA @S9S_MB_2U_LIB.S9S_MB_2U(SCH_1):SMB_1_PLD_3V3AUX_SDA   I271 @S9S_MB_2U_LIB.S9S_MB_2U(SCH_1):PAGE228
     2 SMB_1_PLD_3V3AUX_SDA_R1 @S9S_MB_2U_LIB.S9S_MB_2U(SCH_1):SMB_1_PLD_3V3AUX_SDA_R1   I271 @S9S_MB_2U_LIB.S9S_MB_2U(SCH_1):PAGE228

R4151 Q_RES_0402LF-33.2,1%,1/16W,CHIA
     1 SMB_1_PLD_3V3AUX_SCL @S9S_MB_2U_LIB.S9S_MB_2U(SCH_1):SMB_1_PLD_3V3AUX_SCL   I274 @S9S_MB_2U_LIB.S9S_MB_2U(SCH_1):PAGE228
     2 SMB_2_PLD_3V3AUX_SCL_R1 @S9S_MB_2U_LIB.S9S_MB_2U(SCH_1):SMB_2_PLD_3V3AUX_SCL_R1   I274 @S9S_MB_2U_LIB.S9S_MB_2U(SCH_1):PAGE228

R4152 Q_RES_0402LF-33.2,1%,1/16W,CHIA
     1 SMB_1_PLD_3V3AUX_SDA @S9S_MB_2U_LIB.S9S_MB_2U(SCH_1):SMB_1_PLD_3V3AUX_SDA   I273 @S9S_MB_2U_LIB.S9S_MB_2U(SCH_1):PAGE228
     2 SMB_2_PLD_3V3AUX_SDA_R1 @S9S_MB_2U_LIB.S9S_MB_2U(SCH_1):SMB_2_PLD_3V3AUX_SDA_R1   I273 @S9S_MB_2U_LIB.S9S_MB_2U(SCH_1):PAGE228

R4153 Q_RES_0402LF-10K,1%,1/16W,CHIPA
     1 P3V3_AUX @S9S_MB_2U_LIB.S9S_MB_2U(SCH_1):P3V3_AUX   I145 @S9S_MB_2U_LIB.S9S_MB_2U(SCH_1):PAGE143
     2 PRSNT_CABLE_GPU_A1_N @S9S_MB_2U_LIB.S9S_MB_2U(SCH_1):PRSNT_CABLE_GPU_A1_N   I145 @S9S_MB_2U_LIB.S9S_MB_2U(SCH_1):PAGE143

R4154 Q_RES_0402LF-100K,1%,1/16W,EMPA
     1 PRSNT_CABLE_GPU_A1_N @S9S_MB_2U_LIB.S9S_MB_2U(SCH_1):PRSNT_CABLE_GPU_A1_N   I113 @S9S_MB_2U_LIB.S9S_MB_2U(SCH_1):PAGE143
     2    GND @S9S_MB_2U_LIB.S9S_MB_2U(SCH_1):GND   I113 @S9S_MB_2U_LIB.S9S_MB_2U(SCH_1):PAGE143

R4155 Q_RES_0402LF-4.7K,5%,1/16W,CHIA
     1 P3V3_AUX @S9S_MB_2U_LIB.S9S_MB_2U(SCH_1):P3V3_AUX   I100 @S9S_MB_2U_LIB.S9S_MB_2U(SCH_1):PAGE143
     2 PRSNT_CABLE_GPU_A1 @S9S_MB_2U_LIB.S9S_MB_2U(SCH_1):PRSNT_CABLE_GPU_A1   I100 @S9S_MB_2U_LIB.S9S_MB_2U(SCH_1):PAGE143

R4156 Q_RES_0402LF-4.7K,5%,1/16W,CHIA
     1 P3V3_AUX @S9S_MB_2U_LIB.S9S_MB_2U(SCH_1):P3V3_AUX   I101 @S9S_MB_2U_LIB.S9S_MB_2U(SCH_1):PAGE143
     2 PRSNT_CABLE_GPU_A1_ISO_N @S9S_MB_2U_LIB.S9S_MB_2U(SCH_1):PRSNT_CABLE_GPU_A1_ISO_N   I101 @S9S_MB_2U_LIB.S9S_MB_2U(SCH_1):PAGE143

R4157 Q_RES_0402LF-33.2,1%,1/16W,CHIA
     1 PRSNT_CABLE_GPU_A1_ISO_N @S9S_MB_2U_LIB.S9S_MB_2U(SCH_1):PRSNT_CABLE_GPU_A1_ISO_N   I114 @S9S_MB_2U_LIB.S9S_MB_2U(SCH_1):PAGE312
     2 PRSNT_CABLE_GPU_A1_ISO_R_N @S9S_MB_2U_LIB.S9S_MB_2U(SCH_1):PRSNT_CABLE_GPU_A1_ISO_R_N   I114 @S9S_MB_2U_LIB.S9S_MB_2U(SCH_1):PAGE312

R4158 Q_RES_0402LF-54.9K,1%,1/16W,EMA
     1 P3V3_AUX @S9S_MB_2U_LIB.S9S_MB_2U(SCH_1):P3V3_AUX    I14 @S9S_MB_2U_LIB.S9S_MB_2U(SCH_1):PAGE139
     2 GPU_3V3IO_RSVD1 @S9S_MB_2U_LIB.S9S_MB_2U(SCH_1):GPU_3V3IO_RSVD1    I14 @S9S_MB_2U_LIB.S9S_MB_2U(SCH_1):PAGE139

R4159 Q_RES_0402LF-100K,1%,1/16W,EMPA
     1 GPU_3V3IO_RSVD1 @S9S_MB_2U_LIB.S9S_MB_2U(SCH_1):GPU_3V3IO_RSVD1    I13 @S9S_MB_2U_LIB.S9S_MB_2U(SCH_1):PAGE139
     2    GND @S9S_MB_2U_LIB.S9S_MB_2U(SCH_1):GND    I13 @S9S_MB_2U_LIB.S9S_MB_2U(SCH_1):PAGE139

R4160 Q_RES_0402LF-54.9K,1%,1/16W,EMA
     1 P3V3_AUX @S9S_MB_2U_LIB.S9S_MB_2U(SCH_1):P3V3_AUX     I4 @S9S_MB_2U_LIB.S9S_MB_2U(SCH_1):PAGE139
     2 GPU_3V3IO_RSVD4 @S9S_MB_2U_LIB.S9S_MB_2U(SCH_1):GPU_3V3IO_RSVD4     I4 @S9S_MB_2U_LIB.S9S_MB_2U(SCH_1):PAGE139

R4161 Q_RES_0402LF-100K,1%,1/16W,EMPA
     1 GPU_3V3IO_RSVD4 @S9S_MB_2U_LIB.S9S_MB_2U(SCH_1):GPU_3V3IO_RSVD4     I2 @S9S_MB_2U_LIB.S9S_MB_2U(SCH_1):PAGE139
     2    GND @S9S_MB_2U_LIB.S9S_MB_2U(SCH_1):GND     I2 @S9S_MB_2U_LIB.S9S_MB_2U(SCH_1):PAGE139

R4162 Q_RES_0402LF-54.9K,1%,1/16W,EMA
     1 P3V3_AUX @S9S_MB_2U_LIB.S9S_MB_2U(SCH_1):P3V3_AUX     I9 @S9S_MB_2U_LIB.S9S_MB_2U(SCH_1):PAGE139
     2 GPU_3V3IO_RSVD3 @S9S_MB_2U_LIB.S9S_MB_2U(SCH_1):GPU_3V3IO_RSVD3     I9 @S9S_MB_2U_LIB.S9S_MB_2U(SCH_1):PAGE139

R4163 Q_RES_0402LF-100K,1%,1/16W,EMPA
     1 GPU_3V3IO_RSVD3 @S9S_MB_2U_LIB.S9S_MB_2U(SCH_1):GPU_3V3IO_RSVD3     I8 @S9S_MB_2U_LIB.S9S_MB_2U(SCH_1):PAGE139
     2    GND @S9S_MB_2U_LIB.S9S_MB_2U(SCH_1):GND     I8 @S9S_MB_2U_LIB.S9S_MB_2U(SCH_1):PAGE139

R4164 Q_RES_0402LF-4.7K,5%,1/16W,CHIA
     1 P3V3_AUX @S9S_MB_2U_LIB.S9S_MB_2U(SCH_1):P3V3_AUX    I27 @S9S_MB_2U_LIB.S9S_MB_2U(SCH_1):PAGE139
     2 GPU_3V3IO_RSVD1_N @S9S_MB_2U_LIB.S9S_MB_2U(SCH_1):GPU_3V3IO_RSVD1_N    I27 @S9S_MB_2U_LIB.S9S_MB_2U(SCH_1):PAGE139

R4165 Q_RES_0402LF-4.7K,5%,1/16W,CHIA
     1 P3V3_AUX @S9S_MB_2U_LIB.S9S_MB_2U(SCH_1):P3V3_AUX    I18 @S9S_MB_2U_LIB.S9S_MB_2U(SCH_1):PAGE139
     2 GPU_3V3IO_RSVD4_N @S9S_MB_2U_LIB.S9S_MB_2U(SCH_1):GPU_3V3IO_RSVD4_N    I18 @S9S_MB_2U_LIB.S9S_MB_2U(SCH_1):PAGE139

R4166 Q_RES_0402LF-4.7K,5%,1/16W,CHIA
     1 P3V3_AUX @S9S_MB_2U_LIB.S9S_MB_2U(SCH_1):P3V3_AUX    I23 @S9S_MB_2U_LIB.S9S_MB_2U(SCH_1):PAGE139
     2 GPU_3V3IO_RSVD3_N @S9S_MB_2U_LIB.S9S_MB_2U(SCH_1):GPU_3V3IO_RSVD3_N    I23 @S9S_MB_2U_LIB.S9S_MB_2U(SCH_1):PAGE139

R4167 Q_RES_0402LF-4.7K,5%,1/16W,CHIA
     1 P3V3_AUX @S9S_MB_2U_LIB.S9S_MB_2U(SCH_1):P3V3_AUX    I47 @S9S_MB_2U_LIB.S9S_MB_2U(SCH_1):PAGE139
     2 GPU_3V3IO_RSVD1_ISO @S9S_MB_2U_LIB.S9S_MB_2U(SCH_1):GPU_3V3IO_RSVD1_ISO    I47 @S9S_MB_2U_LIB.S9S_MB_2U(SCH_1):PAGE139

R4168 Q_RES_0402LF-4.7K,5%,1/16W,CHIA
     1 P3V3_AUX @S9S_MB_2U_LIB.S9S_MB_2U(SCH_1):P3V3_AUX    I35 @S9S_MB_2U_LIB.S9S_MB_2U(SCH_1):PAGE139
     2 GPU_3V3IO_RSVD4_ISO @S9S_MB_2U_LIB.S9S_MB_2U(SCH_1):GPU_3V3IO_RSVD4_ISO    I35 @S9S_MB_2U_LIB.S9S_MB_2U(SCH_1):PAGE139

R4169 Q_RES_0402LF-4.7K,5%,1/16W,CHIA
     1 P3V3_AUX @S9S_MB_2U_LIB.S9S_MB_2U(SCH_1):P3V3_AUX    I39 @S9S_MB_2U_LIB.S9S_MB_2U(SCH_1):PAGE139
     2 GPU_3V3IO_RSVD3_ISO @S9S_MB_2U_LIB.S9S_MB_2U(SCH_1):GPU_3V3IO_RSVD3_ISO    I39 @S9S_MB_2U_LIB.S9S_MB_2U(SCH_1):PAGE139

R4170 Q_RES_0402LF-33.2,1%,1/16W,CHIA
     1 GPU_3V3IO_RSVD1_ISO @S9S_MB_2U_LIB.S9S_MB_2U(SCH_1):GPU_3V3IO_RSVD1_ISO   I120 @S9S_MB_2U_LIB.S9S_MB_2U(SCH_1):PAGE312
     2 GPU_3V3IO_RSVD1_ISO_R @S9S_MB_2U_LIB.S9S_MB_2U(SCH_1):GPU_3V3IO_RSVD1_ISO_R   I120 @S9S_MB_2U_LIB.S9S_MB_2U(SCH_1):PAGE312

R4171 Q_RES_0402LF-33.2,1%,1/16W,CHIA
     1 GPU_3V3IO_RSVD3_ISO @S9S_MB_2U_LIB.S9S_MB_2U(SCH_1):GPU_3V3IO_RSVD3_ISO   I121 @S9S_MB_2U_LIB.S9S_MB_2U(SCH_1):PAGE312
     2 GPU_3V3IO_RSVD3_ISO_R @S9S_MB_2U_LIB.S9S_MB_2U(SCH_1):GPU_3V3IO_RSVD3_ISO_R   I121 @S9S_MB_2U_LIB.S9S_MB_2U(SCH_1):PAGE312

R4172 Q_RES_0402LF-33.2,1%,1/16W,CHIA
     1 GPU_3V3IO_RSVD4_ISO @S9S_MB_2U_LIB.S9S_MB_2U(SCH_1):GPU_3V3IO_RSVD4_ISO   I122 @S9S_MB_2U_LIB.S9S_MB_2U(SCH_1):PAGE312
     2 GPU_3V3IO_RSVD4_ISO_R @S9S_MB_2U_LIB.S9S_MB_2U(SCH_1):GPU_3V3IO_RSVD4_ISO_R   I122 @S9S_MB_2U_LIB.S9S_MB_2U(SCH_1):PAGE312

R4173 Q_RES_0402LF-100K,1%,1/16W,EMPA
     1 P3V3_AUX @S9S_MB_2U_LIB.S9S_MB_2U(SCH_1):P3V3_AUX   I202 @S9S_MB_2U_LIB.S9S_MB_2U(SCH_1):PAGE140
     2 UART_BMC_BIC_R_BUF_RX @S9S_MB_2U_LIB.S9S_MB_2U(SCH_1):UART_BMC_BIC_R_BUF_RX   I202 @S9S_MB_2U_LIB.S9S_MB_2U(SCH_1):PAGE140

R4174 Q_RES_0402LF-33.2,1%,1/16W,CHIA
     1 RST_PCIE_PCH_DEV_PERST_N @S9S_MB_2U_LIB.S9S_MB_2U(SCH_1):RST_PCIE_PCH_DEV_PERST_N   I134 @S9S_MB_2U_LIB.S9S_MB_2U(SCH_1):PAGE312
     2 RST_PCIE_PCH_DEV_PERST_E1S_R_N @S9S_MB_2U_LIB.S9S_MB_2U(SCH_1):RST_PCIE_PCH_DEV_PERST_E1S_R_N   I134 @S9S_MB_2U_LIB.S9S_MB_2U(SCH_1):PAGE312

R4175 Q_RES_0402LF-33.2,1%,1/16W,CHIA
     1 RST_PCIE_PCH_DEV_PERST_N @S9S_MB_2U_LIB.S9S_MB_2U(SCH_1):RST_PCIE_PCH_DEV_PERST_N   I135 @S9S_MB_2U_LIB.S9S_MB_2U(SCH_1):PAGE312
     2 RST_PCIE_PCH_DEV_PERST_M2_R_N @S9S_MB_2U_LIB.S9S_MB_2U(SCH_1):RST_PCIE_PCH_DEV_PERST_M2_R_N   I135 @S9S_MB_2U_LIB.S9S_MB_2U(SCH_1):PAGE312

R4176 Q_RES_0402LF-10K,1%,1/16W,CHIPA
     1 P3V3_AUX @S9S_MB_2U_LIB.S9S_MB_2U(SCH_1):P3V3_AUX    I16 @S9S_MB_2U_LIB.S9S_MB_2U(SCH_1):PAGE243
     2 FM_LPC_ESPI_SEL @S9S_MB_2U_LIB.S9S_MB_2U(SCH_1):FM_LPC_ESPI_SEL    I16 @S9S_MB_2U_LIB.S9S_MB_2U(SCH_1):PAGE243

R4177 Q_RES_0402LF-0,5%,1/16W,CHIP,CA
     1 FM_ESPI_PLD_R_EN_BUF_R @S9S_MB_2U_LIB.S9S_MB_2U(SCH_1):FM_ESPI_PLD_R_EN_BUF_R    I19 @S9S_MB_2U_LIB.S9S_MB_2U(SCH_1):PAGE243
     2 FM_ESPI_PLD_R_EN_BUF @S9S_MB_2U_LIB.S9S_MB_2U(SCH_1):FM_ESPI_PLD_R_EN_BUF    I19 @S9S_MB_2U_LIB.S9S_MB_2U(SCH_1):PAGE243

R4178 Q_RES_0402LF-33.2,1%,1/16W,CHIA
     1 SMB_LM75_2_3V3AUX_SCL @S9S_MB_2U_LIB.S9S_MB_2U(SCH_1):SMB_LM75_2_3V3AUX_SCL   I114 @S9S_MB_2U_LIB.S9S_MB_2U(SCH_1):PAGE161
     2 SMB_LM75_2_3V3AUX_SCL_R1 @S9S_MB_2U_LIB.S9S_MB_2U(SCH_1):SMB_LM75_2_3V3AUX_SCL_R1   I114 @S9S_MB_2U_LIB.S9S_MB_2U(SCH_1):PAGE161

R4179 Q_RES_0402LF-33.2,1%,1/16W,CHIA
     1 SMB_LM75_1_3V3AUX_SCL @S9S_MB_2U_LIB.S9S_MB_2U(SCH_1):SMB_LM75_1_3V3AUX_SCL   I109 @S9S_MB_2U_LIB.S9S_MB_2U(SCH_1):PAGE161
     2 SMB_LM75_1_3V3AUX_SCL_R1 @S9S_MB_2U_LIB.S9S_MB_2U(SCH_1):SMB_LM75_1_3V3AUX_SCL_R1   I109 @S9S_MB_2U_LIB.S9S_MB_2U(SCH_1):PAGE161

R4180 Q_RES_0402LF-33.2,1%,1/16W,CHIA
     1 SMB_LM75_0_3V3AUX_SCL @S9S_MB_2U_LIB.S9S_MB_2U(SCH_1):SMB_LM75_0_3V3AUX_SCL    I77 @S9S_MB_2U_LIB.S9S_MB_2U(SCH_1):PAGE161
     2 SMB_LM75_0_3V3AUX_SCL_R1 @S9S_MB_2U_LIB.S9S_MB_2U(SCH_1):SMB_LM75_0_3V3AUX_SCL_R1    I77 @S9S_MB_2U_LIB.S9S_MB_2U(SCH_1):PAGE161

R4181 Q_RES_0402LF-33.2,1%,1/16W,CHIA
     1 SMB_LM75_2_3V3AUX_SDA @S9S_MB_2U_LIB.S9S_MB_2U(SCH_1):SMB_LM75_2_3V3AUX_SDA   I116 @S9S_MB_2U_LIB.S9S_MB_2U(SCH_1):PAGE161
     2 SMB_LM75_2_3V3AUX_SDA_R1 @S9S_MB_2U_LIB.S9S_MB_2U(SCH_1):SMB_LM75_2_3V3AUX_SDA_R1   I116 @S9S_MB_2U_LIB.S9S_MB_2U(SCH_1):PAGE161

R4182 Q_RES_0402LF-33.2,1%,1/16W,CHIA
     1 SMB_LM75_1_3V3AUX_SDA @S9S_MB_2U_LIB.S9S_MB_2U(SCH_1):SMB_LM75_1_3V3AUX_SDA   I107 @S9S_MB_2U_LIB.S9S_MB_2U(SCH_1):PAGE161
     2 SMB_LM75_1_3V3AUX_SDA_R1 @S9S_MB_2U_LIB.S9S_MB_2U(SCH_1):SMB_LM75_1_3V3AUX_SDA_R1   I107 @S9S_MB_2U_LIB.S9S_MB_2U(SCH_1):PAGE161

R4183 Q_RES_0402LF-33.2,1%,1/16W,CHIA
     1 SMB_LM75_0_3V3AUX_SDA @S9S_MB_2U_LIB.S9S_MB_2U(SCH_1):SMB_LM75_0_3V3AUX_SDA    I78 @S9S_MB_2U_LIB.S9S_MB_2U(SCH_1):PAGE161
     2 SMB_LM75_0_3V3AUX_SDA_R1 @S9S_MB_2U_LIB.S9S_MB_2U(SCH_1):SMB_LM75_0_3V3AUX_SDA_R1    I78 @S9S_MB_2U_LIB.S9S_MB_2U(SCH_1):PAGE161

R4184 Q_RES_0402LF-1K,1%,1/16W,EMPTYA
     1 P3V3_AUX @S9S_MB_2U_LIB.S9S_MB_2U(SCH_1):P3V3_AUX   I142 @S9S_MB_2U_LIB.S9S_MB_2U(SCH_1):PAGE161
     2 U273_3_ADD2 @S9S_MB_2U_LIB.S9S_MB_2U(SCH_1):U273_3_ADD2   I142 @S9S_MB_2U_LIB.S9S_MB_2U(SCH_1):PAGE161

R4185 Q_RES_0402LF-1K,1%,1/16W,CHIP,A
     1 U273_3_ADD2 @S9S_MB_2U_LIB.S9S_MB_2U(SCH_1):U273_3_ADD2   I141 @S9S_MB_2U_LIB.S9S_MB_2U(SCH_1):PAGE161
     2    GND @S9S_MB_2U_LIB.S9S_MB_2U(SCH_1):GND   I141 @S9S_MB_2U_LIB.S9S_MB_2U(SCH_1):PAGE161

R4186 Q_RES_0402LF-1K,1%,1/16W,EMPTYA
     1 P3V3_AUX @S9S_MB_2U_LIB.S9S_MB_2U(SCH_1):P3V3_AUX   I122 @S9S_MB_2U_LIB.S9S_MB_2U(SCH_1):PAGE161
     2 U272_2_ADD2 @S9S_MB_2U_LIB.S9S_MB_2U(SCH_1):U272_2_ADD2   I122 @S9S_MB_2U_LIB.S9S_MB_2U(SCH_1):PAGE161

R4187 Q_RES_0402LF-1K,1%,1/16W,CHIP,A
     1 U272_2_ADD2 @S9S_MB_2U_LIB.S9S_MB_2U(SCH_1):U272_2_ADD2   I121 @S9S_MB_2U_LIB.S9S_MB_2U(SCH_1):PAGE161
     2    GND @S9S_MB_2U_LIB.S9S_MB_2U(SCH_1):GND   I121 @S9S_MB_2U_LIB.S9S_MB_2U(SCH_1):PAGE161

R4188 Q_RES_0402LF-1K,1%,1/16W,EMPTYA
     1 P3V3_AUX @S9S_MB_2U_LIB.S9S_MB_2U(SCH_1):P3V3_AUX   I101 @S9S_MB_2U_LIB.S9S_MB_2U(SCH_1):PAGE161
     2 U271_1_ADD2 @S9S_MB_2U_LIB.S9S_MB_2U(SCH_1):U271_1_ADD2   I101 @S9S_MB_2U_LIB.S9S_MB_2U(SCH_1):PAGE161

R4189 Q_RES_0402LF-1K,1%,1/16W,CHIP,A
     1 U271_1_ADD2 @S9S_MB_2U_LIB.S9S_MB_2U(SCH_1):U271_1_ADD2   I102 @S9S_MB_2U_LIB.S9S_MB_2U(SCH_1):PAGE161
     2    GND @S9S_MB_2U_LIB.S9S_MB_2U(SCH_1):GND   I102 @S9S_MB_2U_LIB.S9S_MB_2U(SCH_1):PAGE161

R4190 Q_RES_0402LF-1K,1%,1/16W,EMPTYA
     1 P3V3_AUX @S9S_MB_2U_LIB.S9S_MB_2U(SCH_1):P3V3_AUX    I91 @S9S_MB_2U_LIB.S9S_MB_2U(SCH_1):PAGE161
     2 U270_0_ADD2 @S9S_MB_2U_LIB.S9S_MB_2U(SCH_1):U270_0_ADD2    I91 @S9S_MB_2U_LIB.S9S_MB_2U(SCH_1):PAGE161

R4191 Q_RES_0402LF-1K,1%,1/16W,CHIP,A
     1 U270_0_ADD2 @S9S_MB_2U_LIB.S9S_MB_2U(SCH_1):U270_0_ADD2    I89 @S9S_MB_2U_LIB.S9S_MB_2U(SCH_1):PAGE161
     2    GND @S9S_MB_2U_LIB.S9S_MB_2U(SCH_1):GND    I89 @S9S_MB_2U_LIB.S9S_MB_2U(SCH_1):PAGE161

R4192 Q_RES_0402LF-1K,1%,1/16W,EMPTYA
     1 P3V3_AUX @S9S_MB_2U_LIB.S9S_MB_2U(SCH_1):P3V3_AUX   I148 @S9S_MB_2U_LIB.S9S_MB_2U(SCH_1):PAGE161
     2 U273_3_ADD1 @S9S_MB_2U_LIB.S9S_MB_2U(SCH_1):U273_3_ADD1   I148 @S9S_MB_2U_LIB.S9S_MB_2U(SCH_1):PAGE161

R4193 Q_RES_0402LF-1K,1%,1/16W,CHIP,A
     1 U273_3_ADD1 @S9S_MB_2U_LIB.S9S_MB_2U(SCH_1):U273_3_ADD1   I145 @S9S_MB_2U_LIB.S9S_MB_2U(SCH_1):PAGE161
     2    GND @S9S_MB_2U_LIB.S9S_MB_2U(SCH_1):GND   I145 @S9S_MB_2U_LIB.S9S_MB_2U(SCH_1):PAGE161

R4194 Q_RES_0402LF-1K,1%,1/16W,EMPTYA
     1 P3V3_AUX @S9S_MB_2U_LIB.S9S_MB_2U(SCH_1):P3V3_AUX   I128 @S9S_MB_2U_LIB.S9S_MB_2U(SCH_1):PAGE161
     2 U272_2_ADD1 @S9S_MB_2U_LIB.S9S_MB_2U(SCH_1):U272_2_ADD1   I128 @S9S_MB_2U_LIB.S9S_MB_2U(SCH_1):PAGE161

R4195 Q_RES_0402LF-1K,1%,1/16W,CHIP,A
     1 U272_2_ADD1 @S9S_MB_2U_LIB.S9S_MB_2U(SCH_1):U272_2_ADD1   I125 @S9S_MB_2U_LIB.S9S_MB_2U(SCH_1):PAGE161
     2    GND @S9S_MB_2U_LIB.S9S_MB_2U(SCH_1):GND   I125 @S9S_MB_2U_LIB.S9S_MB_2U(SCH_1):PAGE161

R4196 Q_RES_0402LF-1K,1%,1/16W,EMPTYA
     1 P3V3_AUX @S9S_MB_2U_LIB.S9S_MB_2U(SCH_1):P3V3_AUX    I95 @S9S_MB_2U_LIB.S9S_MB_2U(SCH_1):PAGE161
     2 U271_1_ADD1 @S9S_MB_2U_LIB.S9S_MB_2U(SCH_1):U271_1_ADD1    I95 @S9S_MB_2U_LIB.S9S_MB_2U(SCH_1):PAGE161

R4197 Q_RES_0402LF-1K,1%,1/16W,CHIP,A
     1 U271_1_ADD1 @S9S_MB_2U_LIB.S9S_MB_2U(SCH_1):U271_1_ADD1    I98 @S9S_MB_2U_LIB.S9S_MB_2U(SCH_1):PAGE161
     2    GND @S9S_MB_2U_LIB.S9S_MB_2U(SCH_1):GND    I98 @S9S_MB_2U_LIB.S9S_MB_2U(SCH_1):PAGE161

R4198 Q_RES_0402LF-1K,1%,1/16W,EMPTYA
     1 P3V3_AUX @S9S_MB_2U_LIB.S9S_MB_2U(SCH_1):P3V3_AUX    I82 @S9S_MB_2U_LIB.S9S_MB_2U(SCH_1):PAGE161
     2 U270_0_ADD1 @S9S_MB_2U_LIB.S9S_MB_2U(SCH_1):U270_0_ADD1    I82 @S9S_MB_2U_LIB.S9S_MB_2U(SCH_1):PAGE161

R4199 Q_RES_0402LF-1K,1%,1/16W,CHIP,A
     1 U270_0_ADD1 @S9S_MB_2U_LIB.S9S_MB_2U(SCH_1):U270_0_ADD1    I81 @S9S_MB_2U_LIB.S9S_MB_2U(SCH_1):PAGE161
     2    GND @S9S_MB_2U_LIB.S9S_MB_2U(SCH_1):GND    I81 @S9S_MB_2U_LIB.S9S_MB_2U(SCH_1):PAGE161

R4200 Q_RES_0402LF-1K,1%,1/16W,EMPTYA
     1 P3V3_AUX @S9S_MB_2U_LIB.S9S_MB_2U(SCH_1):P3V3_AUX   I149 @S9S_MB_2U_LIB.S9S_MB_2U(SCH_1):PAGE161
     2 U273_3_ADD0 @S9S_MB_2U_LIB.S9S_MB_2U(SCH_1):U273_3_ADD0   I149 @S9S_MB_2U_LIB.S9S_MB_2U(SCH_1):PAGE161

R4201 Q_RES_0402LF-1K,1%,1/16W,CHIP,A
     1 U273_3_ADD0 @S9S_MB_2U_LIB.S9S_MB_2U(SCH_1):U273_3_ADD0   I147 @S9S_MB_2U_LIB.S9S_MB_2U(SCH_1):PAGE161
     2    GND @S9S_MB_2U_LIB.S9S_MB_2U(SCH_1):GND   I147 @S9S_MB_2U_LIB.S9S_MB_2U(SCH_1):PAGE161

R4202 Q_RES_0402LF-1K,1%,1/16W,EMPTYA
     1 P3V3_AUX @S9S_MB_2U_LIB.S9S_MB_2U(SCH_1):P3V3_AUX   I129 @S9S_MB_2U_LIB.S9S_MB_2U(SCH_1):PAGE161
     2 U272_2_ADD0 @S9S_MB_2U_LIB.S9S_MB_2U(SCH_1):U272_2_ADD0   I129 @S9S_MB_2U_LIB.S9S_MB_2U(SCH_1):PAGE161

R4203 Q_RES_0402LF-1K,1%,1/16W,CHIP,A
     1 U272_2_ADD0 @S9S_MB_2U_LIB.S9S_MB_2U(SCH_1):U272_2_ADD0   I127 @S9S_MB_2U_LIB.S9S_MB_2U(SCH_1):PAGE161
     2    GND @S9S_MB_2U_LIB.S9S_MB_2U(SCH_1):GND   I127 @S9S_MB_2U_LIB.S9S_MB_2U(SCH_1):PAGE161

R4204 Q_RES_0402LF-1K,1%,1/16W,EMPTYA
     1 P3V3_AUX @S9S_MB_2U_LIB.S9S_MB_2U(SCH_1):P3V3_AUX    I94 @S9S_MB_2U_LIB.S9S_MB_2U(SCH_1):PAGE161
     2 U271_1_ADD0 @S9S_MB_2U_LIB.S9S_MB_2U(SCH_1):U271_1_ADD0    I94 @S9S_MB_2U_LIB.S9S_MB_2U(SCH_1):PAGE161

R4205 Q_RES_0402LF-1K,1%,1/16W,CHIP,A
     1 U271_1_ADD0 @S9S_MB_2U_LIB.S9S_MB_2U(SCH_1):U271_1_ADD0    I96 @S9S_MB_2U_LIB.S9S_MB_2U(SCH_1):PAGE161
     2    GND @S9S_MB_2U_LIB.S9S_MB_2U(SCH_1):GND    I96 @S9S_MB_2U_LIB.S9S_MB_2U(SCH_1):PAGE161

R4206 Q_RES_0402LF-1K,1%,1/16W,EMPTYA
     1 P3V3_AUX @S9S_MB_2U_LIB.S9S_MB_2U(SCH_1):P3V3_AUX    I86 @S9S_MB_2U_LIB.S9S_MB_2U(SCH_1):PAGE161
     2 U270_0_ADD0 @S9S_MB_2U_LIB.S9S_MB_2U(SCH_1):U270_0_ADD0    I86 @S9S_MB_2U_LIB.S9S_MB_2U(SCH_1):PAGE161

R4207 Q_RES_0402LF-1K,1%,1/16W,CHIP,A
     1 U270_0_ADD0 @S9S_MB_2U_LIB.S9S_MB_2U(SCH_1):U270_0_ADD0    I85 @S9S_MB_2U_LIB.S9S_MB_2U(SCH_1):PAGE161
     2    GND @S9S_MB_2U_LIB.S9S_MB_2U(SCH_1):GND    I85 @S9S_MB_2U_LIB.S9S_MB_2U(SCH_1):PAGE161

R4208 Q_RES_0402LF-200K,1%,1/16W,EMPA
     1 P3V3_AUX @S9S_MB_2U_LIB.S9S_MB_2U(SCH_1):P3V3_AUX   I171 @S9S_MB_2U_LIB.S9S_MB_2U(SCH_1):PAGE161
     2 FM_THERMAL_ALERT_N @S9S_MB_2U_LIB.S9S_MB_2U(SCH_1):FM_THERMAL_ALERT_N   I171 @S9S_MB_2U_LIB.S9S_MB_2U(SCH_1):PAGE161

R4209 Q_RES_0402LF-200K,1%,1/16W,EMPA
     1 P3V3_AUX @S9S_MB_2U_LIB.S9S_MB_2U(SCH_1):P3V3_AUX   I169 @S9S_MB_2U_LIB.S9S_MB_2U(SCH_1):PAGE161
     2 FM_THERMAL_ALERT_N @S9S_MB_2U_LIB.S9S_MB_2U(SCH_1):FM_THERMAL_ALERT_N   I169 @S9S_MB_2U_LIB.S9S_MB_2U(SCH_1):PAGE161

R4210 Q_RES_0402LF-200K,1%,1/16W,EMPA
     1 P3V3_AUX @S9S_MB_2U_LIB.S9S_MB_2U(SCH_1):P3V3_AUX   I170 @S9S_MB_2U_LIB.S9S_MB_2U(SCH_1):PAGE161
     2 FM_THERMAL_ALERT_N @S9S_MB_2U_LIB.S9S_MB_2U(SCH_1):FM_THERMAL_ALERT_N   I170 @S9S_MB_2U_LIB.S9S_MB_2U(SCH_1):PAGE161

R4211 Q_RES_0402LF-200K,1%,1/16W,CHIA
     1 P3V3_AUX @S9S_MB_2U_LIB.S9S_MB_2U(SCH_1):P3V3_AUX   I168 @S9S_MB_2U_LIB.S9S_MB_2U(SCH_1):PAGE161
     2 FM_THERMAL_ALERT_N @S9S_MB_2U_LIB.S9S_MB_2U(SCH_1):FM_THERMAL_ALERT_N   I168 @S9S_MB_2U_LIB.S9S_MB_2U(SCH_1):PAGE161

R4212 Q_RES_0402LF-0,5%,1/16W,CHIP,CA
     1 FM_THERMAL_ALERT_N @S9S_MB_2U_LIB.S9S_MB_2U(SCH_1):FM_THERMAL_ALERT_N   I135 @S9S_MB_2U_LIB.S9S_MB_2U(SCH_1):PAGE161
     2 FM_LM75_3_ALERT_N @S9S_MB_2U_LIB.S9S_MB_2U(SCH_1):FM_LM75_3_ALERT_N   I135 @S9S_MB_2U_LIB.S9S_MB_2U(SCH_1):PAGE161

R4213 Q_RES_0402LF-0,5%,1/16W,CHIP,CA
     1 FM_THERMAL_ALERT_N @S9S_MB_2U_LIB.S9S_MB_2U(SCH_1):FM_THERMAL_ALERT_N   I115 @S9S_MB_2U_LIB.S9S_MB_2U(SCH_1):PAGE161
     2 FM_LM75_2_ALERT_N @S9S_MB_2U_LIB.S9S_MB_2U(SCH_1):FM_LM75_2_ALERT_N   I115 @S9S_MB_2U_LIB.S9S_MB_2U(SCH_1):PAGE161

R4214 Q_RES_0402LF-0,5%,1/16W,CHIP,CA
     1 FM_THERMAL_ALERT_N @S9S_MB_2U_LIB.S9S_MB_2U(SCH_1):FM_THERMAL_ALERT_N   I108 @S9S_MB_2U_LIB.S9S_MB_2U(SCH_1):PAGE161
     2 FM_G751_1_ALERT_N @S9S_MB_2U_LIB.S9S_MB_2U(SCH_1):FM_G751_1_ALERT_N   I108 @S9S_MB_2U_LIB.S9S_MB_2U(SCH_1):PAGE161

R4215 Q_RES_0402LF-0,5%,1/16W,CHIP,CA
     1 FM_THERMAL_ALERT_N @S9S_MB_2U_LIB.S9S_MB_2U(SCH_1):FM_THERMAL_ALERT_N    I79 @S9S_MB_2U_LIB.S9S_MB_2U(SCH_1):PAGE161
     2 FM_G751_0_ALERT_N @S9S_MB_2U_LIB.S9S_MB_2U(SCH_1):FM_G751_0_ALERT_N    I79 @S9S_MB_2U_LIB.S9S_MB_2U(SCH_1):PAGE161

R4216 Q_RES_0402LF-0,5%,1/16W,CHIP,CA
     1 FM_PVCCFA_EHV_FIVRA_CPU0_EN @S9S_MB_2U_LIB.S9S_MB_2U(SCH_1):FM_PVCCFA_EHV_FIVRA_CPU0_EN    I56 @S9S_MB_2U_LIB.S9S_MB_2U(SCH_1):PAGE252
     2 PVCCFA_EHV_FIVRA_CPU0_EN_R @S9S_MB_2U_LIB.S9S_MB_2U(SCH_1):PVCCFA_EHV_FIVRA_CPU0_EN_R    I56 @S9S_MB_2U_LIB.S9S_MB_2U(SCH_1):PAGE252

R4259 Q_RES_0402LF-33.2,1%,1/16W,CHIA
     1 FM_THERMAL_ALERT_N @S9S_MB_2U_LIB.S9S_MB_2U(SCH_1):FM_THERMAL_ALERT_N   I147 @S9S_MB_2U_LIB.S9S_MB_2U(SCH_1):PAGE313
     2 FM_THERMAL_ALERT_R_N @S9S_MB_2U_LIB.S9S_MB_2U(SCH_1):FM_THERMAL_ALERT_R_N   I147 @S9S_MB_2U_LIB.S9S_MB_2U(SCH_1):PAGE313

R4260 Q_RES_0402LF-240,1%,1/16W,EMPTA
     1 PVNN_TERM_CPU0 @S9S_MB_2U_LIB.S9S_MB_2U(SCH_1):PVNN_TERM_CPU0   I219 @S9S_MB_2U_LIB.S9S_MB_2U(SCH_1):PAGE119
     2 PD_CPU1_BIST_ENABLE @S9S_MB_2U_LIB.S9S_MB_2U(SCH_1):PD_CPU1_BIST_ENABLE   I219 @S9S_MB_2U_LIB.S9S_MB_2U(SCH_1):PAGE119

R4261 Q_RES_0402LF-240,1%,1/16W,EMPTA
     1 PD_CPU1_BIST_ENABLE @S9S_MB_2U_LIB.S9S_MB_2U(SCH_1):PD_CPU1_BIST_ENABLE   I220 @S9S_MB_2U_LIB.S9S_MB_2U(SCH_1):PAGE119
     2    GND @S9S_MB_2U_LIB.S9S_MB_2U(SCH_1):GND   I220 @S9S_MB_2U_LIB.S9S_MB_2U(SCH_1):PAGE119

R4262 Q_RES_0402LF-240,1%,1/16W,EMPTA
     1 PVNN_TERM_CPU0 @S9S_MB_2U_LIB.S9S_MB_2U(SCH_1):PVNN_TERM_CPU0   I215 @S9S_MB_2U_LIB.S9S_MB_2U(SCH_1):PAGE119
     2 PD_CPU0_BIST_ENABLE @S9S_MB_2U_LIB.S9S_MB_2U(SCH_1):PD_CPU0_BIST_ENABLE   I215 @S9S_MB_2U_LIB.S9S_MB_2U(SCH_1):PAGE119

R4263 Q_RES_0402LF-240,1%,1/16W,EMPTA
     1 PD_CPU0_BIST_ENABLE @S9S_MB_2U_LIB.S9S_MB_2U(SCH_1):PD_CPU0_BIST_ENABLE   I216 @S9S_MB_2U_LIB.S9S_MB_2U(SCH_1):PAGE119
     2    GND @S9S_MB_2U_LIB.S9S_MB_2U(SCH_1):GND   I216 @S9S_MB_2U_LIB.S9S_MB_2U(SCH_1):PAGE119

R4264 Q_RES_0402LF-4.7K,5%,1/16W,CHIA
     1 P3V3_AUX @S9S_MB_2U_LIB.S9S_MB_2U(SCH_1):P3V3_AUX    I47 @S9S_MB_2U_LIB.S9S_MB_2U(SCH_1):PAGE230
     2 PWRGD_P3V3_AUX_PDB_BUF_R @S9S_MB_2U_LIB.S9S_MB_2U(SCH_1):PWRGD_P3V3_AUX_PDB_BUF_R    I47 @S9S_MB_2U_LIB.S9S_MB_2U(SCH_1):PAGE230

R4265 Q_RES_0402LF-4.7K,5%,1/16W,EMPA
     1 PWRGD_P3V3_AUX_PDB_BUF_R @S9S_MB_2U_LIB.S9S_MB_2U(SCH_1):PWRGD_P3V3_AUX_PDB_BUF_R    I43 @S9S_MB_2U_LIB.S9S_MB_2U(SCH_1):PAGE230
     2    GND @S9S_MB_2U_LIB.S9S_MB_2U(SCH_1):GND    I43 @S9S_MB_2U_LIB.S9S_MB_2U(SCH_1):PAGE230

R4266 Q_RES_0402LF-33.2,1%,1/16W,CHIA
     1 PWRGD_P3V3_AUX_PDB_BUF_R @S9S_MB_2U_LIB.S9S_MB_2U(SCH_1):PWRGD_P3V3_AUX_PDB_BUF_R    I48 @S9S_MB_2U_LIB.S9S_MB_2U(SCH_1):PAGE230
     2 PWRGD_P3V3_AUX_PDB_BUF @S9S_MB_2U_LIB.S9S_MB_2U(SCH_1):PWRGD_P3V3_AUX_PDB_BUF    I48 @S9S_MB_2U_LIB.S9S_MB_2U(SCH_1):PAGE230

R4267 Q_RES_0402LF-33.2,1%,1/16W,CHIA
     1 PWRGD_P3V3_AUX @S9S_MB_2U_LIB.S9S_MB_2U(SCH_1):PWRGD_P3V3_AUX   I129 @S9S_MB_2U_LIB.S9S_MB_2U(SCH_1):PAGE211
     2 PWRGD_P3V3_AUX_PDB @S9S_MB_2U_LIB.S9S_MB_2U(SCH_1):PWRGD_P3V3_AUX_PDB   I129 @S9S_MB_2U_LIB.S9S_MB_2U(SCH_1):PAGE211

R4268 Q_RES_0402LF-0,5%,1/16W,CHIP,CA
     1 PWRGD_P3V3_AUX_PDB @S9S_MB_2U_LIB.S9S_MB_2U(SCH_1):PWRGD_P3V3_AUX_PDB    I41 @S9S_MB_2U_LIB.S9S_MB_2U(SCH_1):PAGE230
     2 PWRGD_P3V3_AUX_PDB_R @S9S_MB_2U_LIB.S9S_MB_2U(SCH_1):PWRGD_P3V3_AUX_PDB_R    I41 @S9S_MB_2U_LIB.S9S_MB_2U(SCH_1):PAGE230

R4269 Q_RES_0402LF-2.2K,5%,1/16W,EMPA
     1 P3V3_AUX @S9S_MB_2U_LIB.S9S_MB_2U(SCH_1):P3V3_AUX   I102 @S9S_MB_2U_LIB.S9S_MB_2U(SCH_1):PAGE221
     2 SMB_VR_SENSOR_3V3AUX_SCL @S9S_MB_2U_LIB.S9S_MB_2U(SCH_1):SMB_VR_SENSOR_3V3AUX_SCL   I102 @S9S_MB_2U_LIB.S9S_MB_2U(SCH_1):PAGE221

R4270 Q_RES_0402LF-2.2K,5%,1/16W,EMPA
     1 P3V3_AUX @S9S_MB_2U_LIB.S9S_MB_2U(SCH_1):P3V3_AUX    I99 @S9S_MB_2U_LIB.S9S_MB_2U(SCH_1):PAGE221
     2 SMB_VR_SENSOR_3V3AUX_SDA @S9S_MB_2U_LIB.S9S_MB_2U(SCH_1):SMB_VR_SENSOR_3V3AUX_SDA    I99 @S9S_MB_2U_LIB.S9S_MB_2U(SCH_1):PAGE221

R4273 Q_RES_0402LF-1K,1%,1/16W,EMPTYA
     1 P3V3_AUX @S9S_MB_2U_LIB.S9S_MB_2U(SCH_1):P3V3_AUX    I12 @S9S_MB_2U_LIB.S9S_MB_2U(SCH_1):PAGE162
     2 FM_USB3_1_FGB @S9S_MB_2U_LIB.S9S_MB_2U(SCH_1):FM_USB3_1_FGB    I12 @S9S_MB_2U_LIB.S9S_MB_2U(SCH_1):PAGE162

R4274 Q_RES_0402LF-1K,1%,1/16W,EMPTYA
     1 FM_USB3_1_FGB @S9S_MB_2U_LIB.S9S_MB_2U(SCH_1):FM_USB3_1_FGB    I11 @S9S_MB_2U_LIB.S9S_MB_2U(SCH_1):PAGE162
     2    GND @S9S_MB_2U_LIB.S9S_MB_2U(SCH_1):GND    I11 @S9S_MB_2U_LIB.S9S_MB_2U(SCH_1):PAGE162

R4275 Q_RES_0402LF-1K,1%,1/16W,EMPTYA
     1 P3V3_AUX @S9S_MB_2U_LIB.S9S_MB_2U(SCH_1):P3V3_AUX     I3 @S9S_MB_2U_LIB.S9S_MB_2U(SCH_1):PAGE162
     2 FM_USB3_1_EQA @S9S_MB_2U_LIB.S9S_MB_2U(SCH_1):FM_USB3_1_EQA     I3 @S9S_MB_2U_LIB.S9S_MB_2U(SCH_1):PAGE162

R4276 Q_RES_0402LF-68K,1%,1/16W,CHIPA
     1 FM_USB3_1_EQA @S9S_MB_2U_LIB.S9S_MB_2U(SCH_1):FM_USB3_1_EQA     I2 @S9S_MB_2U_LIB.S9S_MB_2U(SCH_1):PAGE162
     2    GND @S9S_MB_2U_LIB.S9S_MB_2U(SCH_1):GND     I2 @S9S_MB_2U_LIB.S9S_MB_2U(SCH_1):PAGE162

R4279 Q_RES_0402LF-1K,1%,1/16W,EMPTYA
     1 P3V3_AUX @S9S_MB_2U_LIB.S9S_MB_2U(SCH_1):P3V3_AUX    I18 @S9S_MB_2U_LIB.S9S_MB_2U(SCH_1):PAGE162
     2 FM_USB3_1_FGA @S9S_MB_2U_LIB.S9S_MB_2U(SCH_1):FM_USB3_1_FGA    I18 @S9S_MB_2U_LIB.S9S_MB_2U(SCH_1):PAGE162

R4280 Q_RES_0402LF-1K,1%,1/16W,EMPTYA
     1 FM_USB3_1_FGA @S9S_MB_2U_LIB.S9S_MB_2U(SCH_1):FM_USB3_1_FGA    I17 @S9S_MB_2U_LIB.S9S_MB_2U(SCH_1):PAGE162
     2    GND @S9S_MB_2U_LIB.S9S_MB_2U(SCH_1):GND    I17 @S9S_MB_2U_LIB.S9S_MB_2U(SCH_1):PAGE162

R4281 Q_RES_0402LF-1K,1%,1/16W,EMPTYA
     1 P3V3_AUX @S9S_MB_2U_LIB.S9S_MB_2U(SCH_1):P3V3_AUX     I7 @S9S_MB_2U_LIB.S9S_MB_2U(SCH_1):PAGE162
     2 FM_USB3_1_EQB @S9S_MB_2U_LIB.S9S_MB_2U(SCH_1):FM_USB3_1_EQB     I7 @S9S_MB_2U_LIB.S9S_MB_2U(SCH_1):PAGE162

R4282 Q_RES_0402LF-68K,1%,1/16W,CHIPA
     1 FM_USB3_1_EQB @S9S_MB_2U_LIB.S9S_MB_2U(SCH_1):FM_USB3_1_EQB     I6 @S9S_MB_2U_LIB.S9S_MB_2U(SCH_1):PAGE162
     2    GND @S9S_MB_2U_LIB.S9S_MB_2U(SCH_1):GND     I6 @S9S_MB_2U_LIB.S9S_MB_2U(SCH_1):PAGE162

R4284 Q_RES_0402LF-1K,1%,1/16W,EMPTYA
     1 P3V3_AUX @S9S_MB_2U_LIB.S9S_MB_2U(SCH_1):P3V3_AUX    I41 @S9S_MB_2U_LIB.S9S_MB_2U(SCH_1):PAGE162
     2 FM_USB3_1_SWB @S9S_MB_2U_LIB.S9S_MB_2U(SCH_1):FM_USB3_1_SWB    I41 @S9S_MB_2U_LIB.S9S_MB_2U(SCH_1):PAGE162

R4285 Q_RES_0402LF-1K,1%,1/16W,EMPTYA
     1 FM_USB3_1_SWB @S9S_MB_2U_LIB.S9S_MB_2U(SCH_1):FM_USB3_1_SWB    I40 @S9S_MB_2U_LIB.S9S_MB_2U(SCH_1):PAGE162
     2    GND @S9S_MB_2U_LIB.S9S_MB_2U(SCH_1):GND    I40 @S9S_MB_2U_LIB.S9S_MB_2U(SCH_1):PAGE162

R4287 Q_RES_0402LF-1K,1%,1/16W,EMPTYA
     1 P3V3_AUX @S9S_MB_2U_LIB.S9S_MB_2U(SCH_1):P3V3_AUX    I49 @S9S_MB_2U_LIB.S9S_MB_2U(SCH_1):PAGE162
     2 FM_USB3_1_SWA @S9S_MB_2U_LIB.S9S_MB_2U(SCH_1):FM_USB3_1_SWA    I49 @S9S_MB_2U_LIB.S9S_MB_2U(SCH_1):PAGE162

R4288 Q_RES_0402LF-1K,1%,1/16W,EMPTYA
     1 FM_USB3_1_SWA @S9S_MB_2U_LIB.S9S_MB_2U(SCH_1):FM_USB3_1_SWA    I48 @S9S_MB_2U_LIB.S9S_MB_2U(SCH_1):PAGE162
     2    GND @S9S_MB_2U_LIB.S9S_MB_2U(SCH_1):GND    I48 @S9S_MB_2U_LIB.S9S_MB_2U(SCH_1):PAGE162

R4289 Q_RES_0402LF-4.7K,1%,1/16W,EMPA
     1 P3V3_AUX @S9S_MB_2U_LIB.S9S_MB_2U(SCH_1):P3V3_AUX    I69 @S9S_MB_2U_LIB.S9S_MB_2U(SCH_1):PAGE162
     2 FM_USB3_1_RXDET_EN @S9S_MB_2U_LIB.S9S_MB_2U(SCH_1):FM_USB3_1_RXDET_EN    I69 @S9S_MB_2U_LIB.S9S_MB_2U(SCH_1):PAGE162

R4290 Q_RES_0402LF-4.7K,1%,1/16W,EMPA
     1 FM_USB3_1_RXDET_EN @S9S_MB_2U_LIB.S9S_MB_2U(SCH_1):FM_USB3_1_RXDET_EN    I68 @S9S_MB_2U_LIB.S9S_MB_2U(SCH_1):PAGE162
     2    GND @S9S_MB_2U_LIB.S9S_MB_2U(SCH_1):GND    I68 @S9S_MB_2U_LIB.S9S_MB_2U(SCH_1):PAGE162

R4291 Q_RES_0402LF-4.7K,1%,1/16W,EMPA
     1 P3V3_AUX @S9S_MB_2U_LIB.S9S_MB_2U(SCH_1):P3V3_AUX    I65 @S9S_MB_2U_LIB.S9S_MB_2U(SCH_1):PAGE162
     2 FM_USB3_1_EN_N @S9S_MB_2U_LIB.S9S_MB_2U(SCH_1):FM_USB3_1_EN_N    I65 @S9S_MB_2U_LIB.S9S_MB_2U(SCH_1):PAGE162

R4292 Q_RES_0402LF-4.7K,1%,1/16W,EMPA
     1 FM_USB3_1_EN_N @S9S_MB_2U_LIB.S9S_MB_2U(SCH_1):FM_USB3_1_EN_N    I63 @S9S_MB_2U_LIB.S9S_MB_2U(SCH_1):PAGE162
     2    GND @S9S_MB_2U_LIB.S9S_MB_2U(SCH_1):GND    I63 @S9S_MB_2U_LIB.S9S_MB_2U(SCH_1):PAGE162

R4293 Q_RES_0402LF-100,1%,1/16W,CHIPA
     1 H_CPU0_MEMHOT_IN_LVC1_R1_N @S9S_MB_2U_LIB.S9S_MB_2U(SCH_1):H_CPU0_MEMHOT_IN_LVC1_R1_N    I34 @S9S_MB_2U_LIB.S9S_MB_2U(SCH_1):PAGE122
     2 H_CPU0_MEMHOT_IN_LVC1_N @S9S_MB_2U_LIB.S9S_MB_2U(SCH_1):H_CPU0_MEMHOT_IN_LVC1_N    I34 @S9S_MB_2U_LIB.S9S_MB_2U(SCH_1):PAGE122

R4294 Q_RES_0402LF-100,1%,1/16W,CHIPA
     1 H_CPU1_MEMHOT_IN_LVC1_R1_N @S9S_MB_2U_LIB.S9S_MB_2U(SCH_1):H_CPU1_MEMHOT_IN_LVC1_R1_N    I33 @S9S_MB_2U_LIB.S9S_MB_2U(SCH_1):PAGE122
     2 H_CPU1_MEMHOT_IN_LVC1_N @S9S_MB_2U_LIB.S9S_MB_2U(SCH_1):H_CPU1_MEMHOT_IN_LVC1_N    I33 @S9S_MB_2U_LIB.S9S_MB_2U(SCH_1):PAGE122

R4295 Q_RES_0402LF-100,1%,1/16W,CHIPA
     1 PWRGD_DRAMPWRGD_CPU0_AB_LVC1_R2 @S9S_MB_2U_LIB.S9S_MB_2U(SCH_1):PWRGD_DRAMPWRGD_CPU0_AB_LVC1_R2    I87 @S9S_MB_2U_LIB.S9S_MB_2U(SCH_1):PAGE124
     2 PWRGD_DRAMPWRGD_CPU0_AB_LVC1_R @S9S_MB_2U_LIB.S9S_MB_2U(SCH_1):PWRGD_DRAMPWRGD_CPU0_AB_LVC1_R    I87 @S9S_MB_2U_LIB.S9S_MB_2U(SCH_1):PAGE124

R4296 Q_RES_0402LF-100,1%,1/16W,CHIPA
     1 PWRGD_DRAMPWRGD_CPU0_CD_LVC1_R2 @S9S_MB_2U_LIB.S9S_MB_2U(SCH_1):PWRGD_DRAMPWRGD_CPU0_CD_LVC1_R2    I85 @S9S_MB_2U_LIB.S9S_MB_2U(SCH_1):PAGE124
     2 PWRGD_DRAMPWRGD_CPU0_CD_LVC1_R @S9S_MB_2U_LIB.S9S_MB_2U(SCH_1):PWRGD_DRAMPWRGD_CPU0_CD_LVC1_R    I85 @S9S_MB_2U_LIB.S9S_MB_2U(SCH_1):PAGE124

R4297 Q_RES_0402LF-100,1%,1/16W,CHIPA
     1 PWRGD_DRAMPWRGD_CPU0_EF_LVC1_R2 @S9S_MB_2U_LIB.S9S_MB_2U(SCH_1):PWRGD_DRAMPWRGD_CPU0_EF_LVC1_R2    I82 @S9S_MB_2U_LIB.S9S_MB_2U(SCH_1):PAGE124
     2 PWRGD_DRAMPWRGD_CPU0_EF_LVC1_R @S9S_MB_2U_LIB.S9S_MB_2U(SCH_1):PWRGD_DRAMPWRGD_CPU0_EF_LVC1_R    I82 @S9S_MB_2U_LIB.S9S_MB_2U(SCH_1):PAGE124

R4298 Q_RES_0402LF-100,1%,1/16W,CHIPA
     1 PWRGD_DRAMPWRGD_CPU0_GH_LVC1_R2 @S9S_MB_2U_LIB.S9S_MB_2U(SCH_1):PWRGD_DRAMPWRGD_CPU0_GH_LVC1_R2    I79 @S9S_MB_2U_LIB.S9S_MB_2U(SCH_1):PAGE124
     2 PWRGD_DRAMPWRGD_CPU0_GH_LVC1_R @S9S_MB_2U_LIB.S9S_MB_2U(SCH_1):PWRGD_DRAMPWRGD_CPU0_GH_LVC1_R    I79 @S9S_MB_2U_LIB.S9S_MB_2U(SCH_1):PAGE124

R4299 Q_RES_0402LF-100,1%,1/16W,CHIPA
     1 PWRGD_DRAMPWRGD_CPU1_AB_LVC1_R2 @S9S_MB_2U_LIB.S9S_MB_2U(SCH_1):PWRGD_DRAMPWRGD_CPU1_AB_LVC1_R2    I72 @S9S_MB_2U_LIB.S9S_MB_2U(SCH_1):PAGE125
     2 PWRGD_DRAMPWRGD_CPU1_AB_LVC1_R @S9S_MB_2U_LIB.S9S_MB_2U(SCH_1):PWRGD_DRAMPWRGD_CPU1_AB_LVC1_R    I72 @S9S_MB_2U_LIB.S9S_MB_2U(SCH_1):PAGE125

R4300 Q_RES_0402LF-100,1%,1/16W,CHIPA
     1 PWRGD_DRAMPWRGD_CPU1_CD_LVC1_R2 @S9S_MB_2U_LIB.S9S_MB_2U(SCH_1):PWRGD_DRAMPWRGD_CPU1_CD_LVC1_R2    I70 @S9S_MB_2U_LIB.S9S_MB_2U(SCH_1):PAGE125
     2 PWRGD_DRAMPWRGD_CPU1_CD_LVC1_R @S9S_MB_2U_LIB.S9S_MB_2U(SCH_1):PWRGD_DRAMPWRGD_CPU1_CD_LVC1_R    I70 @S9S_MB_2U_LIB.S9S_MB_2U(SCH_1):PAGE125

R4301 Q_RES_0402LF-100,1%,1/16W,CHIPA
     1 PWRGD_DRAMPWRGD_CPU1_EF_LVC1_R2 @S9S_MB_2U_LIB.S9S_MB_2U(SCH_1):PWRGD_DRAMPWRGD_CPU1_EF_LVC1_R2    I68 @S9S_MB_2U_LIB.S9S_MB_2U(SCH_1):PAGE125
     2 PWRGD_DRAMPWRGD_CPU1_EF_LVC1_R @S9S_MB_2U_LIB.S9S_MB_2U(SCH_1):PWRGD_DRAMPWRGD_CPU1_EF_LVC1_R    I68 @S9S_MB_2U_LIB.S9S_MB_2U(SCH_1):PAGE125

R4302 Q_RES_0402LF-100,1%,1/16W,CHIPA
     1 PWRGD_DRAMPWRGD_CPU1_GH_LVC1_R2 @S9S_MB_2U_LIB.S9S_MB_2U(SCH_1):PWRGD_DRAMPWRGD_CPU1_GH_LVC1_R2    I66 @S9S_MB_2U_LIB.S9S_MB_2U(SCH_1):PAGE125
     2 PWRGD_DRAMPWRGD_CPU1_GH_LVC1_R @S9S_MB_2U_LIB.S9S_MB_2U(SCH_1):PWRGD_DRAMPWRGD_CPU1_GH_LVC1_R    I66 @S9S_MB_2U_LIB.S9S_MB_2U(SCH_1):PAGE125

R4303 Q_RES_0402LF-22,1%,1/16W,CHIP,A
     1 CLK_100M_E1S_0_R_DP @S9S_MB_2U_LIB.S9S_MB_2U(SCH_1):CLK_100M_E1S_0_R_DP   I121 @S9S_MB_2U_LIB.S9S_MB_2U(SCH_1):PAGE171
     2 CLK_100M_E1S_0_DP @S9S_MB_2U_LIB.S9S_MB_2U(SCH_1):CLK_100M_E1S_0_DP   I121 @S9S_MB_2U_LIB.S9S_MB_2U(SCH_1):PAGE171

R4304 Q_RES_0402LF-22,1%,1/16W,CHIP,A
     1 CLK_100M_E1S_0_R_DN @S9S_MB_2U_LIB.S9S_MB_2U(SCH_1):CLK_100M_E1S_0_R_DN   I122 @S9S_MB_2U_LIB.S9S_MB_2U(SCH_1):PAGE171
     2 CLK_100M_E1S_0_DN @S9S_MB_2U_LIB.S9S_MB_2U(SCH_1):CLK_100M_E1S_0_DN   I122 @S9S_MB_2U_LIB.S9S_MB_2U(SCH_1):PAGE171

R4305 Q_RES_0402LF-0,5%,1/16W,CHIP,CA
     1 CLK_100M_PE_M2_0_R_DP @S9S_MB_2U_LIB.S9S_MB_2U(SCH_1):CLK_100M_PE_M2_0_R_DP   I116 @S9S_MB_2U_LIB.S9S_MB_2U(SCH_1):PAGE171
     2 CLK_100M_PE_M2_0_DP @S9S_MB_2U_LIB.S9S_MB_2U(SCH_1):CLK_100M_PE_M2_0_DP   I116 @S9S_MB_2U_LIB.S9S_MB_2U(SCH_1):PAGE171

R4306 Q_RES_0402LF-0,5%,1/16W,CHIP,CA
     1 CLK_100M_PE_M2_0_R_DN @S9S_MB_2U_LIB.S9S_MB_2U(SCH_1):CLK_100M_PE_M2_0_R_DN   I117 @S9S_MB_2U_LIB.S9S_MB_2U(SCH_1):PAGE171
     2 CLK_100M_PE_M2_0_DN @S9S_MB_2U_LIB.S9S_MB_2U(SCH_1):CLK_100M_PE_M2_0_DN   I117 @S9S_MB_2U_LIB.S9S_MB_2U(SCH_1):PAGE171

R4388 Q_RES_0402LF-150,1%,1/16W,CHIPA
     1 PVNN_TERM_CPU0 @S9S_MB_2U_LIB.S9S_MB_2U(SCH_1):PVNN_TERM_CPU0   I174 @S9S_MB_2U_LIB.S9S_MB_2U(SCH_1):PAGE322
     2 H_CPU_ERR1_LVC1_R_N @S9S_MB_2U_LIB.S9S_MB_2U(SCH_1):H_CPU_ERR1_LVC1_R_N   I174 @S9S_MB_2U_LIB.S9S_MB_2U(SCH_1):PAGE322

R4389 Q_RES_0402LF-150,1%,1/16W,CHIPA
     1 PVNN_TERM_CPU0 @S9S_MB_2U_LIB.S9S_MB_2U(SCH_1):PVNN_TERM_CPU0   I177 @S9S_MB_2U_LIB.S9S_MB_2U(SCH_1):PAGE322
     2 H_CPU_ERR2_LVC1_R_N @S9S_MB_2U_LIB.S9S_MB_2U(SCH_1):H_CPU_ERR2_LVC1_R_N   I177 @S9S_MB_2U_LIB.S9S_MB_2U(SCH_1):PAGE322

R4390 Q_RES_0402LF-150,1%,1/16W,CHIPA
     1 PVNN_TERM_CPU0 @S9S_MB_2U_LIB.S9S_MB_2U(SCH_1):PVNN_TERM_CPU0   I169 @S9S_MB_2U_LIB.S9S_MB_2U(SCH_1):PAGE322
     2 H_CPU_ERR0_LVC1_R_N @S9S_MB_2U_LIB.S9S_MB_2U(SCH_1):H_CPU_ERR0_LVC1_R_N   I169 @S9S_MB_2U_LIB.S9S_MB_2U(SCH_1):PAGE322

R4391 Q_RES_0402LF-150,1%,1/16W,CHIPA
     1 PD_GTL2014_ERROR_B0 @S9S_MB_2U_LIB.S9S_MB_2U(SCH_1):PD_GTL2014_ERROR_B0   I190 @S9S_MB_2U_LIB.S9S_MB_2U(SCH_1):PAGE322
     2    GND @S9S_MB_2U_LIB.S9S_MB_2U(SCH_1):GND   I190 @S9S_MB_2U_LIB.S9S_MB_2U(SCH_1):PAGE322

R4392 Q_RES_0402LF-33.2,1%,1/16W,CHIA
     1 H_CPU_ERR0_LVC2_R_N @S9S_MB_2U_LIB.S9S_MB_2U(SCH_1):H_CPU_ERR0_LVC2_R_N   I183 @S9S_MB_2U_LIB.S9S_MB_2U(SCH_1):PAGE322
     2 H_CPU_ERR0_PCH_R_N @S9S_MB_2U_LIB.S9S_MB_2U(SCH_1):H_CPU_ERR0_PCH_R_N   I183 @S9S_MB_2U_LIB.S9S_MB_2U(SCH_1):PAGE322

R4393 Q_RES_0402LF-33.2,1%,1/16W,CHIA
     1 H_CPU_ERR1_LVC2_R_N @S9S_MB_2U_LIB.S9S_MB_2U(SCH_1):H_CPU_ERR1_LVC2_R_N   I188 @S9S_MB_2U_LIB.S9S_MB_2U(SCH_1):PAGE322
     2 H_CPU_ERR1_PCH_R_N @S9S_MB_2U_LIB.S9S_MB_2U(SCH_1):H_CPU_ERR1_PCH_R_N   I188 @S9S_MB_2U_LIB.S9S_MB_2U(SCH_1):PAGE322

R4394 Q_RES_0402LF-33.2,1%,1/16W,CHIA
     1 H_CPU_ERR2_LVC2_R_N @S9S_MB_2U_LIB.S9S_MB_2U(SCH_1):H_CPU_ERR2_LVC2_R_N   I189 @S9S_MB_2U_LIB.S9S_MB_2U(SCH_1):PAGE322
     2 H_CPU_ERR2_PCH_R_N @S9S_MB_2U_LIB.S9S_MB_2U(SCH_1):H_CPU_ERR2_PCH_R_N   I189 @S9S_MB_2U_LIB.S9S_MB_2U(SCH_1):PAGE322

R4395 Q_RES_0402LF-100,1%,1/16W,CHIPA
     1 PVNN_TERM_CPU0 @S9S_MB_2U_LIB.S9S_MB_2U(SCH_1):PVNN_TERM_CPU0    I13 @S9S_MB_2U_LIB.S9S_MB_2U(SCH_1):PAGE121
     2 H_CPU0_THERMTRIP_LVC1_R_N @S9S_MB_2U_LIB.S9S_MB_2U(SCH_1):H_CPU0_THERMTRIP_LVC1_R_N    I13 @S9S_MB_2U_LIB.S9S_MB_2U(SCH_1):PAGE121

R4396 Q_RES_0402LF-100,1%,1/16W,CHIPA
     1 PVNN_TERM_CPU1 @S9S_MB_2U_LIB.S9S_MB_2U(SCH_1):PVNN_TERM_CPU1     I4 @S9S_MB_2U_LIB.S9S_MB_2U(SCH_1):PAGE121
     2 H_CPU1_THERMTRIP_LVC1_R_N @S9S_MB_2U_LIB.S9S_MB_2U(SCH_1):H_CPU1_THERMTRIP_LVC1_R_N     I4 @S9S_MB_2U_LIB.S9S_MB_2U(SCH_1):PAGE121

R4397 Q_RES_0402LF-1.5K,1%,1/16W,CHIA
     1 H_CPU0_THERMTRIP_N @S9S_MB_2U_LIB.S9S_MB_2U(SCH_1):H_CPU0_THERMTRIP_N    I16 @S9S_MB_2U_LIB.S9S_MB_2U(SCH_1):PAGE121
     2 H_CPU0_THERMTRIP_R_N @S9S_MB_2U_LIB.S9S_MB_2U(SCH_1):H_CPU0_THERMTRIP_R_N    I16 @S9S_MB_2U_LIB.S9S_MB_2U(SCH_1):PAGE121

R4398 Q_RES_0402LF-1.5K,1%,1/16W,CHIA
     1 H_CPU1_THERMTRIP_N @S9S_MB_2U_LIB.S9S_MB_2U(SCH_1):H_CPU1_THERMTRIP_N    I10 @S9S_MB_2U_LIB.S9S_MB_2U(SCH_1):PAGE121
     2 H_CPU1_THERMTRIP_R_N @S9S_MB_2U_LIB.S9S_MB_2U(SCH_1):H_CPU1_THERMTRIP_R_N    I10 @S9S_MB_2U_LIB.S9S_MB_2U(SCH_1):PAGE121

R4399 Q_RES_0402LF-33.2,1%,1/16W,CHIA
     1 H_CPU0_THERMTRIP_VT_N @S9S_MB_2U_LIB.S9S_MB_2U(SCH_1):H_CPU0_THERMTRIP_VT_N    I35 @S9S_MB_2U_LIB.S9S_MB_2U(SCH_1):PAGE121
     2 H_CPU0_THERMTRIP_LVC1_N @S9S_MB_2U_LIB.S9S_MB_2U(SCH_1):H_CPU0_THERMTRIP_LVC1_N    I35 @S9S_MB_2U_LIB.S9S_MB_2U(SCH_1):PAGE121

R4400 Q_RES_0402LF-33.2,1%,1/16W,CHIA
     1 H_CPU1_THERMTRIP_VT_N @S9S_MB_2U_LIB.S9S_MB_2U(SCH_1):H_CPU1_THERMTRIP_VT_N    I29 @S9S_MB_2U_LIB.S9S_MB_2U(SCH_1):PAGE121
     2 H_CPU1_THERMTRIP_LVC1_N @S9S_MB_2U_LIB.S9S_MB_2U(SCH_1):H_CPU1_THERMTRIP_LVC1_N    I29 @S9S_MB_2U_LIB.S9S_MB_2U(SCH_1):PAGE121

R4401 Q_RES_0402LF-100,1%,1/16W,CHIPA
     1 PVNN_TERM_CPU0 @S9S_MB_2U_LIB.S9S_MB_2U(SCH_1):PVNN_TERM_CPU0     I8 @S9S_MB_2U_LIB.S9S_MB_2U(SCH_1):PAGE122
     2 H_CPU0_MEMHOT_OUT_LVC1_R_N @S9S_MB_2U_LIB.S9S_MB_2U(SCH_1):H_CPU0_MEMHOT_OUT_LVC1_R_N     I8 @S9S_MB_2U_LIB.S9S_MB_2U(SCH_1):PAGE122

R4402 Q_RES_0402LF-100,1%,1/16W,CHIPA
     1 PVNN_TERM_CPU1 @S9S_MB_2U_LIB.S9S_MB_2U(SCH_1):PVNN_TERM_CPU1     I5 @S9S_MB_2U_LIB.S9S_MB_2U(SCH_1):PAGE122
     2 H_CPU1_MEMHOT_OUT_LVC1_R_N @S9S_MB_2U_LIB.S9S_MB_2U(SCH_1):H_CPU1_MEMHOT_OUT_LVC1_R_N     I5 @S9S_MB_2U_LIB.S9S_MB_2U(SCH_1):PAGE122

R4403 Q_RES_0402LF-1.5K,1%,1/16W,CHIA
     1 H_CPU0_MEMHOT_OUT @S9S_MB_2U_LIB.S9S_MB_2U(SCH_1):H_CPU0_MEMHOT_OUT    I21 @S9S_MB_2U_LIB.S9S_MB_2U(SCH_1):PAGE122
     2 H_CPU0_MEMHOT_OUT_R @S9S_MB_2U_LIB.S9S_MB_2U(SCH_1):H_CPU0_MEMHOT_OUT_R    I21 @S9S_MB_2U_LIB.S9S_MB_2U(SCH_1):PAGE122

R4404 Q_RES_0402LF-1.5K,1%,1/16W,CHIA
     1 H_CPU1_MEMHOT_OUT @S9S_MB_2U_LIB.S9S_MB_2U(SCH_1):H_CPU1_MEMHOT_OUT    I20 @S9S_MB_2U_LIB.S9S_MB_2U(SCH_1):PAGE122
     2 H_CPU1_MEMHOT_OUT_R @S9S_MB_2U_LIB.S9S_MB_2U(SCH_1):H_CPU1_MEMHOT_OUT_R    I20 @S9S_MB_2U_LIB.S9S_MB_2U(SCH_1):PAGE122

R4405 Q_RES_0402LF-4.75K,1%,1/16W,CHA
     1   P3V3 @S9S_MB_2U_LIB.S9S_MB_2U(SCH_1):P3V3    I27 @S9S_MB_2U_LIB.S9S_MB_2U(SCH_1):PAGE122
     2 H_CPU0_MEMHOT_OUT_VT_N @S9S_MB_2U_LIB.S9S_MB_2U(SCH_1):H_CPU0_MEMHOT_OUT_VT_N    I27 @S9S_MB_2U_LIB.S9S_MB_2U(SCH_1):PAGE122

R4406 Q_RES_0402LF-4.75K,1%,1/16W,CHA
     1   P3V3 @S9S_MB_2U_LIB.S9S_MB_2U(SCH_1):P3V3    I24 @S9S_MB_2U_LIB.S9S_MB_2U(SCH_1):PAGE122
     2 H_CPU1_MEMHOT_OUT_VT_N @S9S_MB_2U_LIB.S9S_MB_2U(SCH_1):H_CPU1_MEMHOT_OUT_VT_N    I24 @S9S_MB_2U_LIB.S9S_MB_2U(SCH_1):PAGE122

R4407 Q_RES_0402LF-33.2,1%,1/16W,CHIA
     1 H_CPU0_MEMHOT_OUT_VT_N @S9S_MB_2U_LIB.S9S_MB_2U(SCH_1):H_CPU0_MEMHOT_OUT_VT_N    I31 @S9S_MB_2U_LIB.S9S_MB_2U(SCH_1):PAGE122
     2 H_CPU0_MEMHOT_OUT_LVC1_N @S9S_MB_2U_LIB.S9S_MB_2U(SCH_1):H_CPU0_MEMHOT_OUT_LVC1_N    I31 @S9S_MB_2U_LIB.S9S_MB_2U(SCH_1):PAGE122

R4408 Q_RES_0402LF-33.2,1%,1/16W,CHIA
     1 H_CPU1_MEMHOT_OUT_VT_N @S9S_MB_2U_LIB.S9S_MB_2U(SCH_1):H_CPU1_MEMHOT_OUT_VT_N    I18 @S9S_MB_2U_LIB.S9S_MB_2U(SCH_1):PAGE122
     2 H_CPU1_MEMHOT_OUT_LVC1_N @S9S_MB_2U_LIB.S9S_MB_2U(SCH_1):H_CPU1_MEMHOT_OUT_LVC1_N    I18 @S9S_MB_2U_LIB.S9S_MB_2U(SCH_1):PAGE122

R4409 Q_RES_0402LF-1.5K,1%,1/16W,CHIA
     1 H_CPU0_MEMTRIP @S9S_MB_2U_LIB.S9S_MB_2U(SCH_1):H_CPU0_MEMTRIP    I15 @S9S_MB_2U_LIB.S9S_MB_2U(SCH_1):PAGE123
     2 H_CPU0_MEMTRIP_R @S9S_MB_2U_LIB.S9S_MB_2U(SCH_1):H_CPU0_MEMTRIP_R    I15 @S9S_MB_2U_LIB.S9S_MB_2U(SCH_1):PAGE123

R4410 Q_RES_0402LF-1.5K,1%,1/16W,CHIA
     1 H_CPU1_MEMTRIP @S9S_MB_2U_LIB.S9S_MB_2U(SCH_1):H_CPU1_MEMTRIP    I14 @S9S_MB_2U_LIB.S9S_MB_2U(SCH_1):PAGE123
     2 H_CPU1_MEMTRIP_R @S9S_MB_2U_LIB.S9S_MB_2U(SCH_1):H_CPU1_MEMTRIP_R    I14 @S9S_MB_2U_LIB.S9S_MB_2U(SCH_1):PAGE123

R4411 Q_RES_0402LF-4.75K,1%,1/16W,CHA
     1   P3V3 @S9S_MB_2U_LIB.S9S_MB_2U(SCH_1):P3V3    I32 @S9S_MB_2U_LIB.S9S_MB_2U(SCH_1):PAGE123
     2 H_CPU0_MEMTRIP_VT_N @S9S_MB_2U_LIB.S9S_MB_2U(SCH_1):H_CPU0_MEMTRIP_VT_N    I32 @S9S_MB_2U_LIB.S9S_MB_2U(SCH_1):PAGE123

R4412 Q_RES_0402LF-4.75K,1%,1/16W,CHA
     1   P3V3 @S9S_MB_2U_LIB.S9S_MB_2U(SCH_1):P3V3    I29 @S9S_MB_2U_LIB.S9S_MB_2U(SCH_1):PAGE123
     2 H_CPU1_MEMTRIP_VT_N @S9S_MB_2U_LIB.S9S_MB_2U(SCH_1):H_CPU1_MEMTRIP_VT_N    I29 @S9S_MB_2U_LIB.S9S_MB_2U(SCH_1):PAGE123

R4413 Q_RES_0402LF-33.2,1%,1/16W,CHIA
     1 H_CPU0_MEMTRIP_VT_N @S9S_MB_2U_LIB.S9S_MB_2U(SCH_1):H_CPU0_MEMTRIP_VT_N    I33 @S9S_MB_2U_LIB.S9S_MB_2U(SCH_1):PAGE123
     2 H_CPU0_MEMTRIP_LVC1_N @S9S_MB_2U_LIB.S9S_MB_2U(SCH_1):H_CPU0_MEMTRIP_LVC1_N    I33 @S9S_MB_2U_LIB.S9S_MB_2U(SCH_1):PAGE123

R4414 Q_RES_0402LF-33.2,1%,1/16W,CHIA
     1 H_CPU1_MEMTRIP_VT_N @S9S_MB_2U_LIB.S9S_MB_2U(SCH_1):H_CPU1_MEMTRIP_VT_N    I31 @S9S_MB_2U_LIB.S9S_MB_2U(SCH_1):PAGE123
     2 H_CPU1_MEMTRIP_LVC1_N @S9S_MB_2U_LIB.S9S_MB_2U(SCH_1):H_CPU1_MEMTRIP_LVC1_N    I31 @S9S_MB_2U_LIB.S9S_MB_2U(SCH_1):PAGE123

R4419 Q_RES_0402LF-49.9,1%,1/16W,EMPA
     1 USB2_HOST_BMC_B_DP @S9S_MB_2U_LIB.S9S_MB_2U(SCH_1):USB2_HOST_BMC_B_DP   I203 @S9S_MB_2U_LIB.S9S_MB_2U(SCH_1):PAGE155
     2    GND @S9S_MB_2U_LIB.S9S_MB_2U(SCH_1):GND   I203 @S9S_MB_2U_LIB.S9S_MB_2U(SCH_1):PAGE155

R4420 Q_RES_0402LF-49.9,1%,1/16W,EMPA
     1 USB2_HOST_BMC_B_DN @S9S_MB_2U_LIB.S9S_MB_2U(SCH_1):USB2_HOST_BMC_B_DN   I202 @S9S_MB_2U_LIB.S9S_MB_2U(SCH_1):PAGE155
     2    GND @S9S_MB_2U_LIB.S9S_MB_2U(SCH_1):GND   I202 @S9S_MB_2U_LIB.S9S_MB_2U(SCH_1):PAGE155

R4448 Q_RES_0402LF-10K,1%,1/16W,EMPTA
     1 P3V3_AUX @S9S_MB_2U_LIB.S9S_MB_2U(SCH_1):P3V3_AUX     I9 @S9S_MB_2U_LIB.S9S_MB_2U(SCH_1):PAGE194
     2 USB_HUB_2_PSELF @S9S_MB_2U_LIB.S9S_MB_2U(SCH_1):USB_HUB_2_PSELF     I9 @S9S_MB_2U_LIB.S9S_MB_2U(SCH_1):PAGE194

R4449 Q_RES_0402LF-10K,1%,1/16W,EMPTA
     1 USB_HUB_2_PSELF @S9S_MB_2U_LIB.S9S_MB_2U(SCH_1):USB_HUB_2_PSELF     I8 @S9S_MB_2U_LIB.S9S_MB_2U(SCH_1):PAGE194
     2    GND @S9S_MB_2U_LIB.S9S_MB_2U(SCH_1):GND     I8 @S9S_MB_2U_LIB.S9S_MB_2U(SCH_1):PAGE194

R4450 Q_RES_0402LF-0,5%,1/16W,EMPTY,A
     1 P3V3_AUX @S9S_MB_2U_LIB.S9S_MB_2U(SCH_1):P3V3_AUX    I41 @S9S_MB_2U_LIB.S9S_MB_2U(SCH_1):PAGE194
     2 P3V3_AUX_USB_HUB_2 @S9S_MB_2U_LIB.S9S_MB_2U(SCH_1):P3V3_AUX_USB_HUB_2    I41 @S9S_MB_2U_LIB.S9S_MB_2U(SCH_1):PAGE194

R4451 Q_RES_0402LF-33.2,1%,1/16W,EMPA
     1 RST_USB_HUB_N @S9S_MB_2U_LIB.S9S_MB_2U(SCH_1):RST_USB_HUB_N    I13 @S9S_MB_2U_LIB.S9S_MB_2U(SCH_1):PAGE194
     2 RST_USB_HUB_2_R_N @S9S_MB_2U_LIB.S9S_MB_2U(SCH_1):RST_USB_HUB_2_R_N    I13 @S9S_MB_2U_LIB.S9S_MB_2U(SCH_1):PAGE194

R4452 Q_RES_0402LF-10K,1%,1/16W,EMPTA
     1 P3V3_AUX @S9S_MB_2U_LIB.S9S_MB_2U(SCH_1):P3V3_AUX    I27 @S9S_MB_2U_LIB.S9S_MB_2U(SCH_1):PAGE194
     2 RST_USB_HUB_2_R_N @S9S_MB_2U_LIB.S9S_MB_2U(SCH_1):RST_USB_HUB_2_R_N    I27 @S9S_MB_2U_LIB.S9S_MB_2U(SCH_1):PAGE194

R4453 Q_RES_0402LF-47K,0.1%,1/16W,EMA
     1    GND @S9S_MB_2U_LIB.S9S_MB_2U(SCH_1):GND    I26 @S9S_MB_2U_LIB.S9S_MB_2U(SCH_1):PAGE194
     2 RST_USB_HUB_2_R_N @S9S_MB_2U_LIB.S9S_MB_2U(SCH_1):RST_USB_HUB_2_R_N    I26 @S9S_MB_2U_LIB.S9S_MB_2U(SCH_1):PAGE194

R4454 Q_RES_0402LF-0,5%,1/16W,EMPTY,A
     1 USB2_HUB_2_EXT_DP @S9S_MB_2U_LIB.S9S_MB_2U(SCH_1):USB2_HUB_2_EXT_DP    I17 @S9S_MB_2U_LIB.S9S_MB_2U(SCH_1):PAGE194
     2 USB2_HUB_2_BUF_EXT_R_DP @S9S_MB_2U_LIB.S9S_MB_2U(SCH_1):USB2_HUB_2_BUF_EXT_R_DP    I17 @S9S_MB_2U_LIB.S9S_MB_2U(SCH_1):PAGE194

R4455 Q_RES_0402LF-0,5%,1/16W,EMPTY,A
     1 USB2_HUB_2_EXT_DN @S9S_MB_2U_LIB.S9S_MB_2U(SCH_1):USB2_HUB_2_EXT_DN    I16 @S9S_MB_2U_LIB.S9S_MB_2U(SCH_1):PAGE194
     2 USB2_HUB_2_BUF_EXT_R_DN @S9S_MB_2U_LIB.S9S_MB_2U(SCH_1):USB2_HUB_2_BUF_EXT_R_DN    I16 @S9S_MB_2U_LIB.S9S_MB_2U(SCH_1):PAGE194

R4456 Q_RES_0402LF-10K,1%,1/16W,EMPTA
     1 P3V3_AUX @S9S_MB_2U_LIB.S9S_MB_2U(SCH_1):P3V3_AUX    I25 @S9S_MB_2U_LIB.S9S_MB_2U(SCH_1):PAGE194
     2 USB_HUB_2_OVCUR1 @S9S_MB_2U_LIB.S9S_MB_2U(SCH_1):USB_HUB_2_OVCUR1    I25 @S9S_MB_2U_LIB.S9S_MB_2U(SCH_1):PAGE194

R4457 Q_RES_0402LF-10K,1%,1/16W,EMPTA
     1 P3V3_AUX @S9S_MB_2U_LIB.S9S_MB_2U(SCH_1):P3V3_AUX    I24 @S9S_MB_2U_LIB.S9S_MB_2U(SCH_1):PAGE194
     2 USB_HUB_2_OVCUR2 @S9S_MB_2U_LIB.S9S_MB_2U(SCH_1):USB_HUB_2_OVCUR2    I24 @S9S_MB_2U_LIB.S9S_MB_2U(SCH_1):PAGE194

R4458 Q_RES_0402LF-10K,1%,1/16W,EMPTA
     1 P3V3_AUX @S9S_MB_2U_LIB.S9S_MB_2U(SCH_1):P3V3_AUX    I23 @S9S_MB_2U_LIB.S9S_MB_2U(SCH_1):PAGE194
     2 USB_HUB_2_OVCUR3 @S9S_MB_2U_LIB.S9S_MB_2U(SCH_1):USB_HUB_2_OVCUR3    I23 @S9S_MB_2U_LIB.S9S_MB_2U(SCH_1):PAGE194

R4459 Q_RES_0402LF-10K,1%,1/16W,EMPTA
     1 P3V3_AUX @S9S_MB_2U_LIB.S9S_MB_2U(SCH_1):P3V3_AUX    I22 @S9S_MB_2U_LIB.S9S_MB_2U(SCH_1):PAGE194
     2 USB_HUB_2_OVCUR4 @S9S_MB_2U_LIB.S9S_MB_2U(SCH_1):USB_HUB_2_OVCUR4    I22 @S9S_MB_2U_LIB.S9S_MB_2U(SCH_1):PAGE194

R4460 Q_RES_0402LF-0,5%,1/16W,CHIP,CA
     1 USB2_HOST_PCH_0_DP @S9S_MB_2U_LIB.S9S_MB_2U(SCH_1):USB2_HOST_PCH_0_DP    I18 @S9S_MB_2U_LIB.S9S_MB_2U(SCH_1):PAGE194
     2 USB2_HUB_2_BUF_EXT_R_DP @S9S_MB_2U_LIB.S9S_MB_2U(SCH_1):USB2_HUB_2_BUF_EXT_R_DP    I18 @S9S_MB_2U_LIB.S9S_MB_2U(SCH_1):PAGE194

R4461 Q_RES_0402LF-0,5%,1/16W,CHIP,CA
     1 USB2_HOST_PCH_0_DN @S9S_MB_2U_LIB.S9S_MB_2U(SCH_1):USB2_HOST_PCH_0_DN    I19 @S9S_MB_2U_LIB.S9S_MB_2U(SCH_1):PAGE194
     2 USB2_HUB_2_BUF_EXT_R_DN @S9S_MB_2U_LIB.S9S_MB_2U(SCH_1):USB2_HUB_2_BUF_EXT_R_DN    I19 @S9S_MB_2U_LIB.S9S_MB_2U(SCH_1):PAGE194

R4462 Q_RES_0402LF-0,5%,1/16W,EMPTY,A
     1 P3V3_AUX_USB_HUB_2 @S9S_MB_2U_LIB.S9S_MB_2U(SCH_1):P3V3_AUX_USB_HUB_2    I50 @S9S_MB_2U_LIB.S9S_MB_2U(SCH_1):PAGE194
     2 USB_HUB_2_DVDD @S9S_MB_2U_LIB.S9S_MB_2U(SCH_1):USB_HUB_2_DVDD    I50 @S9S_MB_2U_LIB.S9S_MB_2U(SCH_1):PAGE194

R4463 Q_RES_0402LF-680,1%,1/16W,EMPTA
     1 USB_HUB_2_RREF @S9S_MB_2U_LIB.S9S_MB_2U(SCH_1):USB_HUB_2_RREF    I37 @S9S_MB_2U_LIB.S9S_MB_2U(SCH_1):PAGE194
     2    GND @S9S_MB_2U_LIB.S9S_MB_2U(SCH_1):GND    I37 @S9S_MB_2U_LIB.S9S_MB_2U(SCH_1):PAGE194

R4464 Q_RES_0402LF-100K,1%,1/16W,EMPA
     1 USB_HUB_2_PGANG @S9S_MB_2U_LIB.S9S_MB_2U(SCH_1):USB_HUB_2_PGANG    I38 @S9S_MB_2U_LIB.S9S_MB_2U(SCH_1):PAGE194
     2    GND @S9S_MB_2U_LIB.S9S_MB_2U(SCH_1):GND    I38 @S9S_MB_2U_LIB.S9S_MB_2U(SCH_1):PAGE194

R4465 Q_RES_0402LF-3.9K,5%,1/16W,EMPA
     1 PD_USB_HUB_2_EQ @S9S_MB_2U_LIB.S9S_MB_2U(SCH_1):PD_USB_HUB_2_EQ     I4 @S9S_MB_2U_LIB.S9S_MB_2U(SCH_1):PAGE194
     2    GND @S9S_MB_2U_LIB.S9S_MB_2U(SCH_1):GND     I4 @S9S_MB_2U_LIB.S9S_MB_2U(SCH_1):PAGE194

R4466 Q_RES_0402LF-0,5%,1/16W,EMPTY,A
     1 USB_HUB_2_TEST @S9S_MB_2U_LIB.S9S_MB_2U(SCH_1):USB_HUB_2_TEST    I75 @S9S_MB_2U_LIB.S9S_MB_2U(SCH_1):PAGE194
     2    GND @S9S_MB_2U_LIB.S9S_MB_2U(SCH_1):GND    I75 @S9S_MB_2U_LIB.S9S_MB_2U(SCH_1):PAGE194

R4467 Q_RES_0402LF-0,5%,1/16W,CHIP,CA
     1 USB2_HUB_2_BUF_EXT_R_DP @S9S_MB_2U_LIB.S9S_MB_2U(SCH_1):USB2_HUB_2_BUF_EXT_R_DP    I61 @S9S_MB_2U_LIB.S9S_MB_2U(SCH_1):PAGE194
     2 USB2_HUB_2_BUF_EXT_DP @S9S_MB_2U_LIB.S9S_MB_2U(SCH_1):USB2_HUB_2_BUF_EXT_DP    I61 @S9S_MB_2U_LIB.S9S_MB_2U(SCH_1):PAGE194

R4468 Q_RES_0402LF-0,5%,1/16W,CHIP,CA
     1 USB2_HUB_2_BUF_EXT_R_DN @S9S_MB_2U_LIB.S9S_MB_2U(SCH_1):USB2_HUB_2_BUF_EXT_R_DN    I60 @S9S_MB_2U_LIB.S9S_MB_2U(SCH_1):PAGE194
     2 USB2_HUB_2_BUF_EXT_DN @S9S_MB_2U_LIB.S9S_MB_2U(SCH_1):USB2_HUB_2_BUF_EXT_DN    I60 @S9S_MB_2U_LIB.S9S_MB_2U(SCH_1):PAGE194

R4471 Q_RES_0402LF-0,5%,1/16W,EMPTY,A
     1 USB2_PCH_0_R_DP @S9S_MB_2U_LIB.S9S_MB_2U(SCH_1):USB2_PCH_0_R_DP    I77 @S9S_MB_2U_LIB.S9S_MB_2U(SCH_1):PAGE194
     2 USB2_0_DP @S9S_MB_2U_LIB.S9S_MB_2U(SCH_1):USB2_0_DP    I77 @S9S_MB_2U_LIB.S9S_MB_2U(SCH_1):PAGE194

R4472 Q_RES_0402LF-0,5%,1/16W,EMPTY,A
     1 USB2_PCH_0_R_DN @S9S_MB_2U_LIB.S9S_MB_2U(SCH_1):USB2_PCH_0_R_DN    I78 @S9S_MB_2U_LIB.S9S_MB_2U(SCH_1):PAGE194
     2 USB2_0_DN @S9S_MB_2U_LIB.S9S_MB_2U(SCH_1):USB2_0_DN    I78 @S9S_MB_2U_LIB.S9S_MB_2U(SCH_1):PAGE194

R4473 Q_RES_0402LF-0,5%,1/16W,CHIP,CA
     1 USB2_0_DP @S9S_MB_2U_LIB.S9S_MB_2U(SCH_1):USB2_0_DP    I73 @S9S_MB_2U_LIB.S9S_MB_2U(SCH_1):PAGE194
     2 USB2_HOST_PCH_0_DP @S9S_MB_2U_LIB.S9S_MB_2U(SCH_1):USB2_HOST_PCH_0_DP    I73 @S9S_MB_2U_LIB.S9S_MB_2U(SCH_1):PAGE194

R4474 Q_RES_0402LF-0,5%,1/16W,CHIP,CA
     1 USB2_0_DN @S9S_MB_2U_LIB.S9S_MB_2U(SCH_1):USB2_0_DN    I72 @S9S_MB_2U_LIB.S9S_MB_2U(SCH_1):PAGE194
     2 USB2_HOST_PCH_0_DN @S9S_MB_2U_LIB.S9S_MB_2U(SCH_1):USB2_HOST_PCH_0_DN    I72 @S9S_MB_2U_LIB.S9S_MB_2U(SCH_1):PAGE194

R4475 Q_RES_0603LF-1,1%,1/10W,CHIP,CA
     1 P3V3_9ZXL045 @S9S_MB_2U_LIB.S9S_MB_2U(SCH_1):P3V3_9ZXL045    I11 @S9S_MB_2U_LIB.S9S_MB_2U(SCH_1):PAGE200
     2 P3V3_9ZXL045_VDDR @S9S_MB_2U_LIB.S9S_MB_2U(SCH_1):P3V3_9ZXL045_VDDR    I11 @S9S_MB_2U_LIB.S9S_MB_2U(SCH_1):PAGE200

R4476 Q_RES_0402LF-49.9,1%,1/16W,CHIA
     1 FM_PLD_CLKS_DEV_EN @S9S_MB_2U_LIB.S9S_MB_2U(SCH_1):FM_PLD_CLKS_DEV_EN    I39 @S9S_MB_2U_LIB.S9S_MB_2U(SCH_1):PAGE200
     2 FM_9ZXL045_DEV_EN @S9S_MB_2U_LIB.S9S_MB_2U(SCH_1):FM_9ZXL045_DEV_EN    I39 @S9S_MB_2U_LIB.S9S_MB_2U(SCH_1):PAGE200

R4477 Q_RES_0402LF-33.2,1%,1/16W,CHIA
     1 FM_9ZXL045_0_OE_N @S9S_MB_2U_LIB.S9S_MB_2U(SCH_1):FM_9ZXL045_0_OE_N    I74 @S9S_MB_2U_LIB.S9S_MB_2U(SCH_1):PAGE200
     2 CLK_SWB_BUF2_OE_N @S9S_MB_2U_LIB.S9S_MB_2U(SCH_1):CLK_SWB_BUF2_OE_N    I74 @S9S_MB_2U_LIB.S9S_MB_2U(SCH_1):PAGE200

R4478 Q_RES_0402LF-33.2,1%,1/16W,CHIA
     1 FM_9ZXL045_1_OE_N @S9S_MB_2U_LIB.S9S_MB_2U(SCH_1):FM_9ZXL045_1_OE_N    I75 @S9S_MB_2U_LIB.S9S_MB_2U(SCH_1):PAGE200
     2 CLK_GPU_1_OE_N @S9S_MB_2U_LIB.S9S_MB_2U(SCH_1):CLK_GPU_1_OE_N    I75 @S9S_MB_2U_LIB.S9S_MB_2U(SCH_1):PAGE200

R4479 Q_RES_0402LF-33.2,1%,1/16W,CHIA
     1 FM_9ZXL045_2_OE_N @S9S_MB_2U_LIB.S9S_MB_2U(SCH_1):FM_9ZXL045_2_OE_N    I76 @S9S_MB_2U_LIB.S9S_MB_2U(SCH_1):PAGE200
     2 CLK_GPU_2_OE_N @S9S_MB_2U_LIB.S9S_MB_2U(SCH_1):CLK_GPU_2_OE_N    I76 @S9S_MB_2U_LIB.S9S_MB_2U(SCH_1):PAGE200

R4480 Q_RES_0402LF-33.2,1%,1/16W,CHIA
     1 SMB_HOST_CLK_BUF_ISO_3V3AUX_SCL @S9S_MB_2U_LIB.S9S_MB_2U(SCH_1):SMB_HOST_CLK_BUF_ISO_3V3AUX_SCL    I24 @S9S_MB_2U_LIB.S9S_MB_2U(SCH_1):PAGE225
     2 SMB_HOST_9ZXL045_3V3AUX_SCL @S9S_MB_2U_LIB.S9S_MB_2U(SCH_1):SMB_HOST_9ZXL045_3V3AUX_SCL    I24 @S9S_MB_2U_LIB.S9S_MB_2U(SCH_1):PAGE225

R4481 Q_RES_0402LF-33.2,1%,1/16W,CHIA
     1 SMB_HOST_CLK_BUF_ISO_3V3AUX_SDA @S9S_MB_2U_LIB.S9S_MB_2U(SCH_1):SMB_HOST_CLK_BUF_ISO_3V3AUX_SDA    I25 @S9S_MB_2U_LIB.S9S_MB_2U(SCH_1):PAGE225
     2 SMB_HOST_9ZXL045_3V3AUX_SDA @S9S_MB_2U_LIB.S9S_MB_2U(SCH_1):SMB_HOST_9ZXL045_3V3AUX_SDA    I25 @S9S_MB_2U_LIB.S9S_MB_2U(SCH_1):PAGE225

R4482 Q_RES_0402LF-49.9,1%,1/16W,EMPA
     1 USB2_HOST_BMC_B_BUF_DP @S9S_MB_2U_LIB.S9S_MB_2U(SCH_1):USB2_HOST_BMC_B_BUF_DP   I208 @S9S_MB_2U_LIB.S9S_MB_2U(SCH_1):PAGE155
     2    GND @S9S_MB_2U_LIB.S9S_MB_2U(SCH_1):GND   I208 @S9S_MB_2U_LIB.S9S_MB_2U(SCH_1):PAGE155

R4483 Q_RES_0402LF-49.9,1%,1/16W,EMPA
     1 USB2_HOST_BMC_B_BUF_DN @S9S_MB_2U_LIB.S9S_MB_2U(SCH_1):USB2_HOST_BMC_B_BUF_DN   I206 @S9S_MB_2U_LIB.S9S_MB_2U(SCH_1):PAGE155
     2    GND @S9S_MB_2U_LIB.S9S_MB_2U(SCH_1):GND   I206 @S9S_MB_2U_LIB.S9S_MB_2U(SCH_1):PAGE155

R4486 Q_RES_0402LF-49.9,1%,1/16W,EMPA
     1 USB2_HOST_PCH_0_DP @S9S_MB_2U_LIB.S9S_MB_2U(SCH_1):USB2_HOST_PCH_0_DP    I90 @S9S_MB_2U_LIB.S9S_MB_2U(SCH_1):PAGE194
     2    GND @S9S_MB_2U_LIB.S9S_MB_2U(SCH_1):GND    I90 @S9S_MB_2U_LIB.S9S_MB_2U(SCH_1):PAGE194

R4487 Q_RES_0402LF-49.9,1%,1/16W,EMPA
     1 USB2_HOST_PCH_0_DN @S9S_MB_2U_LIB.S9S_MB_2U(SCH_1):USB2_HOST_PCH_0_DN    I88 @S9S_MB_2U_LIB.S9S_MB_2U(SCH_1):PAGE194
     2    GND @S9S_MB_2U_LIB.S9S_MB_2U(SCH_1):GND    I88 @S9S_MB_2U_LIB.S9S_MB_2U(SCH_1):PAGE194

R4489 Q_RES_0402LF-4.75K,1%,1/16W,CHA
     1   P3V3 @S9S_MB_2U_LIB.S9S_MB_2U(SCH_1):P3V3    I30 @S9S_MB_2U_LIB.S9S_MB_2U(SCH_1):PAGE200
     2 CLK_9ZXL045_SADR0 @S9S_MB_2U_LIB.S9S_MB_2U(SCH_1):CLK_9ZXL045_SADR0    I30 @S9S_MB_2U_LIB.S9S_MB_2U(SCH_1):PAGE200

R4490 Q_RES_0402LF-4.75K,1%,1/16W,EMA
     1 CLK_9ZXL045_SADR0 @S9S_MB_2U_LIB.S9S_MB_2U(SCH_1):CLK_9ZXL045_SADR0    I31 @S9S_MB_2U_LIB.S9S_MB_2U(SCH_1):PAGE200
     2    GND @S9S_MB_2U_LIB.S9S_MB_2U(SCH_1):GND    I31 @S9S_MB_2U_LIB.S9S_MB_2U(SCH_1):PAGE200

R4491 Q_RES_0402LF-10K,1%,1/16W,CHIPA
     1   P3V3 @S9S_MB_2U_LIB.S9S_MB_2U(SCH_1):P3V3    I48 @S9S_MB_2U_LIB.S9S_MB_2U(SCH_1):PAGE200
     2 CLK_9ZXL045_HIBW @S9S_MB_2U_LIB.S9S_MB_2U(SCH_1):CLK_9ZXL045_HIBW    I48 @S9S_MB_2U_LIB.S9S_MB_2U(SCH_1):PAGE200

R4492 Q_RES_0402LF-10K,1%,1/16W,CHIPA
     1 CLK_9ZXL045_HIBW @S9S_MB_2U_LIB.S9S_MB_2U(SCH_1):CLK_9ZXL045_HIBW    I49 @S9S_MB_2U_LIB.S9S_MB_2U(SCH_1):PAGE200
     2    GND @S9S_MB_2U_LIB.S9S_MB_2U(SCH_1):GND    I49 @S9S_MB_2U_LIB.S9S_MB_2U(SCH_1):PAGE200

R4493 Q_RES_0603LF-1,1%,1/10W,CHIP,CA
     1 P3V3_9ZXL045 @S9S_MB_2U_LIB.S9S_MB_2U(SCH_1):P3V3_9ZXL045     I4 @S9S_MB_2U_LIB.S9S_MB_2U(SCH_1):PAGE200
     2 P3V3_9ZXL045_VDDA @S9S_MB_2U_LIB.S9S_MB_2U(SCH_1):P3V3_9ZXL045_VDDA     I4 @S9S_MB_2U_LIB.S9S_MB_2U(SCH_1):PAGE200

R4494 Q_RES_0402LF-10K,1%,1/16W,CHIPA
     1 FM_9ZXL045_3_OE_N @S9S_MB_2U_LIB.S9S_MB_2U(SCH_1):FM_9ZXL045_3_OE_N    I69 @S9S_MB_2U_LIB.S9S_MB_2U(SCH_1):PAGE200
     2   P3V3 @S9S_MB_2U_LIB.S9S_MB_2U(SCH_1):P3V3    I69 @S9S_MB_2U_LIB.S9S_MB_2U(SCH_1):PAGE200

R4495 Q_RES_0402LF-33.2,1%,1/16W,CHIA
     1 OCP_SFF_CLK_OE_R_N @S9S_MB_2U_LIB.S9S_MB_2U(SCH_1):OCP_SFF_CLK_OE_R_N   I141 @S9S_MB_2U_LIB.S9S_MB_2U(SCH_1):PAGE314
     2 OCP_SFF_CLK_OE_N @S9S_MB_2U_LIB.S9S_MB_2U(SCH_1):OCP_SFF_CLK_OE_N   I141 @S9S_MB_2U_LIB.S9S_MB_2U(SCH_1):PAGE314

R4496 Q_RES_0402LF-33.2,1%,1/16W,CHIA
     1 SMB_HOST_CLK_BUF_ISO_3V3AUX_SCL @S9S_MB_2U_LIB.S9S_MB_2U(SCH_1):SMB_HOST_CLK_BUF_ISO_3V3AUX_SCL    I27 @S9S_MB_2U_LIB.S9S_MB_2U(SCH_1):PAGE225
     2 SMB_HOST_DB2000_3V3AUX_SCL @S9S_MB_2U_LIB.S9S_MB_2U(SCH_1):SMB_HOST_DB2000_3V3AUX_SCL    I27 @S9S_MB_2U_LIB.S9S_MB_2U(SCH_1):PAGE225

R4497 Q_RES_0402LF-33.2,1%,1/16W,CHIA
     1 SMB_HOST_CLK_BUF_ISO_3V3AUX_SDA @S9S_MB_2U_LIB.S9S_MB_2U(SCH_1):SMB_HOST_CLK_BUF_ISO_3V3AUX_SDA    I26 @S9S_MB_2U_LIB.S9S_MB_2U(SCH_1):PAGE225
     2 SMB_HOST_DB2000_3V3AUX_SDA @S9S_MB_2U_LIB.S9S_MB_2U(SCH_1):SMB_HOST_DB2000_3V3AUX_SDA    I26 @S9S_MB_2U_LIB.S9S_MB_2U(SCH_1):PAGE225

R4498 Q_RES_0402LF-4.7K,5%,1/16W,CHIA
     1   P3V3 @S9S_MB_2U_LIB.S9S_MB_2U(SCH_1):P3V3    I11 @S9S_MB_2U_LIB.S9S_MB_2U(SCH_1):PAGE225
     2 SMB_HOST_CLK_BUF_ISO_3V3AUX_S_1 @S9S_MB_2U_LIB.S9S_MB_2U(SCH_1):SMB_HOST_CLK_BUF_ISO_3V3AUX_SCL_R    I11 @S9S_MB_2U_LIB.S9S_MB_2U(SCH_1):PAGE225

R4499 Q_RES_0402LF-4.7K,5%,1/16W,CHIA
     1   P3V3 @S9S_MB_2U_LIB.S9S_MB_2U(SCH_1):P3V3    I12 @S9S_MB_2U_LIB.S9S_MB_2U(SCH_1):PAGE225
     2 SMB_HOST_CLK_BUF_ISO_3V3AUX_S_2 @S9S_MB_2U_LIB.S9S_MB_2U(SCH_1):SMB_HOST_CLK_BUF_ISO_3V3AUX_SDA_R    I12 @S9S_MB_2U_LIB.S9S_MB_2U(SCH_1):PAGE225

R4500 Q_RES_0402LF-10K,1%,1/16W,EMPTA
     1   P3V3 @S9S_MB_2U_LIB.S9S_MB_2U(SCH_1):P3V3    I32 @S9S_MB_2U_LIB.S9S_MB_2U(SCH_1):PAGE225
     2 PU_CLK_BUF_ISO_EN @S9S_MB_2U_LIB.S9S_MB_2U(SCH_1):PU_CLK_BUF_ISO_EN    I32 @S9S_MB_2U_LIB.S9S_MB_2U(SCH_1):PAGE225

R4501 Q_RES_0402LF-0,5%,1/16W,CHIP,CA
     1 CLK_GEN2_XTAL_IN_R @S9S_MB_2U_LIB.S9S_MB_2U(SCH_1):CLK_GEN2_XTAL_IN_R   I160 @S9S_MB_2U_LIB.S9S_MB_2U(SCH_1):PAGE201
     2 CLK_GEN2_XTAL_IN @S9S_MB_2U_LIB.S9S_MB_2U(SCH_1):CLK_GEN2_XTAL_IN   I160 @S9S_MB_2U_LIB.S9S_MB_2U(SCH_1):PAGE201

R4502 Q_RES_0402LF-33.2,1%,1/16W,CHIA
     1 SMB_HOST_3V3AUX_SCL_R4 @S9S_MB_2U_LIB.S9S_MB_2U(SCH_1):SMB_HOST_3V3AUX_SCL_R4   I148 @S9S_MB_2U_LIB.S9S_MB_2U(SCH_1):PAGE133
     2 SMB_HOST_3V3AUX_XDP_R_SCL @S9S_MB_2U_LIB.S9S_MB_2U(SCH_1):SMB_HOST_3V3AUX_XDP_R_SCL   I148 @S9S_MB_2U_LIB.S9S_MB_2U(SCH_1):PAGE133

R4503 Q_RES_0402LF-0,5%,1/16W,CHIP,CA
     1 SMB_HOST_3V3AUX_SDA_R4 @S9S_MB_2U_LIB.S9S_MB_2U(SCH_1):SMB_HOST_3V3AUX_SDA_R4   I153 @S9S_MB_2U_LIB.S9S_MB_2U(SCH_1):PAGE133
     2 SMB_HOST_3V3AUX_XDP_R_SDA @S9S_MB_2U_LIB.S9S_MB_2U(SCH_1):SMB_HOST_3V3AUX_XDP_R_SDA   I153 @S9S_MB_2U_LIB.S9S_MB_2U(SCH_1):PAGE133

R4504 Q_RES_0402LF-0,5%,1/16W,CHIP,CA
     1 SMB_SML1_PMBUS_3V3AUX_PCH_SDA @S9S_MB_2U_LIB.S9S_MB_2U(SCH_1):SMB_SML1_PMBUS_3V3AUX_PCH_SDA   I308 @S9S_MB_2U_LIB.S9S_MB_2U(SCH_1):PAGE175
     2 SMB_SML1_PMBUS_3V3AUX_PCH_SDA_1 @S9S_MB_2U_LIB.S9S_MB_2U(SCH_1):SMB_SML1_PMBUS_3V3AUX_PCH_SDA_R1   I308 @S9S_MB_2U_LIB.S9S_MB_2U(SCH_1):PAGE175

R4505 Q_RES_0402LF-33.2,1%,1/16W,CHIA
     1 SMB_SML1_PMBUS_3V3AUX_PCH_SCL @S9S_MB_2U_LIB.S9S_MB_2U(SCH_1):SMB_SML1_PMBUS_3V3AUX_PCH_SCL   I305 @S9S_MB_2U_LIB.S9S_MB_2U(SCH_1):PAGE175
     2 SMB_SML1_PMBUS_3V3AUX_PCH_SCL_1 @S9S_MB_2U_LIB.S9S_MB_2U(SCH_1):SMB_SML1_PMBUS_3V3AUX_PCH_SCL_R1   I305 @S9S_MB_2U_LIB.S9S_MB_2U(SCH_1):PAGE175

R4506 Q_RES_0402LF-33.2,1%,1/16W,CHIA
     1 SMB_SML0_3V3AUX_SCL @S9S_MB_2U_LIB.S9S_MB_2U(SCH_1):SMB_SML0_3V3AUX_SCL    I90 @S9S_MB_2U_LIB.S9S_MB_2U(SCH_1):PAGE227
     2 SMB_SML0_3V3AUX_SCL_R1 @S9S_MB_2U_LIB.S9S_MB_2U(SCH_1):SMB_SML0_3V3AUX_SCL_R1    I90 @S9S_MB_2U_LIB.S9S_MB_2U(SCH_1):PAGE227

R4507 Q_RES_0402LF-33.2,1%,1/16W,CHIA
     1 SMB_SML0_3V3AUX_SDA @S9S_MB_2U_LIB.S9S_MB_2U(SCH_1):SMB_SML0_3V3AUX_SDA    I89 @S9S_MB_2U_LIB.S9S_MB_2U(SCH_1):PAGE227
     2 SMB_SML0_3V3AUX_SDA_R1 @S9S_MB_2U_LIB.S9S_MB_2U(SCH_1):SMB_SML0_3V3AUX_SDA_R1    I89 @S9S_MB_2U_LIB.S9S_MB_2U(SCH_1):PAGE227

R4508 Q_RES_0402LF-33.2,1%,1/16W,CHIA
     1 SMB_1_PLD_3V3AUX_SCL @S9S_MB_2U_LIB.S9S_MB_2U(SCH_1):SMB_1_PLD_3V3AUX_SCL    I87 @S9S_MB_2U_LIB.S9S_MB_2U(SCH_1):PAGE227
     2 SMB_1_PLD_3V3AUX_SCL_R3 @S9S_MB_2U_LIB.S9S_MB_2U(SCH_1):SMB_1_PLD_3V3AUX_SCL_R3    I87 @S9S_MB_2U_LIB.S9S_MB_2U(SCH_1):PAGE227

R4509 Q_RES_0402LF-33.2,1%,1/16W,CHIA
     1 SMB_1_PLD_3V3AUX_SDA @S9S_MB_2U_LIB.S9S_MB_2U(SCH_1):SMB_1_PLD_3V3AUX_SDA    I88 @S9S_MB_2U_LIB.S9S_MB_2U(SCH_1):PAGE227
     2 SMB_1_PLD_3V3AUX_SDA_R3 @S9S_MB_2U_LIB.S9S_MB_2U(SCH_1):SMB_1_PLD_3V3AUX_SDA_R3    I88 @S9S_MB_2U_LIB.S9S_MB_2U(SCH_1):PAGE227

R4510 Q_RES_0402LF-33.2,1%,1/16W,CHIA
     1 SMB_HOST_3V3AUX_SCL @S9S_MB_2U_LIB.S9S_MB_2U(SCH_1):SMB_HOST_3V3AUX_SCL   I285 @S9S_MB_2U_LIB.S9S_MB_2U(SCH_1):PAGE228
     2 SMB_HOST_3V3AUX_SCL_R4 @S9S_MB_2U_LIB.S9S_MB_2U(SCH_1):SMB_HOST_3V3AUX_SCL_R4   I285 @S9S_MB_2U_LIB.S9S_MB_2U(SCH_1):PAGE228

R4511 Q_RES_0402LF-0,5%,1/16W,CHIP,CA
     1 SMB_HOST_3V3AUX_SDA @S9S_MB_2U_LIB.S9S_MB_2U(SCH_1):SMB_HOST_3V3AUX_SDA   I284 @S9S_MB_2U_LIB.S9S_MB_2U(SCH_1):PAGE228
     2 SMB_HOST_3V3AUX_SDA_R4 @S9S_MB_2U_LIB.S9S_MB_2U(SCH_1):SMB_HOST_3V3AUX_SDA_R4   I284 @S9S_MB_2U_LIB.S9S_MB_2U(SCH_1):PAGE228

R4512 Q_RES_0402LF-33.2,1%,1/16W,CHIA
     1 SMB_HOST_3V3AUX_SCL @S9S_MB_2U_LIB.S9S_MB_2U(SCH_1):SMB_HOST_3V3AUX_SCL   I305 @S9S_MB_2U_LIB.S9S_MB_2U(SCH_1):PAGE228
     2 SMB_HOST_3V3AUX_SCL_R5 @S9S_MB_2U_LIB.S9S_MB_2U(SCH_1):SMB_HOST_3V3AUX_SCL_R5   I305 @S9S_MB_2U_LIB.S9S_MB_2U(SCH_1):PAGE228

R4513 Q_RES_0402LF-0,5%,1/16W,CHIP,CA
     1 SMB_HOST_3V3AUX_SDA @S9S_MB_2U_LIB.S9S_MB_2U(SCH_1):SMB_HOST_3V3AUX_SDA   I306 @S9S_MB_2U_LIB.S9S_MB_2U(SCH_1):PAGE228
     2 SMB_HOST_3V3AUX_SDA_R5 @S9S_MB_2U_LIB.S9S_MB_2U(SCH_1):SMB_HOST_3V3AUX_SDA_R5   I306 @S9S_MB_2U_LIB.S9S_MB_2U(SCH_1):PAGE228

R4514 Q_RES_0402LF-4.7K,1%,1/16W,EMPA
     1 CLK_GEN2_GPU_FPGA_OE_R2_N @S9S_MB_2U_LIB.S9S_MB_2U(SCH_1):CLK_GEN2_GPU_FPGA_OE_R2_N   I161 @S9S_MB_2U_LIB.S9S_MB_2U(SCH_1):PAGE201
     2    GND @S9S_MB_2U_LIB.S9S_MB_2U(SCH_1):GND   I161 @S9S_MB_2U_LIB.S9S_MB_2U(SCH_1):PAGE201

R4515 Q_RES_0402LF-100K,1%,1/16W,CHIA
     1 P3V3_AUX @S9S_MB_2U_LIB.S9S_MB_2U(SCH_1):P3V3_AUX   I200 @S9S_MB_2U_LIB.S9S_MB_2U(SCH_1):PAGE140
     2 UART_BMC_BIC_RX @S9S_MB_2U_LIB.S9S_MB_2U(SCH_1):UART_BMC_BIC_RX   I200 @S9S_MB_2U_LIB.S9S_MB_2U(SCH_1):PAGE140

R4516 Q_RES_0402LF-10K,1%,1/16W,CHIPA
     1   P3V3 @S9S_MB_2U_LIB.S9S_MB_2U(SCH_1):P3V3   I539 @S9S_MB_2U_LIB.S9S_MB_2U(SCH_1):PAGE195
     2 CLK_SWB_OE_N @S9S_MB_2U_LIB.S9S_MB_2U(SCH_1):CLK_SWB_OE_N   I539 @S9S_MB_2U_LIB.S9S_MB_2U(SCH_1):PAGE195

R4517 Q_RES_0402LF-10K,1%,1/16W,CHIPA
     1   P3V3 @S9S_MB_2U_LIB.S9S_MB_2U(SCH_1):P3V3   I540 @S9S_MB_2U_LIB.S9S_MB_2U(SCH_1):PAGE195
     2 OCP_SFF_CLK_OE_N @S9S_MB_2U_LIB.S9S_MB_2U(SCH_1):OCP_SFF_CLK_OE_N   I540 @S9S_MB_2U_LIB.S9S_MB_2U(SCH_1):PAGE195

R4518 Q_RES_0402LF-10K,1%,1/16W,CHIPA
     1   P3V3 @S9S_MB_2U_LIB.S9S_MB_2U(SCH_1):P3V3    I77 @S9S_MB_2U_LIB.S9S_MB_2U(SCH_1):PAGE200
     2 CLK_GPU_2_OE_N @S9S_MB_2U_LIB.S9S_MB_2U(SCH_1):CLK_GPU_2_OE_N    I77 @S9S_MB_2U_LIB.S9S_MB_2U(SCH_1):PAGE200

R4519 Q_RES_0402LF-10K,1%,1/16W,CHIPA
     1   P3V3 @S9S_MB_2U_LIB.S9S_MB_2U(SCH_1):P3V3    I78 @S9S_MB_2U_LIB.S9S_MB_2U(SCH_1):PAGE200
     2 CLK_GPU_1_OE_N @S9S_MB_2U_LIB.S9S_MB_2U(SCH_1):CLK_GPU_1_OE_N    I78 @S9S_MB_2U_LIB.S9S_MB_2U(SCH_1):PAGE200

R4520 Q_RES_0402LF-10K,1%,1/16W,CHIPA
     1   P3V3 @S9S_MB_2U_LIB.S9S_MB_2U(SCH_1):P3V3    I79 @S9S_MB_2U_LIB.S9S_MB_2U(SCH_1):PAGE200
     2 CLK_SWB_BUF2_OE_N @S9S_MB_2U_LIB.S9S_MB_2U(SCH_1):CLK_SWB_BUF2_OE_N    I79 @S9S_MB_2U_LIB.S9S_MB_2U(SCH_1):PAGE200

R4521 Q_RES_0402LF-10K,1%,1/16W,CHIPA
     1 P3V3_AUX @S9S_MB_2U_LIB.S9S_MB_2U(SCH_1):P3V3_AUX   I163 @S9S_MB_2U_LIB.S9S_MB_2U(SCH_1):PAGE201
     2 CLK_GEN2_BMC_RC_OE_N @S9S_MB_2U_LIB.S9S_MB_2U(SCH_1):CLK_GEN2_BMC_RC_OE_N   I163 @S9S_MB_2U_LIB.S9S_MB_2U(SCH_1):PAGE201

R4530 Q_RES_0402LF-33.2,1%,1/16W,CHIA
     1 SMB_SML1_PMBUS_HSC_SCL_R3 @S9S_MB_2U_LIB.S9S_MB_2U(SCH_1):SMB_SML1_PMBUS_HSC_SCL_R3   I293 @S9S_MB_2U_LIB.S9S_MB_2U(SCH_1):PAGE228
     2 SMB_SML1_PMBUS_HSC_SCL @S9S_MB_2U_LIB.S9S_MB_2U(SCH_1):SMB_SML1_PMBUS_HSC_SCL   I293 @S9S_MB_2U_LIB.S9S_MB_2U(SCH_1):PAGE228

R4531 Q_RES_0402LF-0,5%,1/16W,CHIP,CA
     1 SMB_SML1_PMBUS_HSC_SDA_R3 @S9S_MB_2U_LIB.S9S_MB_2U(SCH_1):SMB_SML1_PMBUS_HSC_SDA_R3   I296 @S9S_MB_2U_LIB.S9S_MB_2U(SCH_1):PAGE228
     2 SMB_SML1_PMBUS_HSC_SDA @S9S_MB_2U_LIB.S9S_MB_2U(SCH_1):SMB_SML1_PMBUS_HSC_SDA   I296 @S9S_MB_2U_LIB.S9S_MB_2U(SCH_1):PAGE228

R4532 Q_RES_0402LF-10K,1%,1/16W,CHIPA
     1 P3V3_AUX @S9S_MB_2U_LIB.S9S_MB_2U(SCH_1):P3V3_AUX    I76 @S9S_MB_2U_LIB.S9S_MB_2U(SCH_1):PAGE236
     2 HP_LVC3_OCP_V3_1_P12V_PWRGD @S9S_MB_2U_LIB.S9S_MB_2U(SCH_1):HP_LVC3_OCP_V3_1_P12V_PWRGD    I76 @S9S_MB_2U_LIB.S9S_MB_2U(SCH_1):PAGE236

R4533 Q_RES_0402LF-2K,1%,1/16W,EMPTYA
     1 PWRGD_DRAMPWRGD_CPU1_GH_R_LVC1 @S9S_MB_2U_LIB.S9S_MB_2U(SCH_1):PWRGD_DRAMPWRGD_CPU1_GH_R_LVC1    I19 @S9S_MB_2U_LIB.S9S_MB_2U(SCH_1):PAGE208
     2    GND @S9S_MB_2U_LIB.S9S_MB_2U(SCH_1):GND    I19 @S9S_MB_2U_LIB.S9S_MB_2U(SCH_1):PAGE208

R4534 Q_RES_0402LF-0,5%,1/16W,CHIP,CA
     1 CLK_SWB_OE_N @S9S_MB_2U_LIB.S9S_MB_2U(SCH_1):CLK_SWB_OE_N   I487 @S9S_MB_2U_LIB.S9S_MB_2U(SCH_1):PAGE195
     2 FM_DB2000_8_OE_N @S9S_MB_2U_LIB.S9S_MB_2U(SCH_1):FM_DB2000_8_OE_N   I487 @S9S_MB_2U_LIB.S9S_MB_2U(SCH_1):PAGE195

R4535 Q_RES_0402LF-10,1%,1/16W,CHIP,A
     1 CLK_100M_BMC_P3E_DP @S9S_MB_2U_LIB.S9S_MB_2U(SCH_1):CLK_100M_BMC_P3E_DP    I91 @S9S_MB_2U_LIB.S9S_MB_2U(SCH_1):PAGE227
     2 CLK_100M_BMC_P3E_DP_R @S9S_MB_2U_LIB.S9S_MB_2U(SCH_1):CLK_100M_BMC_P3E_DP_R    I91 @S9S_MB_2U_LIB.S9S_MB_2U(SCH_1):PAGE227

R4536 Q_RES_0402LF-10,1%,1/16W,CHIP,A
     1 CLK_100M_BMC_P3E_DN @S9S_MB_2U_LIB.S9S_MB_2U(SCH_1):CLK_100M_BMC_P3E_DN    I92 @S9S_MB_2U_LIB.S9S_MB_2U(SCH_1):PAGE227
     2 CLK_100M_BMC_P3E_DN_R @S9S_MB_2U_LIB.S9S_MB_2U(SCH_1):CLK_100M_BMC_P3E_DN_R    I92 @S9S_MB_2U_LIB.S9S_MB_2U(SCH_1):PAGE227

R4537 Q_RES_0402LF-0,5%,1/16W,CHIP,CA
     1 FM_P2E_EN_N @S9S_MB_2U_LIB.S9S_MB_2U(SCH_1):FM_P2E_EN_N    I73 @S9S_MB_2U_LIB.S9S_MB_2U(SCH_1):PAGE136
     2 CLK_GEN2_GPU_FPGA_OE_OR_N @S9S_MB_2U_LIB.S9S_MB_2U(SCH_1):CLK_GEN2_GPU_FPGA_OE_OR_N    I73 @S9S_MB_2U_LIB.S9S_MB_2U(SCH_1):PAGE136

R4540 Q_RES_0402LF-33.2,1%,1/16W,CHIA
     1 SMB_HOST_CLK_BUF_ISO_3V3AUX_S_1 @S9S_MB_2U_LIB.S9S_MB_2U(SCH_1):SMB_HOST_CLK_BUF_ISO_3V3AUX_SCL_R    I33 @S9S_MB_2U_LIB.S9S_MB_2U(SCH_1):PAGE225
     2 SMB_HOST_CLK_BUF_ISO_3V3AUX_SCL @S9S_MB_2U_LIB.S9S_MB_2U(SCH_1):SMB_HOST_CLK_BUF_ISO_3V3AUX_SCL    I33 @S9S_MB_2U_LIB.S9S_MB_2U(SCH_1):PAGE225

R4541 Q_RES_0402LF-33.2,1%,1/16W,CHIA
     1 SMB_HOST_CLK_BUF_ISO_3V3AUX_S_2 @S9S_MB_2U_LIB.S9S_MB_2U(SCH_1):SMB_HOST_CLK_BUF_ISO_3V3AUX_SDA_R    I34 @S9S_MB_2U_LIB.S9S_MB_2U(SCH_1):PAGE225
     2 SMB_HOST_CLK_BUF_ISO_3V3AUX_SDA @S9S_MB_2U_LIB.S9S_MB_2U(SCH_1):SMB_HOST_CLK_BUF_ISO_3V3AUX_SDA    I34 @S9S_MB_2U_LIB.S9S_MB_2U(SCH_1):PAGE225

R4543 Q_RES_0402LF-4.7K,5%,1/16W,CHIA
     1 P3V3_AUX @S9S_MB_2U_LIB.S9S_MB_2U(SCH_1):P3V3_AUX    I85 @S9S_MB_2U_LIB.S9S_MB_2U(SCH_1):PAGE139
     2 HGX_DETECT_N @S9S_MB_2U_LIB.S9S_MB_2U(SCH_1):HGX_DETECT_N    I85 @S9S_MB_2U_LIB.S9S_MB_2U(SCH_1):PAGE139

R4544 Q_RES_0402LF-100K,1%,1/16W,EMPA
     1 HGX_DETECT_N @S9S_MB_2U_LIB.S9S_MB_2U(SCH_1):HGX_DETECT_N    I62 @S9S_MB_2U_LIB.S9S_MB_2U(SCH_1):PAGE139
     2    GND @S9S_MB_2U_LIB.S9S_MB_2U(SCH_1):GND    I62 @S9S_MB_2U_LIB.S9S_MB_2U(SCH_1):PAGE139

R4545 Q_RES_0402LF-4.7K,5%,1/16W,CHIA
     1 P3V3_AUX @S9S_MB_2U_LIB.S9S_MB_2U(SCH_1):P3V3_AUX    I57 @S9S_MB_2U_LIB.S9S_MB_2U(SCH_1):PAGE139
     2 HGX_DETECT @S9S_MB_2U_LIB.S9S_MB_2U(SCH_1):HGX_DETECT    I57 @S9S_MB_2U_LIB.S9S_MB_2U(SCH_1):PAGE139

R4546 Q_RES_0402LF-4.7K,5%,1/16W,EMPA
     1 P3V3_AUX @S9S_MB_2U_LIB.S9S_MB_2U(SCH_1):P3V3_AUX    I50 @S9S_MB_2U_LIB.S9S_MB_2U(SCH_1):PAGE139
     2 HGX_DETECT_N_ISO @S9S_MB_2U_LIB.S9S_MB_2U(SCH_1):HGX_DETECT_N_ISO    I50 @S9S_MB_2U_LIB.S9S_MB_2U(SCH_1):PAGE139

R4547 Q_RES_0402LF-100K,1%,1/16W,EMPA
     1 P3V3_AUX @S9S_MB_2U_LIB.S9S_MB_2U(SCH_1):P3V3_AUX    I89 @S9S_MB_2U_LIB.S9S_MB_2U(SCH_1):PAGE139
     2 SWB_HSC_EN @S9S_MB_2U_LIB.S9S_MB_2U(SCH_1):SWB_HSC_EN    I89 @S9S_MB_2U_LIB.S9S_MB_2U(SCH_1):PAGE139

R4548 Q_RES_0402LF-100K,1%,1/16W,CHIA
     1 SWB_HSC_EN @S9S_MB_2U_LIB.S9S_MB_2U(SCH_1):SWB_HSC_EN    I87 @S9S_MB_2U_LIB.S9S_MB_2U(SCH_1):PAGE139
     2    GND @S9S_MB_2U_LIB.S9S_MB_2U(SCH_1):GND    I87 @S9S_MB_2U_LIB.S9S_MB_2U(SCH_1):PAGE139

R4549 Q_RES_0402LF-4.7K,5%,1/16W,EMPA
     1 P3V3_AUX @S9S_MB_2U_LIB.S9S_MB_2U(SCH_1):P3V3_AUX    I98 @S9S_MB_2U_LIB.S9S_MB_2U(SCH_1):PAGE139
     2 SWB_HSC_EN_BUF_R @S9S_MB_2U_LIB.S9S_MB_2U(SCH_1):SWB_HSC_EN_BUF_R    I98 @S9S_MB_2U_LIB.S9S_MB_2U(SCH_1):PAGE139

R4550 Q_RES_0402LF-49.9,1%,1/16W,CHIA
     1 SWB_HSC_EN_BUF_R @S9S_MB_2U_LIB.S9S_MB_2U(SCH_1):SWB_HSC_EN_BUF_R   I110 @S9S_MB_2U_LIB.S9S_MB_2U(SCH_1):PAGE139
     2 SWB_HSC_EN_BUF @S9S_MB_2U_LIB.S9S_MB_2U(SCH_1):SWB_HSC_EN_BUF   I110 @S9S_MB_2U_LIB.S9S_MB_2U(SCH_1):PAGE139

R4551 Q_RES_0402LF-54.9K,1%,1/16W,EMA
     1 P3V3_AUX @S9S_MB_2U_LIB.S9S_MB_2U(SCH_1):P3V3_AUX    I51 @S9S_MB_2U_LIB.S9S_MB_2U(SCH_1):PAGE230
     2 HPDB_HSC_PWRGD @S9S_MB_2U_LIB.S9S_MB_2U(SCH_1):HPDB_HSC_PWRGD    I51 @S9S_MB_2U_LIB.S9S_MB_2U(SCH_1):PAGE230

R4552 Q_RES_0402LF-100K,1%,1/16W,CHIA
     1 HPDB_HSC_PWRGD @S9S_MB_2U_LIB.S9S_MB_2U(SCH_1):HPDB_HSC_PWRGD    I50 @S9S_MB_2U_LIB.S9S_MB_2U(SCH_1):PAGE230
     2    GND @S9S_MB_2U_LIB.S9S_MB_2U(SCH_1):GND    I50 @S9S_MB_2U_LIB.S9S_MB_2U(SCH_1):PAGE230

R4553 Q_RES_0402LF-4.7K,5%,1/16W,CHIA
     1 P3V3_AUX @S9S_MB_2U_LIB.S9S_MB_2U(SCH_1):P3V3_AUX    I55 @S9S_MB_2U_LIB.S9S_MB_2U(SCH_1):PAGE230
     2 HPDB_HSC_PWRGD_N @S9S_MB_2U_LIB.S9S_MB_2U(SCH_1):HPDB_HSC_PWRGD_N    I55 @S9S_MB_2U_LIB.S9S_MB_2U(SCH_1):PAGE230

R4554 Q_RES_0402LF-4.7K,5%,1/16W,CHIA
     1 P3V3_AUX @S9S_MB_2U_LIB.S9S_MB_2U(SCH_1):P3V3_AUX    I59 @S9S_MB_2U_LIB.S9S_MB_2U(SCH_1):PAGE230
     2 HPDB_HSC_PWRGD_ISO @S9S_MB_2U_LIB.S9S_MB_2U(SCH_1):HPDB_HSC_PWRGD_ISO    I59 @S9S_MB_2U_LIB.S9S_MB_2U(SCH_1):PAGE230

R4555 Q_RES_0402LF-4.7K,5%,1/16W,EMPA
     1 SWB_HSC_EN_BUF_R @S9S_MB_2U_LIB.S9S_MB_2U(SCH_1):SWB_HSC_EN_BUF_R    I99 @S9S_MB_2U_LIB.S9S_MB_2U(SCH_1):PAGE139
     2    GND @S9S_MB_2U_LIB.S9S_MB_2U(SCH_1):GND    I99 @S9S_MB_2U_LIB.S9S_MB_2U(SCH_1):PAGE139

R4556 Q_RES_0402LF-33.2,1%,1/16W,CHIA
     1 HGX_DETECT_N_R @S9S_MB_2U_LIB.S9S_MB_2U(SCH_1):HGX_DETECT_N_R   I143 @S9S_MB_2U_LIB.S9S_MB_2U(SCH_1):PAGE312
     2 HGX_DETECT_N @S9S_MB_2U_LIB.S9S_MB_2U(SCH_1):HGX_DETECT_N   I143 @S9S_MB_2U_LIB.S9S_MB_2U(SCH_1):PAGE312

R4557 Q_RES_0402LF-33.2,1%,1/16W,CHIA
     1 HPDB_HSC_PWRGD_ISO @S9S_MB_2U_LIB.S9S_MB_2U(SCH_1):HPDB_HSC_PWRGD_ISO   I145 @S9S_MB_2U_LIB.S9S_MB_2U(SCH_1):PAGE312
     2 HPDB_HSC_PWRGD_ISO_R @S9S_MB_2U_LIB.S9S_MB_2U(SCH_1):HPDB_HSC_PWRGD_ISO_R   I145 @S9S_MB_2U_LIB.S9S_MB_2U(SCH_1):PAGE312

R4558 Q_RES_0402LF-33.2,1%,1/16W,CHIA
     1 SWB_HSC_EN @S9S_MB_2U_LIB.S9S_MB_2U(SCH_1):SWB_HSC_EN   I150 @S9S_MB_2U_LIB.S9S_MB_2U(SCH_1):PAGE312
     2 SWB_HSC_EN_R @S9S_MB_2U_LIB.S9S_MB_2U(SCH_1):SWB_HSC_EN_R   I150 @S9S_MB_2U_LIB.S9S_MB_2U(SCH_1):PAGE312

R4559 Q_RES_0402LF-100K,1%,1/16W,CHIA
     1 SWB_HSC_PWRGD @S9S_MB_2U_LIB.S9S_MB_2U(SCH_1):SWB_HSC_PWRGD   I129 @S9S_MB_2U_LIB.S9S_MB_2U(SCH_1):PAGE143
     2    GND @S9S_MB_2U_LIB.S9S_MB_2U(SCH_1):GND   I129 @S9S_MB_2U_LIB.S9S_MB_2U(SCH_1):PAGE143

R4560 Q_RES_0402LF-4.7K,5%,1/16W,CHIA
     1 P3V3_AUX @S9S_MB_2U_LIB.S9S_MB_2U(SCH_1):P3V3_AUX   I124 @S9S_MB_2U_LIB.S9S_MB_2U(SCH_1):PAGE143
     2 SWB_HSC_PWRGD_N @S9S_MB_2U_LIB.S9S_MB_2U(SCH_1):SWB_HSC_PWRGD_N   I124 @S9S_MB_2U_LIB.S9S_MB_2U(SCH_1):PAGE143

R4561 Q_RES_0402LF-4.7K,5%,1/16W,CHIA
     1 P3V3_AUX @S9S_MB_2U_LIB.S9S_MB_2U(SCH_1):P3V3_AUX   I116 @S9S_MB_2U_LIB.S9S_MB_2U(SCH_1):PAGE143
     2 SWB_HSC_PWRGD_ISO @S9S_MB_2U_LIB.S9S_MB_2U(SCH_1):SWB_HSC_PWRGD_ISO   I116 @S9S_MB_2U_LIB.S9S_MB_2U(SCH_1):PAGE143

R4562 Q_RES_0402LF-100K,1%,1/16W,EMPA
     1 P3V3_AUX @S9S_MB_2U_LIB.S9S_MB_2U(SCH_1):P3V3_AUX   I132 @S9S_MB_2U_LIB.S9S_MB_2U(SCH_1):PAGE143
     2 SWB_HSC_PWRGD @S9S_MB_2U_LIB.S9S_MB_2U(SCH_1):SWB_HSC_PWRGD   I132 @S9S_MB_2U_LIB.S9S_MB_2U(SCH_1):PAGE143

R4563 Q_RES_0402LF-33.2,1%,1/16W,CHIA
     1 SWB_HSC_PWRGD_ISO_R @S9S_MB_2U_LIB.S9S_MB_2U(SCH_1):SWB_HSC_PWRGD_ISO_R   I158 @S9S_MB_2U_LIB.S9S_MB_2U(SCH_1):PAGE312
     2 SWB_HSC_PWRGD_ISO @S9S_MB_2U_LIB.S9S_MB_2U(SCH_1):SWB_HSC_PWRGD_ISO   I158 @S9S_MB_2U_LIB.S9S_MB_2U(SCH_1):PAGE312

R4564 Q_RES_0402LF-10K,1%,1/16W,CHIPA
     1 PD_GPP_I_14 @S9S_MB_2U_LIB.S9S_MB_2U(SCH_1):PD_GPP_I_14   I239 @S9S_MB_2U_LIB.S9S_MB_2U(SCH_1):PAGE176
     2    GND @S9S_MB_2U_LIB.S9S_MB_2U(SCH_1):GND   I239 @S9S_MB_2U_LIB.S9S_MB_2U(SCH_1):PAGE176

R4565 Q_RES_0402LF-10K,1%,1/16W,CHIPA
     1 PD_GPP_I_13 @S9S_MB_2U_LIB.S9S_MB_2U(SCH_1):PD_GPP_I_13   I240 @S9S_MB_2U_LIB.S9S_MB_2U(SCH_1):PAGE176
     2    GND @S9S_MB_2U_LIB.S9S_MB_2U(SCH_1):GND   I240 @S9S_MB_2U_LIB.S9S_MB_2U(SCH_1):PAGE176

R4567 Q_RES_0402LF-5.11K,1%,1/16W,CHA
     1 P3V3_PDB_AUX_ADC @S9S_MB_2U_LIB.S9S_MB_2U(SCH_1):P3V3_PDB_AUX_ADC   I348 @S9S_MB_2U_LIB.S9S_MB_2U(SCH_1):PAGE239
     2 P1V581_PDB_ADC @S9S_MB_2U_LIB.S9S_MB_2U(SCH_1):P1V581_PDB_ADC   I348 @S9S_MB_2U_LIB.S9S_MB_2U(SCH_1):PAGE239

R4568 Q_RES_0402LF-4.7K,1%,1/16W,CHIA
     1 P1V581_PDB_ADC @S9S_MB_2U_LIB.S9S_MB_2U(SCH_1):P1V581_PDB_ADC   I346 @S9S_MB_2U_LIB.S9S_MB_2U(SCH_1):PAGE239
     2    GND @S9S_MB_2U_LIB.S9S_MB_2U(SCH_1):GND   I346 @S9S_MB_2U_LIB.S9S_MB_2U(SCH_1):PAGE239

R4569 Q_RES_0402LF-0,5%,1/16W,EMPTY,A
     1 GPU_3V3IO_RSVD1 @S9S_MB_2U_LIB.S9S_MB_2U(SCH_1):GPU_3V3IO_RSVD1   I107 @S9S_MB_2U_LIB.S9S_MB_2U(SCH_1):PAGE139
     2 GPU_3V3IO_RSVD1_ISO @S9S_MB_2U_LIB.S9S_MB_2U(SCH_1):GPU_3V3IO_RSVD1_ISO   I107 @S9S_MB_2U_LIB.S9S_MB_2U(SCH_1):PAGE139

R4570 Q_RES_0402LF-0,5%,1/16W,EMPTY,A
     1 GPU_3V3IO_RSVD3 @S9S_MB_2U_LIB.S9S_MB_2U(SCH_1):GPU_3V3IO_RSVD3   I109 @S9S_MB_2U_LIB.S9S_MB_2U(SCH_1):PAGE139
     2 GPU_3V3IO_RSVD3_ISO @S9S_MB_2U_LIB.S9S_MB_2U(SCH_1):GPU_3V3IO_RSVD3_ISO   I109 @S9S_MB_2U_LIB.S9S_MB_2U(SCH_1):PAGE139

R4571 Q_RES_0402LF-0,5%,1/16W,EMPTY,A
     1 GPU_3V3IO_RSVD4 @S9S_MB_2U_LIB.S9S_MB_2U(SCH_1):GPU_3V3IO_RSVD4   I108 @S9S_MB_2U_LIB.S9S_MB_2U(SCH_1):PAGE139
     2 GPU_3V3IO_RSVD4_ISO @S9S_MB_2U_LIB.S9S_MB_2U(SCH_1):GPU_3V3IO_RSVD4_ISO   I108 @S9S_MB_2U_LIB.S9S_MB_2U(SCH_1):PAGE139

R4572 Q_RES_0402LF-0,5%,1/16W,EMPTY,A
     1 GPU_3V3IO_RSVD1_FFU @S9S_MB_2U_LIB.S9S_MB_2U(SCH_1):GPU_3V3IO_RSVD1_FFU   I141 @S9S_MB_2U_LIB.S9S_MB_2U(SCH_1):PAGE143
     2 GPU_3V3IO_RSVD1_FFU_ISO @S9S_MB_2U_LIB.S9S_MB_2U(SCH_1):GPU_3V3IO_RSVD1_FFU_ISO   I141 @S9S_MB_2U_LIB.S9S_MB_2U(SCH_1):PAGE143

R4573 Q_RES_0402LF-0,5%,1/16W,EMPTY,A
     1 PRSNT_CABLE_GPU_B3_N @S9S_MB_2U_LIB.S9S_MB_2U(SCH_1):PRSNT_CABLE_GPU_B3_N   I140 @S9S_MB_2U_LIB.S9S_MB_2U(SCH_1):PAGE143
     2 PRSNT_CABLE_GPU_B3_ISO_N @S9S_MB_2U_LIB.S9S_MB_2U(SCH_1):PRSNT_CABLE_GPU_B3_ISO_N   I140 @S9S_MB_2U_LIB.S9S_MB_2U(SCH_1):PAGE143

R4574 Q_RES_0402LF-0,5%,1/16W,EMPTY,A
     1 PRSNT_CABLE_GPU_A1_N @S9S_MB_2U_LIB.S9S_MB_2U(SCH_1):PRSNT_CABLE_GPU_A1_N   I136 @S9S_MB_2U_LIB.S9S_MB_2U(SCH_1):PAGE143
     2 PRSNT_CABLE_GPU_A1_ISO_N @S9S_MB_2U_LIB.S9S_MB_2U(SCH_1):PRSNT_CABLE_GPU_A1_ISO_N   I136 @S9S_MB_2U_LIB.S9S_MB_2U(SCH_1):PAGE143

R4575 Q_RES_0402LF-0,5%,1/16W,EMPTY,A
     1 GPU_3V3IO_RSVD0_FFU @S9S_MB_2U_LIB.S9S_MB_2U(SCH_1):GPU_3V3IO_RSVD0_FFU   I142 @S9S_MB_2U_LIB.S9S_MB_2U(SCH_1):PAGE143
     2 GPU_3V3IO_RSVD0_FFU_ISO @S9S_MB_2U_LIB.S9S_MB_2U(SCH_1):GPU_3V3IO_RSVD0_FFU_ISO   I142 @S9S_MB_2U_LIB.S9S_MB_2U(SCH_1):PAGE143

R4576 Q_RES_0402LF-0,5%,1/16W,EMPTY,A
     1 GPU_3V3IO_RSVD5_FFU @S9S_MB_2U_LIB.S9S_MB_2U(SCH_1):GPU_3V3IO_RSVD5_FFU   I139 @S9S_MB_2U_LIB.S9S_MB_2U(SCH_1):PAGE143
     2 GPU_3V3IO_RSVD5_FFU_ISO @S9S_MB_2U_LIB.S9S_MB_2U(SCH_1):GPU_3V3IO_RSVD5_FFU_ISO   I139 @S9S_MB_2U_LIB.S9S_MB_2U(SCH_1):PAGE143

R4577 Q_RES_0402LF-0,5%,1/16W,EMPTY,A
     1 GPU_3V3IO_RSVD3_FFU @S9S_MB_2U_LIB.S9S_MB_2U(SCH_1):GPU_3V3IO_RSVD3_FFU   I137 @S9S_MB_2U_LIB.S9S_MB_2U(SCH_1):PAGE143
     2 GPU_3V3IO_RSVD3_FFU_ISO @S9S_MB_2U_LIB.S9S_MB_2U(SCH_1):GPU_3V3IO_RSVD3_FFU_ISO   I137 @S9S_MB_2U_LIB.S9S_MB_2U(SCH_1):PAGE143

R4578 Q_RES_0402LF-0,5%,1/16W,EMPTY,A
     1 PRSNT_CABLE_GPU_A2_N @S9S_MB_2U_LIB.S9S_MB_2U(SCH_1):PRSNT_CABLE_GPU_A2_N   I138 @S9S_MB_2U_LIB.S9S_MB_2U(SCH_1):PAGE143
     2 PRSNT_CABLE_GPU_A2_ISO_N @S9S_MB_2U_LIB.S9S_MB_2U(SCH_1):PRSNT_CABLE_GPU_A2_ISO_N   I138 @S9S_MB_2U_LIB.S9S_MB_2U(SCH_1):PAGE143

R4579 Q_RES_0402LF-10K,1%,1/16W,CHIPA
     1 P3V3_AUX @S9S_MB_2U_LIB.S9S_MB_2U(SCH_1):P3V3_AUX    I67 @S9S_MB_2U_LIB.S9S_MB_2U(SCH_1):PAGE184
     2 FAB_BMC_REV_ID0 @S9S_MB_2U_LIB.S9S_MB_2U(SCH_1):FAB_BMC_REV_ID0    I67 @S9S_MB_2U_LIB.S9S_MB_2U(SCH_1):PAGE184

R4580 Q_RES_0402LF-10K,1%,1/16W,EMPTA
     1 P3V3_AUX @S9S_MB_2U_LIB.S9S_MB_2U(SCH_1):P3V3_AUX     I5 @S9S_MB_2U_LIB.S9S_MB_2U(SCH_1):PAGE184
     2 FM_BOARD_BMC_SKU_ID4 @S9S_MB_2U_LIB.S9S_MB_2U(SCH_1):FM_BOARD_BMC_SKU_ID4     I5 @S9S_MB_2U_LIB.S9S_MB_2U(SCH_1):PAGE184

R4581 Q_RES_0402LF-1K,1%,1/16W,CHIP,A
     1 FM_BOARD_BMC_SKU_ID4 @S9S_MB_2U_LIB.S9S_MB_2U(SCH_1):FM_BOARD_BMC_SKU_ID4     I1 @S9S_MB_2U_LIB.S9S_MB_2U(SCH_1):PAGE184
     2    GND @S9S_MB_2U_LIB.S9S_MB_2U(SCH_1):GND     I1 @S9S_MB_2U_LIB.S9S_MB_2U(SCH_1):PAGE184

R4582 Q_RES_0402LF-10K,1%,1/16W,EMPTA
     1 P3V3_AUX @S9S_MB_2U_LIB.S9S_MB_2U(SCH_1):P3V3_AUX    I23 @S9S_MB_2U_LIB.S9S_MB_2U(SCH_1):PAGE184
     2 FM_BOARD_BMC_SKU_ID1 @S9S_MB_2U_LIB.S9S_MB_2U(SCH_1):FM_BOARD_BMC_SKU_ID1    I23 @S9S_MB_2U_LIB.S9S_MB_2U(SCH_1):PAGE184

R4583 Q_RES_0402LF-1K,1%,1/16W,CHIP,A
     1 FM_BOARD_BMC_SKU_ID1 @S9S_MB_2U_LIB.S9S_MB_2U(SCH_1):FM_BOARD_BMC_SKU_ID1    I18 @S9S_MB_2U_LIB.S9S_MB_2U(SCH_1):PAGE184
     2    GND @S9S_MB_2U_LIB.S9S_MB_2U(SCH_1):GND    I18 @S9S_MB_2U_LIB.S9S_MB_2U(SCH_1):PAGE184

R4584 Q_RES_0402LF-10K,1%,1/16W,EMPTA
     1 P3V3_AUX @S9S_MB_2U_LIB.S9S_MB_2U(SCH_1):P3V3_AUX    I24 @S9S_MB_2U_LIB.S9S_MB_2U(SCH_1):PAGE184
     2 FM_BOARD_BMC_SKU_ID0 @S9S_MB_2U_LIB.S9S_MB_2U(SCH_1):FM_BOARD_BMC_SKU_ID0    I24 @S9S_MB_2U_LIB.S9S_MB_2U(SCH_1):PAGE184

R4585 Q_RES_0402LF-1K,1%,1/16W,CHIP,A
     1 FM_BOARD_BMC_SKU_ID0 @S9S_MB_2U_LIB.S9S_MB_2U(SCH_1):FM_BOARD_BMC_SKU_ID0    I20 @S9S_MB_2U_LIB.S9S_MB_2U(SCH_1):PAGE184
     2    GND @S9S_MB_2U_LIB.S9S_MB_2U(SCH_1):GND    I20 @S9S_MB_2U_LIB.S9S_MB_2U(SCH_1):PAGE184

R4586 Q_RES_0402LF-10K,1%,1/16W,CHIPA
     1 P3V3_AUX @S9S_MB_2U_LIB.S9S_MB_2U(SCH_1):P3V3_AUX    I62 @S9S_MB_2U_LIB.S9S_MB_2U(SCH_1):PAGE184
     2 FAB_BMC_REV_ID2 @S9S_MB_2U_LIB.S9S_MB_2U(SCH_1):FAB_BMC_REV_ID2    I62 @S9S_MB_2U_LIB.S9S_MB_2U(SCH_1):PAGE184

R4588 Q_RES_0402LF-1K,1%,1/16W,EMPTYA
     1 FAB_BMC_REV_ID2 @S9S_MB_2U_LIB.S9S_MB_2U(SCH_1):FAB_BMC_REV_ID2    I58 @S9S_MB_2U_LIB.S9S_MB_2U(SCH_1):PAGE184
     2    GND @S9S_MB_2U_LIB.S9S_MB_2U(SCH_1):GND    I58 @S9S_MB_2U_LIB.S9S_MB_2U(SCH_1):PAGE184

R4589 Q_RES_0402LF-10K,1%,1/16W,CHIPA
     1 P3V3_AUX @S9S_MB_2U_LIB.S9S_MB_2U(SCH_1):P3V3_AUX    I63 @S9S_MB_2U_LIB.S9S_MB_2U(SCH_1):PAGE184
     2 FAB_BMC_REV_ID1 @S9S_MB_2U_LIB.S9S_MB_2U(SCH_1):FAB_BMC_REV_ID1    I63 @S9S_MB_2U_LIB.S9S_MB_2U(SCH_1):PAGE184

R4590 Q_RES_0402LF-1K,1%,1/16W,EMPTYA
     1 FAB_BMC_REV_ID1 @S9S_MB_2U_LIB.S9S_MB_2U(SCH_1):FAB_BMC_REV_ID1    I59 @S9S_MB_2U_LIB.S9S_MB_2U(SCH_1):PAGE184
     2    GND @S9S_MB_2U_LIB.S9S_MB_2U(SCH_1):GND    I59 @S9S_MB_2U_LIB.S9S_MB_2U(SCH_1):PAGE184

R4591 Q_RES_0402LF-10K,1%,1/16W,EMPTA
     1 P3V3_AUX @S9S_MB_2U_LIB.S9S_MB_2U(SCH_1):P3V3_AUX     I6 @S9S_MB_2U_LIB.S9S_MB_2U(SCH_1):PAGE184
     2 FM_BOARD_BMC_SKU_ID3 @S9S_MB_2U_LIB.S9S_MB_2U(SCH_1):FM_BOARD_BMC_SKU_ID3     I6 @S9S_MB_2U_LIB.S9S_MB_2U(SCH_1):PAGE184

R4592 Q_RES_0402LF-1K,1%,1/16W,CHIP,A
     1 FM_BOARD_BMC_SKU_ID3 @S9S_MB_2U_LIB.S9S_MB_2U(SCH_1):FM_BOARD_BMC_SKU_ID3     I4 @S9S_MB_2U_LIB.S9S_MB_2U(SCH_1):PAGE184
     2    GND @S9S_MB_2U_LIB.S9S_MB_2U(SCH_1):GND     I4 @S9S_MB_2U_LIB.S9S_MB_2U(SCH_1):PAGE184

R4593 Q_RES_0402LF-0,5%,1/16W,CHIP,CA
     1 IRQ_PVCCIN_CPU0_VRHOT_R_N @S9S_MB_2U_LIB.S9S_MB_2U(SCH_1):IRQ_PVCCIN_CPU0_VRHOT_R_N    I66 @S9S_MB_2U_LIB.S9S_MB_2U(SCH_1):PAGE252
     2 IRQ_PVCCIN_CPU0_VRHOT_N @S9S_MB_2U_LIB.S9S_MB_2U(SCH_1):IRQ_PVCCIN_CPU0_VRHOT_N    I66 @S9S_MB_2U_LIB.S9S_MB_2U(SCH_1):PAGE252

R4594 Q_RES_0402LF-0,5%,1/16W,CHIP,CA
     1 SMB_VR_3V3AUX_SCL_R @S9S_MB_2U_LIB.S9S_MB_2U(SCH_1):SMB_VR_3V3AUX_SCL_R    I58 @S9S_MB_2U_LIB.S9S_MB_2U(SCH_1):PAGE278
     2 SMB_CLK_PVCCINFAON_CPU1 @S9S_MB_2U_LIB.S9S_MB_2U(SCH_1):SMB_CLK_PVCCINFAON_CPU1    I58 @S9S_MB_2U_LIB.S9S_MB_2U(SCH_1):PAGE278

R4595 Q_RES_0402LF-0,5%,1/16W,CHIP,CA
     1 SMB_VR_3V3AUX_SCL_R @S9S_MB_2U_LIB.S9S_MB_2U(SCH_1):SMB_VR_3V3AUX_SCL_R    I39 @S9S_MB_2U_LIB.S9S_MB_2U(SCH_1):PAGE282
     2 SMB_CLK_PVCCD_HV_CPU1 @S9S_MB_2U_LIB.S9S_MB_2U(SCH_1):SMB_CLK_PVCCD_HV_CPU1    I39 @S9S_MB_2U_LIB.S9S_MB_2U(SCH_1):PAGE282

R4596 Q_RES_0402LF-1K,1%,1/16W,EMPTYA
     1 FAB_BMC_REV_ID0 @S9S_MB_2U_LIB.S9S_MB_2U(SCH_1):FAB_BMC_REV_ID0    I61 @S9S_MB_2U_LIB.S9S_MB_2U(SCH_1):PAGE184
     2    GND @S9S_MB_2U_LIB.S9S_MB_2U(SCH_1):GND    I61 @S9S_MB_2U_LIB.S9S_MB_2U(SCH_1):PAGE184

R4597 Q_RES_0402LF-10K,1%,1/16W,EMPTA
     1 P3V3_AUX @S9S_MB_2U_LIB.S9S_MB_2U(SCH_1):P3V3_AUX    I22 @S9S_MB_2U_LIB.S9S_MB_2U(SCH_1):PAGE184
     2 FM_BOARD_BMC_SKU_ID2 @S9S_MB_2U_LIB.S9S_MB_2U(SCH_1):FM_BOARD_BMC_SKU_ID2    I22 @S9S_MB_2U_LIB.S9S_MB_2U(SCH_1):PAGE184

R4598 Q_RES_0402LF-1K,1%,1/16W,CHIP,A
     1 FM_BOARD_BMC_SKU_ID2 @S9S_MB_2U_LIB.S9S_MB_2U(SCH_1):FM_BOARD_BMC_SKU_ID2    I16 @S9S_MB_2U_LIB.S9S_MB_2U(SCH_1):PAGE184
     2    GND @S9S_MB_2U_LIB.S9S_MB_2U(SCH_1):GND    I16 @S9S_MB_2U_LIB.S9S_MB_2U(SCH_1):PAGE184

R4599 Q_RES_0402LF-0,5%,1/16W,CHIP,CA
     1 HP_LVC3_OCP_V3_2_P12V_PWRGD @S9S_MB_2U_LIB.S9S_MB_2U(SCH_1):HP_LVC3_OCP_V3_2_P12V_PWRGD   I159 @S9S_MB_2U_LIB.S9S_MB_2U(SCH_1):PAGE313
     2 HP_LVC3_OCP_V3_2_HSC_PWRGD_PLD_ @S9S_MB_2U_LIB.S9S_MB_2U(SCH_1):HP_LVC3_OCP_V3_2_HSC_PWRGD_PLD_R   I159 @S9S_MB_2U_LIB.S9S_MB_2U(SCH_1):PAGE313

R4600 Q_RES_0402LF-0,5%,1/16W,CHIP,CA
     1 HP_LVC3_OCP_V3_1_P12V_PWRGD @S9S_MB_2U_LIB.S9S_MB_2U(SCH_1):HP_LVC3_OCP_V3_1_P12V_PWRGD   I160 @S9S_MB_2U_LIB.S9S_MB_2U(SCH_1):PAGE313
     2 HP_LVC3_OCP_V3_1_HSC_PWRGD_PLD_ @S9S_MB_2U_LIB.S9S_MB_2U(SCH_1):HP_LVC3_OCP_V3_1_HSC_PWRGD_PLD_R   I160 @S9S_MB_2U_LIB.S9S_MB_2U(SCH_1):PAGE313

R4601 Q_RES_0402LF-0,5%,1/16W,CHIP,CA
     1 CLK_50M_NCSI_OCP_SFF_ISO @S9S_MB_2U_LIB.S9S_MB_2U(SCH_1):CLK_50M_NCSI_OCP_SFF_ISO    I90 @S9S_MB_2U_LIB.S9S_MB_2U(SCH_1):PAGE152
     2 CLK_50M_NCSI_OCP_SFF_ISO_R @S9S_MB_2U_LIB.S9S_MB_2U(SCH_1):CLK_50M_NCSI_OCP_SFF_ISO_R    I90 @S9S_MB_2U_LIB.S9S_MB_2U(SCH_1):PAGE152

R4602 Q_RES_0402LF-0,5%,1/16W,CHIP,CA
     1 CLK_50M_NCSI_OCP_V3_2_ISO @S9S_MB_2U_LIB.S9S_MB_2U(SCH_1):CLK_50M_NCSI_OCP_V3_2_ISO    I90 @S9S_MB_2U_LIB.S9S_MB_2U(SCH_1):PAGE156
     2 CLK_50M_NCSI_OCP_V3_2_ISO_R @S9S_MB_2U_LIB.S9S_MB_2U(SCH_1):CLK_50M_NCSI_OCP_V3_2_ISO_R    I90 @S9S_MB_2U_LIB.S9S_MB_2U(SCH_1):PAGE156

R4603 Q_RES_0402LF-10K,1%,1/16W,CHIPA
     1 SMB_BMC_GPU_EN @S9S_MB_2U_LIB.S9S_MB_2U(SCH_1):SMB_BMC_GPU_EN    I48 @S9S_MB_2U_LIB.S9S_MB_2U(SCH_1):PAGE222
     2    GND @S9S_MB_2U_LIB.S9S_MB_2U(SCH_1):GND    I48 @S9S_MB_2U_LIB.S9S_MB_2U(SCH_1):PAGE222

R4604 Q_RES_0402LF-4.7K,5%,1/16W,CHIA
     1 P3V3_AUX @S9S_MB_2U_LIB.S9S_MB_2U(SCH_1):P3V3_AUX    I18 @S9S_MB_2U_LIB.S9S_MB_2U(SCH_1):PAGE213
     2 PWRGD_PS_PWROK_PLD_N @S9S_MB_2U_LIB.S9S_MB_2U(SCH_1):PWRGD_PS_PWROK_PLD_N    I18 @S9S_MB_2U_LIB.S9S_MB_2U(SCH_1):PAGE213

R4605 Q_RES_0402LF-4.7K,5%,1/16W,CHIA
     1 P3V3_AUX @S9S_MB_2U_LIB.S9S_MB_2U(SCH_1):P3V3_AUX    I22 @S9S_MB_2U_LIB.S9S_MB_2U(SCH_1):PAGE213
     2 PWRGD_PS_PWROK_PLD_ISO @S9S_MB_2U_LIB.S9S_MB_2U(SCH_1):PWRGD_PS_PWROK_PLD_ISO    I22 @S9S_MB_2U_LIB.S9S_MB_2U(SCH_1):PAGE213

R4606 Q_RES_0402LF-0,5%,1/16W,CHIP,CA
     1 E1S_0_LED_ACT_R_N @S9S_MB_2U_LIB.S9S_MB_2U(SCH_1):E1S_0_LED_ACT_R_N   I180 @S9S_MB_2U_LIB.S9S_MB_2U(SCH_1):PAGE313
     2 E1S_0_LED_ACT_N @S9S_MB_2U_LIB.S9S_MB_2U(SCH_1):E1S_0_LED_ACT_N   I180 @S9S_MB_2U_LIB.S9S_MB_2U(SCH_1):PAGE313

R4607 Q_RES_0402LF-0,5%,1/16W,CHIP,CA
     1 LED_HDD_ACTIVITY_B_N @S9S_MB_2U_LIB.S9S_MB_2U(SCH_1):LED_HDD_ACTIVITY_B_N   I183 @S9S_MB_2U_LIB.S9S_MB_2U(SCH_1):PAGE313
     2 LED_HDD_ACTIVITY_B_PLD_N @S9S_MB_2U_LIB.S9S_MB_2U(SCH_1):LED_HDD_ACTIVITY_B_PLD_N   I183 @S9S_MB_2U_LIB.S9S_MB_2U(SCH_1):PAGE313

R4608 Q_RES_0402LF-33.2,1%,1/16W,CHIA
     1 GPU_FPGA_RST_N @S9S_MB_2U_LIB.S9S_MB_2U(SCH_1):GPU_FPGA_RST_N   I190 @S9S_MB_2U_LIB.S9S_MB_2U(SCH_1):PAGE313
     2 GPU_FPGA_RST_R_N @S9S_MB_2U_LIB.S9S_MB_2U(SCH_1):GPU_FPGA_RST_R_N   I190 @S9S_MB_2U_LIB.S9S_MB_2U(SCH_1):PAGE313

R4609 Q_RES_0402LF-33.2,1%,1/16W,CHIA
     1 FM_JTAG_TCK_MUX_SEL_R @S9S_MB_2U_LIB.S9S_MB_2U(SCH_1):FM_JTAG_TCK_MUX_SEL_R   I194 @S9S_MB_2U_LIB.S9S_MB_2U(SCH_1):PAGE313
     2 FM_JTAG_TCK_MUX_SEL @S9S_MB_2U_LIB.S9S_MB_2U(SCH_1):FM_JTAG_TCK_MUX_SEL   I194 @S9S_MB_2U_LIB.S9S_MB_2U(SCH_1):PAGE313

R4610 Q_RES_0402LF-33.2,1%,1/16W,CHIA
     1 CLK_GEN2_GPU_FPGA_OE_R_N @S9S_MB_2U_LIB.S9S_MB_2U(SCH_1):CLK_GEN2_GPU_FPGA_OE_R_N   I200 @S9S_MB_2U_LIB.S9S_MB_2U(SCH_1):PAGE313
     2 CLK_GEN2_GPU_FPGA_OE_N @S9S_MB_2U_LIB.S9S_MB_2U(SCH_1):CLK_GEN2_GPU_FPGA_OE_N   I200 @S9S_MB_2U_LIB.S9S_MB_2U(SCH_1):PAGE313

R4611 Q_RES_0402LF-33.2,1%,1/16W,CHIA
     1 FM_BMC_CPU_FBRK_OUT_R_N @S9S_MB_2U_LIB.S9S_MB_2U(SCH_1):FM_BMC_CPU_FBRK_OUT_R_N   I206 @S9S_MB_2U_LIB.S9S_MB_2U(SCH_1):PAGE313
     2 FM_BMC_CPU_FBRK_OUT_N @S9S_MB_2U_LIB.S9S_MB_2U(SCH_1):FM_BMC_CPU_FBRK_OUT_N   I206 @S9S_MB_2U_LIB.S9S_MB_2U(SCH_1):PAGE313

R4612 Q_RES_0402LF-33.2,1%,1/16W,CHIA
     1 FM_PCH_SPKR @S9S_MB_2U_LIB.S9S_MB_2U(SCH_1):FM_PCH_SPKR   I211 @S9S_MB_2U_LIB.S9S_MB_2U(SCH_1):PAGE313
     2 FM_PCH_SPKR_R @S9S_MB_2U_LIB.S9S_MB_2U(SCH_1):FM_PCH_SPKR_R   I211 @S9S_MB_2U_LIB.S9S_MB_2U(SCH_1):PAGE313

R4613 Q_RES_0402LF-0,5%,1/16W,EMPTY,A
     1 OCP_V3_1_P3V3_PWRGD @S9S_MB_2U_LIB.S9S_MB_2U(SCH_1):OCP_V3_1_P3V3_PWRGD   I232 @S9S_MB_2U_LIB.S9S_MB_2U(SCH_1):PAGE154
     2 HP_OCP_V3_1_RST_R @S9S_MB_2U_LIB.S9S_MB_2U(SCH_1):HP_OCP_V3_1_RST_R   I232 @S9S_MB_2U_LIB.S9S_MB_2U(SCH_1):PAGE154

R4614 Q_RES_0402LF-33.2,1%,1/16W,CHIA
     1 HP_OCP_V3_1_RST @S9S_MB_2U_LIB.S9S_MB_2U(SCH_1):HP_OCP_V3_1_RST   I238 @S9S_MB_2U_LIB.S9S_MB_2U(SCH_1):PAGE154
     2 HP_OCP_V3_1_RST_R @S9S_MB_2U_LIB.S9S_MB_2U(SCH_1):HP_OCP_V3_1_RST_R   I238 @S9S_MB_2U_LIB.S9S_MB_2U(SCH_1):PAGE154

R4615 Q_RES_0402LF-0,5%,1/16W,EMPTY,A
     1 OCP_V3_2_P3V3_PWRGD @S9S_MB_2U_LIB.S9S_MB_2U(SCH_1):OCP_V3_2_P3V3_PWRGD    I96 @S9S_MB_2U_LIB.S9S_MB_2U(SCH_1):PAGE132
     2 HP_OCP_V3_2_RST_R @S9S_MB_2U_LIB.S9S_MB_2U(SCH_1):HP_OCP_V3_2_RST_R    I96 @S9S_MB_2U_LIB.S9S_MB_2U(SCH_1):PAGE132

R4616 Q_RES_0402LF-33.2,1%,1/16W,CHIA
     1 HP_OCP_V3_2_RST @S9S_MB_2U_LIB.S9S_MB_2U(SCH_1):HP_OCP_V3_2_RST   I100 @S9S_MB_2U_LIB.S9S_MB_2U(SCH_1):PAGE132
     2 HP_OCP_V3_2_RST_R @S9S_MB_2U_LIB.S9S_MB_2U(SCH_1):HP_OCP_V3_2_RST_R   I100 @S9S_MB_2U_LIB.S9S_MB_2U(SCH_1):PAGE132

R4617 Q_RES_0402LF-33.2,1%,1/16W,CHIA
     1 HP_LVC3_OCP_V3_2_PWRGD @S9S_MB_2U_LIB.S9S_MB_2U(SCH_1):HP_LVC3_OCP_V3_2_PWRGD    I99 @S9S_MB_2U_LIB.S9S_MB_2U(SCH_1):PAGE132
     2 HP_LVC3_OCP_V3_2_PWRGD_R @S9S_MB_2U_LIB.S9S_MB_2U(SCH_1):HP_LVC3_OCP_V3_2_PWRGD_R    I99 @S9S_MB_2U_LIB.S9S_MB_2U(SCH_1):PAGE132

R4618 Q_RES_0402LF-33.2,1%,1/16W,CHIA
     1 HP_LVC3_OCP_V3_1_PWRGD @S9S_MB_2U_LIB.S9S_MB_2U(SCH_1):HP_LVC3_OCP_V3_1_PWRGD   I237 @S9S_MB_2U_LIB.S9S_MB_2U(SCH_1):PAGE154
     2 HP_LVC3_OCP_V3_1_PWRGD_R @S9S_MB_2U_LIB.S9S_MB_2U(SCH_1):HP_LVC3_OCP_V3_1_PWRGD_R   I237 @S9S_MB_2U_LIB.S9S_MB_2U(SCH_1):PAGE154

R4620 Q_RES_0402LF-4.7K,5%,1/16W,CHIA
     1 P3V3_AUX @S9S_MB_2U_LIB.S9S_MB_2U(SCH_1):P3V3_AUX    I45 @S9S_MB_2U_LIB.S9S_MB_2U(SCH_1):PAGE326
     2 IRQ_UV_DETECT_N @S9S_MB_2U_LIB.S9S_MB_2U(SCH_1):IRQ_UV_DETECT_N    I45 @S9S_MB_2U_LIB.S9S_MB_2U(SCH_1):PAGE326

R4621 Q_RES_0402LF-33.2,1%,1/16W,CHIA
     1 H_CPU_CATERR_LVC2_BMC_R_N @S9S_MB_2U_LIB.S9S_MB_2U(SCH_1):H_CPU_CATERR_LVC2_BMC_R_N   I101 @S9S_MB_2U_LIB.S9S_MB_2U(SCH_1):PAGE321
     2 H_CPU_CATERR_LVC2_BMC_N @S9S_MB_2U_LIB.S9S_MB_2U(SCH_1):H_CPU_CATERR_LVC2_BMC_N   I101 @S9S_MB_2U_LIB.S9S_MB_2U(SCH_1):PAGE321

R4622 Q_RES_0402LF-2K,1%,1/16W,CHIP,A
     1 RST_PERST_SWB_N @S9S_MB_2U_LIB.S9S_MB_2U(SCH_1):RST_PERST_SWB_N    I66 @S9S_MB_2U_LIB.S9S_MB_2U(SCH_1):PAGE208
     2    GND @S9S_MB_2U_LIB.S9S_MB_2U(SCH_1):GND    I66 @S9S_MB_2U_LIB.S9S_MB_2U(SCH_1):PAGE208

R4623 Q_RES_0402LF-1K,1%,1/16W,CHIP,A
     1 P3V3_AUX @S9S_MB_2U_LIB.S9S_MB_2U(SCH_1):P3V3_AUX    I11 @S9S_MB_2U_LIB.S9S_MB_2U(SCH_1):PAGE235
     2 PU_JTAG_SW_PU @S9S_MB_2U_LIB.S9S_MB_2U(SCH_1):PU_JTAG_SW_PU    I11 @S9S_MB_2U_LIB.S9S_MB_2U(SCH_1):PAGE235

R4624 Q_RES_0402LF-0,5%,1/16W,CHIP,CA
     1 JTAG_BMC_SW_OE @S9S_MB_2U_LIB.S9S_MB_2U(SCH_1):JTAG_BMC_SW_OE    I14 @S9S_MB_2U_LIB.S9S_MB_2U(SCH_1):PAGE235
     2 JTAG_BMC_SW_R_OE @S9S_MB_2U_LIB.S9S_MB_2U(SCH_1):JTAG_BMC_SW_R_OE    I14 @S9S_MB_2U_LIB.S9S_MB_2U(SCH_1):PAGE235

R4625 Q_RES_0402LF-100,1%,1/16W,CHIPA
     1 JTAG_BMC_SW_OE @S9S_MB_2U_LIB.S9S_MB_2U(SCH_1):JTAG_BMC_SW_OE   I140 @S9S_MB_2U_LIB.S9S_MB_2U(SCH_1):PAGE314
     2 JTAG_BMC_SW_PLD_OE @S9S_MB_2U_LIB.S9S_MB_2U(SCH_1):JTAG_BMC_SW_PLD_OE   I140 @S9S_MB_2U_LIB.S9S_MB_2U(SCH_1):PAGE314

R4626 Q_RES_0402LF-0,5%,1/16W,CHIP,CA
     1 JTAG_BMC_TDO @S9S_MB_2U_LIB.S9S_MB_2U(SCH_1):JTAG_BMC_TDO    I18 @S9S_MB_2U_LIB.S9S_MB_2U(SCH_1):PAGE235
     2 JTAG_BMC_TDO_R @S9S_MB_2U_LIB.S9S_MB_2U(SCH_1):JTAG_BMC_TDO_R    I18 @S9S_MB_2U_LIB.S9S_MB_2U(SCH_1):PAGE235

R4627 Q_RES_0402LF-0,5%,1/16W,CHIP,CA
     1 JTAG_BMC_TDI @S9S_MB_2U_LIB.S9S_MB_2U(SCH_1):JTAG_BMC_TDI    I17 @S9S_MB_2U_LIB.S9S_MB_2U(SCH_1):PAGE235
     2 JTAG_BMC_TDI_R @S9S_MB_2U_LIB.S9S_MB_2U(SCH_1):JTAG_BMC_TDI_R    I17 @S9S_MB_2U_LIB.S9S_MB_2U(SCH_1):PAGE235

R4628 Q_RES_0402LF-0,5%,1/16W,CHIP,CA
     1 JTAG_BMC_TMS @S9S_MB_2U_LIB.S9S_MB_2U(SCH_1):JTAG_BMC_TMS    I16 @S9S_MB_2U_LIB.S9S_MB_2U(SCH_1):PAGE235
     2 JTAG_BMC_TMS_R @S9S_MB_2U_LIB.S9S_MB_2U(SCH_1):JTAG_BMC_TMS_R    I16 @S9S_MB_2U_LIB.S9S_MB_2U(SCH_1):PAGE235

R4629 Q_RES_0402LF-0,5%,1/16W,CHIP,CA
     1 JTAG_BMC_TCK @S9S_MB_2U_LIB.S9S_MB_2U(SCH_1):JTAG_BMC_TCK    I15 @S9S_MB_2U_LIB.S9S_MB_2U(SCH_1):PAGE235
     2 JTAG_BMC_TCK_R @S9S_MB_2U_LIB.S9S_MB_2U(SCH_1):JTAG_BMC_TCK_R    I15 @S9S_MB_2U_LIB.S9S_MB_2U(SCH_1):PAGE235

R4630 Q_RES_0402LF-0,5%,1/16W,CHIP,CA
     1 JTAG_BMC_SW_TDO_R @S9S_MB_2U_LIB.S9S_MB_2U(SCH_1):JTAG_BMC_SW_TDO_R    I27 @S9S_MB_2U_LIB.S9S_MB_2U(SCH_1):PAGE235
     2 JTAG_BMC_SW_TDO @S9S_MB_2U_LIB.S9S_MB_2U(SCH_1):JTAG_BMC_SW_TDO    I27 @S9S_MB_2U_LIB.S9S_MB_2U(SCH_1):PAGE235

R4631 Q_RES_0402LF-0,5%,1/16W,CHIP,CA
     1 JTAG_BMC_SW_TDI_R @S9S_MB_2U_LIB.S9S_MB_2U(SCH_1):JTAG_BMC_SW_TDI_R    I25 @S9S_MB_2U_LIB.S9S_MB_2U(SCH_1):PAGE235
     2 JTAG_BMC_SW_TDI @S9S_MB_2U_LIB.S9S_MB_2U(SCH_1):JTAG_BMC_SW_TDI    I25 @S9S_MB_2U_LIB.S9S_MB_2U(SCH_1):PAGE235

R4632 Q_RES_0402LF-0,5%,1/16W,CHIP,CA
     1 JTAG_BMC_SW_TMS_R @S9S_MB_2U_LIB.S9S_MB_2U(SCH_1):JTAG_BMC_SW_TMS_R    I26 @S9S_MB_2U_LIB.S9S_MB_2U(SCH_1):PAGE235
     2 JTAG_BMC_SW_TMS @S9S_MB_2U_LIB.S9S_MB_2U(SCH_1):JTAG_BMC_SW_TMS    I26 @S9S_MB_2U_LIB.S9S_MB_2U(SCH_1):PAGE235

R4633 Q_RES_0402LF-0,5%,1/16W,CHIP,CA
     1 JTAG_BMC_SW_TCK_R @S9S_MB_2U_LIB.S9S_MB_2U(SCH_1):JTAG_BMC_SW_TCK_R    I24 @S9S_MB_2U_LIB.S9S_MB_2U(SCH_1):PAGE235
     2 JTAG_BMC_SW_TCK @S9S_MB_2U_LIB.S9S_MB_2U(SCH_1):JTAG_BMC_SW_TCK    I24 @S9S_MB_2U_LIB.S9S_MB_2U(SCH_1):PAGE235

R4634 Q_RES_0402LF-1K,1%,1/16W,EMPTYA
     1 P3V3_AUX @S9S_MB_2U_LIB.S9S_MB_2U(SCH_1):P3V3_AUX     I4 @S9S_MB_2U_LIB.S9S_MB_2U(SCH_1):PAGE235
     2 JTAG_BMC_SW_OE @S9S_MB_2U_LIB.S9S_MB_2U(SCH_1):JTAG_BMC_SW_OE     I4 @S9S_MB_2U_LIB.S9S_MB_2U(SCH_1):PAGE235

R4635 Q_RES_0402LF-10K,1%,1/16W,CHIPA
     1 JTAG_BMC_SW_OE @S9S_MB_2U_LIB.S9S_MB_2U(SCH_1):JTAG_BMC_SW_OE     I3 @S9S_MB_2U_LIB.S9S_MB_2U(SCH_1):PAGE235
     2    GND @S9S_MB_2U_LIB.S9S_MB_2U(SCH_1):GND     I3 @S9S_MB_2U_LIB.S9S_MB_2U(SCH_1):PAGE235

R4636 Q_RES_0402LF-200K,1%,1/16W,CHIA
     1 USB3_PCH_RX_DP<4> @S9S_MB_2U_LIB.S9S_MB_2U(SCH_1):USB3_PCH_RX_DP(4)    I23 @S9S_MB_2U_LIB.S9S_MB_2U(SCH_1):PAGE162
     2    GND @S9S_MB_2U_LIB.S9S_MB_2U(SCH_1):GND    I23 @S9S_MB_2U_LIB.S9S_MB_2U(SCH_1):PAGE162

R4637 Q_RES_0402LF-200K,1%,1/16W,CHIA
     1 USB3_PCH_RX_DN<4> @S9S_MB_2U_LIB.S9S_MB_2U(SCH_1):USB3_PCH_RX_DN(4)    I24 @S9S_MB_2U_LIB.S9S_MB_2U(SCH_1):PAGE162
     2    GND @S9S_MB_2U_LIB.S9S_MB_2U(SCH_1):GND    I24 @S9S_MB_2U_LIB.S9S_MB_2U(SCH_1):PAGE162

R4638 Q_RES_1206LF-243,1%,1/4W,CHIP,A
     1    P5V @S9S_MB_2U_LIB.S9S_MB_2U(SCH_1):P5V    I77 @S9S_MB_2U_LIB.S9S_MB_2U(SCH_1):PAGE246
     2 VR_P5V_EN_D @S9S_MB_2U_LIB.S9S_MB_2U(SCH_1):VR_P5V_EN_D    I77 @S9S_MB_2U_LIB.S9S_MB_2U(SCH_1):PAGE246

R4639 Q_RES_1206LF-243,1%,1/4W,CHIP,A
     1    P5V @S9S_MB_2U_LIB.S9S_MB_2U(SCH_1):P5V    I78 @S9S_MB_2U_LIB.S9S_MB_2U(SCH_1):PAGE246
     2 VR_P5V_EN_D @S9S_MB_2U_LIB.S9S_MB_2U(SCH_1):VR_P5V_EN_D    I78 @S9S_MB_2U_LIB.S9S_MB_2U(SCH_1):PAGE246

R4640 Q_RES_1206LF-243,1%,1/4W,CHIP,A
     1    P5V @S9S_MB_2U_LIB.S9S_MB_2U(SCH_1):P5V    I79 @S9S_MB_2U_LIB.S9S_MB_2U(SCH_1):PAGE246
     2 VR_P5V_EN_D @S9S_MB_2U_LIB.S9S_MB_2U(SCH_1):VR_P5V_EN_D    I79 @S9S_MB_2U_LIB.S9S_MB_2U(SCH_1):PAGE246

R4641 Q_RES_1206LF-243,1%,1/4W,CHIP,A
     1    P5V @S9S_MB_2U_LIB.S9S_MB_2U(SCH_1):P5V    I80 @S9S_MB_2U_LIB.S9S_MB_2U(SCH_1):PAGE246
     2 VR_P5V_EN_D @S9S_MB_2U_LIB.S9S_MB_2U(SCH_1):VR_P5V_EN_D    I80 @S9S_MB_2U_LIB.S9S_MB_2U(SCH_1):PAGE246

R4642 Q_RES_0402LF-1K,1%,1/16W,EMPTYA
     1 P3V3_AUX @S9S_MB_2U_LIB.S9S_MB_2U(SCH_1):P3V3_AUX     I7 @S9S_MB_2U_LIB.S9S_MB_2U(SCH_1):PAGE159
     2 FM_P2E_BUF2_VODB_DB @S9S_MB_2U_LIB.S9S_MB_2U(SCH_1):FM_P2E_BUF2_VODB_DB     I7 @S9S_MB_2U_LIB.S9S_MB_2U(SCH_1):PAGE159

R4643 Q_RES_0402LF-1K,1%,1/16W,EMPTYA
     1 P3V3_AUX @S9S_MB_2U_LIB.S9S_MB_2U(SCH_1):P3V3_AUX    I13 @S9S_MB_2U_LIB.S9S_MB_2U(SCH_1):PAGE159
     2 FM_P2E_BUF2_VODA_DB @S9S_MB_2U_LIB.S9S_MB_2U(SCH_1):FM_P2E_BUF2_VODA_DB    I13 @S9S_MB_2U_LIB.S9S_MB_2U(SCH_1):PAGE159

R4644 Q_RES_0402LF-1K,1%,1/16W,EMPTYA
     1 P3V3_AUX @S9S_MB_2U_LIB.S9S_MB_2U(SCH_1):P3V3_AUX    I11 @S9S_MB_2U_LIB.S9S_MB_2U(SCH_1):PAGE159
     2 FM_P2E_BUF2_EQB1 @S9S_MB_2U_LIB.S9S_MB_2U(SCH_1):FM_P2E_BUF2_EQB1    I11 @S9S_MB_2U_LIB.S9S_MB_2U(SCH_1):PAGE159

R4645 Q_RES_0402LF-1K,1%,1/16W,EMPTYA
     1 P3V3_AUX @S9S_MB_2U_LIB.S9S_MB_2U(SCH_1):P3V3_AUX    I16 @S9S_MB_2U_LIB.S9S_MB_2U(SCH_1):PAGE159
     2 FM_P2E_BUF2_EQB0 @S9S_MB_2U_LIB.S9S_MB_2U(SCH_1):FM_P2E_BUF2_EQB0    I16 @S9S_MB_2U_LIB.S9S_MB_2U(SCH_1):PAGE159

R4646 Q_RES_0402LF-1K,1%,1/16W,EMPTYA
     1 FM_P2E_BUF2_EQB0 @S9S_MB_2U_LIB.S9S_MB_2U(SCH_1):FM_P2E_BUF2_EQB0    I15 @S9S_MB_2U_LIB.S9S_MB_2U(SCH_1):PAGE159
     2    GND @S9S_MB_2U_LIB.S9S_MB_2U(SCH_1):GND    I15 @S9S_MB_2U_LIB.S9S_MB_2U(SCH_1):PAGE159

R4647 Q_RES_0402LF-1K,1%,1/16W,CHIP,A
     1 FM_P2E_BUF2_VODA_DB @S9S_MB_2U_LIB.S9S_MB_2U(SCH_1):FM_P2E_BUF2_VODA_DB     I4 @S9S_MB_2U_LIB.S9S_MB_2U(SCH_1):PAGE159
     2    GND @S9S_MB_2U_LIB.S9S_MB_2U(SCH_1):GND     I4 @S9S_MB_2U_LIB.S9S_MB_2U(SCH_1):PAGE159

R4648 Q_RES_0402LF-1K,1%,1/16W,EMPTYA
     1 P3V3_AUX @S9S_MB_2U_LIB.S9S_MB_2U(SCH_1):P3V3_AUX    I72 @S9S_MB_2U_LIB.S9S_MB_2U(SCH_1):PAGE159
     2 FM_P2E_BUF2_EQA1 @S9S_MB_2U_LIB.S9S_MB_2U(SCH_1):FM_P2E_BUF2_EQA1    I72 @S9S_MB_2U_LIB.S9S_MB_2U(SCH_1):PAGE159

R4649 Q_RES_0402LF-1K,1%,1/16W,EMPTYA
     1 P3V3_AUX @S9S_MB_2U_LIB.S9S_MB_2U(SCH_1):P3V3_AUX    I74 @S9S_MB_2U_LIB.S9S_MB_2U(SCH_1):PAGE159
     2 FM_P2E_BUF2_EQA0 @S9S_MB_2U_LIB.S9S_MB_2U(SCH_1):FM_P2E_BUF2_EQA0    I74 @S9S_MB_2U_LIB.S9S_MB_2U(SCH_1):PAGE159

R4650 Q_RES_0402LF-1K,1%,1/16W,EMPTYA
     1 FM_P2E_BUF2_EQA0 @S9S_MB_2U_LIB.S9S_MB_2U(SCH_1):FM_P2E_BUF2_EQA0    I71 @S9S_MB_2U_LIB.S9S_MB_2U(SCH_1):PAGE159
     2    GND @S9S_MB_2U_LIB.S9S_MB_2U(SCH_1):GND    I71 @S9S_MB_2U_LIB.S9S_MB_2U(SCH_1):PAGE159

R4651 Q_RES_0402LF-0,5%,1/16W,CHIP,CA
     1 FM_P2E_EN2_N @S9S_MB_2U_LIB.S9S_MB_2U(SCH_1):FM_P2E_EN2_N   I102 @S9S_MB_2U_LIB.S9S_MB_2U(SCH_1):PAGE159
     2 CLK_GEN2_GPU_FPGA_OE_OR_N @S9S_MB_2U_LIB.S9S_MB_2U(SCH_1):CLK_GEN2_GPU_FPGA_OE_OR_N   I102 @S9S_MB_2U_LIB.S9S_MB_2U(SCH_1):PAGE159

R4652 Q_RES_0402LF-0,5%,1/16W,EMPTY,A
     1 A_HSC_LOW_DRAIN @S9S_MB_2U_LIB.S9S_MB_2U(SCH_1):A_HSC_LOW_DRAIN    I48 @S9S_MB_2U_LIB.S9S_MB_2U(SCH_1):PAGE326
     2 HSC_D_OC @S9S_MB_2U_LIB.S9S_MB_2U(SCH_1):HSC_D_OC    I48 @S9S_MB_2U_LIB.S9S_MB_2U(SCH_1):PAGE326

R4653 Q_RES_0402LF-1K,1%,1/16W,CHIP,A
     1 FM_P2E_BUF2_VODB_DB @S9S_MB_2U_LIB.S9S_MB_2U(SCH_1):FM_P2E_BUF2_VODB_DB     I2 @S9S_MB_2U_LIB.S9S_MB_2U(SCH_1):PAGE159
     2    GND @S9S_MB_2U_LIB.S9S_MB_2U(SCH_1):GND     I2 @S9S_MB_2U_LIB.S9S_MB_2U(SCH_1):PAGE159

R4654 Q_RES_0402LF-1K,1%,1/16W,CHIP,A
     1 FM_P2E_BUF2_EQA1 @S9S_MB_2U_LIB.S9S_MB_2U(SCH_1):FM_P2E_BUF2_EQA1    I67 @S9S_MB_2U_LIB.S9S_MB_2U(SCH_1):PAGE159
     2    GND @S9S_MB_2U_LIB.S9S_MB_2U(SCH_1):GND    I67 @S9S_MB_2U_LIB.S9S_MB_2U(SCH_1):PAGE159

R4655 Q_RES_0402LF-1K,1%,1/16W,EMPTYA
     1 P3V3_AUX @S9S_MB_2U_LIB.S9S_MB_2U(SCH_1):P3V3_AUX    I62 @S9S_MB_2U_LIB.S9S_MB_2U(SCH_1):PAGE159
     2 FM_P2E_BUF2_RXDET @S9S_MB_2U_LIB.S9S_MB_2U(SCH_1):FM_P2E_BUF2_RXDET    I62 @S9S_MB_2U_LIB.S9S_MB_2U(SCH_1):PAGE159

R4656 Q_RES_0402LF-1K,1%,1/16W,CHIP,A
     1 P3V3_AUX @S9S_MB_2U_LIB.S9S_MB_2U(SCH_1):P3V3_AUX    I66 @S9S_MB_2U_LIB.S9S_MB_2U(SCH_1):PAGE159
     2 FM_P2E_BUF2_SD_TH @S9S_MB_2U_LIB.S9S_MB_2U(SCH_1):FM_P2E_BUF2_SD_TH    I66 @S9S_MB_2U_LIB.S9S_MB_2U(SCH_1):PAGE159

R4657 Q_RES_0402LF-1K,1%,1/16W,EMPTYA
     1 FM_P2E_BUF2_SD_TH @S9S_MB_2U_LIB.S9S_MB_2U(SCH_1):FM_P2E_BUF2_SD_TH    I65 @S9S_MB_2U_LIB.S9S_MB_2U(SCH_1):PAGE159
     2    GND @S9S_MB_2U_LIB.S9S_MB_2U(SCH_1):GND    I65 @S9S_MB_2U_LIB.S9S_MB_2U(SCH_1):PAGE159

R4658 Q_RES_0402LF-1K,1%,1/16W,EMPTYA
     1 FM_P2E_BUF2_VOD_SEL @S9S_MB_2U_LIB.S9S_MB_2U(SCH_1):FM_P2E_BUF2_VOD_SEL    I80 @S9S_MB_2U_LIB.S9S_MB_2U(SCH_1):PAGE159
     2    GND @S9S_MB_2U_LIB.S9S_MB_2U(SCH_1):GND    I80 @S9S_MB_2U_LIB.S9S_MB_2U(SCH_1):PAGE159

R4659 Q_RES_0402LF-0,5%,1/16W,CHIP,CA
     1 P2E_MB_BMC_TX_C_DP<0> @S9S_MB_2U_LIB.S9S_MB_2U(SCH_1):P2E_MB_BMC_TX_C_DP(0)    I46 @S9S_MB_2U_LIB.S9S_MB_2U(SCH_1):PAGE159
     2 P2E_MB_BMC_TX_C_R1_DP<0> @S9S_MB_2U_LIB.S9S_MB_2U(SCH_1):P2E_MB_BMC_TX_C_R1_DP(0)    I46 @S9S_MB_2U_LIB.S9S_MB_2U(SCH_1):PAGE159

R4660 Q_RES_0402LF-0,5%,1/16W,CHIP,CA
     1 P2E_MB_BMC_TX_C_DN<0> @S9S_MB_2U_LIB.S9S_MB_2U(SCH_1):P2E_MB_BMC_TX_C_DN(0)    I45 @S9S_MB_2U_LIB.S9S_MB_2U(SCH_1):PAGE159
     2 P2E_MB_BMC_TX_C_R1_DN<0> @S9S_MB_2U_LIB.S9S_MB_2U(SCH_1):P2E_MB_BMC_TX_C_R1_DN(0)    I45 @S9S_MB_2U_LIB.S9S_MB_2U(SCH_1):PAGE159

R4661 Q_RES_0402LF-0,5%,1/16W,EMPTY,A
     1 P2E_MB_BMC_TX_C_DP<0> @S9S_MB_2U_LIB.S9S_MB_2U(SCH_1):P2E_MB_BMC_TX_C_DP(0)    I44 @S9S_MB_2U_LIB.S9S_MB_2U(SCH_1):PAGE159
     2 P2E_MB_BMC_TX_C_R2_DP<0> @S9S_MB_2U_LIB.S9S_MB_2U(SCH_1):P2E_MB_BMC_TX_C_R2_DP(0)    I44 @S9S_MB_2U_LIB.S9S_MB_2U(SCH_1):PAGE159

R4662 Q_RES_0402LF-0,5%,1/16W,EMPTY,A
     1 P2E_MB_BMC_TX_C_DN<0> @S9S_MB_2U_LIB.S9S_MB_2U(SCH_1):P2E_MB_BMC_TX_C_DN(0)    I43 @S9S_MB_2U_LIB.S9S_MB_2U(SCH_1):PAGE159
     2 P2E_MB_BMC_TX_C_R2_DN<0> @S9S_MB_2U_LIB.S9S_MB_2U(SCH_1):P2E_MB_BMC_TX_C_R2_DN(0)    I43 @S9S_MB_2U_LIB.S9S_MB_2U(SCH_1):PAGE159

R4663 Q_RES_0402LF-0,5%,1/16W,CHIP,CA
     1 P2E_MB_BMC_RX_DP<0> @S9S_MB_2U_LIB.S9S_MB_2U(SCH_1):P2E_MB_BMC_RX_DP(0)    I41 @S9S_MB_2U_LIB.S9S_MB_2U(SCH_1):PAGE159
     2 P2E_MB_BMC_RX_R1_DP<0> @S9S_MB_2U_LIB.S9S_MB_2U(SCH_1):P2E_MB_BMC_RX_R1_DP(0)    I41 @S9S_MB_2U_LIB.S9S_MB_2U(SCH_1):PAGE159

R4664 Q_RES_0402LF-0,5%,1/16W,CHIP,CA
     1 P2E_MB_BMC_RX_DN<0> @S9S_MB_2U_LIB.S9S_MB_2U(SCH_1):P2E_MB_BMC_RX_DN(0)    I42 @S9S_MB_2U_LIB.S9S_MB_2U(SCH_1):PAGE159
     2 P2E_MB_BMC_RX_R1_DN<0> @S9S_MB_2U_LIB.S9S_MB_2U(SCH_1):P2E_MB_BMC_RX_R1_DN(0)    I42 @S9S_MB_2U_LIB.S9S_MB_2U(SCH_1):PAGE159

R4665 Q_RES_0402LF-0,5%,1/16W,EMPTY,A
     1 P2E_MB_BMC_RX_DP<0> @S9S_MB_2U_LIB.S9S_MB_2U(SCH_1):P2E_MB_BMC_RX_DP(0)    I36 @S9S_MB_2U_LIB.S9S_MB_2U(SCH_1):PAGE159
     2 P2E_MB_BMC_RX_R2_DP<0> @S9S_MB_2U_LIB.S9S_MB_2U(SCH_1):P2E_MB_BMC_RX_R2_DP(0)    I36 @S9S_MB_2U_LIB.S9S_MB_2U(SCH_1):PAGE159

R4666 Q_RES_0402LF-0,5%,1/16W,EMPTY,A
     1 P2E_MB_BMC_RX_DN<0> @S9S_MB_2U_LIB.S9S_MB_2U(SCH_1):P2E_MB_BMC_RX_DN(0)    I35 @S9S_MB_2U_LIB.S9S_MB_2U(SCH_1):PAGE159
     2 P2E_MB_BMC_RX_R2_DN<0> @S9S_MB_2U_LIB.S9S_MB_2U(SCH_1):P2E_MB_BMC_RX_R2_DN(0)    I35 @S9S_MB_2U_LIB.S9S_MB_2U(SCH_1):PAGE159

R4667 Q_RES_0402LF-160K,1%,1/16W,EMPA
     1 HSC_CSOUT @S9S_MB_2U_LIB.S9S_MB_2U(SCH_1):HSC_CSOUT    I14 @S9S_MB_2U_LIB.S9S_MB_2U(SCH_1):PAGE326
     2 A_HSC_LOW @S9S_MB_2U_LIB.S9S_MB_2U(SCH_1):A_HSC_LOW    I14 @S9S_MB_2U_LIB.S9S_MB_2U(SCH_1):PAGE326

R4668 Q_RES_0402LF-10K,1%,1/16W,EMPTA
     1 A_HSC_LOW @S9S_MB_2U_LIB.S9S_MB_2U(SCH_1):A_HSC_LOW    I13 @S9S_MB_2U_LIB.S9S_MB_2U(SCH_1):PAGE326
     2    GND @S9S_MB_2U_LIB.S9S_MB_2U(SCH_1):GND    I13 @S9S_MB_2U_LIB.S9S_MB_2U(SCH_1):PAGE326

R4669 Q_RES_0402LF-160K,1%,1/16W,EMPA
     1 HSC_CSOUT @S9S_MB_2U_LIB.S9S_MB_2U(SCH_1):HSC_CSOUT    I25 @S9S_MB_2U_LIB.S9S_MB_2U(SCH_1):PAGE326
     2 A_HSC_HIGH @S9S_MB_2U_LIB.S9S_MB_2U(SCH_1):A_HSC_HIGH    I25 @S9S_MB_2U_LIB.S9S_MB_2U(SCH_1):PAGE326

R4670 Q_RES_0402LF-10K,1%,1/16W,EMPTA
     1 A_HSC_HIGH @S9S_MB_2U_LIB.S9S_MB_2U(SCH_1):A_HSC_HIGH    I24 @S9S_MB_2U_LIB.S9S_MB_2U(SCH_1):PAGE326
     2    GND @S9S_MB_2U_LIB.S9S_MB_2U(SCH_1):GND    I24 @S9S_MB_2U_LIB.S9S_MB_2U(SCH_1):PAGE326

R4671 Q_RES_0402LF-10K,1%,1/16W,EMPTA
     1 P3V3_AUX @S9S_MB_2U_LIB.S9S_MB_2U(SCH_1):P3V3_AUX    I51 @S9S_MB_2U_LIB.S9S_MB_2U(SCH_1):PAGE326
     2 HSC_D_OC @S9S_MB_2U_LIB.S9S_MB_2U(SCH_1):HSC_D_OC    I51 @S9S_MB_2U_LIB.S9S_MB_2U(SCH_1):PAGE326

R4672 Q_RES_0402LF-10K,1%,1/16W,EMPTA
     1 P3V3_AUX @S9S_MB_2U_LIB.S9S_MB_2U(SCH_1):P3V3_AUX    I53 @S9S_MB_2U_LIB.S9S_MB_2U(SCH_1):PAGE326
     2 A_HSC_LOW_GATE @S9S_MB_2U_LIB.S9S_MB_2U(SCH_1):A_HSC_LOW_GATE    I53 @S9S_MB_2U_LIB.S9S_MB_2U(SCH_1):PAGE326

R4673 Q_RES_0402LF-0,5%,1/16W,EMPTY,A
     1 A_HSC_LOW_GATE @S9S_MB_2U_LIB.S9S_MB_2U(SCH_1):A_HSC_LOW_GATE    I44 @S9S_MB_2U_LIB.S9S_MB_2U(SCH_1):PAGE326
     2    GND @S9S_MB_2U_LIB.S9S_MB_2U(SCH_1):GND    I44 @S9S_MB_2U_LIB.S9S_MB_2U(SCH_1):PAGE326

R4674 Q_RES_0402LF-10K,1%,1/16W,CHIPA
     1 FM_SLP_SUS_RSM_RST_N @S9S_MB_2U_LIB.S9S_MB_2U(SCH_1):FM_SLP_SUS_RSM_RST_N    I46 @S9S_MB_2U_LIB.S9S_MB_2U(SCH_1):PAGE209
     2    GND @S9S_MB_2U_LIB.S9S_MB_2U(SCH_1):GND    I46 @S9S_MB_2U_LIB.S9S_MB_2U(SCH_1):PAGE209

R4677 Q_RES_0402LF-33.2,1%,1/16W,CHIA
     1 PWRGD_P3V3_R1 @S9S_MB_2U_LIB.S9S_MB_2U(SCH_1):PWRGD_P3V3_R1    I91 @S9S_MB_2U_LIB.S9S_MB_2U(SCH_1):PAGE246
     2 PWRGD_P3V3 @S9S_MB_2U_LIB.S9S_MB_2U(SCH_1):PWRGD_P3V3    I91 @S9S_MB_2U_LIB.S9S_MB_2U(SCH_1):PAGE246

R4678 Q_RES_0402LF-1K,1%,1/16W,CHIP,A
     1 PWRGD_P5V_ISO_R @S9S_MB_2U_LIB.S9S_MB_2U(SCH_1):PWRGD_P5V_ISO_R   I104 @S9S_MB_2U_LIB.S9S_MB_2U(SCH_1):PAGE246
     2 PWRGD_P5V_ISO @S9S_MB_2U_LIB.S9S_MB_2U(SCH_1):PWRGD_P5V_ISO   I104 @S9S_MB_2U_LIB.S9S_MB_2U(SCH_1):PAGE246

R4679 Q_RES_0402LF-10K,1%,1/16W,CHIPA
     1    P5V @S9S_MB_2U_LIB.S9S_MB_2U(SCH_1):P5V    I96 @S9S_MB_2U_LIB.S9S_MB_2U(SCH_1):PAGE246
     2 PWRGD_P5V @S9S_MB_2U_LIB.S9S_MB_2U(SCH_1):PWRGD_P5V    I96 @S9S_MB_2U_LIB.S9S_MB_2U(SCH_1):PAGE246

R4680 Q_RES_0402LF-100K,1%,1/16W,CHIA
     1 P12V_AUX @S9S_MB_2U_LIB.S9S_MB_2U(SCH_1):P12V_AUX   I102 @S9S_MB_2U_LIB.S9S_MB_2U(SCH_1):PAGE246
     2 PWRGD_P5V_N @S9S_MB_2U_LIB.S9S_MB_2U(SCH_1):PWRGD_P5V_N   I102 @S9S_MB_2U_LIB.S9S_MB_2U(SCH_1):PAGE246

R4681 Q_RES_0402LF-100K,1%,1/16W,CHIA
     1 PWRGD_P3V3_R1 @S9S_MB_2U_LIB.S9S_MB_2U(SCH_1):PWRGD_P3V3_R1   I109 @S9S_MB_2U_LIB.S9S_MB_2U(SCH_1):PAGE246
     2    GND @S9S_MB_2U_LIB.S9S_MB_2U(SCH_1):GND   I109 @S9S_MB_2U_LIB.S9S_MB_2U(SCH_1):PAGE246

R4682 Q_RES_0402LF-100K,1%,1/16W,CHIA
     1 PWRGD_P5V @S9S_MB_2U_LIB.S9S_MB_2U(SCH_1):PWRGD_P5V   I112 @S9S_MB_2U_LIB.S9S_MB_2U(SCH_1):PAGE246
     2    GND @S9S_MB_2U_LIB.S9S_MB_2U(SCH_1):GND   I112 @S9S_MB_2U_LIB.S9S_MB_2U(SCH_1):PAGE246

R4684 Q_RES_0402LF-0,5%,1/16W,EMPTY,A
     1 P12V_HSC_TEMP_ALERT_N @S9S_MB_2U_LIB.S9S_MB_2U(SCH_1):P12V_HSC_TEMP_ALERT_N    I14 @S9S_MB_2U_LIB.S9S_MB_2U(SCH_1):PAGE327
     2 P12V_HSC_TEMP_ALERT_R_N @S9S_MB_2U_LIB.S9S_MB_2U(SCH_1):P12V_HSC_TEMP_ALERT_R_N    I14 @S9S_MB_2U_LIB.S9S_MB_2U(SCH_1):PAGE327

R4685 Q_RES_0402LF-10.5K,1%,1/16W,EMA
     1 P3V3_AUX @S9S_MB_2U_LIB.S9S_MB_2U(SCH_1):P3V3_AUX    I23 @S9S_MB_2U_LIB.S9S_MB_2U(SCH_1):PAGE327
     2 P12V_HSC_TEMP_ALERT_R_N @S9S_MB_2U_LIB.S9S_MB_2U(SCH_1):P12V_HSC_TEMP_ALERT_R_N    I23 @S9S_MB_2U_LIB.S9S_MB_2U(SCH_1):PAGE327

R4686 Q_RES_0402LF-10.5K,1%,1/16W,EMA
     1 P3V3_AUX @S9S_MB_2U_LIB.S9S_MB_2U(SCH_1):P3V3_AUX    I17 @S9S_MB_2U_LIB.S9S_MB_2U(SCH_1):PAGE327
     2 P12V_HSC_T_CRIT_R_N @S9S_MB_2U_LIB.S9S_MB_2U(SCH_1):P12V_HSC_T_CRIT_R_N    I17 @S9S_MB_2U_LIB.S9S_MB_2U(SCH_1):PAGE327

R4687 Q_RES_0402LF-4.7K,1%,1/16W,EMPA
     1    GND @S9S_MB_2U_LIB.S9S_MB_2U(SCH_1):GND    I19 @S9S_MB_2U_LIB.S9S_MB_2U(SCH_1):PAGE240
     2 HSC_TYPE_ADC_A1 @S9S_MB_2U_LIB.S9S_MB_2U(SCH_1):HSC_TYPE_ADC_A1    I19 @S9S_MB_2U_LIB.S9S_MB_2U(SCH_1):PAGE240

R4688 Q_RES_0402LF-4.7K,1%,1/16W,EMPA
     1    GND @S9S_MB_2U_LIB.S9S_MB_2U(SCH_1):GND    I18 @S9S_MB_2U_LIB.S9S_MB_2U(SCH_1):PAGE240
     2 HSC_TYPE_ADC_A0 @S9S_MB_2U_LIB.S9S_MB_2U(SCH_1):HSC_TYPE_ADC_A0    I18 @S9S_MB_2U_LIB.S9S_MB_2U(SCH_1):PAGE240

R4689 Q_RES_0402LF-33.2,1%,1/16W,EMPA
     1 SMB_LM75_0_3V3AUX_SCL @S9S_MB_2U_LIB.S9S_MB_2U(SCH_1):SMB_LM75_0_3V3AUX_SCL    I38 @S9S_MB_2U_LIB.S9S_MB_2U(SCH_1):PAGE240
     2 SMB_HSC_TYPE_ADC_SCL @S9S_MB_2U_LIB.S9S_MB_2U(SCH_1):SMB_HSC_TYPE_ADC_SCL    I38 @S9S_MB_2U_LIB.S9S_MB_2U(SCH_1):PAGE240

R4690 Q_RES_0402LF-33.2,1%,1/16W,EMPA
     1 SMB_LM75_0_3V3AUX_SDA @S9S_MB_2U_LIB.S9S_MB_2U(SCH_1):SMB_LM75_0_3V3AUX_SDA    I37 @S9S_MB_2U_LIB.S9S_MB_2U(SCH_1):PAGE240
     2 SMB_HSC_TYPE_ADC_SDA @S9S_MB_2U_LIB.S9S_MB_2U(SCH_1):SMB_HSC_TYPE_ADC_SDA    I37 @S9S_MB_2U_LIB.S9S_MB_2U(SCH_1):PAGE240

R4691 Q_RES_0402LF-0,5%,1/16W,EMPTY,A
     1 HSC_TYPE_ADC_A0 @S9S_MB_2U_LIB.S9S_MB_2U(SCH_1):HSC_TYPE_ADC_A0    I16 @S9S_MB_2U_LIB.S9S_MB_2U(SCH_1):PAGE240
     2 SMB_HSC_TYPE_ADC_SDA @S9S_MB_2U_LIB.S9S_MB_2U(SCH_1):SMB_HSC_TYPE_ADC_SDA    I16 @S9S_MB_2U_LIB.S9S_MB_2U(SCH_1):PAGE240

R4692 Q_RES_0402LF-4.7K,1%,1/16W,EMPA
     1 P3V3_AUX @S9S_MB_2U_LIB.S9S_MB_2U(SCH_1):P3V3_AUX    I35 @S9S_MB_2U_LIB.S9S_MB_2U(SCH_1):PAGE240
     2 TP_HSC_TYPE_ADC_ALERT @S9S_MB_2U_LIB.S9S_MB_2U(SCH_1):TP_HSC_TYPE_ADC_ALERT    I35 @S9S_MB_2U_LIB.S9S_MB_2U(SCH_1):PAGE240

R4693 Q_RES_0402LF-0,5%,1/16W,EMPTY,A
     1 HSC_CSOUT @S9S_MB_2U_LIB.S9S_MB_2U(SCH_1):HSC_CSOUT    I29 @S9S_MB_2U_LIB.S9S_MB_2U(SCH_1):PAGE326
     2 HSC_D_OC @S9S_MB_2U_LIB.S9S_MB_2U(SCH_1):HSC_D_OC    I29 @S9S_MB_2U_LIB.S9S_MB_2U(SCH_1):PAGE326

R4694 Q_RES_0402LF-1K,1%,1/16W,CHIP,A
     1 FM_P2E_BUF2_EQB1 @S9S_MB_2U_LIB.S9S_MB_2U(SCH_1):FM_P2E_BUF2_EQB1    I10 @S9S_MB_2U_LIB.S9S_MB_2U(SCH_1):PAGE159
     2    GND @S9S_MB_2U_LIB.S9S_MB_2U(SCH_1):GND    I10 @S9S_MB_2U_LIB.S9S_MB_2U(SCH_1):PAGE159

R4695 Q_RES_0402LF-0,5%,1/16W,CHIP,CA
     1 SMB_SML1_PMBUS_HSC_SCL @S9S_MB_2U_LIB.S9S_MB_2U(SCH_1):SMB_SML1_PMBUS_HSC_SCL    I26 @S9S_MB_2U_LIB.S9S_MB_2U(SCH_1):PAGE327
     2 SMB_SML1_PMBUS_HSC_MODULE_SCL @S9S_MB_2U_LIB.S9S_MB_2U(SCH_1):SMB_SML1_PMBUS_HSC_MODULE_SCL    I26 @S9S_MB_2U_LIB.S9S_MB_2U(SCH_1):PAGE327

R4696 Q_RES_0402LF-0,5%,1/16W,CHIP,CA
     1 SMB_SML1_PMBUS_HSC_SDA @S9S_MB_2U_LIB.S9S_MB_2U(SCH_1):SMB_SML1_PMBUS_HSC_SDA    I25 @S9S_MB_2U_LIB.S9S_MB_2U(SCH_1):PAGE327
     2 SMB_SML1_PMBUS_HSC_MODULE_SDA @S9S_MB_2U_LIB.S9S_MB_2U(SCH_1):SMB_SML1_PMBUS_HSC_MODULE_SDA    I25 @S9S_MB_2U_LIB.S9S_MB_2U(SCH_1):PAGE327

R4697 Q_RES_0402LF-0,5%,1/16W,CHIP,CA
     1 RST_SRST_PLD_BMC_R_N @S9S_MB_2U_LIB.S9S_MB_2U(SCH_1):RST_SRST_PLD_BMC_R_N    I14 @S9S_MB_2U_LIB.S9S_MB_2U(SCH_1):PAGE314
     2 RST_SRST_PLD_BMC_N @S9S_MB_2U_LIB.S9S_MB_2U(SCH_1):RST_SRST_PLD_BMC_N    I14 @S9S_MB_2U_LIB.S9S_MB_2U(SCH_1):PAGE314

R4701 Q_RES_0402LF-4.7K,5%,1/16W,CHIA
     1 P3V3_AUX @S9S_MB_2U_LIB.S9S_MB_2U(SCH_1):P3V3_AUX    I41 @S9S_MB_2U_LIB.S9S_MB_2U(SCH_1):PAGE233
     2 FM_FAN_PWR_EN @S9S_MB_2U_LIB.S9S_MB_2U(SCH_1):FM_FAN_PWR_EN    I41 @S9S_MB_2U_LIB.S9S_MB_2U(SCH_1):PAGE233

R4702 Q_RES_0402LF-560,1%,1/16W,CHIPA
     1 LED_P12V_AUX_R1 @S9S_MB_2U_LIB.S9S_MB_2U(SCH_1):LED_P12V_AUX_R1    I64 @S9S_MB_2U_LIB.S9S_MB_2U(SCH_1):PAGE241
     2 LED_P12V_AUX_R2 @S9S_MB_2U_LIB.S9S_MB_2U(SCH_1):LED_P12V_AUX_R2    I64 @S9S_MB_2U_LIB.S9S_MB_2U(SCH_1):PAGE241

R4703 Q_RES_0402LF-560,1%,1/16W,CHIPA
     1 LED_P12V_PSU_R1 @S9S_MB_2U_LIB.S9S_MB_2U(SCH_1):LED_P12V_PSU_R1    I61 @S9S_MB_2U_LIB.S9S_MB_2U(SCH_1):PAGE241
     2 LED_P12V_PSU_R2 @S9S_MB_2U_LIB.S9S_MB_2U(SCH_1):LED_P12V_PSU_R2    I61 @S9S_MB_2U_LIB.S9S_MB_2U(SCH_1):PAGE241

R4704 Q_RES_0402LF-560,1%,1/16W,CHIPA
     1 LED_P12V_AUX_R2 @S9S_MB_2U_LIB.S9S_MB_2U(SCH_1):LED_P12V_AUX_R2    I65 @S9S_MB_2U_LIB.S9S_MB_2U(SCH_1):PAGE241
     2 LED_P12V_AUX_R3 @S9S_MB_2U_LIB.S9S_MB_2U(SCH_1):LED_P12V_AUX_R3    I65 @S9S_MB_2U_LIB.S9S_MB_2U(SCH_1):PAGE241

R4705 Q_RES_0402LF-560,1%,1/16W,CHIPA
     1 LED_P12V_PSU_R2 @S9S_MB_2U_LIB.S9S_MB_2U(SCH_1):LED_P12V_PSU_R2    I62 @S9S_MB_2U_LIB.S9S_MB_2U(SCH_1):PAGE241
     2 LED_P12V_PSU_R3 @S9S_MB_2U_LIB.S9S_MB_2U(SCH_1):LED_P12V_PSU_R3    I62 @S9S_MB_2U_LIB.S9S_MB_2U(SCH_1):PAGE241

R4706 Q_RES_0402LF-560,1%,1/16W,CHIPA
     1 LED_P12V_AUX_R3 @S9S_MB_2U_LIB.S9S_MB_2U(SCH_1):LED_P12V_AUX_R3    I66 @S9S_MB_2U_LIB.S9S_MB_2U(SCH_1):PAGE241
     2 P12V_AUX @S9S_MB_2U_LIB.S9S_MB_2U(SCH_1):P12V_AUX    I66 @S9S_MB_2U_LIB.S9S_MB_2U(SCH_1):PAGE241

R4707 Q_RES_0402LF-560,1%,1/16W,CHIPA
     1 LED_P12V_PSU_R3 @S9S_MB_2U_LIB.S9S_MB_2U(SCH_1):LED_P12V_PSU_R3    I63 @S9S_MB_2U_LIB.S9S_MB_2U(SCH_1):PAGE241
     2 P12V_PSU @S9S_MB_2U_LIB.S9S_MB_2U(SCH_1):P12V_PSU    I63 @S9S_MB_2U_LIB.S9S_MB_2U(SCH_1):PAGE241

R4708 Q_RES_0402LF-0,5%,1/16W,EMPTY,A
     1 P12V_SCM_FAULT_N @S9S_MB_2U_LIB.S9S_MB_2U(SCH_1):P12V_SCM_FAULT_N    I77 @S9S_MB_2U_LIB.S9S_MB_2U(SCH_1):PAGE229
     2 P12V_SCM_FAULT_R_N @S9S_MB_2U_LIB.S9S_MB_2U(SCH_1):P12V_SCM_FAULT_R_N    I77 @S9S_MB_2U_LIB.S9S_MB_2U(SCH_1):PAGE229

R4709 Q_RES_0402LF-0,5%,1/16W,CHIP,CA
     1 P12V_SCM_FLTB_N @S9S_MB_2U_LIB.S9S_MB_2U(SCH_1):P12V_SCM_FLTB_N    I44 @S9S_MB_2U_LIB.S9S_MB_2U(SCH_1):PAGE229
     2 P12V_SCM_FAULT_R_N @S9S_MB_2U_LIB.S9S_MB_2U(SCH_1):P12V_SCM_FAULT_R_N    I44 @S9S_MB_2U_LIB.S9S_MB_2U(SCH_1):PAGE229

R4710 Q_RES_0402LF-4.7K,5%,1/16W,CHIA
     1 P3V3_AUX @S9S_MB_2U_LIB.S9S_MB_2U(SCH_1):P3V3_AUX    I74 @S9S_MB_2U_LIB.S9S_MB_2U(SCH_1):PAGE241
     2 LED_P12V_SCM_FAULT_D1 @S9S_MB_2U_LIB.S9S_MB_2U(SCH_1):LED_P12V_SCM_FAULT_D1    I74 @S9S_MB_2U_LIB.S9S_MB_2U(SCH_1):PAGE241

R4711 Q_RES_0402LF-249,1%,1/16W,CHIPA
     1 LED_P12V_SCM_FAULT @S9S_MB_2U_LIB.S9S_MB_2U(SCH_1):LED_P12V_SCM_FAULT    I68 @S9S_MB_2U_LIB.S9S_MB_2U(SCH_1):PAGE241
     2 P3V3_AUX @S9S_MB_2U_LIB.S9S_MB_2U(SCH_1):P3V3_AUX    I68 @S9S_MB_2U_LIB.S9S_MB_2U(SCH_1):PAGE241

R4712 Q_RES_0402LF-100K,1%,1/16W,CHIA
     1 RST_PFR_OVR_RTC @S9S_MB_2U_LIB.S9S_MB_2U(SCH_1):RST_PFR_OVR_RTC   I125 @S9S_MB_2U_LIB.S9S_MB_2U(SCH_1):PAGE177
     2    GND @S9S_MB_2U_LIB.S9S_MB_2U(SCH_1):GND   I125 @S9S_MB_2U_LIB.S9S_MB_2U(SCH_1):PAGE177

R4713 Q_RES_0402LF-100K,1%,1/16W,CHIA
     1 RST_PFR_OVR_SRTC @S9S_MB_2U_LIB.S9S_MB_2U(SCH_1):RST_PFR_OVR_SRTC   I127 @S9S_MB_2U_LIB.S9S_MB_2U(SCH_1):PAGE177
     2    GND @S9S_MB_2U_LIB.S9S_MB_2U(SCH_1):GND   I127 @S9S_MB_2U_LIB.S9S_MB_2U(SCH_1):PAGE177

R4714 Q_RES_0402LF-33.2,1%,1/16W,CHIA
     1 SMB_HOST_3V3AUX_SDA_R4 @S9S_MB_2U_LIB.S9S_MB_2U(SCH_1):SMB_HOST_3V3AUX_SDA_R4   I197 @S9S_MB_2U_LIB.S9S_MB_2U(SCH_1):PAGE314
     2 SMB_HOST_3V3AUX_PLD_SDA @S9S_MB_2U_LIB.S9S_MB_2U(SCH_1):SMB_HOST_3V3AUX_PLD_SDA   I197 @S9S_MB_2U_LIB.S9S_MB_2U(SCH_1):PAGE314

R4715 Q_RES_0402LF-33.2,1%,1/16W,CHIA
     1 SMB_HOST_3V3AUX_SCL_R4 @S9S_MB_2U_LIB.S9S_MB_2U(SCH_1):SMB_HOST_3V3AUX_SCL_R4   I198 @S9S_MB_2U_LIB.S9S_MB_2U(SCH_1):PAGE314
     2 SMB_HOST_3V3AUX_PLD_SCL @S9S_MB_2U_LIB.S9S_MB_2U(SCH_1):SMB_HOST_3V3AUX_PLD_SCL   I198 @S9S_MB_2U_LIB.S9S_MB_2U(SCH_1):PAGE314

R4716 Q_RES_0402LF-8.45K,1%,1/16W,EMA
     1 P3V3_AUX @S9S_MB_2U_LIB.S9S_MB_2U(SCH_1):P3V3_AUX    I40 @S9S_MB_2U_LIB.S9S_MB_2U(SCH_1):PAGE213
     2 FM_AC_PWR_BTN_R_N @S9S_MB_2U_LIB.S9S_MB_2U(SCH_1):FM_AC_PWR_BTN_R_N    I40 @S9S_MB_2U_LIB.S9S_MB_2U(SCH_1):PAGE213

R4717 Q_RES_0402LF-0,5%,1/16W,EMPTY,A
     1 FM_AC_PWR_BTN_R_N @S9S_MB_2U_LIB.S9S_MB_2U(SCH_1):FM_AC_PWR_BTN_R_N    I41 @S9S_MB_2U_LIB.S9S_MB_2U(SCH_1):PAGE213
     2 FM_AC_PWR_BTN_PLD_N @S9S_MB_2U_LIB.S9S_MB_2U(SCH_1):FM_AC_PWR_BTN_PLD_N    I41 @S9S_MB_2U_LIB.S9S_MB_2U(SCH_1):PAGE213

R4718 Q_RES_0402LF-33.2,1%,1/16W,EMPA
     1 FM_AC_PWR_BTN_PLD_ISO_R_N @S9S_MB_2U_LIB.S9S_MB_2U(SCH_1):FM_AC_PWR_BTN_PLD_ISO_R_N    I33 @S9S_MB_2U_LIB.S9S_MB_2U(SCH_1):PAGE213
     2 FM_AC_PWR_BTN_PLD_ISO_N @S9S_MB_2U_LIB.S9S_MB_2U(SCH_1):FM_AC_PWR_BTN_PLD_ISO_N    I33 @S9S_MB_2U_LIB.S9S_MB_2U(SCH_1):PAGE213

R4719 Q_RES_0402LF-10K,1%,1/16W,CHIPA
     1 P3V3_AUX @S9S_MB_2U_LIB.S9S_MB_2U(SCH_1):P3V3_AUX    I32 @S9S_MB_2U_LIB.S9S_MB_2U(SCH_1):PAGE213
     2 FM_AC_PWR_BTN_PLD_ISO_N @S9S_MB_2U_LIB.S9S_MB_2U(SCH_1):FM_AC_PWR_BTN_PLD_ISO_N    I32 @S9S_MB_2U_LIB.S9S_MB_2U(SCH_1):PAGE213

R4720 Q_RES_0402LF-0,5%,1/16W,CHIP,CA
     1 FM_AC_PWR_BTN_N @S9S_MB_2U_LIB.S9S_MB_2U(SCH_1):FM_AC_PWR_BTN_N    I57 @S9S_MB_2U_LIB.S9S_MB_2U(SCH_1):PAGE227
     2 FM_AC_PWR_BTN_R_N @S9S_MB_2U_LIB.S9S_MB_2U(SCH_1):FM_AC_PWR_BTN_R_N    I57 @S9S_MB_2U_LIB.S9S_MB_2U(SCH_1):PAGE227

R4721 Q_RES_0402LF-0,5%,1/16W,CHIP,CA
     1 FM_AC_PWR_BTN_R_N @S9S_MB_2U_LIB.S9S_MB_2U(SCH_1):FM_AC_PWR_BTN_R_N    I35 @S9S_MB_2U_LIB.S9S_MB_2U(SCH_1):PAGE233
     2 FM_AC_PWR_BTN_PDB_N @S9S_MB_2U_LIB.S9S_MB_2U(SCH_1):FM_AC_PWR_BTN_PDB_N    I35 @S9S_MB_2U_LIB.S9S_MB_2U(SCH_1):PAGE233

R4722 Q_RES_0402LF-10K,1%,1/16W,CHIPA
     1 FM_PCH_BMC_RST_R_N @S9S_MB_2U_LIB.S9S_MB_2U(SCH_1):FM_PCH_BMC_RST_R_N   I246 @S9S_MB_2U_LIB.S9S_MB_2U(SCH_1):PAGE176
     2 P3V3_AUX @S9S_MB_2U_LIB.S9S_MB_2U(SCH_1):P3V3_AUX   I246 @S9S_MB_2U_LIB.S9S_MB_2U(SCH_1):PAGE176

R4723 Q_RES_0402LF-33.2,1%,1/16W,CHIA
     1 FM_PCH_BMC_RST_R_N @S9S_MB_2U_LIB.S9S_MB_2U(SCH_1):FM_PCH_BMC_RST_R_N   I213 @S9S_MB_2U_LIB.S9S_MB_2U(SCH_1):PAGE312
     2 FM_PCH_BMC_RST_N @S9S_MB_2U_LIB.S9S_MB_2U(SCH_1):FM_PCH_BMC_RST_N   I213 @S9S_MB_2U_LIB.S9S_MB_2U(SCH_1):PAGE312

R4724 Q_RES_0402LF-100K,1%,1/16W,EMPA
     1 PRSNT_SWB_N @S9S_MB_2U_LIB.S9S_MB_2U(SCH_1):PRSNT_SWB_N    I34 @S9S_MB_2U_LIB.S9S_MB_2U(SCH_1):PAGE147
     2    GND @S9S_MB_2U_LIB.S9S_MB_2U(SCH_1):GND    I34 @S9S_MB_2U_LIB.S9S_MB_2U(SCH_1):PAGE147

R4725 Q_RES_0402LF-4.7K,5%,1/16W,CHIA
     1 P3V3_AUX @S9S_MB_2U_LIB.S9S_MB_2U(SCH_1):P3V3_AUX    I28 @S9S_MB_2U_LIB.S9S_MB_2U(SCH_1):PAGE147
     2 PRSNT_SWB @S9S_MB_2U_LIB.S9S_MB_2U(SCH_1):PRSNT_SWB    I28 @S9S_MB_2U_LIB.S9S_MB_2U(SCH_1):PAGE147

R4726 Q_RES_0402LF-4.7K,5%,1/16W,CHIA
     1 P3V3_AUX @S9S_MB_2U_LIB.S9S_MB_2U(SCH_1):P3V3_AUX    I18 @S9S_MB_2U_LIB.S9S_MB_2U(SCH_1):PAGE147
     2 PRSNT_SWB_ISO_N @S9S_MB_2U_LIB.S9S_MB_2U(SCH_1):PRSNT_SWB_ISO_N    I18 @S9S_MB_2U_LIB.S9S_MB_2U(SCH_1):PAGE147

R4727 Q_RES_0402LF-10K,1%,1/16W,CHIPA
     1 P3V3_AUX @S9S_MB_2U_LIB.S9S_MB_2U(SCH_1):P3V3_AUX    I33 @S9S_MB_2U_LIB.S9S_MB_2U(SCH_1):PAGE147
     2 PRSNT_SWB_N @S9S_MB_2U_LIB.S9S_MB_2U(SCH_1):PRSNT_SWB_N    I33 @S9S_MB_2U_LIB.S9S_MB_2U(SCH_1):PAGE147

R4728 Q_RES_0402LF-0,5%,1/16W,CHIP,CA
     1 PRSNT_SWB_ISO_N @S9S_MB_2U_LIB.S9S_MB_2U(SCH_1):PRSNT_SWB_ISO_N   I137 @S9S_MB_2U_LIB.S9S_MB_2U(SCH_1):PAGE214
     2 PRSNT_SWB_ISO_R1_N @S9S_MB_2U_LIB.S9S_MB_2U(SCH_1):PRSNT_SWB_ISO_R1_N   I137 @S9S_MB_2U_LIB.S9S_MB_2U(SCH_1):PAGE214

R4729 Q_RES_0402LF-0,5%,1/16W,CHIP,CA
     1 GPU_PRSNT_N_ISO @S9S_MB_2U_LIB.S9S_MB_2U(SCH_1):GPU_PRSNT_N_ISO   I140 @S9S_MB_2U_LIB.S9S_MB_2U(SCH_1):PAGE214
     2 GPU_PRSNT_N_ISO_R1 @S9S_MB_2U_LIB.S9S_MB_2U(SCH_1):GPU_PRSNT_N_ISO_R1   I140 @S9S_MB_2U_LIB.S9S_MB_2U(SCH_1):PAGE214

R4730 Q_RES_0402LF-10K,1%,1/16W,CHIPA
     1 P3V3_AUX @S9S_MB_2U_LIB.S9S_MB_2U(SCH_1):P3V3_AUX    I41 @S9S_MB_2U_LIB.S9S_MB_2U(SCH_1):PAGE147
     2 PRSNT_CABLE_SWB_B2_N @S9S_MB_2U_LIB.S9S_MB_2U(SCH_1):PRSNT_CABLE_SWB_B2_N    I41 @S9S_MB_2U_LIB.S9S_MB_2U(SCH_1):PAGE147

R4731 Q_RES_0402LF-100K,1%,1/16W,EMPA
     1 PRSNT_CABLE_SWB_B2_N @S9S_MB_2U_LIB.S9S_MB_2U(SCH_1):PRSNT_CABLE_SWB_B2_N    I42 @S9S_MB_2U_LIB.S9S_MB_2U(SCH_1):PAGE147
     2    GND @S9S_MB_2U_LIB.S9S_MB_2U(SCH_1):GND    I42 @S9S_MB_2U_LIB.S9S_MB_2U(SCH_1):PAGE147

R4732 Q_RES_0402LF-4.7K,5%,1/16W,CHIA
     1 P3V3_AUX @S9S_MB_2U_LIB.S9S_MB_2U(SCH_1):P3V3_AUX    I36 @S9S_MB_2U_LIB.S9S_MB_2U(SCH_1):PAGE147
     2 PRSNT_CABLE_SWB_B2 @S9S_MB_2U_LIB.S9S_MB_2U(SCH_1):PRSNT_CABLE_SWB_B2    I36 @S9S_MB_2U_LIB.S9S_MB_2U(SCH_1):PAGE147

R4733 Q_RES_0402LF-4.7K,5%,1/16W,CHIA
     1 P3V3_AUX @S9S_MB_2U_LIB.S9S_MB_2U(SCH_1):P3V3_AUX    I25 @S9S_MB_2U_LIB.S9S_MB_2U(SCH_1):PAGE147
     2 PRSNT_CABLE_SWB_B2_ISO_N @S9S_MB_2U_LIB.S9S_MB_2U(SCH_1):PRSNT_CABLE_SWB_B2_ISO_N    I25 @S9S_MB_2U_LIB.S9S_MB_2U(SCH_1):PAGE147

R4734 Q_RES_0402LF-0,5%,1/16W,CHIP,CA
     1 PRSNT_CABLE_GPU_B3_ISO_N @S9S_MB_2U_LIB.S9S_MB_2U(SCH_1):PRSNT_CABLE_GPU_B3_ISO_N   I144 @S9S_MB_2U_LIB.S9S_MB_2U(SCH_1):PAGE214
     2 PRSNT_CABLE_GPU_B3_ISO_R1_N @S9S_MB_2U_LIB.S9S_MB_2U(SCH_1):PRSNT_CABLE_GPU_B3_ISO_R1_N   I144 @S9S_MB_2U_LIB.S9S_MB_2U(SCH_1):PAGE214

R4735 Q_RES_0402LF-0,5%,1/16W,CHIP,CA
     1 PRSNT_CABLE_SWB_B2_ISO_N @S9S_MB_2U_LIB.S9S_MB_2U(SCH_1):PRSNT_CABLE_SWB_B2_ISO_N   I148 @S9S_MB_2U_LIB.S9S_MB_2U(SCH_1):PAGE214
     2 PRSNT_CABLE_SWB_B2_ISO_R_N @S9S_MB_2U_LIB.S9S_MB_2U(SCH_1):PRSNT_CABLE_SWB_B2_ISO_R_N   I148 @S9S_MB_2U_LIB.S9S_MB_2U(SCH_1):PAGE214

R4736 Q_RES_0402LF-0,5%,1/16W,CHIP,CA
     1 PRSNT_CABLE_GPU_A2_ISO_N @S9S_MB_2U_LIB.S9S_MB_2U(SCH_1):PRSNT_CABLE_GPU_A2_ISO_N   I153 @S9S_MB_2U_LIB.S9S_MB_2U(SCH_1):PAGE214
     2 PRSNT_CABLE_GPU_A2_ISO_R1_N @S9S_MB_2U_LIB.S9S_MB_2U(SCH_1):PRSNT_CABLE_GPU_A2_ISO_R1_N   I153 @S9S_MB_2U_LIB.S9S_MB_2U(SCH_1):PAGE214

R4737 Q_RES_0402LF-10K,1%,1/16W,CHIPA
     1 P3V3_AUX @S9S_MB_2U_LIB.S9S_MB_2U(SCH_1):P3V3_AUX    I58 @S9S_MB_2U_LIB.S9S_MB_2U(SCH_1):PAGE147
     2 PRSNT_CABLE_SWB_B1_N @S9S_MB_2U_LIB.S9S_MB_2U(SCH_1):PRSNT_CABLE_SWB_B1_N    I58 @S9S_MB_2U_LIB.S9S_MB_2U(SCH_1):PAGE147

R4738 Q_RES_0402LF-100K,1%,1/16W,EMPA
     1 PRSNT_CABLE_SWB_B1_N @S9S_MB_2U_LIB.S9S_MB_2U(SCH_1):PRSNT_CABLE_SWB_B1_N    I60 @S9S_MB_2U_LIB.S9S_MB_2U(SCH_1):PAGE147
     2    GND @S9S_MB_2U_LIB.S9S_MB_2U(SCH_1):GND    I60 @S9S_MB_2U_LIB.S9S_MB_2U(SCH_1):PAGE147

R4739 Q_RES_0402LF-4.7K,5%,1/16W,CHIA
     1 P3V3_AUX @S9S_MB_2U_LIB.S9S_MB_2U(SCH_1):P3V3_AUX    I54 @S9S_MB_2U_LIB.S9S_MB_2U(SCH_1):PAGE147
     2 PRSNT_CABLE_SWB_B1 @S9S_MB_2U_LIB.S9S_MB_2U(SCH_1):PRSNT_CABLE_SWB_B1    I54 @S9S_MB_2U_LIB.S9S_MB_2U(SCH_1):PAGE147

R4740 Q_RES_0402LF-4.7K,5%,1/16W,CHIA
     1 P3V3_AUX @S9S_MB_2U_LIB.S9S_MB_2U(SCH_1):P3V3_AUX    I50 @S9S_MB_2U_LIB.S9S_MB_2U(SCH_1):PAGE147
     2 PRSNT_CABLE_SWB_B1_ISO_N @S9S_MB_2U_LIB.S9S_MB_2U(SCH_1):PRSNT_CABLE_SWB_B1_ISO_N    I50 @S9S_MB_2U_LIB.S9S_MB_2U(SCH_1):PAGE147

R4741 Q_RES_0402LF-0,5%,1/16W,CHIP,CA
     1 PRSNT_CABLE_SWB_B1_ISO_N @S9S_MB_2U_LIB.S9S_MB_2U(SCH_1):PRSNT_CABLE_SWB_B1_ISO_N   I156 @S9S_MB_2U_LIB.S9S_MB_2U(SCH_1):PAGE214
     2 PRSNT_CABLE_SWB_B1_ISO_R_N @S9S_MB_2U_LIB.S9S_MB_2U(SCH_1):PRSNT_CABLE_SWB_B1_ISO_R_N   I156 @S9S_MB_2U_LIB.S9S_MB_2U(SCH_1):PAGE214

R4742 Q_RES_0402LF-0,5%,1/16W,CHIP,CA
     1 PRSNT_CABLE_GPU_A1_ISO_N @S9S_MB_2U_LIB.S9S_MB_2U(SCH_1):PRSNT_CABLE_GPU_A1_ISO_N   I161 @S9S_MB_2U_LIB.S9S_MB_2U(SCH_1):PAGE214
     2 PRSNT_CABLE_GPU_A1_ISO_R1_N @S9S_MB_2U_LIB.S9S_MB_2U(SCH_1):PRSNT_CABLE_GPU_A1_ISO_R1_N   I161 @S9S_MB_2U_LIB.S9S_MB_2U(SCH_1):PAGE214

R4745 Q_RES_0402LF-10K,1%,1/16W,CHIPA
     1 P3V3_AUX @S9S_MB_2U_LIB.S9S_MB_2U(SCH_1):P3V3_AUX   I256 @S9S_MB_2U_LIB.S9S_MB_2U(SCH_1):PAGE154
     2 OCP_SFF_AUX_PWR_PLD_EN_R @S9S_MB_2U_LIB.S9S_MB_2U(SCH_1):OCP_SFF_AUX_PWR_PLD_EN_R   I256 @S9S_MB_2U_LIB.S9S_MB_2U(SCH_1):PAGE154

R4746 Q_RES_0402LF-33.2,1%,1/16W,CHIA
     1 HP_LVC3_OCP_V3_1_PWRGD_R @S9S_MB_2U_LIB.S9S_MB_2U(SCH_1):HP_LVC3_OCP_V3_1_PWRGD_R   I245 @S9S_MB_2U_LIB.S9S_MB_2U(SCH_1):PAGE154
     2 HP_LVC3_OCP_V3_1_PWRGD_R2 @S9S_MB_2U_LIB.S9S_MB_2U(SCH_1):HP_LVC3_OCP_V3_1_PWRGD_R2   I245 @S9S_MB_2U_LIB.S9S_MB_2U(SCH_1):PAGE154

R4747 Q_RES_0402LF-33.2,1%,1/16W,CHIA
     1 OCP_SFF_AUX_PWR_PLD_EN @S9S_MB_2U_LIB.S9S_MB_2U(SCH_1):OCP_SFF_AUX_PWR_PLD_EN   I249 @S9S_MB_2U_LIB.S9S_MB_2U(SCH_1):PAGE154
     2 OCP_SFF_AUX_PWR_PLD_EN_R @S9S_MB_2U_LIB.S9S_MB_2U(SCH_1):OCP_SFF_AUX_PWR_PLD_EN_R   I249 @S9S_MB_2U_LIB.S9S_MB_2U(SCH_1):PAGE154

R4748 Q_RES_0402LF-0,5%,1/16W,EMPTY,A
     1 HP_LVC3_OCP_V3_1_PWRGD_R2 @S9S_MB_2U_LIB.S9S_MB_2U(SCH_1):HP_LVC3_OCP_V3_1_PWRGD_R2   I253 @S9S_MB_2U_LIB.S9S_MB_2U(SCH_1):PAGE154
     2 OCP_SFF_AUX_PWR_EN_R2 @S9S_MB_2U_LIB.S9S_MB_2U(SCH_1):OCP_SFF_AUX_PWR_EN_R2   I253 @S9S_MB_2U_LIB.S9S_MB_2U(SCH_1):PAGE154

R4749 Q_RES_0402LF-0,5%,1/16W,EMPTY,A
     1 OCP_SFF_AUX_PWR_PLD_EN_R @S9S_MB_2U_LIB.S9S_MB_2U(SCH_1):OCP_SFF_AUX_PWR_PLD_EN_R   I254 @S9S_MB_2U_LIB.S9S_MB_2U(SCH_1):PAGE154
     2 OCP_SFF_AUX_PWR_EN_R2 @S9S_MB_2U_LIB.S9S_MB_2U(SCH_1):OCP_SFF_AUX_PWR_EN_R2   I254 @S9S_MB_2U_LIB.S9S_MB_2U(SCH_1):PAGE154

R4750 Q_RES_0402LF-49.9,1%,1/16W,CHIA
     1 OCP_SFF_AUX_PWR_EN_R2 @S9S_MB_2U_LIB.S9S_MB_2U(SCH_1):OCP_SFF_AUX_PWR_EN_R2   I247 @S9S_MB_2U_LIB.S9S_MB_2U(SCH_1):PAGE154
     2 OCP_SFF_AUX_PWR_EN @S9S_MB_2U_LIB.S9S_MB_2U(SCH_1):OCP_SFF_AUX_PWR_EN   I247 @S9S_MB_2U_LIB.S9S_MB_2U(SCH_1):PAGE154

R4751 Q_RES_0402LF-33.2,1%,1/16W,CHIA
     1 HP_LVC3_OCP_V3_1_PWRGD_R @S9S_MB_2U_LIB.S9S_MB_2U(SCH_1):HP_LVC3_OCP_V3_1_PWRGD_R    I79 @S9S_MB_2U_LIB.S9S_MB_2U(SCH_1):PAGE311
     2 HP_LVC3_OCP_V3_1_FUSE_PWRGD @S9S_MB_2U_LIB.S9S_MB_2U(SCH_1):HP_LVC3_OCP_V3_1_FUSE_PWRGD    I79 @S9S_MB_2U_LIB.S9S_MB_2U(SCH_1):PAGE311

R4752 Q_RES_0402LF-0,5%,1/16W,CHIP,CA
     1 HP_LVC3_OCP_V3_1_PRSNT2_N_R @S9S_MB_2U_LIB.S9S_MB_2U(SCH_1):HP_LVC3_OCP_V3_1_PRSNT2_N_R    I45 @S9S_MB_2U_LIB.S9S_MB_2U(SCH_1):PAGE153
     2 HP_LVC3_OCP_V3_1_PRSNT2_PLD_N @S9S_MB_2U_LIB.S9S_MB_2U(SCH_1):HP_LVC3_OCP_V3_1_PRSNT2_PLD_N    I45 @S9S_MB_2U_LIB.S9S_MB_2U(SCH_1):PAGE153

R4753 Q_RES_0402LF-0,5%,1/16W,CHIP,CA
     1 HP_LVC3_OCP_V3_2_PRSNT2_N_R @S9S_MB_2U_LIB.S9S_MB_2U(SCH_1):HP_LVC3_OCP_V3_2_PRSNT2_N_R    I55 @S9S_MB_2U_LIB.S9S_MB_2U(SCH_1):PAGE131
     2 HP_LVC3_OCP_V3_2_PRSNT2_PLD_N @S9S_MB_2U_LIB.S9S_MB_2U(SCH_1):HP_LVC3_OCP_V3_2_PRSNT2_PLD_N    I55 @S9S_MB_2U_LIB.S9S_MB_2U(SCH_1):PAGE131

R4754 Q_RES_0402LF-33.2,1%,1/16W,CHIA
     1 HP_LVC3_OCP_V3_2_PWRGD_R @S9S_MB_2U_LIB.S9S_MB_2U(SCH_1):HP_LVC3_OCP_V3_2_PWRGD_R   I104 @S9S_MB_2U_LIB.S9S_MB_2U(SCH_1):PAGE132
     2 HP_LVC3_OCP_V3_2_PWRGD_R2 @S9S_MB_2U_LIB.S9S_MB_2U(SCH_1):HP_LVC3_OCP_V3_2_PWRGD_R2   I104 @S9S_MB_2U_LIB.S9S_MB_2U(SCH_1):PAGE132

R4755 Q_RES_0402LF-33.2,1%,1/16W,CHIA
     1 OCP_V3_2_AUX_PWR_PLD_EN @S9S_MB_2U_LIB.S9S_MB_2U(SCH_1):OCP_V3_2_AUX_PWR_PLD_EN   I103 @S9S_MB_2U_LIB.S9S_MB_2U(SCH_1):PAGE132
     2 OCP_V3_2_AUX_PWR_PLD_EN_R @S9S_MB_2U_LIB.S9S_MB_2U(SCH_1):OCP_V3_2_AUX_PWR_PLD_EN_R   I103 @S9S_MB_2U_LIB.S9S_MB_2U(SCH_1):PAGE132

R4756 Q_RES_0402LF-10K,1%,1/16W,CHIPA
     1 P3V3_AUX @S9S_MB_2U_LIB.S9S_MB_2U(SCH_1):P3V3_AUX   I105 @S9S_MB_2U_LIB.S9S_MB_2U(SCH_1):PAGE132
     2 OCP_V3_2_AUX_PWR_PLD_EN_R @S9S_MB_2U_LIB.S9S_MB_2U(SCH_1):OCP_V3_2_AUX_PWR_PLD_EN_R   I105 @S9S_MB_2U_LIB.S9S_MB_2U(SCH_1):PAGE132

R4757 Q_RES_0402LF-0,5%,1/16W,EMPTY,A
     1 HP_LVC3_OCP_V3_2_PWRGD_R2 @S9S_MB_2U_LIB.S9S_MB_2U(SCH_1):HP_LVC3_OCP_V3_2_PWRGD_R2   I112 @S9S_MB_2U_LIB.S9S_MB_2U(SCH_1):PAGE132
     2 OCP_V3_2_AUX_PWR_EN_R2 @S9S_MB_2U_LIB.S9S_MB_2U(SCH_1):OCP_V3_2_AUX_PWR_EN_R2   I112 @S9S_MB_2U_LIB.S9S_MB_2U(SCH_1):PAGE132

R4758 Q_RES_0402LF-0,5%,1/16W,EMPTY,A
     1 OCP_V3_2_AUX_PWR_PLD_EN_R @S9S_MB_2U_LIB.S9S_MB_2U(SCH_1):OCP_V3_2_AUX_PWR_PLD_EN_R   I107 @S9S_MB_2U_LIB.S9S_MB_2U(SCH_1):PAGE132
     2 OCP_V3_2_AUX_PWR_EN_R2 @S9S_MB_2U_LIB.S9S_MB_2U(SCH_1):OCP_V3_2_AUX_PWR_EN_R2   I107 @S9S_MB_2U_LIB.S9S_MB_2U(SCH_1):PAGE132

R4759 Q_RES_0402LF-49.9,1%,1/16W,CHIA
     1 OCP_V3_2_AUX_PWR_EN_R2 @S9S_MB_2U_LIB.S9S_MB_2U(SCH_1):OCP_V3_2_AUX_PWR_EN_R2   I111 @S9S_MB_2U_LIB.S9S_MB_2U(SCH_1):PAGE132
     2 OCP_V3_2_AUX_PWR_EN @S9S_MB_2U_LIB.S9S_MB_2U(SCH_1):OCP_V3_2_AUX_PWR_EN   I111 @S9S_MB_2U_LIB.S9S_MB_2U(SCH_1):PAGE132

R4760 Q_RES_0402LF-33.2,1%,1/16W,CHIA
     1 HP_LVC3_OCP_V3_2_PWRGD_R @S9S_MB_2U_LIB.S9S_MB_2U(SCH_1):HP_LVC3_OCP_V3_2_PWRGD_R    I86 @S9S_MB_2U_LIB.S9S_MB_2U(SCH_1):PAGE311
     2 HP_LVC3_OCP_V3_2_FUSE_PWRGD @S9S_MB_2U_LIB.S9S_MB_2U(SCH_1):HP_LVC3_OCP_V3_2_FUSE_PWRGD    I86 @S9S_MB_2U_LIB.S9S_MB_2U(SCH_1):PAGE311

R4761 Q_RES_0402LF-10K,1%,1/16W,CHIPA
     1 P3V3_AUX @S9S_MB_2U_LIB.S9S_MB_2U(SCH_1):P3V3_AUX    I70 @S9S_MB_2U_LIB.S9S_MB_2U(SCH_1):PAGE131
     2 HP_LVC3_OCP_V3_2_PRSNT2_PLD_N @S9S_MB_2U_LIB.S9S_MB_2U(SCH_1):HP_LVC3_OCP_V3_2_PRSNT2_PLD_N    I70 @S9S_MB_2U_LIB.S9S_MB_2U(SCH_1):PAGE131

R4762 Q_RES_0402LF-10K,1%,1/16W,CHIPA
     1 P3V3_AUX @S9S_MB_2U_LIB.S9S_MB_2U(SCH_1):P3V3_AUX    I76 @S9S_MB_2U_LIB.S9S_MB_2U(SCH_1):PAGE153
     2 HP_LVC3_OCP_V3_1_PRSNT2_PLD_N @S9S_MB_2U_LIB.S9S_MB_2U(SCH_1):HP_LVC3_OCP_V3_1_PRSNT2_PLD_N    I76 @S9S_MB_2U_LIB.S9S_MB_2U(SCH_1):PAGE153

R4763 Q_RES_0402LF-10K,1%,1/16W,CHIPA
     1 P3V3_AUX @S9S_MB_2U_LIB.S9S_MB_2U(SCH_1):P3V3_AUX   I119 @S9S_MB_2U_LIB.S9S_MB_2U(SCH_1):PAGE132
     2 HP_OCP_V3_2_EN @S9S_MB_2U_LIB.S9S_MB_2U(SCH_1):HP_OCP_V3_2_EN   I119 @S9S_MB_2U_LIB.S9S_MB_2U(SCH_1):PAGE132

R4764 Q_RES_0402LF-10K,1%,1/16W,CHIPA
     1 P3V3_AUX @S9S_MB_2U_LIB.S9S_MB_2U(SCH_1):P3V3_AUX   I257 @S9S_MB_2U_LIB.S9S_MB_2U(SCH_1):PAGE154
     2 HP_OCP_V3_1_EN @S9S_MB_2U_LIB.S9S_MB_2U(SCH_1):HP_OCP_V3_1_EN   I257 @S9S_MB_2U_LIB.S9S_MB_2U(SCH_1):PAGE154

R4765 Q_RES_0402LF-33.2,1%,1/16W,CHIA
     1 HP_LVC3_E1S_0_HSC_PWRGD @S9S_MB_2U_LIB.S9S_MB_2U(SCH_1):HP_LVC3_E1S_0_HSC_PWRGD    I90 @S9S_MB_2U_LIB.S9S_MB_2U(SCH_1):PAGE311
     2 HP_LVC3_E1S_0_HSC_PWRGD_PLD @S9S_MB_2U_LIB.S9S_MB_2U(SCH_1):HP_LVC3_E1S_0_HSC_PWRGD_PLD    I90 @S9S_MB_2U_LIB.S9S_MB_2U(SCH_1):PAGE311

R4766 Q_RES_0402LF-49.9,1%,1/16W,CHIA
     1 E1S_0_CLK_OE_N @S9S_MB_2U_LIB.S9S_MB_2U(SCH_1):E1S_0_CLK_OE_N   I314 @S9S_MB_2U_LIB.S9S_MB_2U(SCH_1):PAGE175
     2 E1S_0_CLKREQ_N @S9S_MB_2U_LIB.S9S_MB_2U(SCH_1):E1S_0_CLKREQ_N   I314 @S9S_MB_2U_LIB.S9S_MB_2U(SCH_1):PAGE175

R4767 Q_RES_0402LF-49.9,1%,1/16W,CHIA
     1 HP_E1S_0_P3V3_PWRGD @S9S_MB_2U_LIB.S9S_MB_2U(SCH_1):HP_E1S_0_P3V3_PWRGD   I331 @S9S_MB_2U_LIB.S9S_MB_2U(SCH_1):PAGE297
     2 HP_E1S_0_P3V3_PWRGD_PLD @S9S_MB_2U_LIB.S9S_MB_2U(SCH_1):HP_E1S_0_P3V3_PWRGD_PLD   I331 @S9S_MB_2U_LIB.S9S_MB_2U(SCH_1):PAGE297

R4768 Q_RES_0402LF-10K,1%,1/16W,CHIPA
     1 E1S_0_CLK_OE_N @S9S_MB_2U_LIB.S9S_MB_2U(SCH_1):E1S_0_CLK_OE_N   I315 @S9S_MB_2U_LIB.S9S_MB_2U(SCH_1):PAGE175
     2 P3V3_AUX @S9S_MB_2U_LIB.S9S_MB_2U(SCH_1):P3V3_AUX   I315 @S9S_MB_2U_LIB.S9S_MB_2U(SCH_1):PAGE175

R4769 Q_RES_0402LF-100K,1%,1/16W,CHIA
     1 FM_PDB_BUF_EN_R @S9S_MB_2U_LIB.S9S_MB_2U(SCH_1):FM_PDB_BUF_EN_R     I3 @S9S_MB_2U_LIB.S9S_MB_2U(SCH_1):PAGE233
     2    GND @S9S_MB_2U_LIB.S9S_MB_2U(SCH_1):GND     I3 @S9S_MB_2U_LIB.S9S_MB_2U(SCH_1):PAGE233

R4770 Q_RES_0402LF-0,5%,1/16W,CHIP,CA
     1 HP_LVC3_SCM_HSC_PWRGD_R @S9S_MB_2U_LIB.S9S_MB_2U(SCH_1):HP_LVC3_SCM_HSC_PWRGD_R    I91 @S9S_MB_2U_LIB.S9S_MB_2U(SCH_1):PAGE229
     2 HP_LVC3_SCM_HSC_PWRGD @S9S_MB_2U_LIB.S9S_MB_2U(SCH_1):HP_LVC3_SCM_HSC_PWRGD    I91 @S9S_MB_2U_LIB.S9S_MB_2U(SCH_1):PAGE229

R4771 Q_RES_0402LF-33.2,1%,1/16W,CHIA
     1 HP_LVC3_SCM_HSC_PWRGD @S9S_MB_2U_LIB.S9S_MB_2U(SCH_1):HP_LVC3_SCM_HSC_PWRGD    I95 @S9S_MB_2U_LIB.S9S_MB_2U(SCH_1):PAGE311
     2 HP_LVC3_SCM_HSC_PWRGD_PLD @S9S_MB_2U_LIB.S9S_MB_2U(SCH_1):HP_LVC3_SCM_HSC_PWRGD_PLD    I95 @S9S_MB_2U_LIB.S9S_MB_2U(SCH_1):PAGE311

R4772 Q_RES_0402LF-10K,1%,1/16W,EMPTA
     1 P3V3_AUX @S9S_MB_2U_LIB.S9S_MB_2U(SCH_1):P3V3_AUX    I21 @S9S_MB_2U_LIB.S9S_MB_2U(SCH_1):PAGE329
     2 UV_ADR_P2V5_COMP @S9S_MB_2U_LIB.S9S_MB_2U(SCH_1):UV_ADR_P2V5_COMP    I21 @S9S_MB_2U_LIB.S9S_MB_2U(SCH_1):PAGE329

R4773 Q_RES_0402LF-10K,1%,1/16W,EMPTA
     1 P3V3_AUX @S9S_MB_2U_LIB.S9S_MB_2U(SCH_1):P3V3_AUX    I42 @S9S_MB_2U_LIB.S9S_MB_2U(SCH_1):PAGE329
     2 UV_P2V5_COMP @S9S_MB_2U_LIB.S9S_MB_2U(SCH_1):UV_P2V5_COMP    I42 @S9S_MB_2U_LIB.S9S_MB_2U(SCH_1):PAGE329

R4774 Q_RES_0402LF-17.8K,1%,1/16W,EMA
     1 P12V_AUX @S9S_MB_2U_LIB.S9S_MB_2U(SCH_1):P12V_AUX    I17 @S9S_MB_2U_LIB.S9S_MB_2U(SCH_1):PAGE329
     2 P12V_AUX_UV_ADR_TRIGGER @S9S_MB_2U_LIB.S9S_MB_2U(SCH_1):P12V_AUX_UV_ADR_TRIGGER    I17 @S9S_MB_2U_LIB.S9S_MB_2U(SCH_1):PAGE329

R4775 Q_RES_0402LF-5.11K,1%,1/16W,EMA
     1 P12V_AUX_UV_ADR_TRIGGER @S9S_MB_2U_LIB.S9S_MB_2U(SCH_1):P12V_AUX_UV_ADR_TRIGGER     I2 @S9S_MB_2U_LIB.S9S_MB_2U(SCH_1):PAGE329
     2    GND @S9S_MB_2U_LIB.S9S_MB_2U(SCH_1):GND     I2 @S9S_MB_2U_LIB.S9S_MB_2U(SCH_1):PAGE329

R4776 Q_RES_0402LF-17.8K,1%,1/16W,EMA
     1 P12V_AUX @S9S_MB_2U_LIB.S9S_MB_2U(SCH_1):P12V_AUX    I38 @S9S_MB_2U_LIB.S9S_MB_2U(SCH_1):PAGE329
     2 P12V_AUX_UV_TRIGGER @S9S_MB_2U_LIB.S9S_MB_2U(SCH_1):P12V_AUX_UV_TRIGGER    I38 @S9S_MB_2U_LIB.S9S_MB_2U(SCH_1):PAGE329

R4777 Q_RES_0402LF-5.11K,1%,1/16W,EMA
     1 P12V_AUX_UV_TRIGGER @S9S_MB_2U_LIB.S9S_MB_2U(SCH_1):P12V_AUX_UV_TRIGGER    I39 @S9S_MB_2U_LIB.S9S_MB_2U(SCH_1):PAGE329
     2    GND @S9S_MB_2U_LIB.S9S_MB_2U(SCH_1):GND    I39 @S9S_MB_2U_LIB.S9S_MB_2U(SCH_1):PAGE329

R4778 Q_RES_0402LF-1M,1%,1/16W,CHIP,A
     1 P12V_AUX_UV_ADR_TRIGGER @S9S_MB_2U_LIB.S9S_MB_2U(SCH_1):P12V_AUX_UV_ADR_TRIGGER     I9 @S9S_MB_2U_LIB.S9S_MB_2U(SCH_1):PAGE329
     2 FM_UV_ADR_TRIGGER_N_R2 @S9S_MB_2U_LIB.S9S_MB_2U(SCH_1):FM_UV_ADR_TRIGGER_N_R2     I9 @S9S_MB_2U_LIB.S9S_MB_2U(SCH_1):PAGE329

R4779 Q_RES_0402LF-1M,1%,1/16W,CHIP,A
     1 P12V_AUX_UV_TRIGGER @S9S_MB_2U_LIB.S9S_MB_2U(SCH_1):P12V_AUX_UV_TRIGGER    I31 @S9S_MB_2U_LIB.S9S_MB_2U(SCH_1):PAGE329
     2 IRQ_UV_DETECT_R2_N @S9S_MB_2U_LIB.S9S_MB_2U(SCH_1):IRQ_UV_DETECT_R2_N    I31 @S9S_MB_2U_LIB.S9S_MB_2U(SCH_1):PAGE329

R4780 Q_RES_0402LF-0,5%,1/16W,CHIP,CA
     1 PWRGD_P1V05_PCH_AUX_R @S9S_MB_2U_LIB.S9S_MB_2U(SCH_1):PWRGD_P1V05_PCH_AUX_R    I52 @S9S_MB_2U_LIB.S9S_MB_2U(SCH_1):PAGE248
     2 PWRGD_PVNN_PCH_AUX @S9S_MB_2U_LIB.S9S_MB_2U(SCH_1):PWRGD_PVNN_PCH_AUX    I52 @S9S_MB_2U_LIB.S9S_MB_2U(SCH_1):PAGE248

R4781 Q_RES_0402LF-0,5%,1/16W,CHIP,CA
     1 PWRGD_PVCCINFAON_CPU1 @S9S_MB_2U_LIB.S9S_MB_2U(SCH_1):PWRGD_PVCCINFAON_CPU1   I103 @S9S_MB_2U_LIB.S9S_MB_2U(SCH_1):PAGE278
     2 PWRGD_PVCCINFAON_CPU1_R @S9S_MB_2U_LIB.S9S_MB_2U(SCH_1):PWRGD_PVCCINFAON_CPU1_R   I103 @S9S_MB_2U_LIB.S9S_MB_2U(SCH_1):PAGE278

R4782 Q_RES_0402LF-33.2,1%,1/16W,EMPA
     1 FM_UV_ADR_TRIGGER_N_R2 @S9S_MB_2U_LIB.S9S_MB_2U(SCH_1):FM_UV_ADR_TRIGGER_N_R2     I7 @S9S_MB_2U_LIB.S9S_MB_2U(SCH_1):PAGE329
     2 FM_UV_ADR_TRIGGER_N @S9S_MB_2U_LIB.S9S_MB_2U(SCH_1):FM_UV_ADR_TRIGGER_N     I7 @S9S_MB_2U_LIB.S9S_MB_2U(SCH_1):PAGE329

R4783 Q_RES_0402LF-33.2,1%,1/16W,EMPA
     1 IRQ_UV_DETECT_R2_N @S9S_MB_2U_LIB.S9S_MB_2U(SCH_1):IRQ_UV_DETECT_R2_N    I27 @S9S_MB_2U_LIB.S9S_MB_2U(SCH_1):PAGE329
     2 IRQ_UV_DETECT_N @S9S_MB_2U_LIB.S9S_MB_2U(SCH_1):IRQ_UV_DETECT_N    I27 @S9S_MB_2U_LIB.S9S_MB_2U(SCH_1):PAGE329

R4784 Q_RES_0402LF-10K,1%,1/16W,EMPTA
     1 P3V3_AUX @S9S_MB_2U_LIB.S9S_MB_2U(SCH_1):P3V3_AUX     I6 @S9S_MB_2U_LIB.S9S_MB_2U(SCH_1):PAGE329
     2 FM_UV_ADR_TRIGGER_N @S9S_MB_2U_LIB.S9S_MB_2U(SCH_1):FM_UV_ADR_TRIGGER_N     I6 @S9S_MB_2U_LIB.S9S_MB_2U(SCH_1):PAGE329

R4785 Q_RES_0402LF-10K,1%,1/16W,EMPTA
     1 P3V3_AUX @S9S_MB_2U_LIB.S9S_MB_2U(SCH_1):P3V3_AUX    I25 @S9S_MB_2U_LIB.S9S_MB_2U(SCH_1):PAGE329
     2 IRQ_UV_DETECT_N @S9S_MB_2U_LIB.S9S_MB_2U(SCH_1):IRQ_UV_DETECT_N    I25 @S9S_MB_2U_LIB.S9S_MB_2U(SCH_1):PAGE329

R4786 Q_RES_0402LF-10K,1%,1/16W,EMPTA
     1 P3V3_AUX @S9S_MB_2U_LIB.S9S_MB_2U(SCH_1):P3V3_AUX    I65 @S9S_MB_2U_LIB.S9S_MB_2U(SCH_1):PAGE329
     2 DSW_PWROK_P2V5_COMP @S9S_MB_2U_LIB.S9S_MB_2U(SCH_1):DSW_PWROK_P2V5_COMP    I65 @S9S_MB_2U_LIB.S9S_MB_2U(SCH_1):PAGE329

R4787 Q_RES_0402LF-1M,1%,1/16W,EMPTYA
     1 PWRGD_DSW_PWROK_TRIGGER @S9S_MB_2U_LIB.S9S_MB_2U(SCH_1):PWRGD_DSW_PWROK_TRIGGER    I46 @S9S_MB_2U_LIB.S9S_MB_2U(SCH_1):PAGE329
     2 PWRGD_DSW_PWROK_R5 @S9S_MB_2U_LIB.S9S_MB_2U(SCH_1):PWRGD_DSW_PWROK_R5    I46 @S9S_MB_2U_LIB.S9S_MB_2U(SCH_1):PAGE329

R4788 Q_RES_0402LF-33.2,1%,1/16W,EMPA
     1 PWRGD_DSW_PWROK_R5 @S9S_MB_2U_LIB.S9S_MB_2U(SCH_1):PWRGD_DSW_PWROK_R5    I50 @S9S_MB_2U_LIB.S9S_MB_2U(SCH_1):PAGE329
     2 PWRGD_DSW_PWROK @S9S_MB_2U_LIB.S9S_MB_2U(SCH_1):PWRGD_DSW_PWROK    I50 @S9S_MB_2U_LIB.S9S_MB_2U(SCH_1):PAGE329

R4789 Q_RES_0402LF-10K,1%,1/16W,EMPTA
     1 P3V3_AUX @S9S_MB_2U_LIB.S9S_MB_2U(SCH_1):P3V3_AUX    I49 @S9S_MB_2U_LIB.S9S_MB_2U(SCH_1):PAGE329
     2 PWRGD_DSW_PWROK @S9S_MB_2U_LIB.S9S_MB_2U(SCH_1):PWRGD_DSW_PWROK    I49 @S9S_MB_2U_LIB.S9S_MB_2U(SCH_1):PAGE329

R4790 Q_RES_0402LF-4.75K,1%,1/16W,EMA
     1 P12V_AUX @S9S_MB_2U_LIB.S9S_MB_2U(SCH_1):P12V_AUX    I67 @S9S_MB_2U_LIB.S9S_MB_2U(SCH_1):PAGE329
     2 PWRGD_DSW_PWROK_TRIGGER @S9S_MB_2U_LIB.S9S_MB_2U(SCH_1):PWRGD_DSW_PWROK_TRIGGER    I67 @S9S_MB_2U_LIB.S9S_MB_2U(SCH_1):PAGE329

R4791 Q_RES_0402LF-2K,1%,1/16W,EMPTYA
     1 PWRGD_DSW_PWROK_TRIGGER @S9S_MB_2U_LIB.S9S_MB_2U(SCH_1):PWRGD_DSW_PWROK_TRIGGER    I68 @S9S_MB_2U_LIB.S9S_MB_2U(SCH_1):PAGE329
     2    GND @S9S_MB_2U_LIB.S9S_MB_2U(SCH_1):GND    I68 @S9S_MB_2U_LIB.S9S_MB_2U(SCH_1):PAGE329

R4792 Q_RES_0402LF-10K,1%,1/16W,EMPTA
     1 P3V3_AUX @S9S_MB_2U_LIB.S9S_MB_2U(SCH_1):P3V3_AUX    I57 @S9S_MB_2U_LIB.S9S_MB_2U(SCH_1):PAGE326
     2 OC_P2V5_COMP @S9S_MB_2U_LIB.S9S_MB_2U(SCH_1):OC_P2V5_COMP    I57 @S9S_MB_2U_LIB.S9S_MB_2U(SCH_1):PAGE326

R4793 Q_RES_0402LF-1M,1%,1/16W,EMPTYA
     1 HSC_OC_VOL @S9S_MB_2U_LIB.S9S_MB_2U(SCH_1):HSC_OC_VOL    I68 @S9S_MB_2U_LIB.S9S_MB_2U(SCH_1):PAGE326
     2 HSC_D_OC_R2 @S9S_MB_2U_LIB.S9S_MB_2U(SCH_1):HSC_D_OC_R2    I68 @S9S_MB_2U_LIB.S9S_MB_2U(SCH_1):PAGE326

R4794 Q_RES_0402LF-33.2,1%,1/16W,EMPA
     1 HSC_D_OC_R2 @S9S_MB_2U_LIB.S9S_MB_2U(SCH_1):HSC_D_OC_R2    I72 @S9S_MB_2U_LIB.S9S_MB_2U(SCH_1):PAGE326
     2 A_HSC_LOW_GATE @S9S_MB_2U_LIB.S9S_MB_2U(SCH_1):A_HSC_LOW_GATE    I72 @S9S_MB_2U_LIB.S9S_MB_2U(SCH_1):PAGE326

R4795 Q_RES_0402LF-160K,1%,1/16W,EMPA
     1 HSC_CSOUT @S9S_MB_2U_LIB.S9S_MB_2U(SCH_1):HSC_CSOUT    I78 @S9S_MB_2U_LIB.S9S_MB_2U(SCH_1):PAGE326
     2 HSC_OC_VOL @S9S_MB_2U_LIB.S9S_MB_2U(SCH_1):HSC_OC_VOL    I78 @S9S_MB_2U_LIB.S9S_MB_2U(SCH_1):PAGE326

R4796 Q_RES_0402LF-10K,1%,1/16W,EMPTA
     1 HSC_OC_VOL @S9S_MB_2U_LIB.S9S_MB_2U(SCH_1):HSC_OC_VOL    I77 @S9S_MB_2U_LIB.S9S_MB_2U(SCH_1):PAGE326
     2    GND @S9S_MB_2U_LIB.S9S_MB_2U(SCH_1):GND    I77 @S9S_MB_2U_LIB.S9S_MB_2U(SCH_1):PAGE326

R4797 Q_RES_0402LF-10K,1%,1/16W,EMPTA
     1 P3V3_AUX @S9S_MB_2U_LIB.S9S_MB_2U(SCH_1):P3V3_AUX    I80 @S9S_MB_2U_LIB.S9S_MB_2U(SCH_1):PAGE326
     2 A_HSC_LOW_GATE @S9S_MB_2U_LIB.S9S_MB_2U(SCH_1):A_HSC_LOW_GATE    I80 @S9S_MB_2U_LIB.S9S_MB_2U(SCH_1):PAGE326

R4798 Q_RES_0402LF-10K,1%,1/16W,CHIPA
     1 P3V3_AUX @S9S_MB_2U_LIB.S9S_MB_2U(SCH_1):P3V3_AUX    I75 @S9S_MB_2U_LIB.S9S_MB_2U(SCH_1):PAGE147
     2 PRSNT_CABLE_GPU_A3_N @S9S_MB_2U_LIB.S9S_MB_2U(SCH_1):PRSNT_CABLE_GPU_A3_N    I75 @S9S_MB_2U_LIB.S9S_MB_2U(SCH_1):PAGE147

R4799 Q_RES_0402LF-100K,1%,1/16W,EMPA
     1 PRSNT_CABLE_GPU_A3_N @S9S_MB_2U_LIB.S9S_MB_2U(SCH_1):PRSNT_CABLE_GPU_A3_N    I76 @S9S_MB_2U_LIB.S9S_MB_2U(SCH_1):PAGE147
     2    GND @S9S_MB_2U_LIB.S9S_MB_2U(SCH_1):GND    I76 @S9S_MB_2U_LIB.S9S_MB_2U(SCH_1):PAGE147

R4800 Q_RES_0402LF-4.7K,5%,1/16W,CHIA
     1 P3V3_AUX @S9S_MB_2U_LIB.S9S_MB_2U(SCH_1):P3V3_AUX    I70 @S9S_MB_2U_LIB.S9S_MB_2U(SCH_1):PAGE147
     2 PRSNT_CABLE_GPU_A3 @S9S_MB_2U_LIB.S9S_MB_2U(SCH_1):PRSNT_CABLE_GPU_A3    I70 @S9S_MB_2U_LIB.S9S_MB_2U(SCH_1):PAGE147

R4801 Q_RES_0402LF-4.7K,5%,1/16W,CHIA
     1 P3V3_AUX @S9S_MB_2U_LIB.S9S_MB_2U(SCH_1):P3V3_AUX    I65 @S9S_MB_2U_LIB.S9S_MB_2U(SCH_1):PAGE147
     2 PRSNT_CABLE_GPU_A3_ISO_N @S9S_MB_2U_LIB.S9S_MB_2U(SCH_1):PRSNT_CABLE_GPU_A3_ISO_N    I65 @S9S_MB_2U_LIB.S9S_MB_2U(SCH_1):PAGE147

R4802 Q_RES_0402LF-0,5%,1/16W,CHIP,CA
     1 PRSNT_CABLE_GPU_A3_ISO_N @S9S_MB_2U_LIB.S9S_MB_2U(SCH_1):PRSNT_CABLE_GPU_A3_ISO_N   I164 @S9S_MB_2U_LIB.S9S_MB_2U(SCH_1):PAGE214
     2 PRSNT_CABLE_GPU_A3_ISO_R_N @S9S_MB_2U_LIB.S9S_MB_2U(SCH_1):PRSNT_CABLE_GPU_A3_ISO_R_N   I164 @S9S_MB_2U_LIB.S9S_MB_2U(SCH_1):PAGE214

R4803 Q_RES_0402LF-0,5%,1/16W,CHIP,CA
     1 P1V05_PCH_AUX @S9S_MB_2U_LIB.S9S_MB_2U(SCH_1):P1V05_PCH_AUX   I165 @S9S_MB_2U_LIB.S9S_MB_2U(SCH_1):PAGE181
     2 P1V05_PCH_PLL_AUX @S9S_MB_2U_LIB.S9S_MB_2U(SCH_1):P1V05_PCH_PLL_AUX   I165 @S9S_MB_2U_LIB.S9S_MB_2U(SCH_1):PAGE181

R4804 Q_RES_0402LF-1K,1%,1/16W,EMPTYA
     1 P3V3_AUX @S9S_MB_2U_LIB.S9S_MB_2U(SCH_1):P3V3_AUX    I97 @S9S_MB_2U_LIB.S9S_MB_2U(SCH_1):PAGE326
     2 U205_VDD @S9S_MB_2U_LIB.S9S_MB_2U(SCH_1):U205_VDD    I97 @S9S_MB_2U_LIB.S9S_MB_2U(SCH_1):PAGE326

R4805 Q_RES_0402LF-1K,1%,1/16W,EMPTYA
     1 P3V3_AUX @S9S_MB_2U_LIB.S9S_MB_2U(SCH_1):P3V3_AUX    I99 @S9S_MB_2U_LIB.S9S_MB_2U(SCH_1):PAGE326
     2 U369_VDD @S9S_MB_2U_LIB.S9S_MB_2U(SCH_1):U369_VDD    I99 @S9S_MB_2U_LIB.S9S_MB_2U(SCH_1):PAGE326

R4806 Q_RES_0402LF-1K,1%,1/16W,CHIP,A
     1 P12V_AUX @S9S_MB_2U_LIB.S9S_MB_2U(SCH_1):P12V_AUX    I98 @S9S_MB_2U_LIB.S9S_MB_2U(SCH_1):PAGE326
     2 U206_VDD @S9S_MB_2U_LIB.S9S_MB_2U(SCH_1):U206_VDD    I98 @S9S_MB_2U_LIB.S9S_MB_2U(SCH_1):PAGE326

R4807 Q_RES_0402LF-0,5%,1/16W,EMPTY,A
     1 PWRGD_DSW_PWROK_R1 @S9S_MB_2U_LIB.S9S_MB_2U(SCH_1):PWRGD_DSW_PWROK_R1    I13 @S9S_MB_2U_LIB.S9S_MB_2U(SCH_1):PAGE232
     2 PWRGD_DSW_PWROK_R2 @S9S_MB_2U_LIB.S9S_MB_2U(SCH_1):PWRGD_DSW_PWROK_R2    I13 @S9S_MB_2U_LIB.S9S_MB_2U(SCH_1):PAGE232

R4808 Q_RES_0402LF-100K,1%,1/16W,EMPA
     1 PWRGD_DSW_PWROK @S9S_MB_2U_LIB.S9S_MB_2U(SCH_1):PWRGD_DSW_PWROK    I31 @S9S_MB_2U_LIB.S9S_MB_2U(SCH_1):PAGE232
     2    GND @S9S_MB_2U_LIB.S9S_MB_2U(SCH_1):GND    I31 @S9S_MB_2U_LIB.S9S_MB_2U(SCH_1):PAGE232

R4809 Q_RES_0402LF-0,5%,1/16W,CHIP,CA
     1 FM_BMC_INTRUDER_N @S9S_MB_2U_LIB.S9S_MB_2U(SCH_1):FM_BMC_INTRUDER_N     I2 @S9S_MB_2U_LIB.S9S_MB_2U(SCH_1):PAGE227
     2    GND @S9S_MB_2U_LIB.S9S_MB_2U(SCH_1):GND     I2 @S9S_MB_2U_LIB.S9S_MB_2U(SCH_1):PAGE227

R4892 Q_RES_0402LF-49.9,1%,1/16W,EMPA
     1 P12V_HSC_TEMP_R @S9S_MB_2U_LIB.S9S_MB_2U(SCH_1):P12V_HSC_TEMP_R     I5 @S9S_MB_2U_LIB.S9S_MB_2U(SCH_1):PAGE327
     2 P12V_HSC_TEMP_D+ @S9S_MB_2U_LIB.S9S_MB_2U(SCH_1):P12V_HSC_TEMP_D+     I5 @S9S_MB_2U_LIB.S9S_MB_2U(SCH_1):PAGE327

R4893 Q_RES_0402LF-49.9,1%,1/16W,EMPA
     1 P12V_HSC_TEMP_E @S9S_MB_2U_LIB.S9S_MB_2U(SCH_1):P12V_HSC_TEMP_E     I4 @S9S_MB_2U_LIB.S9S_MB_2U(SCH_1):PAGE327
     2 P12V_HSC_TEMP_D- @S9S_MB_2U_LIB.S9S_MB_2U(SCH_1):P12V_HSC_TEMP_D-     I4 @S9S_MB_2U_LIB.S9S_MB_2U(SCH_1):PAGE327

R4894 Q_RES_0402LF-0,5%,1/16W,EMPTY,A
     1 P12V_HSC_TEMP_SCL @S9S_MB_2U_LIB.S9S_MB_2U(SCH_1):P12V_HSC_TEMP_SCL    I15 @S9S_MB_2U_LIB.S9S_MB_2U(SCH_1):PAGE327
     2 SMB_LM75_0_3V3AUX_SCL @S9S_MB_2U_LIB.S9S_MB_2U(SCH_1):SMB_LM75_0_3V3AUX_SCL    I15 @S9S_MB_2U_LIB.S9S_MB_2U(SCH_1):PAGE327

R4895 Q_RES_0402LF-0,5%,1/16W,EMPTY,A
     1 P12V_HSC_TEMP_SDA @S9S_MB_2U_LIB.S9S_MB_2U(SCH_1):P12V_HSC_TEMP_SDA    I16 @S9S_MB_2U_LIB.S9S_MB_2U(SCH_1):PAGE327
     2 SMB_LM75_0_3V3AUX_SDA @S9S_MB_2U_LIB.S9S_MB_2U(SCH_1):SMB_LM75_0_3V3AUX_SDA    I16 @S9S_MB_2U_LIB.S9S_MB_2U(SCH_1):PAGE327

R4896 Q_RES_0402LF-0,5%,1/16W,EMPTY,A
     1 P12V_HSC_T_CRIT_N @S9S_MB_2U_LIB.S9S_MB_2U(SCH_1):P12V_HSC_T_CRIT_N    I11 @S9S_MB_2U_LIB.S9S_MB_2U(SCH_1):PAGE327
     2 P12V_HSC_T_CRIT_R_N @S9S_MB_2U_LIB.S9S_MB_2U(SCH_1):P12V_HSC_T_CRIT_R_N    I11 @S9S_MB_2U_LIB.S9S_MB_2U(SCH_1):PAGE327

R4901 Q_RES_0402LF-82K,1%,1/16W,CHIPA
     1 P12V_PSU_FUSE @S9S_MB_2U_LIB.S9S_MB_2U(SCH_1):P12V_PSU_FUSE    I26 @S9S_MB_2U_LIB.S9S_MB_2U(SCH_1):PAGE303
     2 HSC_EN @S9S_MB_2U_LIB.S9S_MB_2U(SCH_1):HSC_EN    I26 @S9S_MB_2U_LIB.S9S_MB_2U(SCH_1):PAGE303

R5234 Q_RES_0402LF-0,5%,1/16W,CHIP,CA
     1 USB2_HUB_BUF_SWB_R_DP @S9S_MB_2U_LIB.S9S_MB_2U(SCH_1):USB2_HUB_BUF_SWB_R_DP    I91 @S9S_MB_2U_LIB.S9S_MB_2U(SCH_1):PAGE155
     2 USB2_HUB_BUF_SWB_DP @S9S_MB_2U_LIB.S9S_MB_2U(SCH_1):USB2_HUB_BUF_SWB_DP    I91 @S9S_MB_2U_LIB.S9S_MB_2U(SCH_1):PAGE155

R5236 Q_RES_0402LF-0,5%,1/16W,CHIP,CA
     1 USB2_HUB_BUF_SWB_R_DN @S9S_MB_2U_LIB.S9S_MB_2U(SCH_1):USB2_HUB_BUF_SWB_R_DN    I90 @S9S_MB_2U_LIB.S9S_MB_2U(SCH_1):PAGE155
     2 USB2_HUB_BUF_SWB_DN @S9S_MB_2U_LIB.S9S_MB_2U(SCH_1):USB2_HUB_BUF_SWB_DN    I90 @S9S_MB_2U_LIB.S9S_MB_2U(SCH_1):PAGE155

R5238 Q_RES_0402LF-3.9K,5%,1/16W,EMPA
     1 PD_U5201_EQ @S9S_MB_2U_LIB.S9S_MB_2U(SCH_1):PD_U5201_EQ    I83 @S9S_MB_2U_LIB.S9S_MB_2U(SCH_1):PAGE155
     2    GND @S9S_MB_2U_LIB.S9S_MB_2U(SCH_1):GND    I83 @S9S_MB_2U_LIB.S9S_MB_2U(SCH_1):PAGE155

R5377 Q_RES_0402LF-0,5%,1/16W,CHIP,CA
     1 HDD_ACTIVITY_BUF_N @S9S_MB_2U_LIB.S9S_MB_2U(SCH_1):HDD_ACTIVITY_BUF_N   I312 @S9S_MB_2U_LIB.S9S_MB_2U(SCH_1):PAGE182
     2 PU_BUFFER_HDD_ACTIVITY @S9S_MB_2U_LIB.S9S_MB_2U(SCH_1):PU_BUFFER_HDD_ACTIVITY   I312 @S9S_MB_2U_LIB.S9S_MB_2U(SCH_1):PAGE182

R5487 Q_RES_0402LF-0,5%,1/16W,CHIP,CA
     1 HP_LVC3_OCP_V3_1_EN @S9S_MB_2U_LIB.S9S_MB_2U(SCH_1):HP_LVC3_OCP_V3_1_EN    I19 @S9S_MB_2U_LIB.S9S_MB_2U(SCH_1):PAGE153
     2 P3V3_OCP_EN_1_R @S9S_MB_2U_LIB.S9S_MB_2U(SCH_1):P3V3_OCP_EN_1_R    I19 @S9S_MB_2U_LIB.S9S_MB_2U(SCH_1):PAGE153

 SW5 SW_PUSHBUTTON4P_24-SW4S_DTSM-6A
     1 PD_RST_RTCRST_N @S9S_MB_2U_LIB.S9S_MB_2U(SCH_1):PD_RST_RTCRST_N   I122 @S9S_MB_2U_LIB.S9S_MB_2U(SCH_1):PAGE189
     2 PD_RST_RTCRST_N @S9S_MB_2U_LIB.S9S_MB_2U(SCH_1):PD_RST_RTCRST_N   I122 @S9S_MB_2U_LIB.S9S_MB_2U(SCH_1):PAGE189
     3 RST_RTCRST_N @S9S_MB_2U_LIB.S9S_MB_2U(SCH_1):RST_RTCRST_N   I122 @S9S_MB_2U_LIB.S9S_MB_2U(SCH_1):PAGE189
     4 RST_RTCRST_N @S9S_MB_2U_LIB.S9S_MB_2U(SCH_1):RST_RTCRST_N   I122 @S9S_MB_2U_LIB.S9S_MB_2U(SCH_1):PAGE189

  U1 SOCKET4677_AZIF0045P001C01CS-SA
  CY32 CLK_25M_NSSC_CPU1_DP @S9S_MB_2U_LIB.S9S_MB_2U(SCH_1):CLK_25M_NSSC_CPU1_DP    I51 @S9S_MB_2U_LIB.S9S_MB_2U(SCH_1):PAGE44
  CT20 PD_CPU1_TXT_PLTEN @S9S_MB_2U_LIB.S9S_MB_2U(SCH_1):PD_CPU1_TXT_PLTEN    I51 @S9S_MB_2U_LIB.S9S_MB_2U(SCH_1):PAGE44
  BT26 PU_CPU1_TXT_AGENT @S9S_MB_2U_LIB.S9S_MB_2U(SCH_1):PU_CPU1_TXT_AGENT    I51 @S9S_MB_2U_LIB.S9S_MB_2U(SCH_1):PAGE44
  BR25 JTAG_DBP_CPU1_QS_GTL_R_TMS @S9S_MB_2U_LIB.S9S_MB_2U(SCH_1):JTAG_DBP_CPU1_QS_GTL_R_TMS    I51 @S9S_MB_2U_LIB.S9S_MB_2U(SCH_1):PAGE44
  BW25 JTAG_CPU1_MUX_GTL_TDO @S9S_MB_2U_LIB.S9S_MB_2U(SCH_1):JTAG_CPU1_MUX_GTL_TDO    I51 @S9S_MB_2U_LIB.S9S_MB_2U(SCH_1):PAGE44
  BV24 JTAG_DBP_CPU1_GTL_R_TDI @S9S_MB_2U_LIB.S9S_MB_2U(SCH_1):JTAG_DBP_CPU1_GTL_R_TDI    I51 @S9S_MB_2U_LIB.S9S_MB_2U(SCH_1):PAGE44
  BT24 JTAG_DBP_CPU1_GTL_R_TCK @S9S_MB_2U_LIB.S9S_MB_2U(SCH_1):JTAG_DBP_CPU1_GTL_R_TCK    I51 @S9S_MB_2U_LIB.S9S_MB_2U(SCH_1):PAGE44
  CW60 PU_CPU1_SOCKET_ID0 @S9S_MB_2U_LIB.S9S_MB_2U(SCH_1):PU_CPU1_SOCKET_ID0    I51 @S9S_MB_2U_LIB.S9S_MB_2U(SCH_1):PAGE44
  CY61 PU_CPU1_SOCKET_ID1 @S9S_MB_2U_LIB.S9S_MB_2U(SCH_1):PU_CPU1_SOCKET_ID1    I51 @S9S_MB_2U_LIB.S9S_MB_2U(SCH_1):PAGE44
  CT61 PU_CPU1_SOCKET_ID2 @S9S_MB_2U_LIB.S9S_MB_2U(SCH_1):PU_CPU1_SOCKET_ID2    I51 @S9S_MB_2U_LIB.S9S_MB_2U(SCH_1):PAGE44
  AU23 PU_CPU1_SAFE_MODE_BOOT @S9S_MB_2U_LIB.S9S_MB_2U(SCH_1):PU_CPU1_SAFE_MODE_BOOT    I51 @S9S_MB_2U_LIB.S9S_MB_2U(SCH_1):PAGE44
  CE70 CPU1_RSVD<85> @S9S_MB_2U_LIB.S9S_MB_2U(SCH_1):CPU1_RSVD(85)    I51 @S9S_MB_2U_LIB.S9S_MB_2U(SCH_1):PAGE44
  CD71 CPU1_RSVD<82> @S9S_MB_2U_LIB.S9S_MB_2U(SCH_1):CPU1_RSVD(82)    I51 @S9S_MB_2U_LIB.S9S_MB_2U(SCH_1):PAGE44
  BY24 PD_EXT_CLK_SEL_CPU1 @S9S_MB_2U_LIB.S9S_MB_2U(SCH_1):PD_EXT_CLK_SEL_CPU1    I51 @S9S_MB_2U_LIB.S9S_MB_2U(SCH_1):PAGE44
    G5 CPU1_RSVD<157> @S9S_MB_2U_LIB.S9S_MB_2U(SCH_1):CPU1_RSVD(157)    I51 @S9S_MB_2U_LIB.S9S_MB_2U(SCH_1):PAGE44
  CJ72 PUD_XTAL_CPU1_MODE1 @S9S_MB_2U_LIB.S9S_MB_2U(SCH_1):PUD_XTAL_CPU1_MODE1    I51 @S9S_MB_2U_LIB.S9S_MB_2U(SCH_1):PAGE44
  BG72 FM_CPU1_PROC_ID0 @S9S_MB_2U_LIB.S9S_MB_2U(SCH_1):FM_CPU1_PROC_ID0    I51 @S9S_MB_2U_LIB.S9S_MB_2U(SCH_1):PAGE44
  BH71 FM_CPU1_PROC_ID1 @S9S_MB_2U_LIB.S9S_MB_2U(SCH_1):FM_CPU1_PROC_ID1    I51 @S9S_MB_2U_LIB.S9S_MB_2U(SCH_1):PAGE44
  DA52 PD_CPU1_PROCDIS_COD_GTL_N @S9S_MB_2U_LIB.S9S_MB_2U(SCH_1):PD_CPU1_PROCDIS_COD_GTL_N    I51 @S9S_MB_2U_LIB.S9S_MB_2U(SCH_1):PAGE44
  AV22 H_CPU1_PREQ_QS_GTL_R_N @S9S_MB_2U_LIB.S9S_MB_2U(SCH_1):H_CPU1_PREQ_QS_GTL_R_N    I51 @S9S_MB_2U_LIB.S9S_MB_2U(SCH_1):PAGE44
  BP26 H_CPU1_PRDY_QS_GTL_R_N @S9S_MB_2U_LIB.S9S_MB_2U(SCH_1):H_CPU1_PRDY_QS_GTL_R_N    I51 @S9S_MB_2U_LIB.S9S_MB_2U(SCH_1):PAGE44
  BL64 FM_CPU1_PKGID0 @S9S_MB_2U_LIB.S9S_MB_2U(SCH_1):FM_CPU1_PKGID0    I51 @S9S_MB_2U_LIB.S9S_MB_2U(SCH_1):PAGE44
  AY63 FM_CPU1_PKGID1 @S9S_MB_2U_LIB.S9S_MB_2U(SCH_1):FM_CPU1_PKGID1    I51 @S9S_MB_2U_LIB.S9S_MB_2U(SCH_1):PAGE44
  BN64 FM_CPU1_PKGID2 @S9S_MB_2U_LIB.S9S_MB_2U(SCH_1):FM_CPU1_PKGID2    I51 @S9S_MB_2U_LIB.S9S_MB_2U(SCH_1):PAGE44
  BH24 PECI_CPU1_GTL_R @S9S_MB_2U_LIB.S9S_MB_2U(SCH_1):PECI_CPU1_GTL_R    I51 @S9S_MB_2U_LIB.S9S_MB_2U(SCH_1):PAGE44
  BR23 TP_CPU1_BR23 @S9S_MB_2U_LIB.S9S_MB_2U(SCH_1):TP_CPU1_BR23    I51 @S9S_MB_2U_LIB.S9S_MB_2U(SCH_1):PAGE44
  CY59 PU_CPU1_LEGACY_SKT @S9S_MB_2U_LIB.S9S_MB_2U(SCH_1):PU_CPU1_LEGACY_SKT    I51 @S9S_MB_2U_LIB.S9S_MB_2U(SCH_1):PAGE44
  AU17 PU_CPU1_FRMAGENT @S9S_MB_2U_LIB.S9S_MB_2U(SCH_1):PU_CPU1_FRMAGENT    I51 @S9S_MB_2U_LIB.S9S_MB_2U(SCH_1):PAGE44
  AW17 PD_CPU1_DMIMODE_OVERRIDE @S9S_MB_2U_LIB.S9S_MB_2U(SCH_1):PD_CPU1_DMIMODE_OVERRIDE    I51 @S9S_MB_2U_LIB.S9S_MB_2U(SCH_1):PAGE44
  CY55 RST_CPU1_DRAM_GH_N @S9S_MB_2U_LIB.S9S_MB_2U(SCH_1):RST_CPU1_DRAM_GH_N    I51 @S9S_MB_2U_LIB.S9S_MB_2U(SCH_1):PAGE44
  CY42 RST_CPU1_DRAM_EF_N @S9S_MB_2U_LIB.S9S_MB_2U(SCH_1):RST_CPU1_DRAM_EF_N    I51 @S9S_MB_2U_LIB.S9S_MB_2U(SCH_1):PAGE44
  CT18 I3C_SPD_DDREFGH_CPU1_SDA @S9S_MB_2U_LIB.S9S_MB_2U(SCH_1):I3C_SPD_DDREFGH_CPU1_SDA    I51 @S9S_MB_2U_LIB.S9S_MB_2U(SCH_1):PAGE44
  CU17 I3C_SPD_DDREFGH_CPU1_SCL @S9S_MB_2U_LIB.S9S_MB_2U(SCH_1):I3C_SPD_DDREFGH_CPU1_SCL    I51 @S9S_MB_2U_LIB.S9S_MB_2U(SCH_1):PAGE44
  AV51 RST_CPU1_DRAM_CD_N @S9S_MB_2U_LIB.S9S_MB_2U(SCH_1):RST_CPU1_DRAM_CD_N    I51 @S9S_MB_2U_LIB.S9S_MB_2U(SCH_1):PAGE44
  AU50 RST_CPU1_DRAM_AB_N @S9S_MB_2U_LIB.S9S_MB_2U(SCH_1):RST_CPU1_DRAM_AB_N    I51 @S9S_MB_2U_LIB.S9S_MB_2U(SCH_1):PAGE44
  BY22 I3C_SPD_DDRABCD_CPU1_SDA @S9S_MB_2U_LIB.S9S_MB_2U(SCH_1):I3C_SPD_DDRABCD_CPU1_SDA    I51 @S9S_MB_2U_LIB.S9S_MB_2U(SCH_1):PAGE44
  BT22 I3C_SPD_DDRABCD_CPU1_SCL @S9S_MB_2U_LIB.S9S_MB_2U(SCH_1):I3C_SPD_DDRABCD_CPU1_SCL    I51 @S9S_MB_2U_LIB.S9S_MB_2U(SCH_1):PAGE44
  BN23 H_CPU1_BMCINIT_LVC1 @S9S_MB_2U_LIB.S9S_MB_2U(SCH_1):H_CPU1_BMCINIT_LVC1    I51 @S9S_MB_2U_LIB.S9S_MB_2U(SCH_1):PAGE44
  AT18 PD_CPU1_BIST_ENABLE @S9S_MB_2U_LIB.S9S_MB_2U(SCH_1):PD_CPU1_BIST_ENABLE    I51 @S9S_MB_2U_LIB.S9S_MB_2U(SCH_1):PAGE44
  DA27 CLK_100M_DB2000_CPU1_BCLK3_DP @S9S_MB_2U_LIB.S9S_MB_2U(SCH_1):CLK_100M_DB2000_CPU1_BCLK3_DP    I51 @S9S_MB_2U_LIB.S9S_MB_2U(SCH_1):PAGE44
  CW27 CLK_100M_DB2000_CPU1_BCLK3_DN @S9S_MB_2U_LIB.S9S_MB_2U(SCH_1):CLK_100M_DB2000_CPU1_BCLK3_DN    I51 @S9S_MB_2U_LIB.S9S_MB_2U(SCH_1):PAGE44
  AV28 CLK_100M_DB2000_CPU1_BCLK2_DP @S9S_MB_2U_LIB.S9S_MB_2U(SCH_1):CLK_100M_DB2000_CPU1_BCLK2_DP    I51 @S9S_MB_2U_LIB.S9S_MB_2U(SCH_1):PAGE44
  AU29 CLK_100M_DB2000_CPU1_BCLK2_DN @S9S_MB_2U_LIB.S9S_MB_2U(SCH_1):CLK_100M_DB2000_CPU1_BCLK2_DN    I51 @S9S_MB_2U_LIB.S9S_MB_2U(SCH_1):PAGE44
  AV30 CLK_100M_DB2000_CPU1_BCLK0_DP @S9S_MB_2U_LIB.S9S_MB_2U(SCH_1):CLK_100M_DB2000_CPU1_BCLK0_DP    I51 @S9S_MB_2U_LIB.S9S_MB_2U(SCH_1):PAGE44
  CY28 CLK_100M_DB2000_CPU1_BCLK1_DN @S9S_MB_2U_LIB.S9S_MB_2U(SCH_1):CLK_100M_DB2000_CPU1_BCLK1_DN    I51 @S9S_MB_2U_LIB.S9S_MB_2U(SCH_1):PAGE44
  CW29 CLK_100M_DB2000_CPU1_BCLK1_DP @S9S_MB_2U_LIB.S9S_MB_2U(SCH_1):CLK_100M_DB2000_CPU1_BCLK1_DP    I51 @S9S_MB_2U_LIB.S9S_MB_2U(SCH_1):PAGE44
  AT30 CLK_100M_DB2000_CPU1_BCLK0_DN @S9S_MB_2U_LIB.S9S_MB_2U(SCH_1):CLK_100M_DB2000_CPU1_BCLK0_DN    I51 @S9S_MB_2U_LIB.S9S_MB_2U(SCH_1):PAGE44
  CL72 PUD_XTAL_CPU1_MODE0 @S9S_MB_2U_LIB.S9S_MB_2U(SCH_1):PUD_XTAL_CPU1_MODE0    I51 @S9S_MB_2U_LIB.S9S_MB_2U(SCH_1):PAGE44
    D4 CPU1_RSVD<153> @S9S_MB_2U_LIB.S9S_MB_2U(SCH_1):CPU1_RSVD(153)    I51 @S9S_MB_2U_LIB.S9S_MB_2U(SCH_1):PAGE44
  CW31 CLK_25M_NSSC_CPU1_DN @S9S_MB_2U_LIB.S9S_MB_2U(SCH_1):CLK_25M_NSSC_CPU1_DN    I51 @S9S_MB_2U_LIB.S9S_MB_2U(SCH_1):PAGE44
  BP24 H_CPU1_CATERR_LVC1_R_N @S9S_MB_2U_LIB.S9S_MB_2U(SCH_1):H_CPU1_CATERR_LVC1_R_N    I29 @S9S_MB_2U_LIB.S9S_MB_2U(SCH_1):PAGE45
  CA25 SMB_PEHPCPU1_GTL_SCL @S9S_MB_2U_LIB.S9S_MB_2U(SCH_1):SMB_PEHPCPU1_GTL_SCL    I29 @S9S_MB_2U_LIB.S9S_MB_2U(SCH_1):PAGE45
  BY26 SMB_PEHPCPU1_GTL_SDA @S9S_MB_2U_LIB.S9S_MB_2U(SCH_1):SMB_PEHPCPU1_GTL_SDA    I29 @S9S_MB_2U_LIB.S9S_MB_2U(SCH_1):PAGE45
  BV26 FM_PEHPCPU1_ALERT_N @S9S_MB_2U_LIB.S9S_MB_2U(SCH_1):FM_PEHPCPU1_ALERT_N    I29 @S9S_MB_2U_LIB.S9S_MB_2U(SCH_1):PAGE45
   A43 PWRGD_DRAMPWRGD_CPU1_AB_LVC1_R @S9S_MB_2U_LIB.S9S_MB_2U(SCH_1):PWRGD_DRAMPWRGD_CPU1_AB_LVC1_R    I29 @S9S_MB_2U_LIB.S9S_MB_2U(SCH_1):PAGE45
   F47 PWRGD_DRAMPWRGD_CPU1_CD_LVC1_R @S9S_MB_2U_LIB.S9S_MB_2U(SCH_1):PWRGD_DRAMPWRGD_CPU1_CD_LVC1_R    I29 @S9S_MB_2U_LIB.S9S_MB_2U(SCH_1):PAGE45
  CY44 PWRGD_DRAMPWRGD_CPU1_EF_LVC1_R @S9S_MB_2U_LIB.S9S_MB_2U(SCH_1):PWRGD_DRAMPWRGD_CPU1_EF_LVC1_R    I29 @S9S_MB_2U_LIB.S9S_MB_2U(SCH_1):PAGE45
  CW45 PWRGD_DRAMPWRGD_CPU1_GH_LVC1_R @S9S_MB_2U_LIB.S9S_MB_2U(SCH_1):PWRGD_DRAMPWRGD_CPU1_GH_LVC1_R    I29 @S9S_MB_2U_LIB.S9S_MB_2U(SCH_1):PAGE45
  CH22 PD_CPU1_ENH_MCECC_DIS @S9S_MB_2U_LIB.S9S_MB_2U(SCH_1):PD_CPU1_ENH_MCECC_DIS    I29 @S9S_MB_2U_LIB.S9S_MB_2U(SCH_1):PAGE45
  BD22 H_CPU1_ERR2_LVC1_R_N @S9S_MB_2U_LIB.S9S_MB_2U(SCH_1):H_CPU1_ERR2_LVC1_R_N    I29 @S9S_MB_2U_LIB.S9S_MB_2U(SCH_1):PAGE45
  AY22 H_CPU1_ERR1_LVC1_R_N @S9S_MB_2U_LIB.S9S_MB_2U(SCH_1):H_CPU1_ERR1_LVC1_R_N    I29 @S9S_MB_2U_LIB.S9S_MB_2U(SCH_1):PAGE45
  BF22 H_CPU1_ERR0_LVC1_R_N @S9S_MB_2U_LIB.S9S_MB_2U(SCH_1):H_CPU1_ERR0_LVC1_R_N    I29 @S9S_MB_2U_LIB.S9S_MB_2U(SCH_1):PAGE45
  AV57 FM_CPU_FBRK_DEBUG_R_N @S9S_MB_2U_LIB.S9S_MB_2U(SCH_1):FM_CPU_FBRK_DEBUG_R_N    I29 @S9S_MB_2U_LIB.S9S_MB_2U(SCH_1):PAGE45
  AU21 H_CPU1_MEMHOT_IN_LVC1_N @S9S_MB_2U_LIB.S9S_MB_2U(SCH_1):H_CPU1_MEMHOT_IN_LVC1_N    I29 @S9S_MB_2U_LIB.S9S_MB_2U(SCH_1):PAGE45
  CF26 H_CPU1_MEMHOT_OUT_LVC1_R_N @S9S_MB_2U_LIB.S9S_MB_2U(SCH_1):H_CPU1_MEMHOT_OUT_LVC1_R_N    I29 @S9S_MB_2U_LIB.S9S_MB_2U(SCH_1):PAGE45
  AV24 H_CPU1_MEMTRIP_LVC1_R_N @S9S_MB_2U_LIB.S9S_MB_2U(SCH_1):H_CPU1_MEMTRIP_LVC1_R_N    I29 @S9S_MB_2U_LIB.S9S_MB_2U(SCH_1):PAGE45
  AV18 H_CPU1_NMI_LVC1_N @S9S_MB_2U_LIB.S9S_MB_2U(SCH_1):H_CPU1_NMI_LVC1_N    I29 @S9S_MB_2U_LIB.S9S_MB_2U(SCH_1):PAGE45
  CP71 PD_PIROM_CPU1_ADDR2 @S9S_MB_2U_LIB.S9S_MB_2U(SCH_1):PD_PIROM_CPU1_ADDR2    I29 @S9S_MB_2U_LIB.S9S_MB_2U(SCH_1):PAGE45
  CT71 PD_PIROM_CPU1_ADDR1 @S9S_MB_2U_LIB.S9S_MB_2U(SCH_1):PD_PIROM_CPU1_ADDR1    I29 @S9S_MB_2U_LIB.S9S_MB_2U(SCH_1):PAGE45
  CR70 PU_PIROM_CPU1_ADDR0 @S9S_MB_2U_LIB.S9S_MB_2U(SCH_1):PU_PIROM_CPU1_ADDR0    I29 @S9S_MB_2U_LIB.S9S_MB_2U(SCH_1):PAGE45
  CU70 SMB_S3M_CPU1_PIROM_3V3AUX_SCL_1 @S9S_MB_2U_LIB.S9S_MB_2U(SCH_1):SMB_S3M_CPU1_PIROM_3V3AUX_SCL_R1    I29 @S9S_MB_2U_LIB.S9S_MB_2U(SCH_1):PAGE45
  CM71 SMB_S3M_CPU1_PIROM_3V3AUX_SDA_1 @S9S_MB_2U_LIB.S9S_MB_2U(SCH_1):SMB_S3M_CPU1_PIROM_3V3AUX_SDA_R1    I29 @S9S_MB_2U_LIB.S9S_MB_2U(SCH_1):PAGE45
  CR72 PU_PIROM_CPU1_SM_WP @S9S_MB_2U_LIB.S9S_MB_2U(SCH_1):PU_PIROM_CPU1_SM_WP    I29 @S9S_MB_2U_LIB.S9S_MB_2U(SCH_1):PAGE45
  CC25 TP_H_SBLINK7_CPU1_PMDOWN @S9S_MB_2U_LIB.S9S_MB_2U(SCH_1):TP_H_SBLINK7_CPU1_PMDOWN    I29 @S9S_MB_2U_LIB.S9S_MB_2U(SCH_1):PAGE45
  CE23 TP_H_SBLINK6_CPU1_PMDOWN @S9S_MB_2U_LIB.S9S_MB_2U(SCH_1):TP_H_SBLINK6_CPU1_PMDOWN    I29 @S9S_MB_2U_LIB.S9S_MB_2U(SCH_1):PAGE45
  CV18 TP_H_SBLINK5_CPU1_PMDOWN @S9S_MB_2U_LIB.S9S_MB_2U(SCH_1):TP_H_SBLINK5_CPU1_PMDOWN    I29 @S9S_MB_2U_LIB.S9S_MB_2U(SCH_1):PAGE45
  CD24 TP_H_SBLINK4_CPU1_PMDOWN @S9S_MB_2U_LIB.S9S_MB_2U(SCH_1):TP_H_SBLINK4_CPU1_PMDOWN    I29 @S9S_MB_2U_LIB.S9S_MB_2U(SCH_1):PAGE45
  CM26 TP_H_SBLINK3_CPU1_PMDOWN @S9S_MB_2U_LIB.S9S_MB_2U(SCH_1):TP_H_SBLINK3_CPU1_PMDOWN    I29 @S9S_MB_2U_LIB.S9S_MB_2U(SCH_1):PAGE45
  CP26 TP_H_SBLINK2_CPU1_PMDOWN @S9S_MB_2U_LIB.S9S_MB_2U(SCH_1):TP_H_SBLINK2_CPU1_PMDOWN    I29 @S9S_MB_2U_LIB.S9S_MB_2U(SCH_1):PAGE45
  CW39 H_CPU0_PMSYNC_CPU1 @S9S_MB_2U_LIB.S9S_MB_2U(SCH_1):H_CPU0_PMSYNC_CPU1    I29 @S9S_MB_2U_LIB.S9S_MB_2U(SCH_1):PAGE45
  CY40 TP_H_CPU1_PMDOWN_PCH_R @S9S_MB_2U_LIB.S9S_MB_2U(SCH_1):TP_H_CPU1_PMDOWN_PCH_R    I29 @S9S_MB_2U_LIB.S9S_MB_2U(SCH_1):PAGE45
  CP20 H_CPU1_PM_FAST_WAKE_N @S9S_MB_2U_LIB.S9S_MB_2U(SCH_1):H_CPU1_PM_FAST_WAKE_N    I29 @S9S_MB_2U_LIB.S9S_MB_2U(SCH_1):PAGE45
  CF24 TP_H_SBLINK7_CPU1_PMSYNC @S9S_MB_2U_LIB.S9S_MB_2U(SCH_1):TP_H_SBLINK7_CPU1_PMSYNC    I29 @S9S_MB_2U_LIB.S9S_MB_2U(SCH_1):PAGE45
  CH24 TP_H_SBLINK6_CPU1_PMSYNC @S9S_MB_2U_LIB.S9S_MB_2U(SCH_1):TP_H_SBLINK6_CPU1_PMSYNC    I29 @S9S_MB_2U_LIB.S9S_MB_2U(SCH_1):PAGE45
  CR19 TP_H_SBLINK5_CPU1_PMSYNC @S9S_MB_2U_LIB.S9S_MB_2U(SCH_1):TP_H_SBLINK5_CPU1_PMSYNC    I29 @S9S_MB_2U_LIB.S9S_MB_2U(SCH_1):PAGE45
  CE25 TP_H_SBLINK4_CPU1_PMSYNC @S9S_MB_2U_LIB.S9S_MB_2U(SCH_1):TP_H_SBLINK4_CPU1_PMSYNC    I29 @S9S_MB_2U_LIB.S9S_MB_2U(SCH_1):PAGE45
  CH26 TP_H_SBLINK3_CPU1_PMSYNC @S9S_MB_2U_LIB.S9S_MB_2U(SCH_1):TP_H_SBLINK3_CPU1_PMSYNC    I29 @S9S_MB_2U_LIB.S9S_MB_2U(SCH_1):PAGE45
  CL25 TP_H_SBLINK2_CPU1_PMSYNC @S9S_MB_2U_LIB.S9S_MB_2U(SCH_1):TP_H_SBLINK2_CPU1_PMSYNC    I29 @S9S_MB_2U_LIB.S9S_MB_2U(SCH_1):PAGE45
  CN25 H_CPU0_PMDOWN_CPU1 @S9S_MB_2U_LIB.S9S_MB_2U(SCH_1):H_CPU0_PMDOWN_CPU1    I29 @S9S_MB_2U_LIB.S9S_MB_2U(SCH_1):PAGE45
  DA39 TP_H_CPU1_PMSYNC_PCH_INTRP_R @S9S_MB_2U_LIB.S9S_MB_2U(SCH_1):TP_H_CPU1_PMSYNC_PCH_INTRP_R    I29 @S9S_MB_2U_LIB.S9S_MB_2U(SCH_1):PAGE45
  AU19 H_CPU1_PROCHOT_LVC1_N @S9S_MB_2U_LIB.S9S_MB_2U(SCH_1):H_CPU1_PROCHOT_LVC1_N    I29 @S9S_MB_2U_LIB.S9S_MB_2U(SCH_1):PAGE45
  AV20 PWRGD_CPU1_LVC1 @S9S_MB_2U_LIB.S9S_MB_2U(SCH_1):PWRGD_CPU1_LVC1    I29 @S9S_MB_2U_LIB.S9S_MB_2U(SCH_1):PAGE45
  BH61 RST_CPU1_LVC1_N @S9S_MB_2U_LIB.S9S_MB_2U(SCH_1):RST_CPU1_LVC1_N    I29 @S9S_MB_2U_LIB.S9S_MB_2U(SCH_1):PAGE45
  CL21 CPU1_RSVD<107> @S9S_MB_2U_LIB.S9S_MB_2U(SCH_1):CPU1_RSVD(107)    I29 @S9S_MB_2U_LIB.S9S_MB_2U(SCH_1):PAGE45
  CL64 CPU1_RSVD<110> @S9S_MB_2U_LIB.S9S_MB_2U(SCH_1):CPU1_RSVD(110)    I29 @S9S_MB_2U_LIB.S9S_MB_2U(SCH_1):PAGE45
  CM63 CPU1_RSVD<115> @S9S_MB_2U_LIB.S9S_MB_2U(SCH_1):CPU1_RSVD(115)    I29 @S9S_MB_2U_LIB.S9S_MB_2U(SCH_1):PAGE45
  CN62 CPU1_RSVD<120> @S9S_MB_2U_LIB.S9S_MB_2U(SCH_1):CPU1_RSVD(120)    I29 @S9S_MB_2U_LIB.S9S_MB_2U(SCH_1):PAGE45
  CR23 CPU1_RSVD<126> @S9S_MB_2U_LIB.S9S_MB_2U(SCH_1):CPU1_RSVD(126)    I29 @S9S_MB_2U_LIB.S9S_MB_2U(SCH_1):PAGE45
  CV24 CPU1_RSVD<135> @S9S_MB_2U_LIB.S9S_MB_2U(SCH_1):CPU1_RSVD(135)    I29 @S9S_MB_2U_LIB.S9S_MB_2U(SCH_1):PAGE45
  CW23 CPU1_RSVD<139> @S9S_MB_2U_LIB.S9S_MB_2U(SCH_1):CPU1_RSVD(139)    I29 @S9S_MB_2U_LIB.S9S_MB_2U(SCH_1):PAGE45
  CW25 CPU1_RSVD<140> @S9S_MB_2U_LIB.S9S_MB_2U(SCH_1):CPU1_RSVD(140)    I29 @S9S_MB_2U_LIB.S9S_MB_2U(SCH_1):PAGE45
  CW68 CPU1_RSVD<144> @S9S_MB_2U_LIB.S9S_MB_2U(SCH_1):CPU1_RSVD(144)    I29 @S9S_MB_2U_LIB.S9S_MB_2U(SCH_1):PAGE45
  AV26 CPU1_RSVD<15> @S9S_MB_2U_LIB.S9S_MB_2U(SCH_1):CPU1_RSVD(15)    I29 @S9S_MB_2U_LIB.S9S_MB_2U(SCH_1):PAGE45
  AY26 CPU1_RSVD<25> @S9S_MB_2U_LIB.S9S_MB_2U(SCH_1):CPU1_RSVD(25)    I29 @S9S_MB_2U_LIB.S9S_MB_2U(SCH_1):PAGE45
  AY65 CPU1_RSVD<27> @S9S_MB_2U_LIB.S9S_MB_2U(SCH_1):CPU1_RSVD(27)    I29 @S9S_MB_2U_LIB.S9S_MB_2U(SCH_1):PAGE45
  AT24 CPU1_RSVD<4> @S9S_MB_2U_LIB.S9S_MB_2U(SCH_1):CPU1_RSVD(4)    I29 @S9S_MB_2U_LIB.S9S_MB_2U(SCH_1):PAGE45
  BJ70 CPU1_RSVD<54> @S9S_MB_2U_LIB.S9S_MB_2U(SCH_1):CPU1_RSVD(54)    I29 @S9S_MB_2U_LIB.S9S_MB_2U(SCH_1):PAGE45
  AU25 CPU1_RSVD<6> @S9S_MB_2U_LIB.S9S_MB_2U(SCH_1):CPU1_RSVD(6)    I29 @S9S_MB_2U_LIB.S9S_MB_2U(SCH_1):PAGE45
  BP67 CPU1_RSVD<64> @S9S_MB_2U_LIB.S9S_MB_2U(SCH_1):CPU1_RSVD(64)    I29 @S9S_MB_2U_LIB.S9S_MB_2U(SCH_1):PAGE45
  BP69 CPU1_RSVD<65> @S9S_MB_2U_LIB.S9S_MB_2U(SCH_1):CPU1_RSVD(65)    I29 @S9S_MB_2U_LIB.S9S_MB_2U(SCH_1):PAGE45
  CJ62 CPU1_RSVD<98> @S9S_MB_2U_LIB.S9S_MB_2U(SCH_1):CPU1_RSVD(98)    I29 @S9S_MB_2U_LIB.S9S_MB_2U(SCH_1):PAGE45
  CG66 FM_CPU1_SKTOCC_LVT3_N @S9S_MB_2U_LIB.S9S_MB_2U(SCH_1):FM_CPU1_SKTOCC_LVT3_N    I29 @S9S_MB_2U_LIB.S9S_MB_2U(SCH_1):PAGE45
  BK26 SVID_ALERT0_CPU1_N @S9S_MB_2U_LIB.S9S_MB_2U(SCH_1):SVID_ALERT0_CPU1_N    I29 @S9S_MB_2U_LIB.S9S_MB_2U(SCH_1):PAGE45
  BJ25 SVID_ALERT1_CPU1_N @S9S_MB_2U_LIB.S9S_MB_2U(SCH_1):SVID_ALERT1_CPU1_N    I29 @S9S_MB_2U_LIB.S9S_MB_2U(SCH_1):PAGE45
  BH26 SVID_CLK0_CPU1 @S9S_MB_2U_LIB.S9S_MB_2U(SCH_1):SVID_CLK0_CPU1    I29 @S9S_MB_2U_LIB.S9S_MB_2U(SCH_1):PAGE45
  BF26 SVID_CLK1_CPU1 @S9S_MB_2U_LIB.S9S_MB_2U(SCH_1):SVID_CLK1_CPU1    I29 @S9S_MB_2U_LIB.S9S_MB_2U(SCH_1):PAGE45
  BD26 SVID_DIO0_CPU1 @S9S_MB_2U_LIB.S9S_MB_2U(SCH_1):SVID_DIO0_CPU1    I29 @S9S_MB_2U_LIB.S9S_MB_2U(SCH_1):PAGE45
  BL25 SVID_DIO1_CPU1 @S9S_MB_2U_LIB.S9S_MB_2U(SCH_1):SVID_DIO1_CPU1    I29 @S9S_MB_2U_LIB.S9S_MB_2U(SCH_1):PAGE45
  AY20 PU_TAP_ODT_CPU1_EN @S9S_MB_2U_LIB.S9S_MB_2U(SCH_1):PU_TAP_ODT_CPU1_EN    I29 @S9S_MB_2U_LIB.S9S_MB_2U(SCH_1):PAGE45
  AV59 TP_EV_CPU1_EXT_BGREF @S9S_MB_2U_LIB.S9S_MB_2U(SCH_1):TP_EV_CPU1_EXT_BGREF    I29 @S9S_MB_2U_LIB.S9S_MB_2U(SCH_1):PAGE45
  BL62 H_CPU1_THERMTRIP_LVC1_R_N @S9S_MB_2U_LIB.S9S_MB_2U(SCH_1):H_CPU1_THERMTRIP_LVC1_R_N    I29 @S9S_MB_2U_LIB.S9S_MB_2U(SCH_1):PAGE45
  CV20 PWRGD_PLT_AUX_CPU1_LVT3 @S9S_MB_2U_LIB.S9S_MB_2U(SCH_1):PWRGD_PLT_AUX_CPU1_LVT3     I5 @S9S_MB_2U_LIB.S9S_MB_2U(SCH_1):PAGE46
  CK22 TP_FM_SYS_RST_CPU1_N @S9S_MB_2U_LIB.S9S_MB_2U(SCH_1):TP_FM_SYS_RST_CPU1_N     I5 @S9S_MB_2U_LIB.S9S_MB_2U(SCH_1):PAGE46
  CK24 TP_FM_IBL_PWRBTN_CPU1_N @S9S_MB_2U_LIB.S9S_MB_2U(SCH_1):TP_FM_IBL_PWRBTN_CPU1_N     I5 @S9S_MB_2U_LIB.S9S_MB_2U(SCH_1):PAGE46
  CL23 TP_I2C_S3M_RTC_CPU1_SCL @S9S_MB_2U_LIB.S9S_MB_2U(SCH_1):TP_I2C_S3M_RTC_CPU1_SCL     I5 @S9S_MB_2U_LIB.S9S_MB_2U(SCH_1):PAGE46
  AU62 NC_SPI_CPU1_NCM_CLK @S9S_MB_2U_LIB.S9S_MB_2U(SCH_1):NC_SPI_CPU1_NCM_CLK     I5 @S9S_MB_2U_LIB.S9S_MB_2U(SCH_1):PAGE46
  CL66 TP_CPU1_SSC_SYNC @S9S_MB_2U_LIB.S9S_MB_2U(SCH_1):TP_CPU1_SSC_SYNC     I5 @S9S_MB_2U_LIB.S9S_MB_2U(SCH_1):PAGE46
  CN21 TP_FM_IBL_SLPS4_CPU1_R_N @S9S_MB_2U_LIB.S9S_MB_2U(SCH_1):TP_FM_IBL_SLPS4_CPU1_R_N     I5 @S9S_MB_2U_LIB.S9S_MB_2U(SCH_1):PAGE46
  CN23 NC_FM_IBL_ADR_ACK_CPU1 @S9S_MB_2U_LIB.S9S_MB_2U(SCH_1):NC_FM_IBL_ADR_ACK_CPU1     I5 @S9S_MB_2U_LIB.S9S_MB_2U(SCH_1):PAGE46
  AU64 NC_ESPI_IBL_CPU1_IO2 @S9S_MB_2U_LIB.S9S_MB_2U(SCH_1):NC_ESPI_IBL_CPU1_IO2     I5 @S9S_MB_2U_LIB.S9S_MB_2U(SCH_1):PAGE46
  CP22 TP_JTAG_CPU1_PLD_TDO_R @S9S_MB_2U_LIB.S9S_MB_2U(SCH_1):TP_JTAG_CPU1_PLD_TDO_R     I5 @S9S_MB_2U_LIB.S9S_MB_2U(SCH_1):PAGE46
  CP24 NC_FM_IBL_ADR_COMPLETE_CPU1_R @S9S_MB_2U_LIB.S9S_MB_2U(SCH_1):NC_FM_IBL_ADR_COMPLETE_CPU1_R     I5 @S9S_MB_2U_LIB.S9S_MB_2U(SCH_1):PAGE46
  CR21 TP_FM_IBL_SLPS3_CPU1_R_N @S9S_MB_2U_LIB.S9S_MB_2U(SCH_1):TP_FM_IBL_SLPS3_CPU1_R_N     I5 @S9S_MB_2U_LIB.S9S_MB_2U(SCH_1):PAGE46
  CT22 TP_JTAG_CPU1_PLD_TDI @S9S_MB_2U_LIB.S9S_MB_2U(SCH_1):TP_JTAG_CPU1_PLD_TDI     I5 @S9S_MB_2U_LIB.S9S_MB_2U(SCH_1):PAGE46
  CT24 NC_FM_IBL_ADR_TRIGGER_CPU1_R @S9S_MB_2U_LIB.S9S_MB_2U(SCH_1):NC_FM_IBL_ADR_TRIGGER_CPU1_R     I5 @S9S_MB_2U_LIB.S9S_MB_2U(SCH_1):PAGE46
  CV22 TP_JTAG_CPU1_PLD_TMS @S9S_MB_2U_LIB.S9S_MB_2U(SCH_1):TP_JTAG_CPU1_PLD_TMS     I5 @S9S_MB_2U_LIB.S9S_MB_2U(SCH_1):PAGE46
  CV69 NC_UART_IBL_CPU1_TXD @S9S_MB_2U_LIB.S9S_MB_2U(SCH_1):NC_UART_IBL_CPU1_TXD     I5 @S9S_MB_2U_LIB.S9S_MB_2U(SCH_1):PAGE46
  CV71 NC_UART_IBL_CPU1_CTS @S9S_MB_2U_LIB.S9S_MB_2U(SCH_1):NC_UART_IBL_CPU1_CTS     I5 @S9S_MB_2U_LIB.S9S_MB_2U(SCH_1):PAGE46
  CW21 TP_FM_IBL_SLPS5_CPU1_R_N @S9S_MB_2U_LIB.S9S_MB_2U(SCH_1):TP_FM_IBL_SLPS5_CPU1_R_N     I5 @S9S_MB_2U_LIB.S9S_MB_2U(SCH_1):PAGE46
  CY20 FM_S3M_CPU1_CPLD_CRC_ERROR @S9S_MB_2U_LIB.S9S_MB_2U(SCH_1):FM_S3M_CPU1_CPLD_CRC_ERROR     I5 @S9S_MB_2U_LIB.S9S_MB_2U(SCH_1):PAGE46
  CY22 PD_JTAG_CPU1_PLD_TCK @S9S_MB_2U_LIB.S9S_MB_2U(SCH_1):PD_JTAG_CPU1_PLD_TCK     I5 @S9S_MB_2U_LIB.S9S_MB_2U(SCH_1):PAGE46
  CY69 NC_UART_IBL_CPU1_RXD @S9S_MB_2U_LIB.S9S_MB_2U(SCH_1):NC_UART_IBL_CPU1_RXD     I5 @S9S_MB_2U_LIB.S9S_MB_2U(SCH_1):PAGE46
  CY71 NC_UART_IBL_CPU1_RTS @S9S_MB_2U_LIB.S9S_MB_2U(SCH_1):NC_UART_IBL_CPU1_RTS     I5 @S9S_MB_2U_LIB.S9S_MB_2U(SCH_1):PAGE46
  AV63 NC_SPI_S3M_CPU1_CS1_LVC1_R_N @S9S_MB_2U_LIB.S9S_MB_2U(SCH_1):NC_SPI_S3M_CPU1_CS1_LVC1_R_N     I5 @S9S_MB_2U_LIB.S9S_MB_2U(SCH_1):PAGE46
  AW19 TP_FM_WAKE_CPU1_N @S9S_MB_2U_LIB.S9S_MB_2U(SCH_1):TP_FM_WAKE_CPU1_N     I5 @S9S_MB_2U_LIB.S9S_MB_2U(SCH_1):PAGE46
  AW64 NC_SPI_S3M_CPU1_IO1_LVC1_R @S9S_MB_2U_LIB.S9S_MB_2U(SCH_1):NC_SPI_S3M_CPU1_IO1_LVC1_R     I5 @S9S_MB_2U_LIB.S9S_MB_2U(SCH_1):PAGE46
  AY61 NC_SPI_CPU1_NCM_IO1 @S9S_MB_2U_LIB.S9S_MB_2U(SCH_1):NC_SPI_CPU1_NCM_IO1     I5 @S9S_MB_2U_LIB.S9S_MB_2U(SCH_1):PAGE46
  AY67 NC_SPI_CPU1_NCM_CS0_N @S9S_MB_2U_LIB.S9S_MB_2U(SCH_1):NC_SPI_CPU1_NCM_CS0_N     I5 @S9S_MB_2U_LIB.S9S_MB_2U(SCH_1):PAGE46
  BA62 NC_SPI_S3M_CPU1_IO0_LVC1_R @S9S_MB_2U_LIB.S9S_MB_2U(SCH_1):NC_SPI_S3M_CPU1_IO0_LVC1_R     I5 @S9S_MB_2U_LIB.S9S_MB_2U(SCH_1):PAGE46
  BA66 NC_SPI_CPU1_NCM_IO0 @S9S_MB_2U_LIB.S9S_MB_2U(SCH_1):NC_SPI_CPU1_NCM_IO0     I5 @S9S_MB_2U_LIB.S9S_MB_2U(SCH_1):PAGE46
  BA68 NC_SPI_S3M_CPU1_OE_LVC1_R_N @S9S_MB_2U_LIB.S9S_MB_2U(SCH_1):NC_SPI_S3M_CPU1_OE_LVC1_R_N     I5 @S9S_MB_2U_LIB.S9S_MB_2U(SCH_1):PAGE46
  BB61 NC_SPI_S3M_CPU1_CS0_LVC1_R_N @S9S_MB_2U_LIB.S9S_MB_2U(SCH_1):NC_SPI_S3M_CPU1_CS0_LVC1_R_N     I5 @S9S_MB_2U_LIB.S9S_MB_2U(SCH_1):PAGE46
  BB67 NC_SPI_CPU1_NCM_OE_N @S9S_MB_2U_LIB.S9S_MB_2U(SCH_1):NC_SPI_CPU1_NCM_OE_N     I5 @S9S_MB_2U_LIB.S9S_MB_2U(SCH_1):PAGE46
  BC25 TP_I3C_MNG3_BMC_SW_SDA @S9S_MB_2U_LIB.S9S_MB_2U(SCH_1):TP_I3C_MNG3_BMC_SW_SDA     I5 @S9S_MB_2U_LIB.S9S_MB_2U(SCH_1):PAGE46
  BC64 NC_SPI_S3M_CPU1_CLK_LVC1_R @S9S_MB_2U_LIB.S9S_MB_2U(SCH_1):NC_SPI_S3M_CPU1_CLK_LVC1_R     I5 @S9S_MB_2U_LIB.S9S_MB_2U(SCH_1):PAGE46
  BD61 NC_SPI_S3M_CPU1_IO3_LVC1_R @S9S_MB_2U_LIB.S9S_MB_2U(SCH_1):NC_SPI_S3M_CPU1_IO3_LVC1_R     I5 @S9S_MB_2U_LIB.S9S_MB_2U(SCH_1):PAGE46
  BD63 NC_ESPI_IBL_CPU1_ALERT1_N @S9S_MB_2U_LIB.S9S_MB_2U(SCH_1):NC_ESPI_IBL_CPU1_ALERT1_N     I5 @S9S_MB_2U_LIB.S9S_MB_2U(SCH_1):PAGE46
  BD65 NC_SPI_S3M_CPU1_IO2_LVC1_R @S9S_MB_2U_LIB.S9S_MB_2U(SCH_1):NC_SPI_S3M_CPU1_IO2_LVC1_R     I5 @S9S_MB_2U_LIB.S9S_MB_2U(SCH_1):PAGE46
  BE25 TP_I3C_MNG3_BMC_SW_SCL @S9S_MB_2U_LIB.S9S_MB_2U(SCH_1):TP_I3C_MNG3_BMC_SW_SCL     I5 @S9S_MB_2U_LIB.S9S_MB_2U(SCH_1):PAGE46
  BE62 NC_ESPI_IBL_CPU1_ALERT0_N @S9S_MB_2U_LIB.S9S_MB_2U(SCH_1):NC_ESPI_IBL_CPU1_ALERT0_N     I5 @S9S_MB_2U_LIB.S9S_MB_2U(SCH_1):PAGE46
  BF65 NC_ESPI_IBL_CPU1_CS0_N @S9S_MB_2U_LIB.S9S_MB_2U(SCH_1):NC_ESPI_IBL_CPU1_CS0_N     I5 @S9S_MB_2U_LIB.S9S_MB_2U(SCH_1):PAGE46
  BG62 NC_ESPI_IBL_CPU1_CLK @S9S_MB_2U_LIB.S9S_MB_2U(SCH_1):NC_ESPI_IBL_CPU1_CLK     I5 @S9S_MB_2U_LIB.S9S_MB_2U(SCH_1):PAGE46
  BG64 NC_ESPI_IBL_CPU1_RESET_N @S9S_MB_2U_LIB.S9S_MB_2U(SCH_1):NC_ESPI_IBL_CPU1_RESET_N     I5 @S9S_MB_2U_LIB.S9S_MB_2U(SCH_1):PAGE46
  BH63 NC_ESPI_IBL_CPU1_OE_N @S9S_MB_2U_LIB.S9S_MB_2U(SCH_1):NC_ESPI_IBL_CPU1_OE_N     I5 @S9S_MB_2U_LIB.S9S_MB_2U(SCH_1):PAGE46
  BH65 NC_ESPI_IBL_CPU1_CS1_N @S9S_MB_2U_LIB.S9S_MB_2U(SCH_1):NC_ESPI_IBL_CPU1_CS1_N     I5 @S9S_MB_2U_LIB.S9S_MB_2U(SCH_1):PAGE46
  BJ64 NC_ESPI_IBL_CPU1_IO1 @S9S_MB_2U_LIB.S9S_MB_2U(SCH_1):NC_ESPI_IBL_CPU1_IO1     I5 @S9S_MB_2U_LIB.S9S_MB_2U(SCH_1):PAGE46
  BK63 NC_ESPI_IBL_CPU1_IO0 @S9S_MB_2U_LIB.S9S_MB_2U(SCH_1):NC_ESPI_IBL_CPU1_IO0     I5 @S9S_MB_2U_LIB.S9S_MB_2U(SCH_1):PAGE46
  BM63 NC_ESPI_IBL_CPU1_IO3 @S9S_MB_2U_LIB.S9S_MB_2U(SCH_1):NC_ESPI_IBL_CPU1_IO3     I5 @S9S_MB_2U_LIB.S9S_MB_2U(SCH_1):PAGE46
  CD65 TP_SGPIO_S3M_CPU1_GSXRST_N @S9S_MB_2U_LIB.S9S_MB_2U(SCH_1):TP_SGPIO_S3M_CPU1_GSXRST_N     I5 @S9S_MB_2U_LIB.S9S_MB_2U(SCH_1):PAGE46
  CF61 PUD_PCH_BOOT_MODE_CPU1 @S9S_MB_2U_LIB.S9S_MB_2U(SCH_1):PUD_PCH_BOOT_MODE_CPU1     I5 @S9S_MB_2U_LIB.S9S_MB_2U(SCH_1):PAGE46
  CF63 TP_SGPIO_S3M_CPU1_GSXCLK @S9S_MB_2U_LIB.S9S_MB_2U(SCH_1):TP_SGPIO_S3M_CPU1_GSXCLK     I5 @S9S_MB_2U_LIB.S9S_MB_2U(SCH_1):PAGE46
  CF65 TP_SGPIO_S3M_CPU1_GSXDOUT @S9S_MB_2U_LIB.S9S_MB_2U(SCH_1):TP_SGPIO_S3M_CPU1_GSXDOUT     I5 @S9S_MB_2U_LIB.S9S_MB_2U(SCH_1):PAGE46
  CH63 TP_SGPIO_S3M_CPU1_GSXDIN @S9S_MB_2U_LIB.S9S_MB_2U(SCH_1):TP_SGPIO_S3M_CPU1_GSXDIN     I5 @S9S_MB_2U_LIB.S9S_MB_2U(SCH_1):PAGE46
  CH71 TP_PWRGD_S0_PWROK_CPU1_LVC1 @S9S_MB_2U_LIB.S9S_MB_2U(SCH_1):TP_PWRGD_S0_PWROK_CPU1_LVC1     I5 @S9S_MB_2U_LIB.S9S_MB_2U(SCH_1):PAGE46
  CJ21 TP_CPU1_IBL_GRST_WARN_CPU1_N @S9S_MB_2U_LIB.S9S_MB_2U(SCH_1):TP_CPU1_IBL_GRST_WARN_CPU1_N     I5 @S9S_MB_2U_LIB.S9S_MB_2U(SCH_1):PAGE46
  CJ23 TP_I2C_S3M_RTC_CPU1_SDA @S9S_MB_2U_LIB.S9S_MB_2U(SCH_1):TP_I2C_S3M_RTC_CPU1_SDA     I5 @S9S_MB_2U_LIB.S9S_MB_2U(SCH_1):PAGE46
  CJ25 TP_I2C_S3M_RTC_CPU1_RST_N @S9S_MB_2U_LIB.S9S_MB_2U(SCH_1):TP_I2C_S3M_RTC_CPU1_RST_N     I5 @S9S_MB_2U_LIB.S9S_MB_2U(SCH_1):PAGE46
  CJ66 TP_SGPIO_S3M_CPU1_GSXDLOAD @S9S_MB_2U_LIB.S9S_MB_2U(SCH_1):TP_SGPIO_S3M_CPU1_GSXDLOAD     I5 @S9S_MB_2U_LIB.S9S_MB_2U(SCH_1):PAGE46
  AW70 FM_S3M_CPU1_LVC1_GPIO_4 @S9S_MB_2U_LIB.S9S_MB_2U(SCH_1):FM_S3M_CPU1_LVC1_GPIO_4     I5 @S9S_MB_2U_LIB.S9S_MB_2U(SCH_1):PAGE46
  AY69 FM_S3M_CPU1_LVC1_GPIO_3 @S9S_MB_2U_LIB.S9S_MB_2U(SCH_1):FM_S3M_CPU1_LVC1_GPIO_3     I5 @S9S_MB_2U_LIB.S9S_MB_2U(SCH_1):PAGE46
  AV69 FM_S3M_CPU1_LVC1_GPIO_2 @S9S_MB_2U_LIB.S9S_MB_2U(SCH_1):FM_S3M_CPU1_LVC1_GPIO_2     I5 @S9S_MB_2U_LIB.S9S_MB_2U(SCH_1):PAGE46
  AV71 FM_S3M_CPU1_LVC1_GPIO_1 @S9S_MB_2U_LIB.S9S_MB_2U(SCH_1):FM_S3M_CPU1_LVC1_GPIO_1     I5 @S9S_MB_2U_LIB.S9S_MB_2U(SCH_1):PAGE46
  BA70 FM_S3M_CPU1_LVC1_GPIO_0 @S9S_MB_2U_LIB.S9S_MB_2U(SCH_1):FM_S3M_CPU1_LVC1_GPIO_0     I5 @S9S_MB_2U_LIB.S9S_MB_2U(SCH_1):PAGE46
  CE64 SMB_S3M_CPU1_SCL @S9S_MB_2U_LIB.S9S_MB_2U(SCH_1):SMB_S3M_CPU1_SCL     I5 @S9S_MB_2U_LIB.S9S_MB_2U(SCH_1):PAGE46
  CD63 SMB_S3M_CPU1_SDA @S9S_MB_2U_LIB.S9S_MB_2U(SCH_1):SMB_S3M_CPU1_SDA     I5 @S9S_MB_2U_LIB.S9S_MB_2U(SCH_1):PAGE46
  CJ64 PU_S3M_CPU1_CPLD_CONFD @S9S_MB_2U_LIB.S9S_MB_2U(SCH_1):PU_S3M_CPU1_CPLD_CONFD     I5 @S9S_MB_2U_LIB.S9S_MB_2U(SCH_1):PAGE46
  CK65 FM_S3M_CPU1_CPLD_CONFIG_N @S9S_MB_2U_LIB.S9S_MB_2U(SCH_1):FM_S3M_CPU1_CPLD_CONFIG_N     I5 @S9S_MB_2U_LIB.S9S_MB_2U(SCH_1):PAGE46
  CH65 PU_S3M_CPU1_CPLD_STATUS @S9S_MB_2U_LIB.S9S_MB_2U(SCH_1):PU_S3M_CPU1_CPLD_STATUS     I5 @S9S_MB_2U_LIB.S9S_MB_2U(SCH_1):PAGE46
  BC23 TP_CPU1_IFST_DONE_LVC1_R @S9S_MB_2U_LIB.S9S_MB_2U(SCH_1):TP_CPU1_IFST_DONE_LVC1_R    I16 @S9S_MB_2U_LIB.S9S_MB_2U(SCH_1):PAGE47
  BE23 TP_CPU1_IFST_KOT_LVC1_R @S9S_MB_2U_LIB.S9S_MB_2U(SCH_1):TP_CPU1_IFST_KOT_LVC1_R    I16 @S9S_MB_2U_LIB.S9S_MB_2U(SCH_1):PAGE47
  BF24 TP_CPU1_IFST_TRIG_LVC1_R @S9S_MB_2U_LIB.S9S_MB_2U(SCH_1):TP_CPU1_IFST_TRIG_LVC1_R    I16 @S9S_MB_2U_LIB.S9S_MB_2U(SCH_1):PAGE47
  BL23 DBP_CPU1_MBP0_GTL_R_N @S9S_MB_2U_LIB.S9S_MB_2U(SCH_1):DBP_CPU1_MBP0_GTL_R_N    I16 @S9S_MB_2U_LIB.S9S_MB_2U(SCH_1):PAGE47
  BN25 DBP_CPU1_MBP1_GTL_R_N @S9S_MB_2U_LIB.S9S_MB_2U(SCH_1):DBP_CPU1_MBP1_GTL_R_N    I16 @S9S_MB_2U_LIB.S9S_MB_2U(SCH_1):PAGE47
  BJ23 DBP_CPU1_HOOK8_MBP2_GTL_QS_R_N @S9S_MB_2U_LIB.S9S_MB_2U(SCH_1):DBP_CPU1_HOOK8_MBP2_GTL_QS_R_N    I16 @S9S_MB_2U_LIB.S9S_MB_2U(SCH_1):PAGE47
  BK24 DBP_CPU1_HOOK9_MBP3_GTL_QS_R_N @S9S_MB_2U_LIB.S9S_MB_2U(SCH_1):DBP_CPU1_HOOK9_MBP3_GTL_QS_R_N    I16 @S9S_MB_2U_LIB.S9S_MB_2U(SCH_1):PAGE47
  BD24 H_PMAX_TRIGGER_IO_CPU1 @S9S_MB_2U_LIB.S9S_MB_2U(SCH_1):H_PMAX_TRIGGER_IO_CPU1    I16 @S9S_MB_2U_LIB.S9S_MB_2U(SCH_1):PAGE47
  BH22 H_CPU1_RMCA_LVC1_R_N @S9S_MB_2U_LIB.S9S_MB_2U(SCH_1):H_CPU1_RMCA_LVC1_R_N    I16 @S9S_MB_2U_LIB.S9S_MB_2U(SCH_1):PAGE47
  AU58 NC_CPU1_DDR01_VIEWDIG0 @S9S_MB_2U_LIB.S9S_MB_2U(SCH_1):NC_CPU1_DDR01_VIEWDIG0    I16 @S9S_MB_2U_LIB.S9S_MB_2U(SCH_1):PAGE47
  CE62 NC_CPU1_LGSSPARE3 @S9S_MB_2U_LIB.S9S_MB_2U(SCH_1):NC_CPU1_LGSSPARE3    I16 @S9S_MB_2U_LIB.S9S_MB_2U(SCH_1):PAGE47
  CU62 NC_CPU1_LGSSPARE2 @S9S_MB_2U_LIB.S9S_MB_2U(SCH_1):NC_CPU1_LGSSPARE2    I16 @S9S_MB_2U_LIB.S9S_MB_2U(SCH_1):PAGE47
  CN60 NC_CPU1_LGSSPARE1 @S9S_MB_2U_LIB.S9S_MB_2U(SCH_1):NC_CPU1_LGSSPARE1    I16 @S9S_MB_2U_LIB.S9S_MB_2U(SCH_1):PAGE47
  CP61 NC_CPU1_LGSSPARE5 @S9S_MB_2U_LIB.S9S_MB_2U(SCH_1):NC_CPU1_LGSSPARE5    I16 @S9S_MB_2U_LIB.S9S_MB_2U(SCH_1):PAGE47
  CR60 NC_CPU1_LGSSPARE0 @S9S_MB_2U_LIB.S9S_MB_2U(SCH_1):NC_CPU1_LGSSPARE0    I16 @S9S_MB_2U_LIB.S9S_MB_2U(SCH_1):PAGE47
  CY24 NC_CPU1_DDR45_VIEWDIG0 @S9S_MB_2U_LIB.S9S_MB_2U(SCH_1):NC_CPU1_DDR45_VIEWDIG0    I16 @S9S_MB_2U_LIB.S9S_MB_2U(SCH_1):PAGE47
  CY38 NC_CPU1_DDR45_VIEWDIG1 @S9S_MB_2U_LIB.S9S_MB_2U(SCH_1):NC_CPU1_DDR45_VIEWDIG1    I16 @S9S_MB_2U_LIB.S9S_MB_2U(SCH_1):PAGE47
  CY49 NC_CPU1_DDR67_VIEWDIG1 @S9S_MB_2U_LIB.S9S_MB_2U(SCH_1):NC_CPU1_DDR67_VIEWDIG1    I16 @S9S_MB_2U_LIB.S9S_MB_2U(SCH_1):PAGE47
  DA45 NC_CPU1_DDR67_VIEWDIG0 @S9S_MB_2U_LIB.S9S_MB_2U(SCH_1):NC_CPU1_DDR67_VIEWDIG0    I16 @S9S_MB_2U_LIB.S9S_MB_2U(SCH_1):PAGE47
   H12 TP_CPU1_A0_DEBUG_EN @S9S_MB_2U_LIB.S9S_MB_2U(SCH_1):TP_CPU1_A0_DEBUG_EN    I16 @S9S_MB_2U_LIB.S9S_MB_2U(SCH_1):PAGE47
  AV32 NC_CPU1_DDR23_VIEWDIG0 @S9S_MB_2U_LIB.S9S_MB_2U(SCH_1):NC_CPU1_DDR23_VIEWDIG0    I16 @S9S_MB_2U_LIB.S9S_MB_2U(SCH_1):PAGE47
  AV38 NC_CPU1_THERMADC @S9S_MB_2U_LIB.S9S_MB_2U(SCH_1):NC_CPU1_THERMADC    I16 @S9S_MB_2U_LIB.S9S_MB_2U(SCH_1):PAGE47
  AV40 NC_CPU1_THERMADA @S9S_MB_2U_LIB.S9S_MB_2U(SCH_1):NC_CPU1_THERMADA    I16 @S9S_MB_2U_LIB.S9S_MB_2U(SCH_1):PAGE47
  AU33 NC_CPU1_DDR23_VIEWDIG1 @S9S_MB_2U_LIB.S9S_MB_2U(SCH_1):NC_CPU1_DDR23_VIEWDIG1    I16 @S9S_MB_2U_LIB.S9S_MB_2U(SCH_1):PAGE47
  AU56 NC_CPU1_DDR01_VIEWDIG1 @S9S_MB_2U_LIB.S9S_MB_2U(SCH_1):NC_CPU1_DDR01_VIEWDIG1    I16 @S9S_MB_2U_LIB.S9S_MB_2U(SCH_1):PAGE47
  CC64 NC_CPU1_LGSSPARE4 @S9S_MB_2U_LIB.S9S_MB_2U(SCH_1):NC_CPU1_LGSSPARE4    I16 @S9S_MB_2U_LIB.S9S_MB_2U(SCH_1):PAGE47
  BU11 VSENSE_PVCCD_HV_CPU1_DP @S9S_MB_2U_LIB.S9S_MB_2U(SCH_1):VSENSE_PVCCD_HV_CPU1_DP    I16 @S9S_MB_2U_LIB.S9S_MB_2U(SCH_1):PAGE47
  AY85 VSENSE_PVCCFA_EHV_FIVRA_CPU1_DP @S9S_MB_2U_LIB.S9S_MB_2U(SCH_1):VSENSE_PVCCFA_EHV_FIVRA_CPU1_DP    I16 @S9S_MB_2U_LIB.S9S_MB_2U(SCH_1):PAGE47
  AU11 VSENSE_PVCCFA_EHV_CPU1_DP @S9S_MB_2U_LIB.S9S_MB_2U(SCH_1):VSENSE_PVCCFA_EHV_CPU1_DP    I16 @S9S_MB_2U_LIB.S9S_MB_2U(SCH_1):PAGE47
  CA11 VSENSE_PVCCINFAON_CPU1_DP @S9S_MB_2U_LIB.S9S_MB_2U(SCH_1):VSENSE_PVCCINFAON_CPU1_DP    I16 @S9S_MB_2U_LIB.S9S_MB_2U(SCH_1):PAGE47
  BD87 VSENSE_PVCCIN_CPU1_DP @S9S_MB_2U_LIB.S9S_MB_2U(SCH_1):VSENSE_PVCCIN_CPU1_DP    I16 @S9S_MB_2U_LIB.S9S_MB_2U(SCH_1):PAGE47
  BN11 VSENSE_PVCCD_HV_CPU1_DN @S9S_MB_2U_LIB.S9S_MB_2U(SCH_1):VSENSE_PVCCD_HV_CPU1_DN    I16 @S9S_MB_2U_LIB.S9S_MB_2U(SCH_1):PAGE47
  AT85 VSENSE_PVCCFA_EHV_FIVRA_CPU1_DN @S9S_MB_2U_LIB.S9S_MB_2U(SCH_1):VSENSE_PVCCFA_EHV_FIVRA_CPU1_DN    I16 @S9S_MB_2U_LIB.S9S_MB_2U(SCH_1):PAGE47
  BA11 VSENSE_PVCCFA_EHV_CPU1_DN @S9S_MB_2U_LIB.S9S_MB_2U(SCH_1):VSENSE_PVCCFA_EHV_CPU1_DN    I16 @S9S_MB_2U_LIB.S9S_MB_2U(SCH_1):PAGE47
  CE11 VSENSE_PVCCINFAON_CPU1_DN @S9S_MB_2U_LIB.S9S_MB_2U(SCH_1):VSENSE_PVCCINFAON_CPU1_DN    I16 @S9S_MB_2U_LIB.S9S_MB_2U(SCH_1):PAGE47
  BC90 VSENSE_PVCCIN_CPU1_DN @S9S_MB_2U_LIB.S9S_MB_2U(SCH_1):VSENSE_PVCCIN_CPU1_DN    I16 @S9S_MB_2U_LIB.S9S_MB_2U(SCH_1):PAGE47
  AC78 NC_CPU1_HBM2_VIEWDIG0 @S9S_MB_2U_LIB.S9S_MB_2U(SCH_1):NC_CPU1_HBM2_VIEWDIG0     I1 @S9S_MB_2U_LIB.S9S_MB_2U(SCH_1):PAGE48
  AD77 NC_CPU1_HBM2_VIEWDIG1 @S9S_MB_2U_LIB.S9S_MB_2U(SCH_1):NC_CPU1_HBM2_VIEWDIG1     I1 @S9S_MB_2U_LIB.S9S_MB_2U(SCH_1):PAGE48
  CJ68 NC_CPU1_MDFI_DIE11_NS0 @S9S_MB_2U_LIB.S9S_MB_2U(SCH_1):NC_CPU1_MDFI_DIE11_NS0     I1 @S9S_MB_2U_LIB.S9S_MB_2U(SCH_1):PAGE48
  CJ70 NC_CPU1_MDFI_DIE11_EW0 @S9S_MB_2U_LIB.S9S_MB_2U(SCH_1):NC_CPU1_MDFI_DIE11_EW0     I1 @S9S_MB_2U_LIB.S9S_MB_2U(SCH_1):PAGE48
  CK67 NC_CPU1_MDFI_DIE11_NS1 @S9S_MB_2U_LIB.S9S_MB_2U(SCH_1):NC_CPU1_MDFI_DIE11_NS1     I1 @S9S_MB_2U_LIB.S9S_MB_2U(SCH_1):PAGE48
  CR25 NC_CPU1_VIEWPIN_GNR2 @S9S_MB_2U_LIB.S9S_MB_2U(SCH_1):NC_CPU1_VIEWPIN_GNR2     I1 @S9S_MB_2U_LIB.S9S_MB_2U(SCH_1):PAGE48
  CT26 NC_CPU1_VIEWPIN_GNR0 @S9S_MB_2U_LIB.S9S_MB_2U(SCH_1):NC_CPU1_VIEWPIN_GNR0     I1 @S9S_MB_2U_LIB.S9S_MB_2U(SCH_1):PAGE48
  CW41 NC_CPU1_HBM1_VIEWDIG1 @S9S_MB_2U_LIB.S9S_MB_2U(SCH_1):NC_CPU1_HBM1_VIEWDIG1     I1 @S9S_MB_2U_LIB.S9S_MB_2U(SCH_1):PAGE48
  CW58 NC_CPU1_VIEWPIN_GNR1 @S9S_MB_2U_LIB.S9S_MB_2U(SCH_1):NC_CPU1_VIEWPIN_GNR1     I1 @S9S_MB_2U_LIB.S9S_MB_2U(SCH_1):PAGE48
  CY57 NC_CPU1_VIEWPIN_GNR3 @S9S_MB_2U_LIB.S9S_MB_2U(SCH_1):NC_CPU1_VIEWPIN_GNR3     I1 @S9S_MB_2U_LIB.S9S_MB_2U(SCH_1):PAGE48
  EG17 NC_CPU1_HBM0_VIEWDIG1 @S9S_MB_2U_LIB.S9S_MB_2U(SCH_1):NC_CPU1_HBM0_VIEWDIG1     I1 @S9S_MB_2U_LIB.S9S_MB_2U(SCH_1):PAGE48
   U17 NC_CPU1_HBM0_VIEWDIG0 @S9S_MB_2U_LIB.S9S_MB_2U(SCH_1):NC_CPU1_HBM0_VIEWDIG0     I1 @S9S_MB_2U_LIB.S9S_MB_2U(SCH_1):PAGE48
   W17 NC_CPU1_HBM1_VIEWDIG0 @S9S_MB_2U_LIB.S9S_MB_2U(SCH_1):NC_CPU1_HBM1_VIEWDIG0     I1 @S9S_MB_2U_LIB.S9S_MB_2U(SCH_1):PAGE48
  AV65 NC_CPU1_MDFI_DIE01_EW0 @S9S_MB_2U_LIB.S9S_MB_2U(SCH_1):NC_CPU1_MDFI_DIE01_EW0     I1 @S9S_MB_2U_LIB.S9S_MB_2U(SCH_1):PAGE48
  AY24 NC_CPU1_SOC_SPARE0 @S9S_MB_2U_LIB.S9S_MB_2U(SCH_1):NC_CPU1_SOC_SPARE0     I1 @S9S_MB_2U_LIB.S9S_MB_2U(SCH_1):PAGE48
  BA25 NC_CPU1_SOC_SPARE4 @S9S_MB_2U_LIB.S9S_MB_2U(SCH_1):NC_CPU1_SOC_SPARE4     I1 @S9S_MB_2U_LIB.S9S_MB_2U(SCH_1):PAGE48
  BD71 NC_CPU1_MDFI_DIE01_NS1 @S9S_MB_2U_LIB.S9S_MB_2U(SCH_1):NC_CPU1_MDFI_DIE01_NS1     I1 @S9S_MB_2U_LIB.S9S_MB_2U(SCH_1):PAGE48
  BE21 TP_CPU1_DIE_HVM_EN_LVC1 @S9S_MB_2U_LIB.S9S_MB_2U(SCH_1):TP_CPU1_DIE_HVM_EN_LVC1     I1 @S9S_MB_2U_LIB.S9S_MB_2U(SCH_1):PAGE48
  BF71 NC_CPU1_MDFI_DIE01_NS0 @S9S_MB_2U_LIB.S9S_MB_2U(SCH_1):NC_CPU1_MDFI_DIE01_NS0     I1 @S9S_MB_2U_LIB.S9S_MB_2U(SCH_1):PAGE48
  BG78 NC_CPU1_HBM3_VIEWDIG0 @S9S_MB_2U_LIB.S9S_MB_2U(SCH_1):NC_CPU1_HBM3_VIEWDIG0     I1 @S9S_MB_2U_LIB.S9S_MB_2U(SCH_1):PAGE48
  BJ21 NC_CPU1_MDFI_DIE00_NS1 @S9S_MB_2U_LIB.S9S_MB_2U(SCH_1):NC_CPU1_MDFI_DIE00_NS1     I1 @S9S_MB_2U_LIB.S9S_MB_2U(SCH_1):PAGE48
  BK22 NC_CPU1_MDFI_DIE00_NS0 @S9S_MB_2U_LIB.S9S_MB_2U(SCH_1):NC_CPU1_MDFI_DIE00_NS0     I1 @S9S_MB_2U_LIB.S9S_MB_2U(SCH_1):PAGE48
  BL60 NC_CPU1_HBM3_VIEWDIG1 @S9S_MB_2U_LIB.S9S_MB_2U(SCH_1):NC_CPU1_HBM3_VIEWDIG1     I1 @S9S_MB_2U_LIB.S9S_MB_2U(SCH_1):PAGE48
  BM65 NC_CPU1_SOC_SPARE1 @S9S_MB_2U_LIB.S9S_MB_2U(SCH_1):NC_CPU1_SOC_SPARE1     I1 @S9S_MB_2U_LIB.S9S_MB_2U(SCH_1):PAGE48
  BP22 NC_CPU1_MDFI_DIE00_EW0 @S9S_MB_2U_LIB.S9S_MB_2U(SCH_1):NC_CPU1_MDFI_DIE00_EW0     I1 @S9S_MB_2U_LIB.S9S_MB_2U(SCH_1):PAGE48
  BP65 NC_CPU1_SOC_SPARE5 @S9S_MB_2U_LIB.S9S_MB_2U(SCH_1):NC_CPU1_SOC_SPARE5     I1 @S9S_MB_2U_LIB.S9S_MB_2U(SCH_1):PAGE48
  BR21 NC_CPU1_MDFI_DIE00_EW1 @S9S_MB_2U_LIB.S9S_MB_2U(SCH_1):NC_CPU1_MDFI_DIE00_EW1     I1 @S9S_MB_2U_LIB.S9S_MB_2U(SCH_1):PAGE48
  CC66 NC_CPU1_MDFI_DIE01_EW1 @S9S_MB_2U_LIB.S9S_MB_2U(SCH_1):NC_CPU1_MDFI_DIE01_EW1     I1 @S9S_MB_2U_LIB.S9S_MB_2U(SCH_1):PAGE48
  CD22 NC_CPU1_MDFI_DIE10_NS1 @S9S_MB_2U_LIB.S9S_MB_2U(SCH_1):NC_CPU1_MDFI_DIE10_NS1     I1 @S9S_MB_2U_LIB.S9S_MB_2U(SCH_1):PAGE48
  CD26 NC_CPU1_MDFI_DIE10_EW0 @S9S_MB_2U_LIB.S9S_MB_2U(SCH_1):NC_CPU1_MDFI_DIE10_EW0     I1 @S9S_MB_2U_LIB.S9S_MB_2U(SCH_1):PAGE48
  CD30 NC_CPU1_MDFI_DIE10_EW1 @S9S_MB_2U_LIB.S9S_MB_2U(SCH_1):NC_CPU1_MDFI_DIE10_EW1     I1 @S9S_MB_2U_LIB.S9S_MB_2U(SCH_1):PAGE48
  CF22 NC_CPU1_MDFI_DIE10_NS0 @S9S_MB_2U_LIB.S9S_MB_2U(SCH_1):NC_CPU1_MDFI_DIE10_NS0     I1 @S9S_MB_2U_LIB.S9S_MB_2U(SCH_1):PAGE48
  CH69 NC_CPU1_MDFI_DIE11_EW1 @S9S_MB_2U_LIB.S9S_MB_2U(SCH_1):NC_CPU1_MDFI_DIE11_EW1     I1 @S9S_MB_2U_LIB.S9S_MB_2U(SCH_1):PAGE48
  CL70 TP_CPU1_SPARE12 @S9S_MB_2U_LIB.S9S_MB_2U(SCH_1):TP_CPU1_SPARE12     I2 @S9S_MB_2U_LIB.S9S_MB_2U(SCH_1):PAGE49
  CL60 TP_CPU1_SPARE7 @S9S_MB_2U_LIB.S9S_MB_2U(SCH_1):TP_CPU1_SPARE7     I2 @S9S_MB_2U_LIB.S9S_MB_2U(SCH_1):PAGE49
  CW43 TP_CPU1_SPARE6 @S9S_MB_2U_LIB.S9S_MB_2U(SCH_1):TP_CPU1_SPARE6     I2 @S9S_MB_2U_LIB.S9S_MB_2U(SCH_1):PAGE49
  DA70 TP_CPU1_SPARE4 @S9S_MB_2U_LIB.S9S_MB_2U(SCH_1):TP_CPU1_SPARE4     I2 @S9S_MB_2U_LIB.S9S_MB_2U(SCH_1):PAGE49
  BD77 TP_CPU1_SPARE13 @S9S_MB_2U_LIB.S9S_MB_2U(SCH_1):TP_CPU1_SPARE13     I2 @S9S_MB_2U_LIB.S9S_MB_2U(SCH_1):PAGE49
  CH61 TP_CPU1_SPARE9 @S9S_MB_2U_LIB.S9S_MB_2U(SCH_1):TP_CPU1_SPARE9     I2 @S9S_MB_2U_LIB.S9S_MB_2U(SCH_1):PAGE49
  AU52 TP_CPU1_SPARE5 @S9S_MB_2U_LIB.S9S_MB_2U(SCH_1):TP_CPU1_SPARE5     I2 @S9S_MB_2U_LIB.S9S_MB_2U(SCH_1):PAGE49
  CD69 TP_CPU1_SPARE11 @S9S_MB_2U_LIB.S9S_MB_2U(SCH_1):TP_CPU1_SPARE11     I2 @S9S_MB_2U_LIB.S9S_MB_2U(SCH_1):PAGE49
  CK61 TP_CPU1_SPARE8 @S9S_MB_2U_LIB.S9S_MB_2U(SCH_1):TP_CPU1_SPARE8     I2 @S9S_MB_2U_LIB.S9S_MB_2U(SCH_1):PAGE49
  CG60 TP_CPU1_SPARE10 @S9S_MB_2U_LIB.S9S_MB_2U(SCH_1):TP_CPU1_SPARE10     I2 @S9S_MB_2U_LIB.S9S_MB_2U(SCH_1):PAGE49
   J13 TP_CPU1_PPD @S9S_MB_2U_LIB.S9S_MB_2U(SCH_1):TP_CPU1_PPD     I2 @S9S_MB_2U_LIB.S9S_MB_2U(SCH_1):PAGE49
  BP30 TP_TRC_CPU1_PTI<15> @S9S_MB_2U_LIB.S9S_MB_2U(SCH_1):TP_TRC_CPU1_PTI(15)    I23 @S9S_MB_2U_LIB.S9S_MB_2U(SCH_1):PAGE50
  BN29 TP_TRC_CPU1_PTI<14> @S9S_MB_2U_LIB.S9S_MB_2U(SCH_1):TP_TRC_CPU1_PTI(14)    I23 @S9S_MB_2U_LIB.S9S_MB_2U(SCH_1):PAGE50
  BP28 TP_TRC_CPU1_PTI<13> @S9S_MB_2U_LIB.S9S_MB_2U(SCH_1):TP_TRC_CPU1_PTI(13)    I23 @S9S_MB_2U_LIB.S9S_MB_2U(SCH_1):PAGE50
  BN27 TP_TRC_CPU1_PTI<12> @S9S_MB_2U_LIB.S9S_MB_2U(SCH_1):TP_TRC_CPU1_PTI(12)    I23 @S9S_MB_2U_LIB.S9S_MB_2U(SCH_1):PAGE50
  BT30 TP_TRC_CPU1_PTI<11> @S9S_MB_2U_LIB.S9S_MB_2U(SCH_1):TP_TRC_CPU1_PTI(11)    I23 @S9S_MB_2U_LIB.S9S_MB_2U(SCH_1):PAGE50
  BU29 TP_TRC_CPU1_PTI<10> @S9S_MB_2U_LIB.S9S_MB_2U(SCH_1):TP_TRC_CPU1_PTI(10)    I23 @S9S_MB_2U_LIB.S9S_MB_2U(SCH_1):PAGE50
  BT28 TP_TRC_CPU1_PTI<9> @S9S_MB_2U_LIB.S9S_MB_2U(SCH_1):TP_TRC_CPU1_PTI(9)    I23 @S9S_MB_2U_LIB.S9S_MB_2U(SCH_1):PAGE50
  BU27 TP_TRC_CPU1_PTI<8> @S9S_MB_2U_LIB.S9S_MB_2U(SCH_1):TP_TRC_CPU1_PTI(8)    I23 @S9S_MB_2U_LIB.S9S_MB_2U(SCH_1):PAGE50
  BV28 TP_TRC_CPU1_PTI<7> @S9S_MB_2U_LIB.S9S_MB_2U(SCH_1):TP_TRC_CPU1_PTI(7)    I23 @S9S_MB_2U_LIB.S9S_MB_2U(SCH_1):PAGE50
  CA27 TP_TRC_CPU1_PTI<6> @S9S_MB_2U_LIB.S9S_MB_2U(SCH_1):TP_TRC_CPU1_PTI(6)    I23 @S9S_MB_2U_LIB.S9S_MB_2U(SCH_1):PAGE50
  BV30 TP_TRC_CPU1_PTI<5> @S9S_MB_2U_LIB.S9S_MB_2U(SCH_1):TP_TRC_CPU1_PTI(5)    I23 @S9S_MB_2U_LIB.S9S_MB_2U(SCH_1):PAGE50
  CA29 TP_TRC_CPU1_PTI<4> @S9S_MB_2U_LIB.S9S_MB_2U(SCH_1):TP_TRC_CPU1_PTI(4)    I23 @S9S_MB_2U_LIB.S9S_MB_2U(SCH_1):PAGE50
  BY30 TP_TRC_CPU1_PTI<3> @S9S_MB_2U_LIB.S9S_MB_2U(SCH_1):TP_TRC_CPU1_PTI(3)    I23 @S9S_MB_2U_LIB.S9S_MB_2U(SCH_1):PAGE50
  CC27 TP_TRC_CPU1_PTI<2> @S9S_MB_2U_LIB.S9S_MB_2U(SCH_1):TP_TRC_CPU1_PTI(2)    I23 @S9S_MB_2U_LIB.S9S_MB_2U(SCH_1):PAGE50
  CD28 TP_TRC_CPU1_PTI<1> @S9S_MB_2U_LIB.S9S_MB_2U(SCH_1):TP_TRC_CPU1_PTI(1)    I23 @S9S_MB_2U_LIB.S9S_MB_2U(SCH_1):PAGE50
  CC29 TP_TRC_CPU1_PTI<0> @S9S_MB_2U_LIB.S9S_MB_2U(SCH_1):TP_TRC_CPU1_PTI(0)    I23 @S9S_MB_2U_LIB.S9S_MB_2U(SCH_1):PAGE50
  CB30 TP_TRC_CPU1_PTI0_CLK @S9S_MB_2U_LIB.S9S_MB_2U(SCH_1):TP_TRC_CPU1_PTI0_CLK    I23 @S9S_MB_2U_LIB.S9S_MB_2U(SCH_1):PAGE50
  BY28 TP_TRC_CPU1_PTI1_CLK @S9S_MB_2U_LIB.S9S_MB_2U(SCH_1):TP_TRC_CPU1_PTI1_CLK    I23 @S9S_MB_2U_LIB.S9S_MB_2U(SCH_1):PAGE50
  BN66 TP_TRC_CPU1_PTI<31> @S9S_MB_2U_LIB.S9S_MB_2U(SCH_1):TP_TRC_CPU1_PTI(31)    I23 @S9S_MB_2U_LIB.S9S_MB_2U(SCH_1):PAGE50
  BM67 TP_TRC_CPU1_PTI<30> @S9S_MB_2U_LIB.S9S_MB_2U(SCH_1):TP_TRC_CPU1_PTI(30)    I23 @S9S_MB_2U_LIB.S9S_MB_2U(SCH_1):PAGE50
  BL66 TP_TRC_CPU1_PTI<29> @S9S_MB_2U_LIB.S9S_MB_2U(SCH_1):TP_TRC_CPU1_PTI(29)    I23 @S9S_MB_2U_LIB.S9S_MB_2U(SCH_1):PAGE50
  BJ66 TP_TRC_CPU1_PTI<28> @S9S_MB_2U_LIB.S9S_MB_2U(SCH_1):TP_TRC_CPU1_PTI(28)    I23 @S9S_MB_2U_LIB.S9S_MB_2U(SCH_1):PAGE50
  BG66 TP_TRC_CPU1_PTI<27> @S9S_MB_2U_LIB.S9S_MB_2U(SCH_1):TP_TRC_CPU1_PTI(27)    I23 @S9S_MB_2U_LIB.S9S_MB_2U(SCH_1):PAGE50
  BN68 TP_TRC_CPU1_PTI<26> @S9S_MB_2U_LIB.S9S_MB_2U(SCH_1):TP_TRC_CPU1_PTI(26)    I23 @S9S_MB_2U_LIB.S9S_MB_2U(SCH_1):PAGE50
  BM69 TP_TRC_CPU1_PTI<25> @S9S_MB_2U_LIB.S9S_MB_2U(SCH_1):TP_TRC_CPU1_PTI(25)    I23 @S9S_MB_2U_LIB.S9S_MB_2U(SCH_1):PAGE50
  BK69 TP_TRC_CPU1_PTI<24> @S9S_MB_2U_LIB.S9S_MB_2U(SCH_1):TP_TRC_CPU1_PTI(24)    I23 @S9S_MB_2U_LIB.S9S_MB_2U(SCH_1):PAGE50
  BD67 TP_TRC_CPU1_PTI<23> @S9S_MB_2U_LIB.S9S_MB_2U(SCH_1):TP_TRC_CPU1_PTI(23)    I23 @S9S_MB_2U_LIB.S9S_MB_2U(SCH_1):PAGE50
  BG68 TP_TRC_CPU1_PTI<22> @S9S_MB_2U_LIB.S9S_MB_2U(SCH_1):TP_TRC_CPU1_PTI(22)    I23 @S9S_MB_2U_LIB.S9S_MB_2U(SCH_1):PAGE50
  BC68 TP_TRC_CPU1_PTI<21> @S9S_MB_2U_LIB.S9S_MB_2U(SCH_1):TP_TRC_CPU1_PTI(21)    I23 @S9S_MB_2U_LIB.S9S_MB_2U(SCH_1):PAGE50
  BH69 TP_TRC_CPU1_PTI<20> @S9S_MB_2U_LIB.S9S_MB_2U(SCH_1):TP_TRC_CPU1_PTI(20)    I23 @S9S_MB_2U_LIB.S9S_MB_2U(SCH_1):PAGE50
  BF69 TP_TRC_CPU1_PTI<19> @S9S_MB_2U_LIB.S9S_MB_2U(SCH_1):TP_TRC_CPU1_PTI(19)    I23 @S9S_MB_2U_LIB.S9S_MB_2U(SCH_1):PAGE50
  BD69 TP_TRC_CPU1_PTI<18> @S9S_MB_2U_LIB.S9S_MB_2U(SCH_1):TP_TRC_CPU1_PTI(18)    I23 @S9S_MB_2U_LIB.S9S_MB_2U(SCH_1):PAGE50
  BE70 TP_TRC_CPU1_PTI<17> @S9S_MB_2U_LIB.S9S_MB_2U(SCH_1):TP_TRC_CPU1_PTI(17)    I23 @S9S_MB_2U_LIB.S9S_MB_2U(SCH_1):PAGE50
  BC70 TP_TRC_CPU1_PTI<16> @S9S_MB_2U_LIB.S9S_MB_2U(SCH_1):TP_TRC_CPU1_PTI(16)    I23 @S9S_MB_2U_LIB.S9S_MB_2U(SCH_1):PAGE50
  BF67 TP_TRC_CPU1_PTI2_CLK @S9S_MB_2U_LIB.S9S_MB_2U(SCH_1):TP_TRC_CPU1_PTI2_CLK    I23 @S9S_MB_2U_LIB.S9S_MB_2U(SCH_1):PAGE50
  BK67 TP_TRC_CPU1_PTI3_CLK @S9S_MB_2U_LIB.S9S_MB_2U(SCH_1):TP_TRC_CPU1_PTI3_CLK    I23 @S9S_MB_2U_LIB.S9S_MB_2U(SCH_1):PAGE50
  CL68 NC_CPU1_PE3_APROBE<0> @S9S_MB_2U_LIB.S9S_MB_2U(SCH_1):NC_CPU1_PE3_APROBE(0)    I23 @S9S_MB_2U_LIB.S9S_MB_2U(SCH_1):PAGE50
  CM69 NC_CPU1_PE3_APROBE<1> @S9S_MB_2U_LIB.S9S_MB_2U(SCH_1):NC_CPU1_PE3_APROBE(1)    I23 @S9S_MB_2U_LIB.S9S_MB_2U(SCH_1):PAGE50
  CP69 NC_CPU1_UPI3_APROBE<0> @S9S_MB_2U_LIB.S9S_MB_2U(SCH_1):NC_CPU1_UPI3_APROBE(0)    I23 @S9S_MB_2U_LIB.S9S_MB_2U(SCH_1):PAGE50
  CR68 NC_CPU1_UPI3_APROBE<1> @S9S_MB_2U_LIB.S9S_MB_2U(SCH_1):NC_CPU1_UPI3_APROBE(1)    I23 @S9S_MB_2U_LIB.S9S_MB_2U(SCH_1):PAGE50
  AU66 NC_CPU1_PE4_APROBE<1> @S9S_MB_2U_LIB.S9S_MB_2U(SCH_1):NC_CPU1_PE4_APROBE(1)    I23 @S9S_MB_2U_LIB.S9S_MB_2U(SCH_1):PAGE50
  AU68 NC_CPU1_UPI2_APROBE<0> @S9S_MB_2U_LIB.S9S_MB_2U(SCH_1):NC_CPU1_UPI2_APROBE(0)    I23 @S9S_MB_2U_LIB.S9S_MB_2U(SCH_1):PAGE50
  AN17 NC_CPU1_UPI0_APROBE<0> @S9S_MB_2U_LIB.S9S_MB_2U(SCH_1):NC_CPU1_UPI0_APROBE(0)    I23 @S9S_MB_2U_LIB.S9S_MB_2U(SCH_1):PAGE50
  AV67 NC_CPU1_PE4_APROBE<0> @S9S_MB_2U_LIB.S9S_MB_2U(SCH_1):NC_CPU1_PE4_APROBE(0)    I23 @S9S_MB_2U_LIB.S9S_MB_2U(SCH_1):PAGE50
  AR17 NC_CPU1_UPI0_APROBE<1> @S9S_MB_2U_LIB.S9S_MB_2U(SCH_1):NC_CPU1_UPI0_APROBE(1)    I23 @S9S_MB_2U_LIB.S9S_MB_2U(SCH_1):PAGE50
  AT67 NC_CPU1_UPI2_APROBE<1> @S9S_MB_2U_LIB.S9S_MB_2U(SCH_1):NC_CPU1_UPI2_APROBE(1)    I23 @S9S_MB_2U_LIB.S9S_MB_2U(SCH_1):PAGE50
  BL21 NC_CPU1_PE0_APROBE<1> @S9S_MB_2U_LIB.S9S_MB_2U(SCH_1):NC_CPU1_PE0_APROBE(1)    I23 @S9S_MB_2U_LIB.S9S_MB_2U(SCH_1):PAGE50
  BN21 NC_CPU1_PE0_APROBE<0> @S9S_MB_2U_LIB.S9S_MB_2U(SCH_1):NC_CPU1_PE0_APROBE(0)    I23 @S9S_MB_2U_LIB.S9S_MB_2U(SCH_1):PAGE50
  BV22 NC_CPU1_UPI1_APROBE<0> @S9S_MB_2U_LIB.S9S_MB_2U(SCH_1):NC_CPU1_UPI1_APROBE(0)    I23 @S9S_MB_2U_LIB.S9S_MB_2U(SCH_1):PAGE50
  BW21 NC_CPU1_DMI_APROBE<1> @S9S_MB_2U_LIB.S9S_MB_2U(SCH_1):NC_CPU1_DMI_APROBE(1)    I23 @S9S_MB_2U_LIB.S9S_MB_2U(SCH_1):PAGE50
  BW23 NC_CPU1_PE2_APROBE<1> @S9S_MB_2U_LIB.S9S_MB_2U(SCH_1):NC_CPU1_PE2_APROBE(1)    I23 @S9S_MB_2U_LIB.S9S_MB_2U(SCH_1):PAGE50
  CA21 NC_CPU1_DMI_APROBE<0> @S9S_MB_2U_LIB.S9S_MB_2U(SCH_1):NC_CPU1_DMI_APROBE(0)    I23 @S9S_MB_2U_LIB.S9S_MB_2U(SCH_1):PAGE50
  CA23 NC_CPU1_UPI1_APROBE<1> @S9S_MB_2U_LIB.S9S_MB_2U(SCH_1):NC_CPU1_UPI1_APROBE(1)    I23 @S9S_MB_2U_LIB.S9S_MB_2U(SCH_1):PAGE50
  CC21 NC_CPU1_PE1_APROBE<1> @S9S_MB_2U_LIB.S9S_MB_2U(SCH_1):NC_CPU1_PE1_APROBE(1)    I23 @S9S_MB_2U_LIB.S9S_MB_2U(SCH_1):PAGE50
  CC23 NC_CPU1_PE2_APROBE<0> @S9S_MB_2U_LIB.S9S_MB_2U(SCH_1):NC_CPU1_PE2_APROBE(0)    I23 @S9S_MB_2U_LIB.S9S_MB_2U(SCH_1):PAGE50
  CE21 NC_CPU1_PE1_APROBE<0> @S9S_MB_2U_LIB.S9S_MB_2U(SCH_1):NC_CPU1_PE1_APROBE(0)    I23 @S9S_MB_2U_LIB.S9S_MB_2U(SCH_1):PAGE50
  BA23 PU_CPU1_UPI0_AC_COUPLING @S9S_MB_2U_LIB.S9S_MB_2U(SCH_1):PU_CPU1_UPI0_AC_COUPLING    I23 @S9S_MB_2U_LIB.S9S_MB_2U(SCH_1):PAGE50
  CW19 PU_CPU1_UPI1_AC_COUPLING @S9S_MB_2U_LIB.S9S_MB_2U(SCH_1):PU_CPU1_UPI1_AC_COUPLING    I23 @S9S_MB_2U_LIB.S9S_MB_2U(SCH_1):PAGE50
  BB65 PU_CPU1_UPI2_AC_COUPLING @S9S_MB_2U_LIB.S9S_MB_2U(SCH_1):PU_CPU1_UPI2_AC_COUPLING    I23 @S9S_MB_2U_LIB.S9S_MB_2U(SCH_1):PAGE50
  CK71 PU_CPU1_UPI3_AC_COUPLING @S9S_MB_2U_LIB.S9S_MB_2U(SCH_1):PU_CPU1_UPI3_AC_COUPLING    I23 @S9S_MB_2U_LIB.S9S_MB_2U(SCH_1):PAGE50
  AT49 M_A_CPU1_ALERT_N @S9S_MB_2U_LIB.S9S_MB_2U(SCH_1):M_A_CPU1_ALERT_N     I2 @S9S_MB_2U_LIB.S9S_MB_2U(SCH_1):PAGE51
  AU43 M_A_CPU1_SA_RSP<1> @S9S_MB_2U_LIB.S9S_MB_2U(SCH_1):M_A_CPU1_SA_RSP(1)     I2 @S9S_MB_2U_LIB.S9S_MB_2U(SCH_1):PAGE51
  AT42 M_A_CPU1_SA_RSP<0> @S9S_MB_2U_LIB.S9S_MB_2U(SCH_1):M_A_CPU1_SA_RSP(0)     I2 @S9S_MB_2U_LIB.S9S_MB_2U(SCH_1):PAGE51
  AV42 M_A_CPU1_SB_RSP<1> @S9S_MB_2U_LIB.S9S_MB_2U(SCH_1):M_A_CPU1_SB_RSP(1)     I2 @S9S_MB_2U_LIB.S9S_MB_2U(SCH_1):PAGE51
  AV44 M_A_CPU1_SB_RSP<0> @S9S_MB_2U_LIB.S9S_MB_2U(SCH_1):M_A_CPU1_SB_RSP(0)     I2 @S9S_MB_2U_LIB.S9S_MB_2U(SCH_1):PAGE51
   G45 M_A_CPU1_CLK_DN<1> @S9S_MB_2U_LIB.S9S_MB_2U(SCH_1):M_A_CPU1_CLK_DN(1)     I2 @S9S_MB_2U_LIB.S9S_MB_2U(SCH_1):PAGE51
   B44 M_A_CPU1_CLK_DN<0> @S9S_MB_2U_LIB.S9S_MB_2U(SCH_1):M_A_CPU1_CLK_DN(0)     I2 @S9S_MB_2U_LIB.S9S_MB_2U(SCH_1):PAGE51
   E45 M_A_CPU1_CLK_DP<1> @S9S_MB_2U_LIB.S9S_MB_2U(SCH_1):M_A_CPU1_CLK_DP(1)     I2 @S9S_MB_2U_LIB.S9S_MB_2U(SCH_1):PAGE51
   C43 M_A_CPU1_CLK_DP<0> @S9S_MB_2U_LIB.S9S_MB_2U(SCH_1):M_A_CPU1_CLK_DP(0)     I2 @S9S_MB_2U_LIB.S9S_MB_2U(SCH_1):PAGE51
   C48 M_A_CPU1_SA_CA<6> @S9S_MB_2U_LIB.S9S_MB_2U(SCH_1):M_A_CPU1_SA_CA(6)     I2 @S9S_MB_2U_LIB.S9S_MB_2U(SCH_1):PAGE51
   E50 M_A_CPU1_SA_CA<5> @S9S_MB_2U_LIB.S9S_MB_2U(SCH_1):M_A_CPU1_SA_CA(5)     I2 @S9S_MB_2U_LIB.S9S_MB_2U(SCH_1):PAGE51
   C50 M_A_CPU1_SA_CA<4> @S9S_MB_2U_LIB.S9S_MB_2U(SCH_1):M_A_CPU1_SA_CA(4)     I2 @S9S_MB_2U_LIB.S9S_MB_2U(SCH_1):PAGE51
   F51 M_A_CPU1_SA_CA<3> @S9S_MB_2U_LIB.S9S_MB_2U(SCH_1):M_A_CPU1_SA_CA(3)     I2 @S9S_MB_2U_LIB.S9S_MB_2U(SCH_1):PAGE51
   B51 M_A_CPU1_SA_CA<2> @S9S_MB_2U_LIB.S9S_MB_2U(SCH_1):M_A_CPU1_SA_CA(2)     I2 @S9S_MB_2U_LIB.S9S_MB_2U(SCH_1):PAGE51
   G52 M_A_CPU1_SA_CA<1> @S9S_MB_2U_LIB.S9S_MB_2U(SCH_1):M_A_CPU1_SA_CA(1)     I2 @S9S_MB_2U_LIB.S9S_MB_2U(SCH_1):PAGE51
   A52 M_A_CPU1_SA_CA<0> @S9S_MB_2U_LIB.S9S_MB_2U(SCH_1):M_A_CPU1_SA_CA(0)     I2 @S9S_MB_2U_LIB.S9S_MB_2U(SCH_1):PAGE51
   F53 M_A_CPU1_SA_CS_N<3> @S9S_MB_2U_LIB.S9S_MB_2U(SCH_1):M_A_CPU1_SA_CS_N(3)     I2 @S9S_MB_2U_LIB.S9S_MB_2U(SCH_1):PAGE51
   E54 M_A_CPU1_SA_CS_N<2> @S9S_MB_2U_LIB.S9S_MB_2U(SCH_1):M_A_CPU1_SA_CS_N(2)     I2 @S9S_MB_2U_LIB.S9S_MB_2U(SCH_1):PAGE51
   B53 M_A_CPU1_SA_CS_N<1> @S9S_MB_2U_LIB.S9S_MB_2U(SCH_1):M_A_CPU1_SA_CS_N(1)     I2 @S9S_MB_2U_LIB.S9S_MB_2U(SCH_1):PAGE51
   C54 M_A_CPU1_SA_CS_N<0> @S9S_MB_2U_LIB.S9S_MB_2U(SCH_1):M_A_CPU1_SA_CS_N(0)     I2 @S9S_MB_2U_LIB.S9S_MB_2U(SCH_1):PAGE51
   E62 M_A_CPU1_SA_DQ<31> @S9S_MB_2U_LIB.S9S_MB_2U(SCH_1):M_A_CPU1_SA_DQ(31)     I2 @S9S_MB_2U_LIB.S9S_MB_2U(SCH_1):PAGE51
   F63 M_A_CPU1_SA_DQ<30> @S9S_MB_2U_LIB.S9S_MB_2U(SCH_1):M_A_CPU1_SA_DQ(30)     I2 @S9S_MB_2U_LIB.S9S_MB_2U(SCH_1):PAGE51
   C62 M_A_CPU1_SA_DQ<29> @S9S_MB_2U_LIB.S9S_MB_2U(SCH_1):M_A_CPU1_SA_DQ(29)     I2 @S9S_MB_2U_LIB.S9S_MB_2U(SCH_1):PAGE51
   B63 M_A_CPU1_SA_DQ<28> @S9S_MB_2U_LIB.S9S_MB_2U(SCH_1):M_A_CPU1_SA_DQ(28)     I2 @S9S_MB_2U_LIB.S9S_MB_2U(SCH_1):PAGE51
   F65 M_A_CPU1_SA_DQ<27> @S9S_MB_2U_LIB.S9S_MB_2U(SCH_1):M_A_CPU1_SA_DQ(27)     I2 @S9S_MB_2U_LIB.S9S_MB_2U(SCH_1):PAGE51
   E66 M_A_CPU1_SA_DQ<26> @S9S_MB_2U_LIB.S9S_MB_2U(SCH_1):M_A_CPU1_SA_DQ(26)     I2 @S9S_MB_2U_LIB.S9S_MB_2U(SCH_1):PAGE51
   B65 M_A_CPU1_SA_DQ<25> @S9S_MB_2U_LIB.S9S_MB_2U(SCH_1):M_A_CPU1_SA_DQ(25)     I2 @S9S_MB_2U_LIB.S9S_MB_2U(SCH_1):PAGE51
   C66 M_A_CPU1_SA_DQ<24> @S9S_MB_2U_LIB.S9S_MB_2U(SCH_1):M_A_CPU1_SA_DQ(24)     I2 @S9S_MB_2U_LIB.S9S_MB_2U(SCH_1):PAGE51
   E68 M_A_CPU1_SA_DQ<23> @S9S_MB_2U_LIB.S9S_MB_2U(SCH_1):M_A_CPU1_SA_DQ(23)     I2 @S9S_MB_2U_LIB.S9S_MB_2U(SCH_1):PAGE51
   F69 M_A_CPU1_SA_DQ<22> @S9S_MB_2U_LIB.S9S_MB_2U(SCH_1):M_A_CPU1_SA_DQ(22)     I2 @S9S_MB_2U_LIB.S9S_MB_2U(SCH_1):PAGE51
   C68 M_A_CPU1_SA_DQ<21> @S9S_MB_2U_LIB.S9S_MB_2U(SCH_1):M_A_CPU1_SA_DQ(21)     I2 @S9S_MB_2U_LIB.S9S_MB_2U(SCH_1):PAGE51
   B69 M_A_CPU1_SA_DQ<20> @S9S_MB_2U_LIB.S9S_MB_2U(SCH_1):M_A_CPU1_SA_DQ(20)     I2 @S9S_MB_2U_LIB.S9S_MB_2U(SCH_1):PAGE51
   F71 M_A_CPU1_SA_DQ<19> @S9S_MB_2U_LIB.S9S_MB_2U(SCH_1):M_A_CPU1_SA_DQ(19)     I2 @S9S_MB_2U_LIB.S9S_MB_2U(SCH_1):PAGE51
   D73 M_A_CPU1_SA_DQ<18> @S9S_MB_2U_LIB.S9S_MB_2U(SCH_1):M_A_CPU1_SA_DQ(18)     I2 @S9S_MB_2U_LIB.S9S_MB_2U(SCH_1):PAGE51
   E72 M_A_CPU1_SA_DQ<17> @S9S_MB_2U_LIB.S9S_MB_2U(SCH_1):M_A_CPU1_SA_DQ(17)     I2 @S9S_MB_2U_LIB.S9S_MB_2U(SCH_1):PAGE51
   B73 M_A_CPU1_SA_DQ<16> @S9S_MB_2U_LIB.S9S_MB_2U(SCH_1):M_A_CPU1_SA_DQ(16)     I2 @S9S_MB_2U_LIB.S9S_MB_2U(SCH_1):PAGE51
   M65 M_A_CPU1_SA_DQ<15> @S9S_MB_2U_LIB.S9S_MB_2U(SCH_1):M_A_CPU1_SA_DQ(15)     I2 @S9S_MB_2U_LIB.S9S_MB_2U(SCH_1):PAGE51
   N66 M_A_CPU1_SA_DQ<14> @S9S_MB_2U_LIB.S9S_MB_2U(SCH_1):M_A_CPU1_SA_DQ(14)     I2 @S9S_MB_2U_LIB.S9S_MB_2U(SCH_1):PAGE51
   K65 M_A_CPU1_SA_DQ<13> @S9S_MB_2U_LIB.S9S_MB_2U(SCH_1):M_A_CPU1_SA_DQ(13)     I2 @S9S_MB_2U_LIB.S9S_MB_2U(SCH_1):PAGE51
   J66 M_A_CPU1_SA_DQ<12> @S9S_MB_2U_LIB.S9S_MB_2U(SCH_1):M_A_CPU1_SA_DQ(12)     I2 @S9S_MB_2U_LIB.S9S_MB_2U(SCH_1):PAGE51
   N68 M_A_CPU1_SA_DQ<11> @S9S_MB_2U_LIB.S9S_MB_2U(SCH_1):M_A_CPU1_SA_DQ(11)     I2 @S9S_MB_2U_LIB.S9S_MB_2U(SCH_1):PAGE51
   M69 M_A_CPU1_SA_DQ<10> @S9S_MB_2U_LIB.S9S_MB_2U(SCH_1):M_A_CPU1_SA_DQ(10)     I2 @S9S_MB_2U_LIB.S9S_MB_2U(SCH_1):PAGE51
   J68 M_A_CPU1_SA_DQ<9> @S9S_MB_2U_LIB.S9S_MB_2U(SCH_1):M_A_CPU1_SA_DQ(9)     I2 @S9S_MB_2U_LIB.S9S_MB_2U(SCH_1):PAGE51
   K69 M_A_CPU1_SA_DQ<8> @S9S_MB_2U_LIB.S9S_MB_2U(SCH_1):M_A_CPU1_SA_DQ(8)     I2 @S9S_MB_2U_LIB.S9S_MB_2U(SCH_1):PAGE51
   F75 M_A_CPU1_SA_DQ<7> @S9S_MB_2U_LIB.S9S_MB_2U(SCH_1):M_A_CPU1_SA_DQ(7)     I2 @S9S_MB_2U_LIB.S9S_MB_2U(SCH_1):PAGE51
   G76 M_A_CPU1_SA_DQ<6> @S9S_MB_2U_LIB.S9S_MB_2U(SCH_1):M_A_CPU1_SA_DQ(6)     I2 @S9S_MB_2U_LIB.S9S_MB_2U(SCH_1):PAGE51
   D75 M_A_CPU1_SA_DQ<5> @S9S_MB_2U_LIB.S9S_MB_2U(SCH_1):M_A_CPU1_SA_DQ(5)     I2 @S9S_MB_2U_LIB.S9S_MB_2U(SCH_1):PAGE51
   C76 M_A_CPU1_SA_DQ<4> @S9S_MB_2U_LIB.S9S_MB_2U(SCH_1):M_A_CPU1_SA_DQ(4)     I2 @S9S_MB_2U_LIB.S9S_MB_2U(SCH_1):PAGE51
   G78 M_A_CPU1_SA_DQ<3> @S9S_MB_2U_LIB.S9S_MB_2U(SCH_1):M_A_CPU1_SA_DQ(3)     I2 @S9S_MB_2U_LIB.S9S_MB_2U(SCH_1):PAGE51
   M77 M_A_CPU1_SA_DQ<2> @S9S_MB_2U_LIB.S9S_MB_2U(SCH_1):M_A_CPU1_SA_DQ(2)     I2 @S9S_MB_2U_LIB.S9S_MB_2U(SCH_1):PAGE51
   B79 M_A_CPU1_SA_DQ<1> @S9S_MB_2U_LIB.S9S_MB_2U(SCH_1):M_A_CPU1_SA_DQ(1)     I2 @S9S_MB_2U_LIB.S9S_MB_2U(SCH_1):PAGE51
   B81 M_A_CPU1_SA_DQ<0> @S9S_MB_2U_LIB.S9S_MB_2U(SCH_1):M_A_CPU1_SA_DQ(0)     I2 @S9S_MB_2U_LIB.S9S_MB_2U(SCH_1):PAGE51
   G58 M_A_CPU1_SA_DQS_DN<9> @S9S_MB_2U_LIB.S9S_MB_2U(SCH_1):M_A_CPU1_SA_DQS_DN(9)     I2 @S9S_MB_2U_LIB.S9S_MB_2U(SCH_1):PAGE51
   G64 M_A_CPU1_SA_DQS_DN<8> @S9S_MB_2U_LIB.S9S_MB_2U(SCH_1):M_A_CPU1_SA_DQS_DN(8)     I2 @S9S_MB_2U_LIB.S9S_MB_2U(SCH_1):PAGE51
   G70 M_A_CPU1_SA_DQS_DN<7> @S9S_MB_2U_LIB.S9S_MB_2U(SCH_1):M_A_CPU1_SA_DQS_DN(7)     I2 @S9S_MB_2U_LIB.S9S_MB_2U(SCH_1):PAGE51
   P67 M_A_CPU1_SA_DQS_DN<6> @S9S_MB_2U_LIB.S9S_MB_2U(SCH_1):M_A_CPU1_SA_DQS_DN(6)     I2 @S9S_MB_2U_LIB.S9S_MB_2U(SCH_1):PAGE51
   H77 M_A_CPU1_SA_DQS_DN<5> @S9S_MB_2U_LIB.S9S_MB_2U(SCH_1):M_A_CPU1_SA_DQS_DN(5)     I2 @S9S_MB_2U_LIB.S9S_MB_2U(SCH_1):PAGE51
   A58 M_A_CPU1_SA_DQS_DN<4> @S9S_MB_2U_LIB.S9S_MB_2U(SCH_1):M_A_CPU1_SA_DQS_DN(4)     I2 @S9S_MB_2U_LIB.S9S_MB_2U(SCH_1):PAGE51
   A64 M_A_CPU1_SA_DQS_DN<3> @S9S_MB_2U_LIB.S9S_MB_2U(SCH_1):M_A_CPU1_SA_DQS_DN(3)     I2 @S9S_MB_2U_LIB.S9S_MB_2U(SCH_1):PAGE51
   B71 M_A_CPU1_SA_DQS_DN<2> @S9S_MB_2U_LIB.S9S_MB_2U(SCH_1):M_A_CPU1_SA_DQS_DN(2)     I2 @S9S_MB_2U_LIB.S9S_MB_2U(SCH_1):PAGE51
   H67 M_A_CPU1_SA_DQS_DN<1> @S9S_MB_2U_LIB.S9S_MB_2U(SCH_1):M_A_CPU1_SA_DQS_DN(1)     I2 @S9S_MB_2U_LIB.S9S_MB_2U(SCH_1):PAGE51
   B77 M_A_CPU1_SA_DQS_DN<0> @S9S_MB_2U_LIB.S9S_MB_2U(SCH_1):M_A_CPU1_SA_DQS_DN(0)     I2 @S9S_MB_2U_LIB.S9S_MB_2U(SCH_1):PAGE51
   E58 M_A_CPU1_SA_DQS_DP<9> @S9S_MB_2U_LIB.S9S_MB_2U(SCH_1):M_A_CPU1_SA_DQS_DP(9)     I2 @S9S_MB_2U_LIB.S9S_MB_2U(SCH_1):PAGE51
   E64 M_A_CPU1_SA_DQS_DP<8> @S9S_MB_2U_LIB.S9S_MB_2U(SCH_1):M_A_CPU1_SA_DQS_DP(8)     I2 @S9S_MB_2U_LIB.S9S_MB_2U(SCH_1):PAGE51
   E70 M_A_CPU1_SA_DQS_DP<7> @S9S_MB_2U_LIB.S9S_MB_2U(SCH_1):M_A_CPU1_SA_DQS_DP(7)     I2 @S9S_MB_2U_LIB.S9S_MB_2U(SCH_1):PAGE51
   M67 M_A_CPU1_SA_DQS_DP<6> @S9S_MB_2U_LIB.S9S_MB_2U(SCH_1):M_A_CPU1_SA_DQS_DP(6)     I2 @S9S_MB_2U_LIB.S9S_MB_2U(SCH_1):PAGE51
   F77 M_A_CPU1_SA_DQS_DP<5> @S9S_MB_2U_LIB.S9S_MB_2U(SCH_1):M_A_CPU1_SA_DQS_DP(5)     I2 @S9S_MB_2U_LIB.S9S_MB_2U(SCH_1):PAGE51
   C58 M_A_CPU1_SA_DQS_DP<4> @S9S_MB_2U_LIB.S9S_MB_2U(SCH_1):M_A_CPU1_SA_DQS_DP(4)     I2 @S9S_MB_2U_LIB.S9S_MB_2U(SCH_1):PAGE51
   C64 M_A_CPU1_SA_DQS_DP<3> @S9S_MB_2U_LIB.S9S_MB_2U(SCH_1):M_A_CPU1_SA_DQS_DP(3)     I2 @S9S_MB_2U_LIB.S9S_MB_2U(SCH_1):PAGE51
   C70 M_A_CPU1_SA_DQS_DP<2> @S9S_MB_2U_LIB.S9S_MB_2U(SCH_1):M_A_CPU1_SA_DQS_DP(2)     I2 @S9S_MB_2U_LIB.S9S_MB_2U(SCH_1):PAGE51
   K67 M_A_CPU1_SA_DQS_DP<1> @S9S_MB_2U_LIB.S9S_MB_2U(SCH_1):M_A_CPU1_SA_DQS_DP(1)     I2 @S9S_MB_2U_LIB.S9S_MB_2U(SCH_1):PAGE51
   D77 M_A_CPU1_SA_DQS_DP<0> @S9S_MB_2U_LIB.S9S_MB_2U(SCH_1):M_A_CPU1_SA_DQS_DP(0)     I2 @S9S_MB_2U_LIB.S9S_MB_2U(SCH_1):PAGE51
   E56 M_A_CPU1_SA_CB<7> @S9S_MB_2U_LIB.S9S_MB_2U(SCH_1):M_A_CPU1_SA_CB(7)     I2 @S9S_MB_2U_LIB.S9S_MB_2U(SCH_1):PAGE51
   F57 M_A_CPU1_SA_CB<6> @S9S_MB_2U_LIB.S9S_MB_2U(SCH_1):M_A_CPU1_SA_CB(6)     I2 @S9S_MB_2U_LIB.S9S_MB_2U(SCH_1):PAGE51
   C56 M_A_CPU1_SA_CB<5> @S9S_MB_2U_LIB.S9S_MB_2U(SCH_1):M_A_CPU1_SA_CB(5)     I2 @S9S_MB_2U_LIB.S9S_MB_2U(SCH_1):PAGE51
   B57 M_A_CPU1_SA_CB<4> @S9S_MB_2U_LIB.S9S_MB_2U(SCH_1):M_A_CPU1_SA_CB(4)     I2 @S9S_MB_2U_LIB.S9S_MB_2U(SCH_1):PAGE51
   F59 M_A_CPU1_SA_CB<3> @S9S_MB_2U_LIB.S9S_MB_2U(SCH_1):M_A_CPU1_SA_CB(3)     I2 @S9S_MB_2U_LIB.S9S_MB_2U(SCH_1):PAGE51
   E60 M_A_CPU1_SA_CB<2> @S9S_MB_2U_LIB.S9S_MB_2U(SCH_1):M_A_CPU1_SA_CB(2)     I2 @S9S_MB_2U_LIB.S9S_MB_2U(SCH_1):PAGE51
   B59 M_A_CPU1_SA_CB<1> @S9S_MB_2U_LIB.S9S_MB_2U(SCH_1):M_A_CPU1_SA_CB(1)     I2 @S9S_MB_2U_LIB.S9S_MB_2U(SCH_1):PAGE51
   C60 M_A_CPU1_SA_CB<0> @S9S_MB_2U_LIB.S9S_MB_2U(SCH_1):M_A_CPU1_SA_CB(0)     I2 @S9S_MB_2U_LIB.S9S_MB_2U(SCH_1):PAGE51
   E48 M_A_CPU1_SA_PAR @S9S_MB_2U_LIB.S9S_MB_2U(SCH_1):M_A_CPU1_SA_PAR     I2 @S9S_MB_2U_LIB.S9S_MB_2U(SCH_1):PAGE51
   A39 M_A_CPU1_SB_CA<6> @S9S_MB_2U_LIB.S9S_MB_2U(SCH_1):M_A_CPU1_SB_CA(6)     I2 @S9S_MB_2U_LIB.S9S_MB_2U(SCH_1):PAGE51
   F40 M_A_CPU1_SB_CA<5> @S9S_MB_2U_LIB.S9S_MB_2U(SCH_1):M_A_CPU1_SB_CA(5)     I2 @S9S_MB_2U_LIB.S9S_MB_2U(SCH_1):PAGE51
   B40 M_A_CPU1_SB_CA<4> @S9S_MB_2U_LIB.S9S_MB_2U(SCH_1):M_A_CPU1_SB_CA(4)     I2 @S9S_MB_2U_LIB.S9S_MB_2U(SCH_1):PAGE51
   E41 M_A_CPU1_SB_CA<3> @S9S_MB_2U_LIB.S9S_MB_2U(SCH_1):M_A_CPU1_SB_CA(3)     I2 @S9S_MB_2U_LIB.S9S_MB_2U(SCH_1):PAGE51
   C41 M_A_CPU1_SB_CA<2> @S9S_MB_2U_LIB.S9S_MB_2U(SCH_1):M_A_CPU1_SB_CA(2)     I2 @S9S_MB_2U_LIB.S9S_MB_2U(SCH_1):PAGE51
   F44 M_A_CPU1_SB_CA<1> @S9S_MB_2U_LIB.S9S_MB_2U(SCH_1):M_A_CPU1_SB_CA(1)     I2 @S9S_MB_2U_LIB.S9S_MB_2U(SCH_1):PAGE51
   E43 M_A_CPU1_SB_CA<0> @S9S_MB_2U_LIB.S9S_MB_2U(SCH_1):M_A_CPU1_SB_CA(0)     I2 @S9S_MB_2U_LIB.S9S_MB_2U(SCH_1):PAGE51
   E37 M_A_CPU1_SB_CS_N<3> @S9S_MB_2U_LIB.S9S_MB_2U(SCH_1):M_A_CPU1_SB_CS_N(3)     I2 @S9S_MB_2U_LIB.S9S_MB_2U(SCH_1):PAGE51
   F38 M_A_CPU1_SB_CS_N<2> @S9S_MB_2U_LIB.S9S_MB_2U(SCH_1):M_A_CPU1_SB_CS_N(2)     I2 @S9S_MB_2U_LIB.S9S_MB_2U(SCH_1):PAGE51
   C37 M_A_CPU1_SB_CS_N<1> @S9S_MB_2U_LIB.S9S_MB_2U(SCH_1):M_A_CPU1_SB_CS_N(1)     I2 @S9S_MB_2U_LIB.S9S_MB_2U(SCH_1):PAGE51
   B38 M_A_CPU1_SB_CS_N<0> @S9S_MB_2U_LIB.S9S_MB_2U(SCH_1):M_A_CPU1_SB_CS_N(0)     I2 @S9S_MB_2U_LIB.S9S_MB_2U(SCH_1):PAGE51
    E7 M_A_CPU1_SB_DQ<31> @S9S_MB_2U_LIB.S9S_MB_2U(SCH_1):M_A_CPU1_SB_DQ(31)     I2 @S9S_MB_2U_LIB.S9S_MB_2U(SCH_1):PAGE51
    F8 M_A_CPU1_SB_DQ<30> @S9S_MB_2U_LIB.S9S_MB_2U(SCH_1):M_A_CPU1_SB_DQ(30)     I2 @S9S_MB_2U_LIB.S9S_MB_2U(SCH_1):PAGE51
    C7 M_A_CPU1_SB_DQ<29> @S9S_MB_2U_LIB.S9S_MB_2U(SCH_1):M_A_CPU1_SB_DQ(29)     I2 @S9S_MB_2U_LIB.S9S_MB_2U(SCH_1):PAGE51
    B8 M_A_CPU1_SB_DQ<28> @S9S_MB_2U_LIB.S9S_MB_2U(SCH_1):M_A_CPU1_SB_DQ(28)     I2 @S9S_MB_2U_LIB.S9S_MB_2U(SCH_1):PAGE51
   F10 M_A_CPU1_SB_DQ<27> @S9S_MB_2U_LIB.S9S_MB_2U(SCH_1):M_A_CPU1_SB_DQ(27)     I2 @S9S_MB_2U_LIB.S9S_MB_2U(SCH_1):PAGE51
   E11 M_A_CPU1_SB_DQ<26> @S9S_MB_2U_LIB.S9S_MB_2U(SCH_1):M_A_CPU1_SB_DQ(26)     I2 @S9S_MB_2U_LIB.S9S_MB_2U(SCH_1):PAGE51
   B10 M_A_CPU1_SB_DQ<25> @S9S_MB_2U_LIB.S9S_MB_2U(SCH_1):M_A_CPU1_SB_DQ(25)     I2 @S9S_MB_2U_LIB.S9S_MB_2U(SCH_1):PAGE51
   C11 M_A_CPU1_SB_DQ<24> @S9S_MB_2U_LIB.S9S_MB_2U(SCH_1):M_A_CPU1_SB_DQ(24)     I2 @S9S_MB_2U_LIB.S9S_MB_2U(SCH_1):PAGE51
   E19 M_A_CPU1_SB_DQ<23> @S9S_MB_2U_LIB.S9S_MB_2U(SCH_1):M_A_CPU1_SB_DQ(23)     I2 @S9S_MB_2U_LIB.S9S_MB_2U(SCH_1):PAGE51
   F20 M_A_CPU1_SB_DQ<22> @S9S_MB_2U_LIB.S9S_MB_2U(SCH_1):M_A_CPU1_SB_DQ(22)     I2 @S9S_MB_2U_LIB.S9S_MB_2U(SCH_1):PAGE51
   C19 M_A_CPU1_SB_DQ<21> @S9S_MB_2U_LIB.S9S_MB_2U(SCH_1):M_A_CPU1_SB_DQ(21)     I2 @S9S_MB_2U_LIB.S9S_MB_2U(SCH_1):PAGE51
   B20 M_A_CPU1_SB_DQ<20> @S9S_MB_2U_LIB.S9S_MB_2U(SCH_1):M_A_CPU1_SB_DQ(20)     I2 @S9S_MB_2U_LIB.S9S_MB_2U(SCH_1):PAGE51
   F22 M_A_CPU1_SB_DQ<19> @S9S_MB_2U_LIB.S9S_MB_2U(SCH_1):M_A_CPU1_SB_DQ(19)     I2 @S9S_MB_2U_LIB.S9S_MB_2U(SCH_1):PAGE51
   E23 M_A_CPU1_SB_DQ<18> @S9S_MB_2U_LIB.S9S_MB_2U(SCH_1):M_A_CPU1_SB_DQ(18)     I2 @S9S_MB_2U_LIB.S9S_MB_2U(SCH_1):PAGE51
   B22 M_A_CPU1_SB_DQ<17> @S9S_MB_2U_LIB.S9S_MB_2U(SCH_1):M_A_CPU1_SB_DQ(17)     I2 @S9S_MB_2U_LIB.S9S_MB_2U(SCH_1):PAGE51
   C23 M_A_CPU1_SB_DQ<16> @S9S_MB_2U_LIB.S9S_MB_2U(SCH_1):M_A_CPU1_SB_DQ(16)     I2 @S9S_MB_2U_LIB.S9S_MB_2U(SCH_1):PAGE51
   E25 M_A_CPU1_SB_DQ<15> @S9S_MB_2U_LIB.S9S_MB_2U(SCH_1):M_A_CPU1_SB_DQ(15)     I2 @S9S_MB_2U_LIB.S9S_MB_2U(SCH_1):PAGE51
   F26 M_A_CPU1_SB_DQ<14> @S9S_MB_2U_LIB.S9S_MB_2U(SCH_1):M_A_CPU1_SB_DQ(14)     I2 @S9S_MB_2U_LIB.S9S_MB_2U(SCH_1):PAGE51
   C25 M_A_CPU1_SB_DQ<13> @S9S_MB_2U_LIB.S9S_MB_2U(SCH_1):M_A_CPU1_SB_DQ(13)     I2 @S9S_MB_2U_LIB.S9S_MB_2U(SCH_1):PAGE51
   B26 M_A_CPU1_SB_DQ<12> @S9S_MB_2U_LIB.S9S_MB_2U(SCH_1):M_A_CPU1_SB_DQ(12)     I2 @S9S_MB_2U_LIB.S9S_MB_2U(SCH_1):PAGE51
   F28 M_A_CPU1_SB_DQ<11> @S9S_MB_2U_LIB.S9S_MB_2U(SCH_1):M_A_CPU1_SB_DQ(11)     I2 @S9S_MB_2U_LIB.S9S_MB_2U(SCH_1):PAGE51
   E29 M_A_CPU1_SB_DQ<10> @S9S_MB_2U_LIB.S9S_MB_2U(SCH_1):M_A_CPU1_SB_DQ(10)     I2 @S9S_MB_2U_LIB.S9S_MB_2U(SCH_1):PAGE51
   B28 M_A_CPU1_SB_DQ<9> @S9S_MB_2U_LIB.S9S_MB_2U(SCH_1):M_A_CPU1_SB_DQ(9)     I2 @S9S_MB_2U_LIB.S9S_MB_2U(SCH_1):PAGE51
   C29 M_A_CPU1_SB_DQ<8> @S9S_MB_2U_LIB.S9S_MB_2U(SCH_1):M_A_CPU1_SB_DQ(8)     I2 @S9S_MB_2U_LIB.S9S_MB_2U(SCH_1):PAGE51
   M28 M_A_CPU1_SB_DQ<7> @S9S_MB_2U_LIB.S9S_MB_2U(SCH_1):M_A_CPU1_SB_DQ(7)     I2 @S9S_MB_2U_LIB.S9S_MB_2U(SCH_1):PAGE51
   N29 M_A_CPU1_SB_DQ<6> @S9S_MB_2U_LIB.S9S_MB_2U(SCH_1):M_A_CPU1_SB_DQ(6)     I2 @S9S_MB_2U_LIB.S9S_MB_2U(SCH_1):PAGE51
   K28 M_A_CPU1_SB_DQ<5> @S9S_MB_2U_LIB.S9S_MB_2U(SCH_1):M_A_CPU1_SB_DQ(5)     I2 @S9S_MB_2U_LIB.S9S_MB_2U(SCH_1):PAGE51
   J29 M_A_CPU1_SB_DQ<4> @S9S_MB_2U_LIB.S9S_MB_2U(SCH_1):M_A_CPU1_SB_DQ(4)     I2 @S9S_MB_2U_LIB.S9S_MB_2U(SCH_1):PAGE51
   N31 M_A_CPU1_SB_DQ<3> @S9S_MB_2U_LIB.S9S_MB_2U(SCH_1):M_A_CPU1_SB_DQ(3)     I2 @S9S_MB_2U_LIB.S9S_MB_2U(SCH_1):PAGE51
   M32 M_A_CPU1_SB_DQ<2> @S9S_MB_2U_LIB.S9S_MB_2U(SCH_1):M_A_CPU1_SB_DQ(2)     I2 @S9S_MB_2U_LIB.S9S_MB_2U(SCH_1):PAGE51
   J31 M_A_CPU1_SB_DQ<1> @S9S_MB_2U_LIB.S9S_MB_2U(SCH_1):M_A_CPU1_SB_DQ(1)     I2 @S9S_MB_2U_LIB.S9S_MB_2U(SCH_1):PAGE51
   K32 M_A_CPU1_SB_DQ<0> @S9S_MB_2U_LIB.S9S_MB_2U(SCH_1):M_A_CPU1_SB_DQ(0)     I2 @S9S_MB_2U_LIB.S9S_MB_2U(SCH_1):PAGE51
   A33 M_A_CPU1_SB_DQS_DN<9> @S9S_MB_2U_LIB.S9S_MB_2U(SCH_1):M_A_CPU1_SB_DQS_DN(9)     I2 @S9S_MB_2U_LIB.S9S_MB_2U(SCH_1):PAGE51
    G9 M_A_CPU1_SB_DQS_DN<8> @S9S_MB_2U_LIB.S9S_MB_2U(SCH_1):M_A_CPU1_SB_DQS_DN(8)     I2 @S9S_MB_2U_LIB.S9S_MB_2U(SCH_1):PAGE51
   G21 M_A_CPU1_SB_DQS_DN<7> @S9S_MB_2U_LIB.S9S_MB_2U(SCH_1):M_A_CPU1_SB_DQS_DN(7)     I2 @S9S_MB_2U_LIB.S9S_MB_2U(SCH_1):PAGE51
   G27 M_A_CPU1_SB_DQS_DN<6> @S9S_MB_2U_LIB.S9S_MB_2U(SCH_1):M_A_CPU1_SB_DQS_DN(6)     I2 @S9S_MB_2U_LIB.S9S_MB_2U(SCH_1):PAGE51
   M30 M_A_CPU1_SB_DQS_DN<5> @S9S_MB_2U_LIB.S9S_MB_2U(SCH_1):M_A_CPU1_SB_DQS_DN(5)     I2 @S9S_MB_2U_LIB.S9S_MB_2U(SCH_1):PAGE51
   G33 M_A_CPU1_SB_DQS_DN<4> @S9S_MB_2U_LIB.S9S_MB_2U(SCH_1):M_A_CPU1_SB_DQS_DN(4)     I2 @S9S_MB_2U_LIB.S9S_MB_2U(SCH_1):PAGE51
    A9 M_A_CPU1_SB_DQS_DN<3> @S9S_MB_2U_LIB.S9S_MB_2U(SCH_1):M_A_CPU1_SB_DQS_DN(3)     I2 @S9S_MB_2U_LIB.S9S_MB_2U(SCH_1):PAGE51
   A21 M_A_CPU1_SB_DQS_DN<2> @S9S_MB_2U_LIB.S9S_MB_2U(SCH_1):M_A_CPU1_SB_DQS_DN(2)     I2 @S9S_MB_2U_LIB.S9S_MB_2U(SCH_1):PAGE51
   A27 M_A_CPU1_SB_DQS_DN<1> @S9S_MB_2U_LIB.S9S_MB_2U(SCH_1):M_A_CPU1_SB_DQS_DN(1)     I2 @S9S_MB_2U_LIB.S9S_MB_2U(SCH_1):PAGE51
   H30 M_A_CPU1_SB_DQS_DN<0> @S9S_MB_2U_LIB.S9S_MB_2U(SCH_1):M_A_CPU1_SB_DQS_DN(0)     I2 @S9S_MB_2U_LIB.S9S_MB_2U(SCH_1):PAGE51
   C33 M_A_CPU1_SB_DQS_DP<9> @S9S_MB_2U_LIB.S9S_MB_2U(SCH_1):M_A_CPU1_SB_DQS_DP(9)     I2 @S9S_MB_2U_LIB.S9S_MB_2U(SCH_1):PAGE51
    E9 M_A_CPU1_SB_DQS_DP<8> @S9S_MB_2U_LIB.S9S_MB_2U(SCH_1):M_A_CPU1_SB_DQS_DP(8)     I2 @S9S_MB_2U_LIB.S9S_MB_2U(SCH_1):PAGE51
   E21 M_A_CPU1_SB_DQS_DP<7> @S9S_MB_2U_LIB.S9S_MB_2U(SCH_1):M_A_CPU1_SB_DQS_DP(7)     I2 @S9S_MB_2U_LIB.S9S_MB_2U(SCH_1):PAGE51
   E27 M_A_CPU1_SB_DQS_DP<6> @S9S_MB_2U_LIB.S9S_MB_2U(SCH_1):M_A_CPU1_SB_DQS_DP(6)     I2 @S9S_MB_2U_LIB.S9S_MB_2U(SCH_1):PAGE51
   P30 M_A_CPU1_SB_DQS_DP<5> @S9S_MB_2U_LIB.S9S_MB_2U(SCH_1):M_A_CPU1_SB_DQS_DP(5)     I2 @S9S_MB_2U_LIB.S9S_MB_2U(SCH_1):PAGE51
   E33 M_A_CPU1_SB_DQS_DP<4> @S9S_MB_2U_LIB.S9S_MB_2U(SCH_1):M_A_CPU1_SB_DQS_DP(4)     I2 @S9S_MB_2U_LIB.S9S_MB_2U(SCH_1):PAGE51
    C9 M_A_CPU1_SB_DQS_DP<3> @S9S_MB_2U_LIB.S9S_MB_2U(SCH_1):M_A_CPU1_SB_DQS_DP(3)     I2 @S9S_MB_2U_LIB.S9S_MB_2U(SCH_1):PAGE51
   C21 M_A_CPU1_SB_DQS_DP<2> @S9S_MB_2U_LIB.S9S_MB_2U(SCH_1):M_A_CPU1_SB_DQS_DP(2)     I2 @S9S_MB_2U_LIB.S9S_MB_2U(SCH_1):PAGE51
   C27 M_A_CPU1_SB_DQS_DP<1> @S9S_MB_2U_LIB.S9S_MB_2U(SCH_1):M_A_CPU1_SB_DQS_DP(1)     I2 @S9S_MB_2U_LIB.S9S_MB_2U(SCH_1):PAGE51
   K30 M_A_CPU1_SB_DQS_DP<0> @S9S_MB_2U_LIB.S9S_MB_2U(SCH_1):M_A_CPU1_SB_DQS_DP(0)     I2 @S9S_MB_2U_LIB.S9S_MB_2U(SCH_1):PAGE51
   F34 M_A_CPU1_SB_CB<7> @S9S_MB_2U_LIB.S9S_MB_2U(SCH_1):M_A_CPU1_SB_CB(7)     I2 @S9S_MB_2U_LIB.S9S_MB_2U(SCH_1):PAGE51
   E35 M_A_CPU1_SB_CB<6> @S9S_MB_2U_LIB.S9S_MB_2U(SCH_1):M_A_CPU1_SB_CB(6)     I2 @S9S_MB_2U_LIB.S9S_MB_2U(SCH_1):PAGE51
   B34 M_A_CPU1_SB_CB<5> @S9S_MB_2U_LIB.S9S_MB_2U(SCH_1):M_A_CPU1_SB_CB(5)     I2 @S9S_MB_2U_LIB.S9S_MB_2U(SCH_1):PAGE51
   C35 M_A_CPU1_SB_CB<4> @S9S_MB_2U_LIB.S9S_MB_2U(SCH_1):M_A_CPU1_SB_CB(4)     I2 @S9S_MB_2U_LIB.S9S_MB_2U(SCH_1):PAGE51
   E31 M_A_CPU1_SB_CB<3> @S9S_MB_2U_LIB.S9S_MB_2U(SCH_1):M_A_CPU1_SB_CB(3)     I2 @S9S_MB_2U_LIB.S9S_MB_2U(SCH_1):PAGE51
   F32 M_A_CPU1_SB_CB<2> @S9S_MB_2U_LIB.S9S_MB_2U(SCH_1):M_A_CPU1_SB_CB(2)     I2 @S9S_MB_2U_LIB.S9S_MB_2U(SCH_1):PAGE51
   C31 M_A_CPU1_SB_CB<1> @S9S_MB_2U_LIB.S9S_MB_2U(SCH_1):M_A_CPU1_SB_CB(1)     I2 @S9S_MB_2U_LIB.S9S_MB_2U(SCH_1):PAGE51
   B32 M_A_CPU1_SB_CB<0> @S9S_MB_2U_LIB.S9S_MB_2U(SCH_1):M_A_CPU1_SB_CB(0)     I2 @S9S_MB_2U_LIB.S9S_MB_2U(SCH_1):PAGE51
   G39 M_A_CPU1_SB_PAR @S9S_MB_2U_LIB.S9S_MB_2U(SCH_1):M_A_CPU1_SB_PAR     I2 @S9S_MB_2U_LIB.S9S_MB_2U(SCH_1):PAGE51
  AV49 M_B_CPU1_ALERT_N @S9S_MB_2U_LIB.S9S_MB_2U(SCH_1):M_B_CPU1_ALERT_N    I91 @S9S_MB_2U_LIB.S9S_MB_2U(SCH_1):PAGE52
  AK47 M_B_CPU1_SA_RSP<1> @S9S_MB_2U_LIB.S9S_MB_2U(SCH_1):M_B_CPU1_SA_RSP(1)    I91 @S9S_MB_2U_LIB.S9S_MB_2U(SCH_1):PAGE52
  AL48 M_B_CPU1_SA_RSP<0> @S9S_MB_2U_LIB.S9S_MB_2U(SCH_1):M_B_CPU1_SA_RSP(0)    I91 @S9S_MB_2U_LIB.S9S_MB_2U(SCH_1):PAGE52
  AP47 M_B_CPU1_SB_RSP<1> @S9S_MB_2U_LIB.S9S_MB_2U(SCH_1):M_B_CPU1_SB_RSP(1)    I91 @S9S_MB_2U_LIB.S9S_MB_2U(SCH_1):PAGE52
  AN48 M_B_CPU1_SB_RSP<0> @S9S_MB_2U_LIB.S9S_MB_2U(SCH_1):M_B_CPU1_SB_RSP(0)    I91 @S9S_MB_2U_LIB.S9S_MB_2U(SCH_1):PAGE52
   W45 M_B_CPU1_CLK_DN<1> @S9S_MB_2U_LIB.S9S_MB_2U(SCH_1):M_B_CPU1_CLK_DN(1)    I91 @S9S_MB_2U_LIB.S9S_MB_2U(SCH_1):PAGE52
   R45 M_B_CPU1_CLK_DN<0> @S9S_MB_2U_LIB.S9S_MB_2U(SCH_1):M_B_CPU1_CLK_DN(0)    I91 @S9S_MB_2U_LIB.S9S_MB_2U(SCH_1):PAGE52
  AA45 M_B_CPU1_CLK_DP<1> @S9S_MB_2U_LIB.S9S_MB_2U(SCH_1):M_B_CPU1_CLK_DP(1)    I91 @S9S_MB_2U_LIB.S9S_MB_2U(SCH_1):PAGE52
   U45 M_B_CPU1_CLK_DP<0> @S9S_MB_2U_LIB.S9S_MB_2U(SCH_1):M_B_CPU1_CLK_DP(0)    I91 @S9S_MB_2U_LIB.S9S_MB_2U(SCH_1):PAGE52
   Y44 M_B_CPU1_SA_CA<6> @S9S_MB_2U_LIB.S9S_MB_2U(SCH_1):M_B_CPU1_SA_CA(6)    I91 @S9S_MB_2U_LIB.S9S_MB_2U(SCH_1):PAGE52
   M47 M_B_CPU1_SA_CA<5> @S9S_MB_2U_LIB.S9S_MB_2U(SCH_1):M_B_CPU1_SA_CA(5)    I91 @S9S_MB_2U_LIB.S9S_MB_2U(SCH_1):PAGE52
   K47 M_B_CPU1_SA_CA<4> @S9S_MB_2U_LIB.S9S_MB_2U(SCH_1):M_B_CPU1_SA_CA(4)    I91 @S9S_MB_2U_LIB.S9S_MB_2U(SCH_1):PAGE52
   N48 M_B_CPU1_SA_CA<3> @S9S_MB_2U_LIB.S9S_MB_2U(SCH_1):M_B_CPU1_SA_CA(3)    I91 @S9S_MB_2U_LIB.S9S_MB_2U(SCH_1):PAGE52
   J48 M_B_CPU1_SA_CA<2> @S9S_MB_2U_LIB.S9S_MB_2U(SCH_1):M_B_CPU1_SA_CA(2)    I91 @S9S_MB_2U_LIB.S9S_MB_2U(SCH_1):PAGE52
   P49 M_B_CPU1_SA_CA<1> @S9S_MB_2U_LIB.S9S_MB_2U(SCH_1):M_B_CPU1_SA_CA(1)    I91 @S9S_MB_2U_LIB.S9S_MB_2U(SCH_1):PAGE52
   H49 M_B_CPU1_SA_CA<0> @S9S_MB_2U_LIB.S9S_MB_2U(SCH_1):M_B_CPU1_SA_CA(0)    I91 @S9S_MB_2U_LIB.S9S_MB_2U(SCH_1):PAGE52
   N50 M_B_CPU1_SA_CS_N<3> @S9S_MB_2U_LIB.S9S_MB_2U(SCH_1):M_B_CPU1_SA_CS_N(3)    I91 @S9S_MB_2U_LIB.S9S_MB_2U(SCH_1):PAGE52
   M51 M_B_CPU1_SA_CS_N<2> @S9S_MB_2U_LIB.S9S_MB_2U(SCH_1):M_B_CPU1_SA_CS_N(2)    I91 @S9S_MB_2U_LIB.S9S_MB_2U(SCH_1):PAGE52
   J50 M_B_CPU1_SA_CS_N<1> @S9S_MB_2U_LIB.S9S_MB_2U(SCH_1):M_B_CPU1_SA_CS_N(1)    I91 @S9S_MB_2U_LIB.S9S_MB_2U(SCH_1):PAGE52
   K51 M_B_CPU1_SA_CS_N<0> @S9S_MB_2U_LIB.S9S_MB_2U(SCH_1):M_B_CPU1_SA_CS_N(0)    I91 @S9S_MB_2U_LIB.S9S_MB_2U(SCH_1):PAGE52
   W56 M_B_CPU1_SA_DQ<31> @S9S_MB_2U_LIB.S9S_MB_2U(SCH_1):M_B_CPU1_SA_DQ(31)    I91 @S9S_MB_2U_LIB.S9S_MB_2U(SCH_1):PAGE52
   Y57 M_B_CPU1_SA_DQ<30> @S9S_MB_2U_LIB.S9S_MB_2U(SCH_1):M_B_CPU1_SA_DQ(30)    I91 @S9S_MB_2U_LIB.S9S_MB_2U(SCH_1):PAGE52
   U56 M_B_CPU1_SA_DQ<29> @S9S_MB_2U_LIB.S9S_MB_2U(SCH_1):M_B_CPU1_SA_DQ(29)    I91 @S9S_MB_2U_LIB.S9S_MB_2U(SCH_1):PAGE52
   T57 M_B_CPU1_SA_DQ<28> @S9S_MB_2U_LIB.S9S_MB_2U(SCH_1):M_B_CPU1_SA_DQ(28)    I91 @S9S_MB_2U_LIB.S9S_MB_2U(SCH_1):PAGE52
   Y59 M_B_CPU1_SA_DQ<27> @S9S_MB_2U_LIB.S9S_MB_2U(SCH_1):M_B_CPU1_SA_DQ(27)    I91 @S9S_MB_2U_LIB.S9S_MB_2U(SCH_1):PAGE52
   W60 M_B_CPU1_SA_DQ<26> @S9S_MB_2U_LIB.S9S_MB_2U(SCH_1):M_B_CPU1_SA_DQ(26)    I91 @S9S_MB_2U_LIB.S9S_MB_2U(SCH_1):PAGE52
   T59 M_B_CPU1_SA_DQ<25> @S9S_MB_2U_LIB.S9S_MB_2U(SCH_1):M_B_CPU1_SA_DQ(25)    I91 @S9S_MB_2U_LIB.S9S_MB_2U(SCH_1):PAGE52
   U60 M_B_CPU1_SA_DQ<24> @S9S_MB_2U_LIB.S9S_MB_2U(SCH_1):M_B_CPU1_SA_DQ(24)    I91 @S9S_MB_2U_LIB.S9S_MB_2U(SCH_1):PAGE52
   M59 M_B_CPU1_SA_DQ<23> @S9S_MB_2U_LIB.S9S_MB_2U(SCH_1):M_B_CPU1_SA_DQ(23)    I91 @S9S_MB_2U_LIB.S9S_MB_2U(SCH_1):PAGE52
   N60 M_B_CPU1_SA_DQ<22> @S9S_MB_2U_LIB.S9S_MB_2U(SCH_1):M_B_CPU1_SA_DQ(22)    I91 @S9S_MB_2U_LIB.S9S_MB_2U(SCH_1):PAGE52
   K59 M_B_CPU1_SA_DQ<21> @S9S_MB_2U_LIB.S9S_MB_2U(SCH_1):M_B_CPU1_SA_DQ(21)    I91 @S9S_MB_2U_LIB.S9S_MB_2U(SCH_1):PAGE52
   J60 M_B_CPU1_SA_DQ<20> @S9S_MB_2U_LIB.S9S_MB_2U(SCH_1):M_B_CPU1_SA_DQ(20)    I91 @S9S_MB_2U_LIB.S9S_MB_2U(SCH_1):PAGE52
   N62 M_B_CPU1_SA_DQ<19> @S9S_MB_2U_LIB.S9S_MB_2U(SCH_1):M_B_CPU1_SA_DQ(19)    I91 @S9S_MB_2U_LIB.S9S_MB_2U(SCH_1):PAGE52
   M63 M_B_CPU1_SA_DQ<18> @S9S_MB_2U_LIB.S9S_MB_2U(SCH_1):M_B_CPU1_SA_DQ(18)    I91 @S9S_MB_2U_LIB.S9S_MB_2U(SCH_1):PAGE52
   J62 M_B_CPU1_SA_DQ<17> @S9S_MB_2U_LIB.S9S_MB_2U(SCH_1):M_B_CPU1_SA_DQ(17)    I91 @S9S_MB_2U_LIB.S9S_MB_2U(SCH_1):PAGE52
   K63 M_B_CPU1_SA_DQ<16> @S9S_MB_2U_LIB.S9S_MB_2U(SCH_1):M_B_CPU1_SA_DQ(16)    I91 @S9S_MB_2U_LIB.S9S_MB_2U(SCH_1):PAGE52
   W68 M_B_CPU1_SA_DQ<15> @S9S_MB_2U_LIB.S9S_MB_2U(SCH_1):M_B_CPU1_SA_DQ(15)    I91 @S9S_MB_2U_LIB.S9S_MB_2U(SCH_1):PAGE52
   Y69 M_B_CPU1_SA_DQ<14> @S9S_MB_2U_LIB.S9S_MB_2U(SCH_1):M_B_CPU1_SA_DQ(14)    I91 @S9S_MB_2U_LIB.S9S_MB_2U(SCH_1):PAGE52
   U68 M_B_CPU1_SA_DQ<13> @S9S_MB_2U_LIB.S9S_MB_2U(SCH_1):M_B_CPU1_SA_DQ(13)    I91 @S9S_MB_2U_LIB.S9S_MB_2U(SCH_1):PAGE52
   T69 M_B_CPU1_SA_DQ<12> @S9S_MB_2U_LIB.S9S_MB_2U(SCH_1):M_B_CPU1_SA_DQ(12)    I91 @S9S_MB_2U_LIB.S9S_MB_2U(SCH_1):PAGE52
   Y71 M_B_CPU1_SA_DQ<11> @S9S_MB_2U_LIB.S9S_MB_2U(SCH_1):M_B_CPU1_SA_DQ(11)    I91 @S9S_MB_2U_LIB.S9S_MB_2U(SCH_1):PAGE52
   W72 M_B_CPU1_SA_DQ<10> @S9S_MB_2U_LIB.S9S_MB_2U(SCH_1):M_B_CPU1_SA_DQ(10)    I91 @S9S_MB_2U_LIB.S9S_MB_2U(SCH_1):PAGE52
   T71 M_B_CPU1_SA_DQ<9> @S9S_MB_2U_LIB.S9S_MB_2U(SCH_1):M_B_CPU1_SA_DQ(9)    I91 @S9S_MB_2U_LIB.S9S_MB_2U(SCH_1):PAGE52
   U72 M_B_CPU1_SA_DQ<8> @S9S_MB_2U_LIB.S9S_MB_2U(SCH_1):M_B_CPU1_SA_DQ(8)    I91 @S9S_MB_2U_LIB.S9S_MB_2U(SCH_1):PAGE52
   M71 M_B_CPU1_SA_DQ<7> @S9S_MB_2U_LIB.S9S_MB_2U(SCH_1):M_B_CPU1_SA_DQ(7)    I91 @S9S_MB_2U_LIB.S9S_MB_2U(SCH_1):PAGE52
   N72 M_B_CPU1_SA_DQ<6> @S9S_MB_2U_LIB.S9S_MB_2U(SCH_1):M_B_CPU1_SA_DQ(6)    I91 @S9S_MB_2U_LIB.S9S_MB_2U(SCH_1):PAGE52
   K71 M_B_CPU1_SA_DQ<5> @S9S_MB_2U_LIB.S9S_MB_2U(SCH_1):M_B_CPU1_SA_DQ(5)    I91 @S9S_MB_2U_LIB.S9S_MB_2U(SCH_1):PAGE52
   J72 M_B_CPU1_SA_DQ<4> @S9S_MB_2U_LIB.S9S_MB_2U(SCH_1):M_B_CPU1_SA_DQ(4)    I91 @S9S_MB_2U_LIB.S9S_MB_2U(SCH_1):PAGE52
   N74 M_B_CPU1_SA_DQ<3> @S9S_MB_2U_LIB.S9S_MB_2U(SCH_1):M_B_CPU1_SA_DQ(3)    I91 @S9S_MB_2U_LIB.S9S_MB_2U(SCH_1):PAGE52
   M75 M_B_CPU1_SA_DQ<2> @S9S_MB_2U_LIB.S9S_MB_2U(SCH_1):M_B_CPU1_SA_DQ(2)    I91 @S9S_MB_2U_LIB.S9S_MB_2U(SCH_1):PAGE52
   J74 M_B_CPU1_SA_DQ<1> @S9S_MB_2U_LIB.S9S_MB_2U(SCH_1):M_B_CPU1_SA_DQ(1)    I91 @S9S_MB_2U_LIB.S9S_MB_2U(SCH_1):PAGE52
   K75 M_B_CPU1_SA_DQ<0> @S9S_MB_2U_LIB.S9S_MB_2U(SCH_1):M_B_CPU1_SA_DQ(0)    I91 @S9S_MB_2U_LIB.S9S_MB_2U(SCH_1):PAGE52
   M55 M_B_CPU1_SA_DQS_DN<9> @S9S_MB_2U_LIB.S9S_MB_2U(SCH_1):M_B_CPU1_SA_DQS_DN(9)    I91 @S9S_MB_2U_LIB.S9S_MB_2U(SCH_1):PAGE52
  AA58 M_B_CPU1_SA_DQS_DN<8> @S9S_MB_2U_LIB.S9S_MB_2U(SCH_1):M_B_CPU1_SA_DQS_DN(8)    I91 @S9S_MB_2U_LIB.S9S_MB_2U(SCH_1):PAGE52
   M61 M_B_CPU1_SA_DQS_DN<7> @S9S_MB_2U_LIB.S9S_MB_2U(SCH_1):M_B_CPU1_SA_DQS_DN(7)    I91 @S9S_MB_2U_LIB.S9S_MB_2U(SCH_1):PAGE52
  AA70 M_B_CPU1_SA_DQS_DN<6> @S9S_MB_2U_LIB.S9S_MB_2U(SCH_1):M_B_CPU1_SA_DQS_DN(6)    I91 @S9S_MB_2U_LIB.S9S_MB_2U(SCH_1):PAGE52
   M73 M_B_CPU1_SA_DQS_DN<5> @S9S_MB_2U_LIB.S9S_MB_2U(SCH_1):M_B_CPU1_SA_DQS_DN(5)    I91 @S9S_MB_2U_LIB.S9S_MB_2U(SCH_1):PAGE52
   H55 M_B_CPU1_SA_DQS_DN<4> @S9S_MB_2U_LIB.S9S_MB_2U(SCH_1):M_B_CPU1_SA_DQS_DN(4)    I91 @S9S_MB_2U_LIB.S9S_MB_2U(SCH_1):PAGE52
   R58 M_B_CPU1_SA_DQS_DN<3> @S9S_MB_2U_LIB.S9S_MB_2U(SCH_1):M_B_CPU1_SA_DQS_DN(3)    I91 @S9S_MB_2U_LIB.S9S_MB_2U(SCH_1):PAGE52
   H61 M_B_CPU1_SA_DQS_DN<2> @S9S_MB_2U_LIB.S9S_MB_2U(SCH_1):M_B_CPU1_SA_DQS_DN(2)    I91 @S9S_MB_2U_LIB.S9S_MB_2U(SCH_1):PAGE52
   R70 M_B_CPU1_SA_DQS_DN<1> @S9S_MB_2U_LIB.S9S_MB_2U(SCH_1):M_B_CPU1_SA_DQS_DN(1)    I91 @S9S_MB_2U_LIB.S9S_MB_2U(SCH_1):PAGE52
   H73 M_B_CPU1_SA_DQS_DN<0> @S9S_MB_2U_LIB.S9S_MB_2U(SCH_1):M_B_CPU1_SA_DQS_DN(0)    I91 @S9S_MB_2U_LIB.S9S_MB_2U(SCH_1):PAGE52
   P55 M_B_CPU1_SA_DQS_DP<9> @S9S_MB_2U_LIB.S9S_MB_2U(SCH_1):M_B_CPU1_SA_DQS_DP(9)    I91 @S9S_MB_2U_LIB.S9S_MB_2U(SCH_1):PAGE52
   W58 M_B_CPU1_SA_DQS_DP<8> @S9S_MB_2U_LIB.S9S_MB_2U(SCH_1):M_B_CPU1_SA_DQS_DP(8)    I91 @S9S_MB_2U_LIB.S9S_MB_2U(SCH_1):PAGE52
   P61 M_B_CPU1_SA_DQS_DP<7> @S9S_MB_2U_LIB.S9S_MB_2U(SCH_1):M_B_CPU1_SA_DQS_DP(7)    I91 @S9S_MB_2U_LIB.S9S_MB_2U(SCH_1):PAGE52
   W70 M_B_CPU1_SA_DQS_DP<6> @S9S_MB_2U_LIB.S9S_MB_2U(SCH_1):M_B_CPU1_SA_DQS_DP(6)    I91 @S9S_MB_2U_LIB.S9S_MB_2U(SCH_1):PAGE52
   P73 M_B_CPU1_SA_DQS_DP<5> @S9S_MB_2U_LIB.S9S_MB_2U(SCH_1):M_B_CPU1_SA_DQS_DP(5)    I91 @S9S_MB_2U_LIB.S9S_MB_2U(SCH_1):PAGE52
   K55 M_B_CPU1_SA_DQS_DP<4> @S9S_MB_2U_LIB.S9S_MB_2U(SCH_1):M_B_CPU1_SA_DQS_DP(4)    I91 @S9S_MB_2U_LIB.S9S_MB_2U(SCH_1):PAGE52
   U58 M_B_CPU1_SA_DQS_DP<3> @S9S_MB_2U_LIB.S9S_MB_2U(SCH_1):M_B_CPU1_SA_DQS_DP(3)    I91 @S9S_MB_2U_LIB.S9S_MB_2U(SCH_1):PAGE52
   K61 M_B_CPU1_SA_DQS_DP<2> @S9S_MB_2U_LIB.S9S_MB_2U(SCH_1):M_B_CPU1_SA_DQS_DP(2)    I91 @S9S_MB_2U_LIB.S9S_MB_2U(SCH_1):PAGE52
   U70 M_B_CPU1_SA_DQS_DP<1> @S9S_MB_2U_LIB.S9S_MB_2U(SCH_1):M_B_CPU1_SA_DQS_DP(1)    I91 @S9S_MB_2U_LIB.S9S_MB_2U(SCH_1):PAGE52
   K73 M_B_CPU1_SA_DQS_DP<0> @S9S_MB_2U_LIB.S9S_MB_2U(SCH_1):M_B_CPU1_SA_DQS_DP(0)    I91 @S9S_MB_2U_LIB.S9S_MB_2U(SCH_1):PAGE52
   M53 M_B_CPU1_SA_CB<7> @S9S_MB_2U_LIB.S9S_MB_2U(SCH_1):M_B_CPU1_SA_CB(7)    I91 @S9S_MB_2U_LIB.S9S_MB_2U(SCH_1):PAGE52
   N54 M_B_CPU1_SA_CB<6> @S9S_MB_2U_LIB.S9S_MB_2U(SCH_1):M_B_CPU1_SA_CB(6)    I91 @S9S_MB_2U_LIB.S9S_MB_2U(SCH_1):PAGE52
   K53 M_B_CPU1_SA_CB<5> @S9S_MB_2U_LIB.S9S_MB_2U(SCH_1):M_B_CPU1_SA_CB(5)    I91 @S9S_MB_2U_LIB.S9S_MB_2U(SCH_1):PAGE52
   J54 M_B_CPU1_SA_CB<4> @S9S_MB_2U_LIB.S9S_MB_2U(SCH_1):M_B_CPU1_SA_CB(4)    I91 @S9S_MB_2U_LIB.S9S_MB_2U(SCH_1):PAGE52
   N56 M_B_CPU1_SA_CB<3> @S9S_MB_2U_LIB.S9S_MB_2U(SCH_1):M_B_CPU1_SA_CB(3)    I91 @S9S_MB_2U_LIB.S9S_MB_2U(SCH_1):PAGE52
   M57 M_B_CPU1_SA_CB<2> @S9S_MB_2U_LIB.S9S_MB_2U(SCH_1):M_B_CPU1_SA_CB(2)    I91 @S9S_MB_2U_LIB.S9S_MB_2U(SCH_1):PAGE52
   J56 M_B_CPU1_SA_CB<1> @S9S_MB_2U_LIB.S9S_MB_2U(SCH_1):M_B_CPU1_SA_CB(1)    I91 @S9S_MB_2U_LIB.S9S_MB_2U(SCH_1):PAGE52
   K57 M_B_CPU1_SA_CB<0> @S9S_MB_2U_LIB.S9S_MB_2U(SCH_1):M_B_CPU1_SA_CB(0)    I91 @S9S_MB_2U_LIB.S9S_MB_2U(SCH_1):PAGE52
   W43 M_B_CPU1_SA_PAR @S9S_MB_2U_LIB.S9S_MB_2U(SCH_1):M_B_CPU1_SA_PAR    I91 @S9S_MB_2U_LIB.S9S_MB_2U(SCH_1):PAGE52
   H42 M_B_CPU1_SB_CA<6> @S9S_MB_2U_LIB.S9S_MB_2U(SCH_1):M_B_CPU1_SB_CA(6)    I91 @S9S_MB_2U_LIB.S9S_MB_2U(SCH_1):PAGE52
   N43 M_B_CPU1_SB_CA<5> @S9S_MB_2U_LIB.S9S_MB_2U(SCH_1):M_B_CPU1_SB_CA(5)    I91 @S9S_MB_2U_LIB.S9S_MB_2U(SCH_1):PAGE52
   J43 M_B_CPU1_SB_CA<4> @S9S_MB_2U_LIB.S9S_MB_2U(SCH_1):M_B_CPU1_SB_CA(4)    I91 @S9S_MB_2U_LIB.S9S_MB_2U(SCH_1):PAGE52
   M44 M_B_CPU1_SB_CA<3> @S9S_MB_2U_LIB.S9S_MB_2U(SCH_1):M_B_CPU1_SB_CA(3)    I91 @S9S_MB_2U_LIB.S9S_MB_2U(SCH_1):PAGE52
   K44 M_B_CPU1_SB_CA<2> @S9S_MB_2U_LIB.S9S_MB_2U(SCH_1):M_B_CPU1_SB_CA(2)    I91 @S9S_MB_2U_LIB.S9S_MB_2U(SCH_1):PAGE52
   U43 M_B_CPU1_SB_CA<1> @S9S_MB_2U_LIB.S9S_MB_2U(SCH_1):M_B_CPU1_SB_CA(1)    I91 @S9S_MB_2U_LIB.S9S_MB_2U(SCH_1):PAGE52
   T44 M_B_CPU1_SB_CA<0> @S9S_MB_2U_LIB.S9S_MB_2U(SCH_1):M_B_CPU1_SB_CA(0)    I91 @S9S_MB_2U_LIB.S9S_MB_2U(SCH_1):PAGE52
   M40 M_B_CPU1_SB_CS_N<3> @S9S_MB_2U_LIB.S9S_MB_2U(SCH_1):M_B_CPU1_SB_CS_N(3)    I91 @S9S_MB_2U_LIB.S9S_MB_2U(SCH_1):PAGE52
   N41 M_B_CPU1_SB_CS_N<2> @S9S_MB_2U_LIB.S9S_MB_2U(SCH_1):M_B_CPU1_SB_CS_N(2)    I91 @S9S_MB_2U_LIB.S9S_MB_2U(SCH_1):PAGE52
   K40 M_B_CPU1_SB_CS_N<1> @S9S_MB_2U_LIB.S9S_MB_2U(SCH_1):M_B_CPU1_SB_CS_N(1)    I91 @S9S_MB_2U_LIB.S9S_MB_2U(SCH_1):PAGE52
   J41 M_B_CPU1_SB_CS_N<0> @S9S_MB_2U_LIB.S9S_MB_2U(SCH_1):M_B_CPU1_SB_CS_N(0)    I91 @S9S_MB_2U_LIB.S9S_MB_2U(SCH_1):PAGE52
   F14 M_B_CPU1_SB_DQ<31> @S9S_MB_2U_LIB.S9S_MB_2U(SCH_1):M_B_CPU1_SB_DQ(31)    I91 @S9S_MB_2U_LIB.S9S_MB_2U(SCH_1):PAGE52
   B14 M_B_CPU1_SB_DQ<30> @S9S_MB_2U_LIB.S9S_MB_2U(SCH_1):M_B_CPU1_SB_DQ(30)    I91 @S9S_MB_2U_LIB.S9S_MB_2U(SCH_1):PAGE52
   E13 M_B_CPU1_SB_DQ<29> @S9S_MB_2U_LIB.S9S_MB_2U(SCH_1):M_B_CPU1_SB_DQ(29)    I91 @S9S_MB_2U_LIB.S9S_MB_2U(SCH_1):PAGE52
   C13 M_B_CPU1_SB_DQ<28> @S9S_MB_2U_LIB.S9S_MB_2U(SCH_1):M_B_CPU1_SB_DQ(28)    I91 @S9S_MB_2U_LIB.S9S_MB_2U(SCH_1):PAGE52
   F16 M_B_CPU1_SB_DQ<27> @S9S_MB_2U_LIB.S9S_MB_2U(SCH_1):M_B_CPU1_SB_DQ(27)    I91 @S9S_MB_2U_LIB.S9S_MB_2U(SCH_1):PAGE52
   E17 M_B_CPU1_SB_DQ<26> @S9S_MB_2U_LIB.S9S_MB_2U(SCH_1):M_B_CPU1_SB_DQ(26)    I91 @S9S_MB_2U_LIB.S9S_MB_2U(SCH_1):PAGE52
   B16 M_B_CPU1_SB_DQ<25> @S9S_MB_2U_LIB.S9S_MB_2U(SCH_1):M_B_CPU1_SB_DQ(25)    I91 @S9S_MB_2U_LIB.S9S_MB_2U(SCH_1):PAGE52
   C17 M_B_CPU1_SB_DQ<24> @S9S_MB_2U_LIB.S9S_MB_2U(SCH_1):M_B_CPU1_SB_DQ(24)    I91 @S9S_MB_2U_LIB.S9S_MB_2U(SCH_1):PAGE52
   M16 M_B_CPU1_SB_DQ<23> @S9S_MB_2U_LIB.S9S_MB_2U(SCH_1):M_B_CPU1_SB_DQ(23)    I91 @S9S_MB_2U_LIB.S9S_MB_2U(SCH_1):PAGE52
   N17 M_B_CPU1_SB_DQ<22> @S9S_MB_2U_LIB.S9S_MB_2U(SCH_1):M_B_CPU1_SB_DQ(22)    I91 @S9S_MB_2U_LIB.S9S_MB_2U(SCH_1):PAGE52
   K16 M_B_CPU1_SB_DQ<21> @S9S_MB_2U_LIB.S9S_MB_2U(SCH_1):M_B_CPU1_SB_DQ(21)    I91 @S9S_MB_2U_LIB.S9S_MB_2U(SCH_1):PAGE52
   J17 M_B_CPU1_SB_DQ<20> @S9S_MB_2U_LIB.S9S_MB_2U(SCH_1):M_B_CPU1_SB_DQ(20)    I91 @S9S_MB_2U_LIB.S9S_MB_2U(SCH_1):PAGE52
   N19 M_B_CPU1_SB_DQ<19> @S9S_MB_2U_LIB.S9S_MB_2U(SCH_1):M_B_CPU1_SB_DQ(19)    I91 @S9S_MB_2U_LIB.S9S_MB_2U(SCH_1):PAGE52
   M20 M_B_CPU1_SB_DQ<18> @S9S_MB_2U_LIB.S9S_MB_2U(SCH_1):M_B_CPU1_SB_DQ(18)    I91 @S9S_MB_2U_LIB.S9S_MB_2U(SCH_1):PAGE52
   J19 M_B_CPU1_SB_DQ<17> @S9S_MB_2U_LIB.S9S_MB_2U(SCH_1):M_B_CPU1_SB_DQ(17)    I91 @S9S_MB_2U_LIB.S9S_MB_2U(SCH_1):PAGE52
   K20 M_B_CPU1_SB_DQ<16> @S9S_MB_2U_LIB.S9S_MB_2U(SCH_1):M_B_CPU1_SB_DQ(16)    I91 @S9S_MB_2U_LIB.S9S_MB_2U(SCH_1):PAGE52
   M22 M_B_CPU1_SB_DQ<15> @S9S_MB_2U_LIB.S9S_MB_2U(SCH_1):M_B_CPU1_SB_DQ(15)    I91 @S9S_MB_2U_LIB.S9S_MB_2U(SCH_1):PAGE52
   N23 M_B_CPU1_SB_DQ<14> @S9S_MB_2U_LIB.S9S_MB_2U(SCH_1):M_B_CPU1_SB_DQ(14)    I91 @S9S_MB_2U_LIB.S9S_MB_2U(SCH_1):PAGE52
   K22 M_B_CPU1_SB_DQ<13> @S9S_MB_2U_LIB.S9S_MB_2U(SCH_1):M_B_CPU1_SB_DQ(13)    I91 @S9S_MB_2U_LIB.S9S_MB_2U(SCH_1):PAGE52
   J23 M_B_CPU1_SB_DQ<12> @S9S_MB_2U_LIB.S9S_MB_2U(SCH_1):M_B_CPU1_SB_DQ(12)    I91 @S9S_MB_2U_LIB.S9S_MB_2U(SCH_1):PAGE52
   N25 M_B_CPU1_SB_DQ<11> @S9S_MB_2U_LIB.S9S_MB_2U(SCH_1):M_B_CPU1_SB_DQ(11)    I91 @S9S_MB_2U_LIB.S9S_MB_2U(SCH_1):PAGE52
   M26 M_B_CPU1_SB_DQ<10> @S9S_MB_2U_LIB.S9S_MB_2U(SCH_1):M_B_CPU1_SB_DQ(10)    I91 @S9S_MB_2U_LIB.S9S_MB_2U(SCH_1):PAGE52
   J25 M_B_CPU1_SB_DQ<9> @S9S_MB_2U_LIB.S9S_MB_2U(SCH_1):M_B_CPU1_SB_DQ(9)    I91 @S9S_MB_2U_LIB.S9S_MB_2U(SCH_1):PAGE52
   K26 M_B_CPU1_SB_DQ<8> @S9S_MB_2U_LIB.S9S_MB_2U(SCH_1):M_B_CPU1_SB_DQ(8)    I91 @S9S_MB_2U_LIB.S9S_MB_2U(SCH_1):PAGE52
   W25 M_B_CPU1_SB_DQ<7> @S9S_MB_2U_LIB.S9S_MB_2U(SCH_1):M_B_CPU1_SB_DQ(7)    I91 @S9S_MB_2U_LIB.S9S_MB_2U(SCH_1):PAGE52
   Y26 M_B_CPU1_SB_DQ<6> @S9S_MB_2U_LIB.S9S_MB_2U(SCH_1):M_B_CPU1_SB_DQ(6)    I91 @S9S_MB_2U_LIB.S9S_MB_2U(SCH_1):PAGE52
   U25 M_B_CPU1_SB_DQ<5> @S9S_MB_2U_LIB.S9S_MB_2U(SCH_1):M_B_CPU1_SB_DQ(5)    I91 @S9S_MB_2U_LIB.S9S_MB_2U(SCH_1):PAGE52
   T26 M_B_CPU1_SB_DQ<4> @S9S_MB_2U_LIB.S9S_MB_2U(SCH_1):M_B_CPU1_SB_DQ(4)    I91 @S9S_MB_2U_LIB.S9S_MB_2U(SCH_1):PAGE52
   Y28 M_B_CPU1_SB_DQ<3> @S9S_MB_2U_LIB.S9S_MB_2U(SCH_1):M_B_CPU1_SB_DQ(3)    I91 @S9S_MB_2U_LIB.S9S_MB_2U(SCH_1):PAGE52
   W29 M_B_CPU1_SB_DQ<2> @S9S_MB_2U_LIB.S9S_MB_2U(SCH_1):M_B_CPU1_SB_DQ(2)    I91 @S9S_MB_2U_LIB.S9S_MB_2U(SCH_1):PAGE52
   T28 M_B_CPU1_SB_DQ<1> @S9S_MB_2U_LIB.S9S_MB_2U(SCH_1):M_B_CPU1_SB_DQ(1)    I91 @S9S_MB_2U_LIB.S9S_MB_2U(SCH_1):PAGE52
   U29 M_B_CPU1_SB_DQ<0> @S9S_MB_2U_LIB.S9S_MB_2U(SCH_1):M_B_CPU1_SB_DQ(0)    I91 @S9S_MB_2U_LIB.S9S_MB_2U(SCH_1):PAGE52
   K36 M_B_CPU1_SB_DQS_DN<9> @S9S_MB_2U_LIB.S9S_MB_2U(SCH_1):M_B_CPU1_SB_DQS_DN(9)    I91 @S9S_MB_2U_LIB.S9S_MB_2U(SCH_1):PAGE52
   E15 M_B_CPU1_SB_DQS_DN<8> @S9S_MB_2U_LIB.S9S_MB_2U(SCH_1):M_B_CPU1_SB_DQS_DN(8)    I91 @S9S_MB_2U_LIB.S9S_MB_2U(SCH_1):PAGE52
   M18 M_B_CPU1_SB_DQS_DN<7> @S9S_MB_2U_LIB.S9S_MB_2U(SCH_1):M_B_CPU1_SB_DQS_DN(7)    I91 @S9S_MB_2U_LIB.S9S_MB_2U(SCH_1):PAGE52
   M24 M_B_CPU1_SB_DQS_DN<6> @S9S_MB_2U_LIB.S9S_MB_2U(SCH_1):M_B_CPU1_SB_DQS_DN(6)    I91 @S9S_MB_2U_LIB.S9S_MB_2U(SCH_1):PAGE52
   W27 M_B_CPU1_SB_DQS_DN<5> @S9S_MB_2U_LIB.S9S_MB_2U(SCH_1):M_B_CPU1_SB_DQS_DN(5)    I91 @S9S_MB_2U_LIB.S9S_MB_2U(SCH_1):PAGE52
   P36 M_B_CPU1_SB_DQS_DN<4> @S9S_MB_2U_LIB.S9S_MB_2U(SCH_1):M_B_CPU1_SB_DQS_DN(4)    I91 @S9S_MB_2U_LIB.S9S_MB_2U(SCH_1):PAGE52
   A15 M_B_CPU1_SB_DQS_DN<3> @S9S_MB_2U_LIB.S9S_MB_2U(SCH_1):M_B_CPU1_SB_DQS_DN(3)    I91 @S9S_MB_2U_LIB.S9S_MB_2U(SCH_1):PAGE52
   H18 M_B_CPU1_SB_DQS_DN<2> @S9S_MB_2U_LIB.S9S_MB_2U(SCH_1):M_B_CPU1_SB_DQS_DN(2)    I91 @S9S_MB_2U_LIB.S9S_MB_2U(SCH_1):PAGE52
   H24 M_B_CPU1_SB_DQS_DN<1> @S9S_MB_2U_LIB.S9S_MB_2U(SCH_1):M_B_CPU1_SB_DQS_DN(1)    I91 @S9S_MB_2U_LIB.S9S_MB_2U(SCH_1):PAGE52
   R27 M_B_CPU1_SB_DQS_DN<0> @S9S_MB_2U_LIB.S9S_MB_2U(SCH_1):M_B_CPU1_SB_DQS_DN(0)    I91 @S9S_MB_2U_LIB.S9S_MB_2U(SCH_1):PAGE52
   H36 M_B_CPU1_SB_DQS_DP<9> @S9S_MB_2U_LIB.S9S_MB_2U(SCH_1):M_B_CPU1_SB_DQS_DP(9)    I91 @S9S_MB_2U_LIB.S9S_MB_2U(SCH_1):PAGE52
   G15 M_B_CPU1_SB_DQS_DP<8> @S9S_MB_2U_LIB.S9S_MB_2U(SCH_1):M_B_CPU1_SB_DQS_DP(8)    I91 @S9S_MB_2U_LIB.S9S_MB_2U(SCH_1):PAGE52
   P18 M_B_CPU1_SB_DQS_DP<7> @S9S_MB_2U_LIB.S9S_MB_2U(SCH_1):M_B_CPU1_SB_DQS_DP(7)    I91 @S9S_MB_2U_LIB.S9S_MB_2U(SCH_1):PAGE52
   P24 M_B_CPU1_SB_DQS_DP<6> @S9S_MB_2U_LIB.S9S_MB_2U(SCH_1):M_B_CPU1_SB_DQS_DP(6)    I91 @S9S_MB_2U_LIB.S9S_MB_2U(SCH_1):PAGE52
  AA27 M_B_CPU1_SB_DQS_DP<5> @S9S_MB_2U_LIB.S9S_MB_2U(SCH_1):M_B_CPU1_SB_DQS_DP(5)    I91 @S9S_MB_2U_LIB.S9S_MB_2U(SCH_1):PAGE52
   M36 M_B_CPU1_SB_DQS_DP<4> @S9S_MB_2U_LIB.S9S_MB_2U(SCH_1):M_B_CPU1_SB_DQS_DP(4)    I91 @S9S_MB_2U_LIB.S9S_MB_2U(SCH_1):PAGE52
   C15 M_B_CPU1_SB_DQS_DP<3> @S9S_MB_2U_LIB.S9S_MB_2U(SCH_1):M_B_CPU1_SB_DQS_DP(3)    I91 @S9S_MB_2U_LIB.S9S_MB_2U(SCH_1):PAGE52
   K18 M_B_CPU1_SB_DQS_DP<2> @S9S_MB_2U_LIB.S9S_MB_2U(SCH_1):M_B_CPU1_SB_DQS_DP(2)    I91 @S9S_MB_2U_LIB.S9S_MB_2U(SCH_1):PAGE52
   K24 M_B_CPU1_SB_DQS_DP<1> @S9S_MB_2U_LIB.S9S_MB_2U(SCH_1):M_B_CPU1_SB_DQS_DP(1)    I91 @S9S_MB_2U_LIB.S9S_MB_2U(SCH_1):PAGE52
   U27 M_B_CPU1_SB_DQS_DP<0> @S9S_MB_2U_LIB.S9S_MB_2U(SCH_1):M_B_CPU1_SB_DQS_DP(0)    I91 @S9S_MB_2U_LIB.S9S_MB_2U(SCH_1):PAGE52
   N37 M_B_CPU1_SB_CB<7> @S9S_MB_2U_LIB.S9S_MB_2U(SCH_1):M_B_CPU1_SB_CB(7)    I91 @S9S_MB_2U_LIB.S9S_MB_2U(SCH_1):PAGE52
   M38 M_B_CPU1_SB_CB<6> @S9S_MB_2U_LIB.S9S_MB_2U(SCH_1):M_B_CPU1_SB_CB(6)    I91 @S9S_MB_2U_LIB.S9S_MB_2U(SCH_1):PAGE52
   J37 M_B_CPU1_SB_CB<5> @S9S_MB_2U_LIB.S9S_MB_2U(SCH_1):M_B_CPU1_SB_CB(5)    I91 @S9S_MB_2U_LIB.S9S_MB_2U(SCH_1):PAGE52
   K38 M_B_CPU1_SB_CB<4> @S9S_MB_2U_LIB.S9S_MB_2U(SCH_1):M_B_CPU1_SB_CB(4)    I91 @S9S_MB_2U_LIB.S9S_MB_2U(SCH_1):PAGE52
   M34 M_B_CPU1_SB_CB<3> @S9S_MB_2U_LIB.S9S_MB_2U(SCH_1):M_B_CPU1_SB_CB(3)    I91 @S9S_MB_2U_LIB.S9S_MB_2U(SCH_1):PAGE52
   N35 M_B_CPU1_SB_CB<2> @S9S_MB_2U_LIB.S9S_MB_2U(SCH_1):M_B_CPU1_SB_CB(2)    I91 @S9S_MB_2U_LIB.S9S_MB_2U(SCH_1):PAGE52
   K34 M_B_CPU1_SB_CB<1> @S9S_MB_2U_LIB.S9S_MB_2U(SCH_1):M_B_CPU1_SB_CB(1)    I91 @S9S_MB_2U_LIB.S9S_MB_2U(SCH_1):PAGE52
   J35 M_B_CPU1_SB_CB<0> @S9S_MB_2U_LIB.S9S_MB_2U(SCH_1):M_B_CPU1_SB_CB(0)    I91 @S9S_MB_2U_LIB.S9S_MB_2U(SCH_1):PAGE52
   P42 M_B_CPU1_SB_PAR @S9S_MB_2U_LIB.S9S_MB_2U(SCH_1):M_B_CPU1_SB_PAR    I91 @S9S_MB_2U_LIB.S9S_MB_2U(SCH_1):PAGE52
  AT47 M_C_CPU1_ALERT_N @S9S_MB_2U_LIB.S9S_MB_2U(SCH_1):M_C_CPU1_ALERT_N    I91 @S9S_MB_2U_LIB.S9S_MB_2U(SCH_1):PAGE53
  AD47 M_C_CPU1_SA_RSP<1> @S9S_MB_2U_LIB.S9S_MB_2U(SCH_1):M_C_CPU1_SA_RSP(1)    I91 @S9S_MB_2U_LIB.S9S_MB_2U(SCH_1):PAGE53
  AC48 M_C_CPU1_SA_RSP<0> @S9S_MB_2U_LIB.S9S_MB_2U(SCH_1):M_C_CPU1_SA_RSP(0)    I91 @S9S_MB_2U_LIB.S9S_MB_2U(SCH_1):PAGE53
  AF47 M_C_CPU1_SB_RSP<1> @S9S_MB_2U_LIB.S9S_MB_2U(SCH_1):M_C_CPU1_SB_RSP(1)    I91 @S9S_MB_2U_LIB.S9S_MB_2U(SCH_1):PAGE53
  AG48 M_C_CPU1_SB_RSP<0> @S9S_MB_2U_LIB.S9S_MB_2U(SCH_1):M_C_CPU1_SB_RSP(0)    I91 @S9S_MB_2U_LIB.S9S_MB_2U(SCH_1):PAGE53
  AF49 M_C_CPU1_CLK_DN<1> @S9S_MB_2U_LIB.S9S_MB_2U(SCH_1):M_C_CPU1_CLK_DN(1)    I91 @S9S_MB_2U_LIB.S9S_MB_2U(SCH_1):PAGE53
  AB49 M_C_CPU1_CLK_DN<0> @S9S_MB_2U_LIB.S9S_MB_2U(SCH_1):M_C_CPU1_CLK_DN(0)    I91 @S9S_MB_2U_LIB.S9S_MB_2U(SCH_1):PAGE53
  AH49 M_C_CPU1_CLK_DP<1> @S9S_MB_2U_LIB.S9S_MB_2U(SCH_1):M_C_CPU1_CLK_DP(1)    I91 @S9S_MB_2U_LIB.S9S_MB_2U(SCH_1):PAGE53
  AD49 M_C_CPU1_CLK_DP<0> @S9S_MB_2U_LIB.S9S_MB_2U(SCH_1):M_C_CPU1_CLK_DP(0)    I91 @S9S_MB_2U_LIB.S9S_MB_2U(SCH_1):PAGE53
   U48 M_C_CPU1_SA_CA<6> @S9S_MB_2U_LIB.S9S_MB_2U(SCH_1):M_C_CPU1_SA_CA(6)    I91 @S9S_MB_2U_LIB.S9S_MB_2U(SCH_1):PAGE53
   W50 M_C_CPU1_SA_CA<5> @S9S_MB_2U_LIB.S9S_MB_2U(SCH_1):M_C_CPU1_SA_CA(5)    I91 @S9S_MB_2U_LIB.S9S_MB_2U(SCH_1):PAGE53
   U50 M_C_CPU1_SA_CA<4> @S9S_MB_2U_LIB.S9S_MB_2U(SCH_1):M_C_CPU1_SA_CA(4)    I91 @S9S_MB_2U_LIB.S9S_MB_2U(SCH_1):PAGE53
   Y51 M_C_CPU1_SA_CA<3> @S9S_MB_2U_LIB.S9S_MB_2U(SCH_1):M_C_CPU1_SA_CA(3)    I91 @S9S_MB_2U_LIB.S9S_MB_2U(SCH_1):PAGE53
   T51 M_C_CPU1_SA_CA<2> @S9S_MB_2U_LIB.S9S_MB_2U(SCH_1):M_C_CPU1_SA_CA(2)    I91 @S9S_MB_2U_LIB.S9S_MB_2U(SCH_1):PAGE53
  AA52 M_C_CPU1_SA_CA<1> @S9S_MB_2U_LIB.S9S_MB_2U(SCH_1):M_C_CPU1_SA_CA(1)    I91 @S9S_MB_2U_LIB.S9S_MB_2U(SCH_1):PAGE53
   R52 M_C_CPU1_SA_CA<0> @S9S_MB_2U_LIB.S9S_MB_2U(SCH_1):M_C_CPU1_SA_CA(0)    I91 @S9S_MB_2U_LIB.S9S_MB_2U(SCH_1):PAGE53
   Y53 M_C_CPU1_SA_CS_N<3> @S9S_MB_2U_LIB.S9S_MB_2U(SCH_1):M_C_CPU1_SA_CS_N(3)    I91 @S9S_MB_2U_LIB.S9S_MB_2U(SCH_1):PAGE53
   W54 M_C_CPU1_SA_CS_N<2> @S9S_MB_2U_LIB.S9S_MB_2U(SCH_1):M_C_CPU1_SA_CS_N(2)    I91 @S9S_MB_2U_LIB.S9S_MB_2U(SCH_1):PAGE53
   T53 M_C_CPU1_SA_CS_N<1> @S9S_MB_2U_LIB.S9S_MB_2U(SCH_1):M_C_CPU1_SA_CS_N(1)    I91 @S9S_MB_2U_LIB.S9S_MB_2U(SCH_1):PAGE53
   U54 M_C_CPU1_SA_CS_N<0> @S9S_MB_2U_LIB.S9S_MB_2U(SCH_1):M_C_CPU1_SA_CS_N(0)    I91 @S9S_MB_2U_LIB.S9S_MB_2U(SCH_1):PAGE53
  AF59 M_C_CPU1_SA_DQ<31> @S9S_MB_2U_LIB.S9S_MB_2U(SCH_1):M_C_CPU1_SA_DQ(31)    I91 @S9S_MB_2U_LIB.S9S_MB_2U(SCH_1):PAGE53
  AG60 M_C_CPU1_SA_DQ<30> @S9S_MB_2U_LIB.S9S_MB_2U(SCH_1):M_C_CPU1_SA_DQ(30)    I91 @S9S_MB_2U_LIB.S9S_MB_2U(SCH_1):PAGE53
  AD59 M_C_CPU1_SA_DQ<29> @S9S_MB_2U_LIB.S9S_MB_2U(SCH_1):M_C_CPU1_SA_DQ(29)    I91 @S9S_MB_2U_LIB.S9S_MB_2U(SCH_1):PAGE53
  AC60 M_C_CPU1_SA_DQ<28> @S9S_MB_2U_LIB.S9S_MB_2U(SCH_1):M_C_CPU1_SA_DQ(28)    I91 @S9S_MB_2U_LIB.S9S_MB_2U(SCH_1):PAGE53
  AG62 M_C_CPU1_SA_DQ<27> @S9S_MB_2U_LIB.S9S_MB_2U(SCH_1):M_C_CPU1_SA_DQ(27)    I91 @S9S_MB_2U_LIB.S9S_MB_2U(SCH_1):PAGE53
  AF63 M_C_CPU1_SA_DQ<26> @S9S_MB_2U_LIB.S9S_MB_2U(SCH_1):M_C_CPU1_SA_DQ(26)    I91 @S9S_MB_2U_LIB.S9S_MB_2U(SCH_1):PAGE53
  AC62 M_C_CPU1_SA_DQ<25> @S9S_MB_2U_LIB.S9S_MB_2U(SCH_1):M_C_CPU1_SA_DQ(25)    I91 @S9S_MB_2U_LIB.S9S_MB_2U(SCH_1):PAGE53
  AD63 M_C_CPU1_SA_DQ<24> @S9S_MB_2U_LIB.S9S_MB_2U(SCH_1):M_C_CPU1_SA_DQ(24)    I91 @S9S_MB_2U_LIB.S9S_MB_2U(SCH_1):PAGE53
   W62 M_C_CPU1_SA_DQ<23> @S9S_MB_2U_LIB.S9S_MB_2U(SCH_1):M_C_CPU1_SA_DQ(23)    I91 @S9S_MB_2U_LIB.S9S_MB_2U(SCH_1):PAGE53
   Y63 M_C_CPU1_SA_DQ<22> @S9S_MB_2U_LIB.S9S_MB_2U(SCH_1):M_C_CPU1_SA_DQ(22)    I91 @S9S_MB_2U_LIB.S9S_MB_2U(SCH_1):PAGE53
   U62 M_C_CPU1_SA_DQ<21> @S9S_MB_2U_LIB.S9S_MB_2U(SCH_1):M_C_CPU1_SA_DQ(21)    I91 @S9S_MB_2U_LIB.S9S_MB_2U(SCH_1):PAGE53
   T63 M_C_CPU1_SA_DQ<20> @S9S_MB_2U_LIB.S9S_MB_2U(SCH_1):M_C_CPU1_SA_DQ(20)    I91 @S9S_MB_2U_LIB.S9S_MB_2U(SCH_1):PAGE53
   Y65 M_C_CPU1_SA_DQ<19> @S9S_MB_2U_LIB.S9S_MB_2U(SCH_1):M_C_CPU1_SA_DQ(19)    I91 @S9S_MB_2U_LIB.S9S_MB_2U(SCH_1):PAGE53
   W66 M_C_CPU1_SA_DQ<18> @S9S_MB_2U_LIB.S9S_MB_2U(SCH_1):M_C_CPU1_SA_DQ(18)    I91 @S9S_MB_2U_LIB.S9S_MB_2U(SCH_1):PAGE53
   T65 M_C_CPU1_SA_DQ<17> @S9S_MB_2U_LIB.S9S_MB_2U(SCH_1):M_C_CPU1_SA_DQ(17)    I91 @S9S_MB_2U_LIB.S9S_MB_2U(SCH_1):PAGE53
   U66 M_C_CPU1_SA_DQ<16> @S9S_MB_2U_LIB.S9S_MB_2U(SCH_1):M_C_CPU1_SA_DQ(16)    I91 @S9S_MB_2U_LIB.S9S_MB_2U(SCH_1):PAGE53
  AF65 M_C_CPU1_SA_DQ<15> @S9S_MB_2U_LIB.S9S_MB_2U(SCH_1):M_C_CPU1_SA_DQ(15)    I91 @S9S_MB_2U_LIB.S9S_MB_2U(SCH_1):PAGE53
  AG66 M_C_CPU1_SA_DQ<14> @S9S_MB_2U_LIB.S9S_MB_2U(SCH_1):M_C_CPU1_SA_DQ(14)    I91 @S9S_MB_2U_LIB.S9S_MB_2U(SCH_1):PAGE53
  AD65 M_C_CPU1_SA_DQ<13> @S9S_MB_2U_LIB.S9S_MB_2U(SCH_1):M_C_CPU1_SA_DQ(13)    I91 @S9S_MB_2U_LIB.S9S_MB_2U(SCH_1):PAGE53
  AC66 M_C_CPU1_SA_DQ<12> @S9S_MB_2U_LIB.S9S_MB_2U(SCH_1):M_C_CPU1_SA_DQ(12)    I91 @S9S_MB_2U_LIB.S9S_MB_2U(SCH_1):PAGE53
  AG68 M_C_CPU1_SA_DQ<11> @S9S_MB_2U_LIB.S9S_MB_2U(SCH_1):M_C_CPU1_SA_DQ(11)    I91 @S9S_MB_2U_LIB.S9S_MB_2U(SCH_1):PAGE53
  AF69 M_C_CPU1_SA_DQ<10> @S9S_MB_2U_LIB.S9S_MB_2U(SCH_1):M_C_CPU1_SA_DQ(10)    I91 @S9S_MB_2U_LIB.S9S_MB_2U(SCH_1):PAGE53
  AC68 M_C_CPU1_SA_DQ<9> @S9S_MB_2U_LIB.S9S_MB_2U(SCH_1):M_C_CPU1_SA_DQ(9)    I91 @S9S_MB_2U_LIB.S9S_MB_2U(SCH_1):PAGE53
  AD69 M_C_CPU1_SA_DQ<8> @S9S_MB_2U_LIB.S9S_MB_2U(SCH_1):M_C_CPU1_SA_DQ(8)    I91 @S9S_MB_2U_LIB.S9S_MB_2U(SCH_1):PAGE53
   W74 M_C_CPU1_SA_DQ<7> @S9S_MB_2U_LIB.S9S_MB_2U(SCH_1):M_C_CPU1_SA_DQ(7)    I91 @S9S_MB_2U_LIB.S9S_MB_2U(SCH_1):PAGE53
   Y75 M_C_CPU1_SA_DQ<6> @S9S_MB_2U_LIB.S9S_MB_2U(SCH_1):M_C_CPU1_SA_DQ(6)    I91 @S9S_MB_2U_LIB.S9S_MB_2U(SCH_1):PAGE53
   U74 M_C_CPU1_SA_DQ<5> @S9S_MB_2U_LIB.S9S_MB_2U(SCH_1):M_C_CPU1_SA_DQ(5)    I91 @S9S_MB_2U_LIB.S9S_MB_2U(SCH_1):PAGE53
   T75 M_C_CPU1_SA_DQ<4> @S9S_MB_2U_LIB.S9S_MB_2U(SCH_1):M_C_CPU1_SA_DQ(4)    I91 @S9S_MB_2U_LIB.S9S_MB_2U(SCH_1):PAGE53
   Y77 M_C_CPU1_SA_DQ<3> @S9S_MB_2U_LIB.S9S_MB_2U(SCH_1):M_C_CPU1_SA_DQ(3)    I91 @S9S_MB_2U_LIB.S9S_MB_2U(SCH_1):PAGE53
   W78 M_C_CPU1_SA_DQ<2> @S9S_MB_2U_LIB.S9S_MB_2U(SCH_1):M_C_CPU1_SA_DQ(2)    I91 @S9S_MB_2U_LIB.S9S_MB_2U(SCH_1):PAGE53
   T77 M_C_CPU1_SA_DQ<1> @S9S_MB_2U_LIB.S9S_MB_2U(SCH_1):M_C_CPU1_SA_DQ(1)    I91 @S9S_MB_2U_LIB.S9S_MB_2U(SCH_1):PAGE53
   U78 M_C_CPU1_SA_DQ<0> @S9S_MB_2U_LIB.S9S_MB_2U(SCH_1):M_C_CPU1_SA_DQ(0)    I91 @S9S_MB_2U_LIB.S9S_MB_2U(SCH_1):PAGE53
  AH55 M_C_CPU1_SA_DQS_DN<9> @S9S_MB_2U_LIB.S9S_MB_2U(SCH_1):M_C_CPU1_SA_DQS_DN(9)    I91 @S9S_MB_2U_LIB.S9S_MB_2U(SCH_1):PAGE53
  AF61 M_C_CPU1_SA_DQS_DN<8> @S9S_MB_2U_LIB.S9S_MB_2U(SCH_1):M_C_CPU1_SA_DQS_DN(8)    I91 @S9S_MB_2U_LIB.S9S_MB_2U(SCH_1):PAGE53
  AA64 M_C_CPU1_SA_DQS_DN<7> @S9S_MB_2U_LIB.S9S_MB_2U(SCH_1):M_C_CPU1_SA_DQS_DN(7)    I91 @S9S_MB_2U_LIB.S9S_MB_2U(SCH_1):PAGE53
  AH67 M_C_CPU1_SA_DQS_DN<6> @S9S_MB_2U_LIB.S9S_MB_2U(SCH_1):M_C_CPU1_SA_DQS_DN(6)    I91 @S9S_MB_2U_LIB.S9S_MB_2U(SCH_1):PAGE53
   W76 M_C_CPU1_SA_DQS_DN<5> @S9S_MB_2U_LIB.S9S_MB_2U(SCH_1):M_C_CPU1_SA_DQS_DN(5)    I91 @S9S_MB_2U_LIB.S9S_MB_2U(SCH_1):PAGE53
  AD55 M_C_CPU1_SA_DQS_DN<4> @S9S_MB_2U_LIB.S9S_MB_2U(SCH_1):M_C_CPU1_SA_DQS_DN(4)    I91 @S9S_MB_2U_LIB.S9S_MB_2U(SCH_1):PAGE53
  AB61 M_C_CPU1_SA_DQS_DN<3> @S9S_MB_2U_LIB.S9S_MB_2U(SCH_1):M_C_CPU1_SA_DQS_DN(3)    I91 @S9S_MB_2U_LIB.S9S_MB_2U(SCH_1):PAGE53
   R64 M_C_CPU1_SA_DQS_DN<2> @S9S_MB_2U_LIB.S9S_MB_2U(SCH_1):M_C_CPU1_SA_DQS_DN(2)    I91 @S9S_MB_2U_LIB.S9S_MB_2U(SCH_1):PAGE53
  AB67 M_C_CPU1_SA_DQS_DN<1> @S9S_MB_2U_LIB.S9S_MB_2U(SCH_1):M_C_CPU1_SA_DQS_DN(1)    I91 @S9S_MB_2U_LIB.S9S_MB_2U(SCH_1):PAGE53
   R76 M_C_CPU1_SA_DQS_DN<0> @S9S_MB_2U_LIB.S9S_MB_2U(SCH_1):M_C_CPU1_SA_DQS_DN(0)    I91 @S9S_MB_2U_LIB.S9S_MB_2U(SCH_1):PAGE53
  AF55 M_C_CPU1_SA_DQS_DP<9> @S9S_MB_2U_LIB.S9S_MB_2U(SCH_1):M_C_CPU1_SA_DQS_DP(9)    I91 @S9S_MB_2U_LIB.S9S_MB_2U(SCH_1):PAGE53
  AH61 M_C_CPU1_SA_DQS_DP<8> @S9S_MB_2U_LIB.S9S_MB_2U(SCH_1):M_C_CPU1_SA_DQS_DP(8)    I91 @S9S_MB_2U_LIB.S9S_MB_2U(SCH_1):PAGE53
   W64 M_C_CPU1_SA_DQS_DP<7> @S9S_MB_2U_LIB.S9S_MB_2U(SCH_1):M_C_CPU1_SA_DQS_DP(7)    I91 @S9S_MB_2U_LIB.S9S_MB_2U(SCH_1):PAGE53
  AF67 M_C_CPU1_SA_DQS_DP<6> @S9S_MB_2U_LIB.S9S_MB_2U(SCH_1):M_C_CPU1_SA_DQS_DP(6)    I91 @S9S_MB_2U_LIB.S9S_MB_2U(SCH_1):PAGE53
  AA76 M_C_CPU1_SA_DQS_DP<5> @S9S_MB_2U_LIB.S9S_MB_2U(SCH_1):M_C_CPU1_SA_DQS_DP(5)    I91 @S9S_MB_2U_LIB.S9S_MB_2U(SCH_1):PAGE53
  AB55 M_C_CPU1_SA_DQS_DP<4> @S9S_MB_2U_LIB.S9S_MB_2U(SCH_1):M_C_CPU1_SA_DQS_DP(4)    I91 @S9S_MB_2U_LIB.S9S_MB_2U(SCH_1):PAGE53
  AD61 M_C_CPU1_SA_DQS_DP<3> @S9S_MB_2U_LIB.S9S_MB_2U(SCH_1):M_C_CPU1_SA_DQS_DP(3)    I91 @S9S_MB_2U_LIB.S9S_MB_2U(SCH_1):PAGE53
   U64 M_C_CPU1_SA_DQS_DP<2> @S9S_MB_2U_LIB.S9S_MB_2U(SCH_1):M_C_CPU1_SA_DQS_DP(2)    I91 @S9S_MB_2U_LIB.S9S_MB_2U(SCH_1):PAGE53
  AD67 M_C_CPU1_SA_DQS_DP<1> @S9S_MB_2U_LIB.S9S_MB_2U(SCH_1):M_C_CPU1_SA_DQS_DP(1)    I91 @S9S_MB_2U_LIB.S9S_MB_2U(SCH_1):PAGE53
   U76 M_C_CPU1_SA_DQS_DP<0> @S9S_MB_2U_LIB.S9S_MB_2U(SCH_1):M_C_CPU1_SA_DQS_DP(0)    I91 @S9S_MB_2U_LIB.S9S_MB_2U(SCH_1):PAGE53
  AF53 M_C_CPU1_SA_CB<7> @S9S_MB_2U_LIB.S9S_MB_2U(SCH_1):M_C_CPU1_SA_CB(7)    I91 @S9S_MB_2U_LIB.S9S_MB_2U(SCH_1):PAGE53
  AG54 M_C_CPU1_SA_CB<6> @S9S_MB_2U_LIB.S9S_MB_2U(SCH_1):M_C_CPU1_SA_CB(6)    I91 @S9S_MB_2U_LIB.S9S_MB_2U(SCH_1):PAGE53
  AD53 M_C_CPU1_SA_CB<5> @S9S_MB_2U_LIB.S9S_MB_2U(SCH_1):M_C_CPU1_SA_CB(5)    I91 @S9S_MB_2U_LIB.S9S_MB_2U(SCH_1):PAGE53
  AC54 M_C_CPU1_SA_CB<4> @S9S_MB_2U_LIB.S9S_MB_2U(SCH_1):M_C_CPU1_SA_CB(4)    I91 @S9S_MB_2U_LIB.S9S_MB_2U(SCH_1):PAGE53
  AG56 M_C_CPU1_SA_CB<3> @S9S_MB_2U_LIB.S9S_MB_2U(SCH_1):M_C_CPU1_SA_CB(3)    I91 @S9S_MB_2U_LIB.S9S_MB_2U(SCH_1):PAGE53
  AF57 M_C_CPU1_SA_CB<2> @S9S_MB_2U_LIB.S9S_MB_2U(SCH_1):M_C_CPU1_SA_CB(2)    I91 @S9S_MB_2U_LIB.S9S_MB_2U(SCH_1):PAGE53
  AC56 M_C_CPU1_SA_CB<1> @S9S_MB_2U_LIB.S9S_MB_2U(SCH_1):M_C_CPU1_SA_CB(1)    I91 @S9S_MB_2U_LIB.S9S_MB_2U(SCH_1):PAGE53
  AD57 M_C_CPU1_SA_CB<0> @S9S_MB_2U_LIB.S9S_MB_2U(SCH_1):M_C_CPU1_SA_CB(0)    I91 @S9S_MB_2U_LIB.S9S_MB_2U(SCH_1):PAGE53
   T47 M_C_CPU1_SA_PAR @S9S_MB_2U_LIB.S9S_MB_2U(SCH_1):M_C_CPU1_SA_PAR    I91 @S9S_MB_2U_LIB.S9S_MB_2U(SCH_1):PAGE53
   R39 M_C_CPU1_SB_CA<6> @S9S_MB_2U_LIB.S9S_MB_2U(SCH_1):M_C_CPU1_SB_CA(6)    I91 @S9S_MB_2U_LIB.S9S_MB_2U(SCH_1):PAGE53
   Y40 M_C_CPU1_SB_CA<5> @S9S_MB_2U_LIB.S9S_MB_2U(SCH_1):M_C_CPU1_SB_CA(5)    I91 @S9S_MB_2U_LIB.S9S_MB_2U(SCH_1):PAGE53
   T40 M_C_CPU1_SB_CA<4> @S9S_MB_2U_LIB.S9S_MB_2U(SCH_1):M_C_CPU1_SB_CA(4)    I91 @S9S_MB_2U_LIB.S9S_MB_2U(SCH_1):PAGE53
   W41 M_C_CPU1_SB_CA<3> @S9S_MB_2U_LIB.S9S_MB_2U(SCH_1):M_C_CPU1_SB_CA(3)    I91 @S9S_MB_2U_LIB.S9S_MB_2U(SCH_1):PAGE53
   U41 M_C_CPU1_SB_CA<2> @S9S_MB_2U_LIB.S9S_MB_2U(SCH_1):M_C_CPU1_SB_CA(2)    I91 @S9S_MB_2U_LIB.S9S_MB_2U(SCH_1):PAGE53
   Y47 M_C_CPU1_SB_CA<1> @S9S_MB_2U_LIB.S9S_MB_2U(SCH_1):M_C_CPU1_SB_CA(1)    I91 @S9S_MB_2U_LIB.S9S_MB_2U(SCH_1):PAGE53
   W48 M_C_CPU1_SB_CA<0> @S9S_MB_2U_LIB.S9S_MB_2U(SCH_1):M_C_CPU1_SB_CA(0)    I91 @S9S_MB_2U_LIB.S9S_MB_2U(SCH_1):PAGE53
   W37 M_C_CPU1_SB_CS_N<3> @S9S_MB_2U_LIB.S9S_MB_2U(SCH_1):M_C_CPU1_SB_CS_N(3)    I91 @S9S_MB_2U_LIB.S9S_MB_2U(SCH_1):PAGE53
   Y38 M_C_CPU1_SB_CS_N<2> @S9S_MB_2U_LIB.S9S_MB_2U(SCH_1):M_C_CPU1_SB_CS_N(2)    I91 @S9S_MB_2U_LIB.S9S_MB_2U(SCH_1):PAGE53
   U37 M_C_CPU1_SB_CS_N<1> @S9S_MB_2U_LIB.S9S_MB_2U(SCH_1):M_C_CPU1_SB_CS_N(1)    I91 @S9S_MB_2U_LIB.S9S_MB_2U(SCH_1):PAGE53
   T38 M_C_CPU1_SB_CS_N<0> @S9S_MB_2U_LIB.S9S_MB_2U(SCH_1):M_C_CPU1_SB_CS_N(0)    I91 @S9S_MB_2U_LIB.S9S_MB_2U(SCH_1):PAGE53
  AJ17 M_C_CPU1_SB_DQ<31> @S9S_MB_2U_LIB.S9S_MB_2U(SCH_1):M_C_CPU1_SB_DQ(31)    I91 @S9S_MB_2U_LIB.S9S_MB_2U(SCH_1):PAGE53
  AC17 M_C_CPU1_SB_DQ<30> @S9S_MB_2U_LIB.S9S_MB_2U(SCH_1):M_C_CPU1_SB_DQ(30)    I91 @S9S_MB_2U_LIB.S9S_MB_2U(SCH_1):PAGE53
  AG17 M_C_CPU1_SB_DQ<29> @S9S_MB_2U_LIB.S9S_MB_2U(SCH_1):M_C_CPU1_SB_DQ(29)    I91 @S9S_MB_2U_LIB.S9S_MB_2U(SCH_1):PAGE53
  AA17 M_C_CPU1_SB_DQ<28> @S9S_MB_2U_LIB.S9S_MB_2U(SCH_1):M_C_CPU1_SB_DQ(28)    I91 @S9S_MB_2U_LIB.S9S_MB_2U(SCH_1):PAGE53
  AG19 M_C_CPU1_SB_DQ<27> @S9S_MB_2U_LIB.S9S_MB_2U(SCH_1):M_C_CPU1_SB_DQ(27)    I91 @S9S_MB_2U_LIB.S9S_MB_2U(SCH_1):PAGE53
  AF20 M_C_CPU1_SB_DQ<26> @S9S_MB_2U_LIB.S9S_MB_2U(SCH_1):M_C_CPU1_SB_DQ(26)    I91 @S9S_MB_2U_LIB.S9S_MB_2U(SCH_1):PAGE53
  AC19 M_C_CPU1_SB_DQ<25> @S9S_MB_2U_LIB.S9S_MB_2U(SCH_1):M_C_CPU1_SB_DQ(25)    I91 @S9S_MB_2U_LIB.S9S_MB_2U(SCH_1):PAGE53
  AD20 M_C_CPU1_SB_DQ<24> @S9S_MB_2U_LIB.S9S_MB_2U(SCH_1):M_C_CPU1_SB_DQ(24)    I91 @S9S_MB_2U_LIB.S9S_MB_2U(SCH_1):PAGE53
   W19 M_C_CPU1_SB_DQ<23> @S9S_MB_2U_LIB.S9S_MB_2U(SCH_1):M_C_CPU1_SB_DQ(23)    I91 @S9S_MB_2U_LIB.S9S_MB_2U(SCH_1):PAGE53
   Y20 M_C_CPU1_SB_DQ<22> @S9S_MB_2U_LIB.S9S_MB_2U(SCH_1):M_C_CPU1_SB_DQ(22)    I91 @S9S_MB_2U_LIB.S9S_MB_2U(SCH_1):PAGE53
   U19 M_C_CPU1_SB_DQ<21> @S9S_MB_2U_LIB.S9S_MB_2U(SCH_1):M_C_CPU1_SB_DQ(21)    I91 @S9S_MB_2U_LIB.S9S_MB_2U(SCH_1):PAGE53
   T20 M_C_CPU1_SB_DQ<20> @S9S_MB_2U_LIB.S9S_MB_2U(SCH_1):M_C_CPU1_SB_DQ(20)    I91 @S9S_MB_2U_LIB.S9S_MB_2U(SCH_1):PAGE53
   Y22 M_C_CPU1_SB_DQ<19> @S9S_MB_2U_LIB.S9S_MB_2U(SCH_1):M_C_CPU1_SB_DQ(19)    I91 @S9S_MB_2U_LIB.S9S_MB_2U(SCH_1):PAGE53
   W23 M_C_CPU1_SB_DQ<18> @S9S_MB_2U_LIB.S9S_MB_2U(SCH_1):M_C_CPU1_SB_DQ(18)    I91 @S9S_MB_2U_LIB.S9S_MB_2U(SCH_1):PAGE53
   T22 M_C_CPU1_SB_DQ<17> @S9S_MB_2U_LIB.S9S_MB_2U(SCH_1):M_C_CPU1_SB_DQ(17)    I91 @S9S_MB_2U_LIB.S9S_MB_2U(SCH_1):PAGE53
   U23 M_C_CPU1_SB_DQ<16> @S9S_MB_2U_LIB.S9S_MB_2U(SCH_1):M_C_CPU1_SB_DQ(16)    I91 @S9S_MB_2U_LIB.S9S_MB_2U(SCH_1):PAGE53
  AF28 M_C_CPU1_SB_DQ<15> @S9S_MB_2U_LIB.S9S_MB_2U(SCH_1):M_C_CPU1_SB_DQ(15)    I91 @S9S_MB_2U_LIB.S9S_MB_2U(SCH_1):PAGE53
  AG29 M_C_CPU1_SB_DQ<14> @S9S_MB_2U_LIB.S9S_MB_2U(SCH_1):M_C_CPU1_SB_DQ(14)    I91 @S9S_MB_2U_LIB.S9S_MB_2U(SCH_1):PAGE53
  AD28 M_C_CPU1_SB_DQ<13> @S9S_MB_2U_LIB.S9S_MB_2U(SCH_1):M_C_CPU1_SB_DQ(13)    I91 @S9S_MB_2U_LIB.S9S_MB_2U(SCH_1):PAGE53
  AC29 M_C_CPU1_SB_DQ<12> @S9S_MB_2U_LIB.S9S_MB_2U(SCH_1):M_C_CPU1_SB_DQ(12)    I91 @S9S_MB_2U_LIB.S9S_MB_2U(SCH_1):PAGE53
  AG31 M_C_CPU1_SB_DQ<11> @S9S_MB_2U_LIB.S9S_MB_2U(SCH_1):M_C_CPU1_SB_DQ(11)    I91 @S9S_MB_2U_LIB.S9S_MB_2U(SCH_1):PAGE53
  AF32 M_C_CPU1_SB_DQ<10> @S9S_MB_2U_LIB.S9S_MB_2U(SCH_1):M_C_CPU1_SB_DQ(10)    I91 @S9S_MB_2U_LIB.S9S_MB_2U(SCH_1):PAGE53
  AC31 M_C_CPU1_SB_DQ<9> @S9S_MB_2U_LIB.S9S_MB_2U(SCH_1):M_C_CPU1_SB_DQ(9)    I91 @S9S_MB_2U_LIB.S9S_MB_2U(SCH_1):PAGE53
  AD32 M_C_CPU1_SB_DQ<8> @S9S_MB_2U_LIB.S9S_MB_2U(SCH_1):M_C_CPU1_SB_DQ(8)    I91 @S9S_MB_2U_LIB.S9S_MB_2U(SCH_1):PAGE53
  AF34 M_C_CPU1_SB_DQ<7> @S9S_MB_2U_LIB.S9S_MB_2U(SCH_1):M_C_CPU1_SB_DQ(7)    I91 @S9S_MB_2U_LIB.S9S_MB_2U(SCH_1):PAGE53
  AG35 M_C_CPU1_SB_DQ<6> @S9S_MB_2U_LIB.S9S_MB_2U(SCH_1):M_C_CPU1_SB_DQ(6)    I91 @S9S_MB_2U_LIB.S9S_MB_2U(SCH_1):PAGE53
  AD34 M_C_CPU1_SB_DQ<5> @S9S_MB_2U_LIB.S9S_MB_2U(SCH_1):M_C_CPU1_SB_DQ(5)    I91 @S9S_MB_2U_LIB.S9S_MB_2U(SCH_1):PAGE53
  AC35 M_C_CPU1_SB_DQ<4> @S9S_MB_2U_LIB.S9S_MB_2U(SCH_1):M_C_CPU1_SB_DQ(4)    I91 @S9S_MB_2U_LIB.S9S_MB_2U(SCH_1):PAGE53
  AG37 M_C_CPU1_SB_DQ<3> @S9S_MB_2U_LIB.S9S_MB_2U(SCH_1):M_C_CPU1_SB_DQ(3)    I91 @S9S_MB_2U_LIB.S9S_MB_2U(SCH_1):PAGE53
  AF38 M_C_CPU1_SB_DQ<2> @S9S_MB_2U_LIB.S9S_MB_2U(SCH_1):M_C_CPU1_SB_DQ(2)    I91 @S9S_MB_2U_LIB.S9S_MB_2U(SCH_1):PAGE53
  AC37 M_C_CPU1_SB_DQ<1> @S9S_MB_2U_LIB.S9S_MB_2U(SCH_1):M_C_CPU1_SB_DQ(1)    I91 @S9S_MB_2U_LIB.S9S_MB_2U(SCH_1):PAGE53
  AD38 M_C_CPU1_SB_DQ<0> @S9S_MB_2U_LIB.S9S_MB_2U(SCH_1):M_C_CPU1_SB_DQ(0)    I91 @S9S_MB_2U_LIB.S9S_MB_2U(SCH_1):PAGE53
   R33 M_C_CPU1_SB_DQS_DN<9> @S9S_MB_2U_LIB.S9S_MB_2U(SCH_1):M_C_CPU1_SB_DQS_DN(9)    I91 @S9S_MB_2U_LIB.S9S_MB_2U(SCH_1):PAGE53
  AF18 M_C_CPU1_SB_DQS_DN<8> @S9S_MB_2U_LIB.S9S_MB_2U(SCH_1):M_C_CPU1_SB_DQS_DN(8)    I91 @S9S_MB_2U_LIB.S9S_MB_2U(SCH_1):PAGE53
   W21 M_C_CPU1_SB_DQS_DN<7> @S9S_MB_2U_LIB.S9S_MB_2U(SCH_1):M_C_CPU1_SB_DQS_DN(7)    I91 @S9S_MB_2U_LIB.S9S_MB_2U(SCH_1):PAGE53
  AF30 M_C_CPU1_SB_DQS_DN<6> @S9S_MB_2U_LIB.S9S_MB_2U(SCH_1):M_C_CPU1_SB_DQS_DN(6)    I91 @S9S_MB_2U_LIB.S9S_MB_2U(SCH_1):PAGE53
  AF36 M_C_CPU1_SB_DQS_DN<5> @S9S_MB_2U_LIB.S9S_MB_2U(SCH_1):M_C_CPU1_SB_DQS_DN(5)    I91 @S9S_MB_2U_LIB.S9S_MB_2U(SCH_1):PAGE53
   W33 M_C_CPU1_SB_DQS_DN<4> @S9S_MB_2U_LIB.S9S_MB_2U(SCH_1):M_C_CPU1_SB_DQS_DN(4)    I91 @S9S_MB_2U_LIB.S9S_MB_2U(SCH_1):PAGE53
  AB18 M_C_CPU1_SB_DQS_DN<3> @S9S_MB_2U_LIB.S9S_MB_2U(SCH_1):M_C_CPU1_SB_DQS_DN(3)    I91 @S9S_MB_2U_LIB.S9S_MB_2U(SCH_1):PAGE53
   R21 M_C_CPU1_SB_DQS_DN<2> @S9S_MB_2U_LIB.S9S_MB_2U(SCH_1):M_C_CPU1_SB_DQS_DN(2)    I91 @S9S_MB_2U_LIB.S9S_MB_2U(SCH_1):PAGE53
  AB30 M_C_CPU1_SB_DQS_DN<1> @S9S_MB_2U_LIB.S9S_MB_2U(SCH_1):M_C_CPU1_SB_DQS_DN(1)    I91 @S9S_MB_2U_LIB.S9S_MB_2U(SCH_1):PAGE53
  AB36 M_C_CPU1_SB_DQS_DN<0> @S9S_MB_2U_LIB.S9S_MB_2U(SCH_1):M_C_CPU1_SB_DQS_DN(0)    I91 @S9S_MB_2U_LIB.S9S_MB_2U(SCH_1):PAGE53
   U33 M_C_CPU1_SB_DQS_DP<9> @S9S_MB_2U_LIB.S9S_MB_2U(SCH_1):M_C_CPU1_SB_DQS_DP(9)    I91 @S9S_MB_2U_LIB.S9S_MB_2U(SCH_1):PAGE53
  AH18 M_C_CPU1_SB_DQS_DP<8> @S9S_MB_2U_LIB.S9S_MB_2U(SCH_1):M_C_CPU1_SB_DQS_DP(8)    I91 @S9S_MB_2U_LIB.S9S_MB_2U(SCH_1):PAGE53
  AA21 M_C_CPU1_SB_DQS_DP<7> @S9S_MB_2U_LIB.S9S_MB_2U(SCH_1):M_C_CPU1_SB_DQS_DP(7)    I91 @S9S_MB_2U_LIB.S9S_MB_2U(SCH_1):PAGE53
  AH30 M_C_CPU1_SB_DQS_DP<6> @S9S_MB_2U_LIB.S9S_MB_2U(SCH_1):M_C_CPU1_SB_DQS_DP(6)    I91 @S9S_MB_2U_LIB.S9S_MB_2U(SCH_1):PAGE53
  AH36 M_C_CPU1_SB_DQS_DP<5> @S9S_MB_2U_LIB.S9S_MB_2U(SCH_1):M_C_CPU1_SB_DQS_DP(5)    I91 @S9S_MB_2U_LIB.S9S_MB_2U(SCH_1):PAGE53
  AA33 M_C_CPU1_SB_DQS_DP<4> @S9S_MB_2U_LIB.S9S_MB_2U(SCH_1):M_C_CPU1_SB_DQS_DP(4)    I91 @S9S_MB_2U_LIB.S9S_MB_2U(SCH_1):PAGE53
  AD18 M_C_CPU1_SB_DQS_DP<3> @S9S_MB_2U_LIB.S9S_MB_2U(SCH_1):M_C_CPU1_SB_DQS_DP(3)    I91 @S9S_MB_2U_LIB.S9S_MB_2U(SCH_1):PAGE53
   U21 M_C_CPU1_SB_DQS_DP<2> @S9S_MB_2U_LIB.S9S_MB_2U(SCH_1):M_C_CPU1_SB_DQS_DP(2)    I91 @S9S_MB_2U_LIB.S9S_MB_2U(SCH_1):PAGE53
  AD30 M_C_CPU1_SB_DQS_DP<1> @S9S_MB_2U_LIB.S9S_MB_2U(SCH_1):M_C_CPU1_SB_DQS_DP(1)    I91 @S9S_MB_2U_LIB.S9S_MB_2U(SCH_1):PAGE53
  AD36 M_C_CPU1_SB_DQS_DP<0> @S9S_MB_2U_LIB.S9S_MB_2U(SCH_1):M_C_CPU1_SB_DQS_DP(0)    I91 @S9S_MB_2U_LIB.S9S_MB_2U(SCH_1):PAGE53
   Y34 M_C_CPU1_SB_CB<7> @S9S_MB_2U_LIB.S9S_MB_2U(SCH_1):M_C_CPU1_SB_CB(7)    I91 @S9S_MB_2U_LIB.S9S_MB_2U(SCH_1):PAGE53
   W35 M_C_CPU1_SB_CB<6> @S9S_MB_2U_LIB.S9S_MB_2U(SCH_1):M_C_CPU1_SB_CB(6)    I91 @S9S_MB_2U_LIB.S9S_MB_2U(SCH_1):PAGE53
   T34 M_C_CPU1_SB_CB<5> @S9S_MB_2U_LIB.S9S_MB_2U(SCH_1):M_C_CPU1_SB_CB(5)    I91 @S9S_MB_2U_LIB.S9S_MB_2U(SCH_1):PAGE53
   U35 M_C_CPU1_SB_CB<4> @S9S_MB_2U_LIB.S9S_MB_2U(SCH_1):M_C_CPU1_SB_CB(4)    I91 @S9S_MB_2U_LIB.S9S_MB_2U(SCH_1):PAGE53
   W31 M_C_CPU1_SB_CB<3> @S9S_MB_2U_LIB.S9S_MB_2U(SCH_1):M_C_CPU1_SB_CB(3)    I91 @S9S_MB_2U_LIB.S9S_MB_2U(SCH_1):PAGE53
   Y32 M_C_CPU1_SB_CB<2> @S9S_MB_2U_LIB.S9S_MB_2U(SCH_1):M_C_CPU1_SB_CB(2)    I91 @S9S_MB_2U_LIB.S9S_MB_2U(SCH_1):PAGE53
   U31 M_C_CPU1_SB_CB<1> @S9S_MB_2U_LIB.S9S_MB_2U(SCH_1):M_C_CPU1_SB_CB(1)    I91 @S9S_MB_2U_LIB.S9S_MB_2U(SCH_1):PAGE53
   T32 M_C_CPU1_SB_CB<0> @S9S_MB_2U_LIB.S9S_MB_2U(SCH_1):M_C_CPU1_SB_CB(0)    I91 @S9S_MB_2U_LIB.S9S_MB_2U(SCH_1):PAGE53
  AA39 M_C_CPU1_SB_PAR @S9S_MB_2U_LIB.S9S_MB_2U(SCH_1):M_C_CPU1_SB_PAR    I91 @S9S_MB_2U_LIB.S9S_MB_2U(SCH_1):PAGE53
  AV47 M_D_CPU1_ALERT_N @S9S_MB_2U_LIB.S9S_MB_2U(SCH_1):M_D_CPU1_ALERT_N    I91 @S9S_MB_2U_LIB.S9S_MB_2U(SCH_1):PAGE54
  AC50 M_D_CPU1_SA_RSP<1> @S9S_MB_2U_LIB.S9S_MB_2U(SCH_1):M_D_CPU1_SA_RSP(1)    I91 @S9S_MB_2U_LIB.S9S_MB_2U(SCH_1):PAGE54
  AD51 M_D_CPU1_SA_RSP<0> @S9S_MB_2U_LIB.S9S_MB_2U(SCH_1):M_D_CPU1_SA_RSP(0)    I91 @S9S_MB_2U_LIB.S9S_MB_2U(SCH_1):PAGE54
  AG50 M_D_CPU1_SB_RSP<1> @S9S_MB_2U_LIB.S9S_MB_2U(SCH_1):M_D_CPU1_SB_RSP(1)    I91 @S9S_MB_2U_LIB.S9S_MB_2U(SCH_1):PAGE54
  AF51 M_D_CPU1_SB_RSP<0> @S9S_MB_2U_LIB.S9S_MB_2U(SCH_1):M_D_CPU1_SB_RSP(0)    I91 @S9S_MB_2U_LIB.S9S_MB_2U(SCH_1):PAGE54
  AN45 M_D_CPU1_CLK_DN<1> @S9S_MB_2U_LIB.S9S_MB_2U(SCH_1):M_D_CPU1_CLK_DN(1)    I91 @S9S_MB_2U_LIB.S9S_MB_2U(SCH_1):PAGE54
  AJ45 M_D_CPU1_CLK_DN<0> @S9S_MB_2U_LIB.S9S_MB_2U(SCH_1):M_D_CPU1_CLK_DN(0)    I91 @S9S_MB_2U_LIB.S9S_MB_2U(SCH_1):PAGE54
  AR45 M_D_CPU1_CLK_DP<1> @S9S_MB_2U_LIB.S9S_MB_2U(SCH_1):M_D_CPU1_CLK_DP(1)    I91 @S9S_MB_2U_LIB.S9S_MB_2U(SCH_1):PAGE54
  AL45 M_D_CPU1_CLK_DP<0> @S9S_MB_2U_LIB.S9S_MB_2U(SCH_1):M_D_CPU1_CLK_DP(0)    I91 @S9S_MB_2U_LIB.S9S_MB_2U(SCH_1):PAGE54
  AN43 M_D_CPU1_SA_CA<6> @S9S_MB_2U_LIB.S9S_MB_2U(SCH_1):M_D_CPU1_SA_CA(6)    I91 @S9S_MB_2U_LIB.S9S_MB_2U(SCH_1):PAGE54
  AN50 M_D_CPU1_SA_CA<5> @S9S_MB_2U_LIB.S9S_MB_2U(SCH_1):M_D_CPU1_SA_CA(5)    I91 @S9S_MB_2U_LIB.S9S_MB_2U(SCH_1):PAGE54
  AL50 M_D_CPU1_SA_CA<4> @S9S_MB_2U_LIB.S9S_MB_2U(SCH_1):M_D_CPU1_SA_CA(4)    I91 @S9S_MB_2U_LIB.S9S_MB_2U(SCH_1):PAGE54
  AP51 M_D_CPU1_SA_CA<3> @S9S_MB_2U_LIB.S9S_MB_2U(SCH_1):M_D_CPU1_SA_CA(3)    I91 @S9S_MB_2U_LIB.S9S_MB_2U(SCH_1):PAGE54
  AK51 M_D_CPU1_SA_CA<2> @S9S_MB_2U_LIB.S9S_MB_2U(SCH_1):M_D_CPU1_SA_CA(2)    I91 @S9S_MB_2U_LIB.S9S_MB_2U(SCH_1):PAGE54
  AR52 M_D_CPU1_SA_CA<1> @S9S_MB_2U_LIB.S9S_MB_2U(SCH_1):M_D_CPU1_SA_CA(1)    I91 @S9S_MB_2U_LIB.S9S_MB_2U(SCH_1):PAGE54
  AJ52 M_D_CPU1_SA_CA<0> @S9S_MB_2U_LIB.S9S_MB_2U(SCH_1):M_D_CPU1_SA_CA(0)    I91 @S9S_MB_2U_LIB.S9S_MB_2U(SCH_1):PAGE54
  AP53 M_D_CPU1_SA_CS_N<3> @S9S_MB_2U_LIB.S9S_MB_2U(SCH_1):M_D_CPU1_SA_CS_N(3)    I91 @S9S_MB_2U_LIB.S9S_MB_2U(SCH_1):PAGE54
  AN54 M_D_CPU1_SA_CS_N<2> @S9S_MB_2U_LIB.S9S_MB_2U(SCH_1):M_D_CPU1_SA_CS_N(2)    I91 @S9S_MB_2U_LIB.S9S_MB_2U(SCH_1):PAGE54
  AK53 M_D_CPU1_SA_CS_N<1> @S9S_MB_2U_LIB.S9S_MB_2U(SCH_1):M_D_CPU1_SA_CS_N(1)    I91 @S9S_MB_2U_LIB.S9S_MB_2U(SCH_1):PAGE54
  AL54 M_D_CPU1_SA_CS_N<0> @S9S_MB_2U_LIB.S9S_MB_2U(SCH_1):M_D_CPU1_SA_CS_N(0)    I91 @S9S_MB_2U_LIB.S9S_MB_2U(SCH_1):PAGE54
  AN62 M_D_CPU1_SA_DQ<31> @S9S_MB_2U_LIB.S9S_MB_2U(SCH_1):M_D_CPU1_SA_DQ(31)    I91 @S9S_MB_2U_LIB.S9S_MB_2U(SCH_1):PAGE54
  AP63 M_D_CPU1_SA_DQ<30> @S9S_MB_2U_LIB.S9S_MB_2U(SCH_1):M_D_CPU1_SA_DQ(30)    I91 @S9S_MB_2U_LIB.S9S_MB_2U(SCH_1):PAGE54
  AL62 M_D_CPU1_SA_DQ<29> @S9S_MB_2U_LIB.S9S_MB_2U(SCH_1):M_D_CPU1_SA_DQ(29)    I91 @S9S_MB_2U_LIB.S9S_MB_2U(SCH_1):PAGE54
  AK63 M_D_CPU1_SA_DQ<28> @S9S_MB_2U_LIB.S9S_MB_2U(SCH_1):M_D_CPU1_SA_DQ(28)    I91 @S9S_MB_2U_LIB.S9S_MB_2U(SCH_1):PAGE54
  AP65 M_D_CPU1_SA_DQ<27> @S9S_MB_2U_LIB.S9S_MB_2U(SCH_1):M_D_CPU1_SA_DQ(27)    I91 @S9S_MB_2U_LIB.S9S_MB_2U(SCH_1):PAGE54
  AN66 M_D_CPU1_SA_DQ<26> @S9S_MB_2U_LIB.S9S_MB_2U(SCH_1):M_D_CPU1_SA_DQ(26)    I91 @S9S_MB_2U_LIB.S9S_MB_2U(SCH_1):PAGE54
  AK65 M_D_CPU1_SA_DQ<25> @S9S_MB_2U_LIB.S9S_MB_2U(SCH_1):M_D_CPU1_SA_DQ(25)    I91 @S9S_MB_2U_LIB.S9S_MB_2U(SCH_1):PAGE54
  AL66 M_D_CPU1_SA_DQ<24> @S9S_MB_2U_LIB.S9S_MB_2U(SCH_1):M_D_CPU1_SA_DQ(24)    I91 @S9S_MB_2U_LIB.S9S_MB_2U(SCH_1):PAGE54
  AN68 M_D_CPU1_SA_DQ<23> @S9S_MB_2U_LIB.S9S_MB_2U(SCH_1):M_D_CPU1_SA_DQ(23)    I91 @S9S_MB_2U_LIB.S9S_MB_2U(SCH_1):PAGE54
  AP69 M_D_CPU1_SA_DQ<22> @S9S_MB_2U_LIB.S9S_MB_2U(SCH_1):M_D_CPU1_SA_DQ(22)    I91 @S9S_MB_2U_LIB.S9S_MB_2U(SCH_1):PAGE54
  AL68 M_D_CPU1_SA_DQ<21> @S9S_MB_2U_LIB.S9S_MB_2U(SCH_1):M_D_CPU1_SA_DQ(21)    I91 @S9S_MB_2U_LIB.S9S_MB_2U(SCH_1):PAGE54
  AK69 M_D_CPU1_SA_DQ<20> @S9S_MB_2U_LIB.S9S_MB_2U(SCH_1):M_D_CPU1_SA_DQ(20)    I91 @S9S_MB_2U_LIB.S9S_MB_2U(SCH_1):PAGE54
  AP71 M_D_CPU1_SA_DQ<19> @S9S_MB_2U_LIB.S9S_MB_2U(SCH_1):M_D_CPU1_SA_DQ(19)    I91 @S9S_MB_2U_LIB.S9S_MB_2U(SCH_1):PAGE54
  AN72 M_D_CPU1_SA_DQ<18> @S9S_MB_2U_LIB.S9S_MB_2U(SCH_1):M_D_CPU1_SA_DQ(18)    I91 @S9S_MB_2U_LIB.S9S_MB_2U(SCH_1):PAGE54
  AK71 M_D_CPU1_SA_DQ<17> @S9S_MB_2U_LIB.S9S_MB_2U(SCH_1):M_D_CPU1_SA_DQ(17)    I91 @S9S_MB_2U_LIB.S9S_MB_2U(SCH_1):PAGE54
  AL72 M_D_CPU1_SA_DQ<16> @S9S_MB_2U_LIB.S9S_MB_2U(SCH_1):M_D_CPU1_SA_DQ(16)    I91 @S9S_MB_2U_LIB.S9S_MB_2U(SCH_1):PAGE54
  AN74 M_D_CPU1_SA_DQ<15> @S9S_MB_2U_LIB.S9S_MB_2U(SCH_1):M_D_CPU1_SA_DQ(15)    I91 @S9S_MB_2U_LIB.S9S_MB_2U(SCH_1):PAGE54
  AP75 M_D_CPU1_SA_DQ<14> @S9S_MB_2U_LIB.S9S_MB_2U(SCH_1):M_D_CPU1_SA_DQ(14)    I91 @S9S_MB_2U_LIB.S9S_MB_2U(SCH_1):PAGE54
  AL74 M_D_CPU1_SA_DQ<13> @S9S_MB_2U_LIB.S9S_MB_2U(SCH_1):M_D_CPU1_SA_DQ(13)    I91 @S9S_MB_2U_LIB.S9S_MB_2U(SCH_1):PAGE54
  AK75 M_D_CPU1_SA_DQ<12> @S9S_MB_2U_LIB.S9S_MB_2U(SCH_1):M_D_CPU1_SA_DQ(12)    I91 @S9S_MB_2U_LIB.S9S_MB_2U(SCH_1):PAGE54
  AP77 M_D_CPU1_SA_DQ<11> @S9S_MB_2U_LIB.S9S_MB_2U(SCH_1):M_D_CPU1_SA_DQ(11)    I91 @S9S_MB_2U_LIB.S9S_MB_2U(SCH_1):PAGE54
  AN78 M_D_CPU1_SA_DQ<10> @S9S_MB_2U_LIB.S9S_MB_2U(SCH_1):M_D_CPU1_SA_DQ(10)    I91 @S9S_MB_2U_LIB.S9S_MB_2U(SCH_1):PAGE54
  AK77 M_D_CPU1_SA_DQ<9> @S9S_MB_2U_LIB.S9S_MB_2U(SCH_1):M_D_CPU1_SA_DQ(9)    I91 @S9S_MB_2U_LIB.S9S_MB_2U(SCH_1):PAGE54
  AL78 M_D_CPU1_SA_DQ<8> @S9S_MB_2U_LIB.S9S_MB_2U(SCH_1):M_D_CPU1_SA_DQ(8)    I91 @S9S_MB_2U_LIB.S9S_MB_2U(SCH_1):PAGE54
  AF71 M_D_CPU1_SA_DQ<7> @S9S_MB_2U_LIB.S9S_MB_2U(SCH_1):M_D_CPU1_SA_DQ(7)    I91 @S9S_MB_2U_LIB.S9S_MB_2U(SCH_1):PAGE54
  AG72 M_D_CPU1_SA_DQ<6> @S9S_MB_2U_LIB.S9S_MB_2U(SCH_1):M_D_CPU1_SA_DQ(6)    I91 @S9S_MB_2U_LIB.S9S_MB_2U(SCH_1):PAGE54
  AD71 M_D_CPU1_SA_DQ<5> @S9S_MB_2U_LIB.S9S_MB_2U(SCH_1):M_D_CPU1_SA_DQ(5)    I91 @S9S_MB_2U_LIB.S9S_MB_2U(SCH_1):PAGE54
  AC72 M_D_CPU1_SA_DQ<4> @S9S_MB_2U_LIB.S9S_MB_2U(SCH_1):M_D_CPU1_SA_DQ(4)    I91 @S9S_MB_2U_LIB.S9S_MB_2U(SCH_1):PAGE54
  AG74 M_D_CPU1_SA_DQ<3> @S9S_MB_2U_LIB.S9S_MB_2U(SCH_1):M_D_CPU1_SA_DQ(3)    I91 @S9S_MB_2U_LIB.S9S_MB_2U(SCH_1):PAGE54
  AF75 M_D_CPU1_SA_DQ<2> @S9S_MB_2U_LIB.S9S_MB_2U(SCH_1):M_D_CPU1_SA_DQ(2)    I91 @S9S_MB_2U_LIB.S9S_MB_2U(SCH_1):PAGE54
  AC74 M_D_CPU1_SA_DQ<1> @S9S_MB_2U_LIB.S9S_MB_2U(SCH_1):M_D_CPU1_SA_DQ(1)    I91 @S9S_MB_2U_LIB.S9S_MB_2U(SCH_1):PAGE54
  AD75 M_D_CPU1_SA_DQ<0> @S9S_MB_2U_LIB.S9S_MB_2U(SCH_1):M_D_CPU1_SA_DQ(0)    I91 @S9S_MB_2U_LIB.S9S_MB_2U(SCH_1):PAGE54
  AN58 M_D_CPU1_SA_DQS_DN<9> @S9S_MB_2U_LIB.S9S_MB_2U(SCH_1):M_D_CPU1_SA_DQS_DN(9)    I91 @S9S_MB_2U_LIB.S9S_MB_2U(SCH_1):PAGE54
  AN64 M_D_CPU1_SA_DQS_DN<8> @S9S_MB_2U_LIB.S9S_MB_2U(SCH_1):M_D_CPU1_SA_DQS_DN(8)    I91 @S9S_MB_2U_LIB.S9S_MB_2U(SCH_1):PAGE54
  AN70 M_D_CPU1_SA_DQS_DN<7> @S9S_MB_2U_LIB.S9S_MB_2U(SCH_1):M_D_CPU1_SA_DQS_DN(7)    I91 @S9S_MB_2U_LIB.S9S_MB_2U(SCH_1):PAGE54
  AN76 M_D_CPU1_SA_DQS_DN<6> @S9S_MB_2U_LIB.S9S_MB_2U(SCH_1):M_D_CPU1_SA_DQS_DN(6)    I91 @S9S_MB_2U_LIB.S9S_MB_2U(SCH_1):PAGE54
  AH73 M_D_CPU1_SA_DQS_DN<5> @S9S_MB_2U_LIB.S9S_MB_2U(SCH_1):M_D_CPU1_SA_DQS_DN(5)    I91 @S9S_MB_2U_LIB.S9S_MB_2U(SCH_1):PAGE54
  AJ58 M_D_CPU1_SA_DQS_DN<4> @S9S_MB_2U_LIB.S9S_MB_2U(SCH_1):M_D_CPU1_SA_DQS_DN(4)    I91 @S9S_MB_2U_LIB.S9S_MB_2U(SCH_1):PAGE54
  AJ64 M_D_CPU1_SA_DQS_DN<3> @S9S_MB_2U_LIB.S9S_MB_2U(SCH_1):M_D_CPU1_SA_DQS_DN(3)    I91 @S9S_MB_2U_LIB.S9S_MB_2U(SCH_1):PAGE54
  AJ70 M_D_CPU1_SA_DQS_DN<2> @S9S_MB_2U_LIB.S9S_MB_2U(SCH_1):M_D_CPU1_SA_DQS_DN(2)    I91 @S9S_MB_2U_LIB.S9S_MB_2U(SCH_1):PAGE54
  AJ76 M_D_CPU1_SA_DQS_DN<1> @S9S_MB_2U_LIB.S9S_MB_2U(SCH_1):M_D_CPU1_SA_DQS_DN(1)    I91 @S9S_MB_2U_LIB.S9S_MB_2U(SCH_1):PAGE54
  AB73 M_D_CPU1_SA_DQS_DN<0> @S9S_MB_2U_LIB.S9S_MB_2U(SCH_1):M_D_CPU1_SA_DQS_DN(0)    I91 @S9S_MB_2U_LIB.S9S_MB_2U(SCH_1):PAGE54
  AR58 M_D_CPU1_SA_DQS_DP<9> @S9S_MB_2U_LIB.S9S_MB_2U(SCH_1):M_D_CPU1_SA_DQS_DP(9)    I91 @S9S_MB_2U_LIB.S9S_MB_2U(SCH_1):PAGE54
  AR64 M_D_CPU1_SA_DQS_DP<8> @S9S_MB_2U_LIB.S9S_MB_2U(SCH_1):M_D_CPU1_SA_DQS_DP(8)    I91 @S9S_MB_2U_LIB.S9S_MB_2U(SCH_1):PAGE54
  AR70 M_D_CPU1_SA_DQS_DP<7> @S9S_MB_2U_LIB.S9S_MB_2U(SCH_1):M_D_CPU1_SA_DQS_DP(7)    I91 @S9S_MB_2U_LIB.S9S_MB_2U(SCH_1):PAGE54
  AR76 M_D_CPU1_SA_DQS_DP<6> @S9S_MB_2U_LIB.S9S_MB_2U(SCH_1):M_D_CPU1_SA_DQS_DP(6)    I91 @S9S_MB_2U_LIB.S9S_MB_2U(SCH_1):PAGE54
  AF73 M_D_CPU1_SA_DQS_DP<5> @S9S_MB_2U_LIB.S9S_MB_2U(SCH_1):M_D_CPU1_SA_DQS_DP(5)    I91 @S9S_MB_2U_LIB.S9S_MB_2U(SCH_1):PAGE54
  AL58 M_D_CPU1_SA_DQS_DP<4> @S9S_MB_2U_LIB.S9S_MB_2U(SCH_1):M_D_CPU1_SA_DQS_DP(4)    I91 @S9S_MB_2U_LIB.S9S_MB_2U(SCH_1):PAGE54
  AL64 M_D_CPU1_SA_DQS_DP<3> @S9S_MB_2U_LIB.S9S_MB_2U(SCH_1):M_D_CPU1_SA_DQS_DP(3)    I91 @S9S_MB_2U_LIB.S9S_MB_2U(SCH_1):PAGE54
  AL70 M_D_CPU1_SA_DQS_DP<2> @S9S_MB_2U_LIB.S9S_MB_2U(SCH_1):M_D_CPU1_SA_DQS_DP(2)    I91 @S9S_MB_2U_LIB.S9S_MB_2U(SCH_1):PAGE54
  AL76 M_D_CPU1_SA_DQS_DP<1> @S9S_MB_2U_LIB.S9S_MB_2U(SCH_1):M_D_CPU1_SA_DQS_DP(1)    I91 @S9S_MB_2U_LIB.S9S_MB_2U(SCH_1):PAGE54
  AD73 M_D_CPU1_SA_DQS_DP<0> @S9S_MB_2U_LIB.S9S_MB_2U(SCH_1):M_D_CPU1_SA_DQS_DP(0)    I91 @S9S_MB_2U_LIB.S9S_MB_2U(SCH_1):PAGE54
  AN56 M_D_CPU1_SA_CB<7> @S9S_MB_2U_LIB.S9S_MB_2U(SCH_1):M_D_CPU1_SA_CB(7)    I91 @S9S_MB_2U_LIB.S9S_MB_2U(SCH_1):PAGE54
  AP57 M_D_CPU1_SA_CB<6> @S9S_MB_2U_LIB.S9S_MB_2U(SCH_1):M_D_CPU1_SA_CB(6)    I91 @S9S_MB_2U_LIB.S9S_MB_2U(SCH_1):PAGE54
  AL56 M_D_CPU1_SA_CB<5> @S9S_MB_2U_LIB.S9S_MB_2U(SCH_1):M_D_CPU1_SA_CB(5)    I91 @S9S_MB_2U_LIB.S9S_MB_2U(SCH_1):PAGE54
  AK57 M_D_CPU1_SA_CB<4> @S9S_MB_2U_LIB.S9S_MB_2U(SCH_1):M_D_CPU1_SA_CB(4)    I91 @S9S_MB_2U_LIB.S9S_MB_2U(SCH_1):PAGE54
  AP59 M_D_CPU1_SA_CB<3> @S9S_MB_2U_LIB.S9S_MB_2U(SCH_1):M_D_CPU1_SA_CB(3)    I91 @S9S_MB_2U_LIB.S9S_MB_2U(SCH_1):PAGE54
  AN60 M_D_CPU1_SA_CB<2> @S9S_MB_2U_LIB.S9S_MB_2U(SCH_1):M_D_CPU1_SA_CB(2)    I91 @S9S_MB_2U_LIB.S9S_MB_2U(SCH_1):PAGE54
  AK59 M_D_CPU1_SA_CB<1> @S9S_MB_2U_LIB.S9S_MB_2U(SCH_1):M_D_CPU1_SA_CB(1)    I91 @S9S_MB_2U_LIB.S9S_MB_2U(SCH_1):PAGE54
  AL60 M_D_CPU1_SA_CB<0> @S9S_MB_2U_LIB.S9S_MB_2U(SCH_1):M_D_CPU1_SA_CB(0)    I91 @S9S_MB_2U_LIB.S9S_MB_2U(SCH_1):PAGE54
  AP44 M_D_CPU1_SA_PAR @S9S_MB_2U_LIB.S9S_MB_2U(SCH_1):M_D_CPU1_SA_PAR    I91 @S9S_MB_2U_LIB.S9S_MB_2U(SCH_1):PAGE54
  AB42 M_D_CPU1_SB_CA<6> @S9S_MB_2U_LIB.S9S_MB_2U(SCH_1):M_D_CPU1_SB_CA(6)    I91 @S9S_MB_2U_LIB.S9S_MB_2U(SCH_1):PAGE54
  AG43 M_D_CPU1_SB_CA<5> @S9S_MB_2U_LIB.S9S_MB_2U(SCH_1):M_D_CPU1_SB_CA(5)    I91 @S9S_MB_2U_LIB.S9S_MB_2U(SCH_1):PAGE54
  AC43 M_D_CPU1_SB_CA<4> @S9S_MB_2U_LIB.S9S_MB_2U(SCH_1):M_D_CPU1_SB_CA(4)    I91 @S9S_MB_2U_LIB.S9S_MB_2U(SCH_1):PAGE54
  AF44 M_D_CPU1_SB_CA<3> @S9S_MB_2U_LIB.S9S_MB_2U(SCH_1):M_D_CPU1_SB_CA(3)    I91 @S9S_MB_2U_LIB.S9S_MB_2U(SCH_1):PAGE54
  AD44 M_D_CPU1_SB_CA<2> @S9S_MB_2U_LIB.S9S_MB_2U(SCH_1):M_D_CPU1_SB_CA(2)    I91 @S9S_MB_2U_LIB.S9S_MB_2U(SCH_1):PAGE54
  AL43 M_D_CPU1_SB_CA<1> @S9S_MB_2U_LIB.S9S_MB_2U(SCH_1):M_D_CPU1_SB_CA(1)    I91 @S9S_MB_2U_LIB.S9S_MB_2U(SCH_1):PAGE54
  AK44 M_D_CPU1_SB_CA<0> @S9S_MB_2U_LIB.S9S_MB_2U(SCH_1):M_D_CPU1_SB_CA(0)    I91 @S9S_MB_2U_LIB.S9S_MB_2U(SCH_1):PAGE54
  AD40 M_D_CPU1_SB_CS_N<3> @S9S_MB_2U_LIB.S9S_MB_2U(SCH_1):M_D_CPU1_SB_CS_N(3)    I91 @S9S_MB_2U_LIB.S9S_MB_2U(SCH_1):PAGE54
  AF40 M_D_CPU1_SB_CS_N<2> @S9S_MB_2U_LIB.S9S_MB_2U(SCH_1):M_D_CPU1_SB_CS_N(2)    I91 @S9S_MB_2U_LIB.S9S_MB_2U(SCH_1):PAGE54
  AG41 M_D_CPU1_SB_CS_N<1> @S9S_MB_2U_LIB.S9S_MB_2U(SCH_1):M_D_CPU1_SB_CS_N(1)    I91 @S9S_MB_2U_LIB.S9S_MB_2U(SCH_1):PAGE54
  AC41 M_D_CPU1_SB_CS_N<0> @S9S_MB_2U_LIB.S9S_MB_2U(SCH_1):M_D_CPU1_SB_CS_N(0)    I91 @S9S_MB_2U_LIB.S9S_MB_2U(SCH_1):PAGE54
  AN19 M_D_CPU1_SB_DQ<31> @S9S_MB_2U_LIB.S9S_MB_2U(SCH_1):M_D_CPU1_SB_DQ(31)    I91 @S9S_MB_2U_LIB.S9S_MB_2U(SCH_1):PAGE54
  AP20 M_D_CPU1_SB_DQ<30> @S9S_MB_2U_LIB.S9S_MB_2U(SCH_1):M_D_CPU1_SB_DQ(30)    I91 @S9S_MB_2U_LIB.S9S_MB_2U(SCH_1):PAGE54
  AL19 M_D_CPU1_SB_DQ<29> @S9S_MB_2U_LIB.S9S_MB_2U(SCH_1):M_D_CPU1_SB_DQ(29)    I91 @S9S_MB_2U_LIB.S9S_MB_2U(SCH_1):PAGE54
  AK20 M_D_CPU1_SB_DQ<28> @S9S_MB_2U_LIB.S9S_MB_2U(SCH_1):M_D_CPU1_SB_DQ(28)    I91 @S9S_MB_2U_LIB.S9S_MB_2U(SCH_1):PAGE54
  AP22 M_D_CPU1_SB_DQ<27> @S9S_MB_2U_LIB.S9S_MB_2U(SCH_1):M_D_CPU1_SB_DQ(27)    I91 @S9S_MB_2U_LIB.S9S_MB_2U(SCH_1):PAGE54
  AN23 M_D_CPU1_SB_DQ<26> @S9S_MB_2U_LIB.S9S_MB_2U(SCH_1):M_D_CPU1_SB_DQ(26)    I91 @S9S_MB_2U_LIB.S9S_MB_2U(SCH_1):PAGE54
  AK22 M_D_CPU1_SB_DQ<25> @S9S_MB_2U_LIB.S9S_MB_2U(SCH_1):M_D_CPU1_SB_DQ(25)    I91 @S9S_MB_2U_LIB.S9S_MB_2U(SCH_1):PAGE54
  AL23 M_D_CPU1_SB_DQ<24> @S9S_MB_2U_LIB.S9S_MB_2U(SCH_1):M_D_CPU1_SB_DQ(24)    I91 @S9S_MB_2U_LIB.S9S_MB_2U(SCH_1):PAGE54
  AF22 M_D_CPU1_SB_DQ<23> @S9S_MB_2U_LIB.S9S_MB_2U(SCH_1):M_D_CPU1_SB_DQ(23)    I91 @S9S_MB_2U_LIB.S9S_MB_2U(SCH_1):PAGE54
  AG23 M_D_CPU1_SB_DQ<22> @S9S_MB_2U_LIB.S9S_MB_2U(SCH_1):M_D_CPU1_SB_DQ(22)    I91 @S9S_MB_2U_LIB.S9S_MB_2U(SCH_1):PAGE54
  AD22 M_D_CPU1_SB_DQ<21> @S9S_MB_2U_LIB.S9S_MB_2U(SCH_1):M_D_CPU1_SB_DQ(21)    I91 @S9S_MB_2U_LIB.S9S_MB_2U(SCH_1):PAGE54
  AC23 M_D_CPU1_SB_DQ<20> @S9S_MB_2U_LIB.S9S_MB_2U(SCH_1):M_D_CPU1_SB_DQ(20)    I91 @S9S_MB_2U_LIB.S9S_MB_2U(SCH_1):PAGE54
  AG25 M_D_CPU1_SB_DQ<19> @S9S_MB_2U_LIB.S9S_MB_2U(SCH_1):M_D_CPU1_SB_DQ(19)    I91 @S9S_MB_2U_LIB.S9S_MB_2U(SCH_1):PAGE54
  AF26 M_D_CPU1_SB_DQ<18> @S9S_MB_2U_LIB.S9S_MB_2U(SCH_1):M_D_CPU1_SB_DQ(18)    I91 @S9S_MB_2U_LIB.S9S_MB_2U(SCH_1):PAGE54
  AC25 M_D_CPU1_SB_DQ<17> @S9S_MB_2U_LIB.S9S_MB_2U(SCH_1):M_D_CPU1_SB_DQ(17)    I91 @S9S_MB_2U_LIB.S9S_MB_2U(SCH_1):PAGE54
  AD26 M_D_CPU1_SB_DQ<16> @S9S_MB_2U_LIB.S9S_MB_2U(SCH_1):M_D_CPU1_SB_DQ(16)    I91 @S9S_MB_2U_LIB.S9S_MB_2U(SCH_1):PAGE54
  AN25 M_D_CPU1_SB_DQ<15> @S9S_MB_2U_LIB.S9S_MB_2U(SCH_1):M_D_CPU1_SB_DQ(15)    I91 @S9S_MB_2U_LIB.S9S_MB_2U(SCH_1):PAGE54
  AP26 M_D_CPU1_SB_DQ<14> @S9S_MB_2U_LIB.S9S_MB_2U(SCH_1):M_D_CPU1_SB_DQ(14)    I91 @S9S_MB_2U_LIB.S9S_MB_2U(SCH_1):PAGE54
  AL25 M_D_CPU1_SB_DQ<13> @S9S_MB_2U_LIB.S9S_MB_2U(SCH_1):M_D_CPU1_SB_DQ(13)    I91 @S9S_MB_2U_LIB.S9S_MB_2U(SCH_1):PAGE54
  AK26 M_D_CPU1_SB_DQ<12> @S9S_MB_2U_LIB.S9S_MB_2U(SCH_1):M_D_CPU1_SB_DQ(12)    I91 @S9S_MB_2U_LIB.S9S_MB_2U(SCH_1):PAGE54
  AP28 M_D_CPU1_SB_DQ<11> @S9S_MB_2U_LIB.S9S_MB_2U(SCH_1):M_D_CPU1_SB_DQ(11)    I91 @S9S_MB_2U_LIB.S9S_MB_2U(SCH_1):PAGE54
  AN29 M_D_CPU1_SB_DQ<10> @S9S_MB_2U_LIB.S9S_MB_2U(SCH_1):M_D_CPU1_SB_DQ(10)    I91 @S9S_MB_2U_LIB.S9S_MB_2U(SCH_1):PAGE54
  AK28 M_D_CPU1_SB_DQ<9> @S9S_MB_2U_LIB.S9S_MB_2U(SCH_1):M_D_CPU1_SB_DQ(9)    I91 @S9S_MB_2U_LIB.S9S_MB_2U(SCH_1):PAGE54
  AL29 M_D_CPU1_SB_DQ<8> @S9S_MB_2U_LIB.S9S_MB_2U(SCH_1):M_D_CPU1_SB_DQ(8)    I91 @S9S_MB_2U_LIB.S9S_MB_2U(SCH_1):PAGE54
  AN31 M_D_CPU1_SB_DQ<7> @S9S_MB_2U_LIB.S9S_MB_2U(SCH_1):M_D_CPU1_SB_DQ(7)    I91 @S9S_MB_2U_LIB.S9S_MB_2U(SCH_1):PAGE54
  AP32 M_D_CPU1_SB_DQ<6> @S9S_MB_2U_LIB.S9S_MB_2U(SCH_1):M_D_CPU1_SB_DQ(6)    I91 @S9S_MB_2U_LIB.S9S_MB_2U(SCH_1):PAGE54
  AL31 M_D_CPU1_SB_DQ<5> @S9S_MB_2U_LIB.S9S_MB_2U(SCH_1):M_D_CPU1_SB_DQ(5)    I91 @S9S_MB_2U_LIB.S9S_MB_2U(SCH_1):PAGE54
  AK32 M_D_CPU1_SB_DQ<4> @S9S_MB_2U_LIB.S9S_MB_2U(SCH_1):M_D_CPU1_SB_DQ(4)    I91 @S9S_MB_2U_LIB.S9S_MB_2U(SCH_1):PAGE54
  AP34 M_D_CPU1_SB_DQ<3> @S9S_MB_2U_LIB.S9S_MB_2U(SCH_1):M_D_CPU1_SB_DQ(3)    I91 @S9S_MB_2U_LIB.S9S_MB_2U(SCH_1):PAGE54
  AN35 M_D_CPU1_SB_DQ<2> @S9S_MB_2U_LIB.S9S_MB_2U(SCH_1):M_D_CPU1_SB_DQ(2)    I91 @S9S_MB_2U_LIB.S9S_MB_2U(SCH_1):PAGE54
  AK34 M_D_CPU1_SB_DQ<1> @S9S_MB_2U_LIB.S9S_MB_2U(SCH_1):M_D_CPU1_SB_DQ(1)    I91 @S9S_MB_2U_LIB.S9S_MB_2U(SCH_1):PAGE54
  AL35 M_D_CPU1_SB_DQ<0> @S9S_MB_2U_LIB.S9S_MB_2U(SCH_1):M_D_CPU1_SB_DQ(0)    I91 @S9S_MB_2U_LIB.S9S_MB_2U(SCH_1):PAGE54
  AJ39 M_D_CPU1_SB_DQS_DN<9> @S9S_MB_2U_LIB.S9S_MB_2U(SCH_1):M_D_CPU1_SB_DQS_DN(9)    I91 @S9S_MB_2U_LIB.S9S_MB_2U(SCH_1):PAGE54
  AN21 M_D_CPU1_SB_DQS_DN<8> @S9S_MB_2U_LIB.S9S_MB_2U(SCH_1):M_D_CPU1_SB_DQS_DN(8)    I91 @S9S_MB_2U_LIB.S9S_MB_2U(SCH_1):PAGE54
  AF24 M_D_CPU1_SB_DQS_DN<7> @S9S_MB_2U_LIB.S9S_MB_2U(SCH_1):M_D_CPU1_SB_DQS_DN(7)    I91 @S9S_MB_2U_LIB.S9S_MB_2U(SCH_1):PAGE54
  AN27 M_D_CPU1_SB_DQS_DN<6> @S9S_MB_2U_LIB.S9S_MB_2U(SCH_1):M_D_CPU1_SB_DQS_DN(6)    I91 @S9S_MB_2U_LIB.S9S_MB_2U(SCH_1):PAGE54
  AN33 M_D_CPU1_SB_DQS_DN<5> @S9S_MB_2U_LIB.S9S_MB_2U(SCH_1):M_D_CPU1_SB_DQS_DN(5)    I91 @S9S_MB_2U_LIB.S9S_MB_2U(SCH_1):PAGE54
  AR39 M_D_CPU1_SB_DQS_DN<4> @S9S_MB_2U_LIB.S9S_MB_2U(SCH_1):M_D_CPU1_SB_DQS_DN(4)    I91 @S9S_MB_2U_LIB.S9S_MB_2U(SCH_1):PAGE54
  AJ21 M_D_CPU1_SB_DQS_DN<3> @S9S_MB_2U_LIB.S9S_MB_2U(SCH_1):M_D_CPU1_SB_DQS_DN(3)    I91 @S9S_MB_2U_LIB.S9S_MB_2U(SCH_1):PAGE54
  AB24 M_D_CPU1_SB_DQS_DN<2> @S9S_MB_2U_LIB.S9S_MB_2U(SCH_1):M_D_CPU1_SB_DQS_DN(2)    I91 @S9S_MB_2U_LIB.S9S_MB_2U(SCH_1):PAGE54
  AJ27 M_D_CPU1_SB_DQS_DN<1> @S9S_MB_2U_LIB.S9S_MB_2U(SCH_1):M_D_CPU1_SB_DQS_DN(1)    I91 @S9S_MB_2U_LIB.S9S_MB_2U(SCH_1):PAGE54
  AJ33 M_D_CPU1_SB_DQS_DN<0> @S9S_MB_2U_LIB.S9S_MB_2U(SCH_1):M_D_CPU1_SB_DQS_DN(0)    I91 @S9S_MB_2U_LIB.S9S_MB_2U(SCH_1):PAGE54
  AL39 M_D_CPU1_SB_DQS_DP<9> @S9S_MB_2U_LIB.S9S_MB_2U(SCH_1):M_D_CPU1_SB_DQS_DP(9)    I91 @S9S_MB_2U_LIB.S9S_MB_2U(SCH_1):PAGE54
  AR21 M_D_CPU1_SB_DQS_DP<8> @S9S_MB_2U_LIB.S9S_MB_2U(SCH_1):M_D_CPU1_SB_DQS_DP(8)    I91 @S9S_MB_2U_LIB.S9S_MB_2U(SCH_1):PAGE54
  AH24 M_D_CPU1_SB_DQS_DP<7> @S9S_MB_2U_LIB.S9S_MB_2U(SCH_1):M_D_CPU1_SB_DQS_DP(7)    I91 @S9S_MB_2U_LIB.S9S_MB_2U(SCH_1):PAGE54
  AR27 M_D_CPU1_SB_DQS_DP<6> @S9S_MB_2U_LIB.S9S_MB_2U(SCH_1):M_D_CPU1_SB_DQS_DP(6)    I91 @S9S_MB_2U_LIB.S9S_MB_2U(SCH_1):PAGE54
  AR33 M_D_CPU1_SB_DQS_DP<5> @S9S_MB_2U_LIB.S9S_MB_2U(SCH_1):M_D_CPU1_SB_DQS_DP(5)    I91 @S9S_MB_2U_LIB.S9S_MB_2U(SCH_1):PAGE54
  AN39 M_D_CPU1_SB_DQS_DP<4> @S9S_MB_2U_LIB.S9S_MB_2U(SCH_1):M_D_CPU1_SB_DQS_DP(4)    I91 @S9S_MB_2U_LIB.S9S_MB_2U(SCH_1):PAGE54
  AL21 M_D_CPU1_SB_DQS_DP<3> @S9S_MB_2U_LIB.S9S_MB_2U(SCH_1):M_D_CPU1_SB_DQS_DP(3)    I91 @S9S_MB_2U_LIB.S9S_MB_2U(SCH_1):PAGE54
  AD24 M_D_CPU1_SB_DQS_DP<2> @S9S_MB_2U_LIB.S9S_MB_2U(SCH_1):M_D_CPU1_SB_DQS_DP(2)    I91 @S9S_MB_2U_LIB.S9S_MB_2U(SCH_1):PAGE54
  AL27 M_D_CPU1_SB_DQS_DP<1> @S9S_MB_2U_LIB.S9S_MB_2U(SCH_1):M_D_CPU1_SB_DQS_DP(1)    I91 @S9S_MB_2U_LIB.S9S_MB_2U(SCH_1):PAGE54
  AL33 M_D_CPU1_SB_DQS_DP<0> @S9S_MB_2U_LIB.S9S_MB_2U(SCH_1):M_D_CPU1_SB_DQS_DP(0)    I91 @S9S_MB_2U_LIB.S9S_MB_2U(SCH_1):PAGE54
  AP40 M_D_CPU1_SB_CB<7> @S9S_MB_2U_LIB.S9S_MB_2U(SCH_1):M_D_CPU1_SB_CB(7)    I91 @S9S_MB_2U_LIB.S9S_MB_2U(SCH_1):PAGE54
  AN41 M_D_CPU1_SB_CB<6> @S9S_MB_2U_LIB.S9S_MB_2U(SCH_1):M_D_CPU1_SB_CB(6)    I91 @S9S_MB_2U_LIB.S9S_MB_2U(SCH_1):PAGE54
  AK40 M_D_CPU1_SB_CB<5> @S9S_MB_2U_LIB.S9S_MB_2U(SCH_1):M_D_CPU1_SB_CB(5)    I91 @S9S_MB_2U_LIB.S9S_MB_2U(SCH_1):PAGE54
  AL41 M_D_CPU1_SB_CB<4> @S9S_MB_2U_LIB.S9S_MB_2U(SCH_1):M_D_CPU1_SB_CB(4)    I91 @S9S_MB_2U_LIB.S9S_MB_2U(SCH_1):PAGE54
  AN37 M_D_CPU1_SB_CB<3> @S9S_MB_2U_LIB.S9S_MB_2U(SCH_1):M_D_CPU1_SB_CB(3)    I91 @S9S_MB_2U_LIB.S9S_MB_2U(SCH_1):PAGE54
  AP38 M_D_CPU1_SB_CB<2> @S9S_MB_2U_LIB.S9S_MB_2U(SCH_1):M_D_CPU1_SB_CB(2)    I91 @S9S_MB_2U_LIB.S9S_MB_2U(SCH_1):PAGE54
  AL37 M_D_CPU1_SB_CB<1> @S9S_MB_2U_LIB.S9S_MB_2U(SCH_1):M_D_CPU1_SB_CB(1)    I91 @S9S_MB_2U_LIB.S9S_MB_2U(SCH_1):PAGE54
  AK38 M_D_CPU1_SB_CB<0> @S9S_MB_2U_LIB.S9S_MB_2U(SCH_1):M_D_CPU1_SB_CB(0)    I91 @S9S_MB_2U_LIB.S9S_MB_2U(SCH_1):PAGE54
  AH42 M_D_CPU1_SB_PAR @S9S_MB_2U_LIB.S9S_MB_2U(SCH_1):M_D_CPU1_SB_PAR    I91 @S9S_MB_2U_LIB.S9S_MB_2U(SCH_1):PAGE54
  CY47 M_E_CPU1_ALERT_N @S9S_MB_2U_LIB.S9S_MB_2U(SCH_1):M_E_CPU1_ALERT_N     I7 @S9S_MB_2U_LIB.S9S_MB_2U(SCH_1):PAGE55
  DC43 M_E_CPU1_SA_RSP<1> @S9S_MB_2U_LIB.S9S_MB_2U(SCH_1):M_E_CPU1_SA_RSP(1)     I7 @S9S_MB_2U_LIB.S9S_MB_2U(SCH_1):PAGE55
  DD44 M_E_CPU1_SA_RSP<0> @S9S_MB_2U_LIB.S9S_MB_2U(SCH_1):M_E_CPU1_SA_RSP(0)     I7 @S9S_MB_2U_LIB.S9S_MB_2U(SCH_1):PAGE55
  DG43 M_E_CPU1_SB_RSP<1> @S9S_MB_2U_LIB.S9S_MB_2U(SCH_1):M_E_CPU1_SB_RSP(1)     I7 @S9S_MB_2U_LIB.S9S_MB_2U(SCH_1):PAGE55
  DF44 M_E_CPU1_SB_RSP<0> @S9S_MB_2U_LIB.S9S_MB_2U(SCH_1):M_E_CPU1_SB_RSP(0)     I7 @S9S_MB_2U_LIB.S9S_MB_2U(SCH_1):PAGE55
  EE45 M_E_CPU1_CLK_DN<1> @S9S_MB_2U_LIB.S9S_MB_2U(SCH_1):M_E_CPU1_CLK_DN(1)     I7 @S9S_MB_2U_LIB.S9S_MB_2U(SCH_1):PAGE55
  EJ45 M_E_CPU1_CLK_DN<0> @S9S_MB_2U_LIB.S9S_MB_2U(SCH_1):M_E_CPU1_CLK_DN(0)     I7 @S9S_MB_2U_LIB.S9S_MB_2U(SCH_1):PAGE55
  EC45 M_E_CPU1_CLK_DP<1> @S9S_MB_2U_LIB.S9S_MB_2U(SCH_1):M_E_CPU1_CLK_DP(1)     I7 @S9S_MB_2U_LIB.S9S_MB_2U(SCH_1):PAGE55
  EG45 M_E_CPU1_CLK_DP<0> @S9S_MB_2U_LIB.S9S_MB_2U(SCH_1):M_E_CPU1_CLK_DP(0)     I7 @S9S_MB_2U_LIB.S9S_MB_2U(SCH_1):PAGE55
  ED44 M_E_CPU1_SA_CA<6> @S9S_MB_2U_LIB.S9S_MB_2U(SCH_1):M_E_CPU1_SA_CA(6)     I7 @S9S_MB_2U_LIB.S9S_MB_2U(SCH_1):PAGE55
  EP47 M_E_CPU1_SA_CA<5> @S9S_MB_2U_LIB.S9S_MB_2U(SCH_1):M_E_CPU1_SA_CA(5)     I7 @S9S_MB_2U_LIB.S9S_MB_2U(SCH_1):PAGE55
  EM47 M_E_CPU1_SA_CA<4> @S9S_MB_2U_LIB.S9S_MB_2U(SCH_1):M_E_CPU1_SA_CA(4)     I7 @S9S_MB_2U_LIB.S9S_MB_2U(SCH_1):PAGE55
  EL48 M_E_CPU1_SA_CA<3> @S9S_MB_2U_LIB.S9S_MB_2U(SCH_1):M_E_CPU1_SA_CA(3)     I7 @S9S_MB_2U_LIB.S9S_MB_2U(SCH_1):PAGE55
  EK49 M_E_CPU1_SA_CA<2> @S9S_MB_2U_LIB.S9S_MB_2U(SCH_1):M_E_CPU1_SA_CA(2)     I7 @S9S_MB_2U_LIB.S9S_MB_2U(SCH_1):PAGE55
  ET49 M_E_CPU1_SA_CA<1> @S9S_MB_2U_LIB.S9S_MB_2U(SCH_1):M_E_CPU1_SA_CA(1)     I7 @S9S_MB_2U_LIB.S9S_MB_2U(SCH_1):PAGE55
  EP49 M_E_CPU1_SA_CA<0> @S9S_MB_2U_LIB.S9S_MB_2U(SCH_1):M_E_CPU1_SA_CA(0)     I7 @S9S_MB_2U_LIB.S9S_MB_2U(SCH_1):PAGE55
  EL50 M_E_CPU1_SA_CS_N<3> @S9S_MB_2U_LIB.S9S_MB_2U(SCH_1):M_E_CPU1_SA_CS_N(3)     I7 @S9S_MB_2U_LIB.S9S_MB_2U(SCH_1):PAGE55
  EM51 M_E_CPU1_SA_CS_N<2> @S9S_MB_2U_LIB.S9S_MB_2U(SCH_1):M_E_CPU1_SA_CS_N(2)     I7 @S9S_MB_2U_LIB.S9S_MB_2U(SCH_1):PAGE55
  ET51 M_E_CPU1_SA_CS_N<1> @S9S_MB_2U_LIB.S9S_MB_2U(SCH_1):M_E_CPU1_SA_CS_N(1)     I7 @S9S_MB_2U_LIB.S9S_MB_2U(SCH_1):PAGE55
  EP51 M_E_CPU1_SA_CS_N<0> @S9S_MB_2U_LIB.S9S_MB_2U(SCH_1):M_E_CPU1_SA_CS_N(0)     I7 @S9S_MB_2U_LIB.S9S_MB_2U(SCH_1):PAGE55
  EP59 M_E_CPU1_SA_DQ<31> @S9S_MB_2U_LIB.S9S_MB_2U(SCH_1):M_E_CPU1_SA_DQ(31)     I7 @S9S_MB_2U_LIB.S9S_MB_2U(SCH_1):PAGE55
  ER60 M_E_CPU1_SA_DQ<30> @S9S_MB_2U_LIB.S9S_MB_2U(SCH_1):M_E_CPU1_SA_DQ(30)     I7 @S9S_MB_2U_LIB.S9S_MB_2U(SCH_1):PAGE55
  EM59 M_E_CPU1_SA_DQ<29> @S9S_MB_2U_LIB.S9S_MB_2U(SCH_1):M_E_CPU1_SA_DQ(29)     I7 @S9S_MB_2U_LIB.S9S_MB_2U(SCH_1):PAGE55
  EL60 M_E_CPU1_SA_DQ<28> @S9S_MB_2U_LIB.S9S_MB_2U(SCH_1):M_E_CPU1_SA_DQ(28)     I7 @S9S_MB_2U_LIB.S9S_MB_2U(SCH_1):PAGE55
  ER62 M_E_CPU1_SA_DQ<27> @S9S_MB_2U_LIB.S9S_MB_2U(SCH_1):M_E_CPU1_SA_DQ(27)     I7 @S9S_MB_2U_LIB.S9S_MB_2U(SCH_1):PAGE55
  EP63 M_E_CPU1_SA_DQ<26> @S9S_MB_2U_LIB.S9S_MB_2U(SCH_1):M_E_CPU1_SA_DQ(26)     I7 @S9S_MB_2U_LIB.S9S_MB_2U(SCH_1):PAGE55
  EL62 M_E_CPU1_SA_DQ<25> @S9S_MB_2U_LIB.S9S_MB_2U(SCH_1):M_E_CPU1_SA_DQ(25)     I7 @S9S_MB_2U_LIB.S9S_MB_2U(SCH_1):PAGE55
  EM63 M_E_CPU1_SA_DQ<24> @S9S_MB_2U_LIB.S9S_MB_2U(SCH_1):M_E_CPU1_SA_DQ(24)     I7 @S9S_MB_2U_LIB.S9S_MB_2U(SCH_1):PAGE55
  EP65 M_E_CPU1_SA_DQ<23> @S9S_MB_2U_LIB.S9S_MB_2U(SCH_1):M_E_CPU1_SA_DQ(23)     I7 @S9S_MB_2U_LIB.S9S_MB_2U(SCH_1):PAGE55
  EL66 M_E_CPU1_SA_DQ<22> @S9S_MB_2U_LIB.S9S_MB_2U(SCH_1):M_E_CPU1_SA_DQ(22)     I7 @S9S_MB_2U_LIB.S9S_MB_2U(SCH_1):PAGE55
  EM65 M_E_CPU1_SA_DQ<21> @S9S_MB_2U_LIB.S9S_MB_2U(SCH_1):M_E_CPU1_SA_DQ(21)     I7 @S9S_MB_2U_LIB.S9S_MB_2U(SCH_1):PAGE55
  ER66 M_E_CPU1_SA_DQ<20> @S9S_MB_2U_LIB.S9S_MB_2U(SCH_1):M_E_CPU1_SA_DQ(20)     I7 @S9S_MB_2U_LIB.S9S_MB_2U(SCH_1):PAGE55
  ER68 M_E_CPU1_SA_DQ<19> @S9S_MB_2U_LIB.S9S_MB_2U(SCH_1):M_E_CPU1_SA_DQ(19)     I7 @S9S_MB_2U_LIB.S9S_MB_2U(SCH_1):PAGE55
  EN70 M_E_CPU1_SA_DQ<18> @S9S_MB_2U_LIB.S9S_MB_2U(SCH_1):M_E_CPU1_SA_DQ(18)     I7 @S9S_MB_2U_LIB.S9S_MB_2U(SCH_1):PAGE55
  EM69 M_E_CPU1_SA_DQ<17> @S9S_MB_2U_LIB.S9S_MB_2U(SCH_1):M_E_CPU1_SA_DQ(17)     I7 @S9S_MB_2U_LIB.S9S_MB_2U(SCH_1):PAGE55
  EM71 M_E_CPU1_SA_DQ<16> @S9S_MB_2U_LIB.S9S_MB_2U(SCH_1):M_E_CPU1_SA_DQ(16)     I7 @S9S_MB_2U_LIB.S9S_MB_2U(SCH_1):PAGE55
  EG68 M_E_CPU1_SA_DQ<15> @S9S_MB_2U_LIB.S9S_MB_2U(SCH_1):M_E_CPU1_SA_DQ(15)     I7 @S9S_MB_2U_LIB.S9S_MB_2U(SCH_1):PAGE55
  EH69 M_E_CPU1_SA_DQ<14> @S9S_MB_2U_LIB.S9S_MB_2U(SCH_1):M_E_CPU1_SA_DQ(14)     I7 @S9S_MB_2U_LIB.S9S_MB_2U(SCH_1):PAGE55
  EE68 M_E_CPU1_SA_DQ<13> @S9S_MB_2U_LIB.S9S_MB_2U(SCH_1):M_E_CPU1_SA_DQ(13)     I7 @S9S_MB_2U_LIB.S9S_MB_2U(SCH_1):PAGE55
  ED69 M_E_CPU1_SA_DQ<12> @S9S_MB_2U_LIB.S9S_MB_2U(SCH_1):M_E_CPU1_SA_DQ(12)     I7 @S9S_MB_2U_LIB.S9S_MB_2U(SCH_1):PAGE55
  EH71 M_E_CPU1_SA_DQ<11> @S9S_MB_2U_LIB.S9S_MB_2U(SCH_1):M_E_CPU1_SA_DQ(11)     I7 @S9S_MB_2U_LIB.S9S_MB_2U(SCH_1):PAGE55
  EG72 M_E_CPU1_SA_DQ<10> @S9S_MB_2U_LIB.S9S_MB_2U(SCH_1):M_E_CPU1_SA_DQ(10)     I7 @S9S_MB_2U_LIB.S9S_MB_2U(SCH_1):PAGE55
  ED71 M_E_CPU1_SA_DQ<9> @S9S_MB_2U_LIB.S9S_MB_2U(SCH_1):M_E_CPU1_SA_DQ(9)     I7 @S9S_MB_2U_LIB.S9S_MB_2U(SCH_1):PAGE55
  EE72 M_E_CPU1_SA_DQ<8> @S9S_MB_2U_LIB.S9S_MB_2U(SCH_1):M_E_CPU1_SA_DQ(8)     I7 @S9S_MB_2U_LIB.S9S_MB_2U(SCH_1):PAGE55
  ER72 M_E_CPU1_SA_DQ<7> @S9S_MB_2U_LIB.S9S_MB_2U(SCH_1):M_E_CPU1_SA_DQ(7)     I7 @S9S_MB_2U_LIB.S9S_MB_2U(SCH_1):PAGE55
  EP73 M_E_CPU1_SA_DQ<6> @S9S_MB_2U_LIB.S9S_MB_2U(SCH_1):M_E_CPU1_SA_DQ(6)     I7 @S9S_MB_2U_LIB.S9S_MB_2U(SCH_1):PAGE55
  EK73 M_E_CPU1_SA_DQ<5> @S9S_MB_2U_LIB.S9S_MB_2U(SCH_1):M_E_CPU1_SA_DQ(5)     I7 @S9S_MB_2U_LIB.S9S_MB_2U(SCH_1):PAGE55
  EL74 M_E_CPU1_SA_DQ<4> @S9S_MB_2U_LIB.S9S_MB_2U(SCH_1):M_E_CPU1_SA_DQ(4)     I7 @S9S_MB_2U_LIB.S9S_MB_2U(SCH_1):PAGE55
  ER76 M_E_CPU1_SA_DQ<3> @S9S_MB_2U_LIB.S9S_MB_2U(SCH_1):M_E_CPU1_SA_DQ(3)     I7 @S9S_MB_2U_LIB.S9S_MB_2U(SCH_1):PAGE55
  EP79 M_E_CPU1_SA_DQ<2> @S9S_MB_2U_LIB.S9S_MB_2U(SCH_1):M_E_CPU1_SA_DQ(2)     I7 @S9S_MB_2U_LIB.S9S_MB_2U(SCH_1):PAGE55
  EM77 M_E_CPU1_SA_DQ<1> @S9S_MB_2U_LIB.S9S_MB_2U(SCH_1):M_E_CPU1_SA_DQ(1)     I7 @S9S_MB_2U_LIB.S9S_MB_2U(SCH_1):PAGE55
  EL78 M_E_CPU1_SA_DQ<0> @S9S_MB_2U_LIB.S9S_MB_2U(SCH_1):M_E_CPU1_SA_DQ(0)     I7 @S9S_MB_2U_LIB.S9S_MB_2U(SCH_1):PAGE55
  ET55 M_E_CPU1_SA_DQS_DN<9> @S9S_MB_2U_LIB.S9S_MB_2U(SCH_1):M_E_CPU1_SA_DQS_DN(9)     I7 @S9S_MB_2U_LIB.S9S_MB_2U(SCH_1):PAGE55
  ET61 M_E_CPU1_SA_DQS_DN<8> @S9S_MB_2U_LIB.S9S_MB_2U(SCH_1):M_E_CPU1_SA_DQS_DN(8)     I7 @S9S_MB_2U_LIB.S9S_MB_2U(SCH_1):PAGE55
  EN68 M_E_CPU1_SA_DQS_DN<7> @S9S_MB_2U_LIB.S9S_MB_2U(SCH_1):M_E_CPU1_SA_DQS_DN(7)     I7 @S9S_MB_2U_LIB.S9S_MB_2U(SCH_1):PAGE55
  EJ70 M_E_CPU1_SA_DQS_DN<6> @S9S_MB_2U_LIB.S9S_MB_2U(SCH_1):M_E_CPU1_SA_DQS_DN(6)     I7 @S9S_MB_2U_LIB.S9S_MB_2U(SCH_1):PAGE55
  EM75 M_E_CPU1_SA_DQS_DN<5> @S9S_MB_2U_LIB.S9S_MB_2U(SCH_1):M_E_CPU1_SA_DQS_DN(5)     I7 @S9S_MB_2U_LIB.S9S_MB_2U(SCH_1):PAGE55
  EM55 M_E_CPU1_SA_DQS_DN<4> @S9S_MB_2U_LIB.S9S_MB_2U(SCH_1):M_E_CPU1_SA_DQS_DN(4)     I7 @S9S_MB_2U_LIB.S9S_MB_2U(SCH_1):PAGE55
  EK61 M_E_CPU1_SA_DQS_DN<3> @S9S_MB_2U_LIB.S9S_MB_2U(SCH_1):M_E_CPU1_SA_DQS_DN(3)     I7 @S9S_MB_2U_LIB.S9S_MB_2U(SCH_1):PAGE55
  EK67 M_E_CPU1_SA_DQS_DN<2> @S9S_MB_2U_LIB.S9S_MB_2U(SCH_1):M_E_CPU1_SA_DQS_DN(2)     I7 @S9S_MB_2U_LIB.S9S_MB_2U(SCH_1):PAGE55
  EC70 M_E_CPU1_SA_DQS_DN<1> @S9S_MB_2U_LIB.S9S_MB_2U(SCH_1):M_E_CPU1_SA_DQS_DN(1)     I7 @S9S_MB_2U_LIB.S9S_MB_2U(SCH_1):PAGE55
  EP75 M_E_CPU1_SA_DQS_DN<0> @S9S_MB_2U_LIB.S9S_MB_2U(SCH_1):M_E_CPU1_SA_DQS_DN(0)     I7 @S9S_MB_2U_LIB.S9S_MB_2U(SCH_1):PAGE55
  EP55 M_E_CPU1_SA_DQS_DP<9> @S9S_MB_2U_LIB.S9S_MB_2U(SCH_1):M_E_CPU1_SA_DQS_DP(9)     I7 @S9S_MB_2U_LIB.S9S_MB_2U(SCH_1):PAGE55
  EP61 M_E_CPU1_SA_DQS_DP<8> @S9S_MB_2U_LIB.S9S_MB_2U(SCH_1):M_E_CPU1_SA_DQS_DP(8)     I7 @S9S_MB_2U_LIB.S9S_MB_2U(SCH_1):PAGE55
  EM67 M_E_CPU1_SA_DQS_DP<7> @S9S_MB_2U_LIB.S9S_MB_2U(SCH_1):M_E_CPU1_SA_DQS_DP(7)     I7 @S9S_MB_2U_LIB.S9S_MB_2U(SCH_1):PAGE55
  EG70 M_E_CPU1_SA_DQS_DP<6> @S9S_MB_2U_LIB.S9S_MB_2U(SCH_1):M_E_CPU1_SA_DQS_DP(6)     I7 @S9S_MB_2U_LIB.S9S_MB_2U(SCH_1):PAGE55
  EN74 M_E_CPU1_SA_DQS_DP<5> @S9S_MB_2U_LIB.S9S_MB_2U(SCH_1):M_E_CPU1_SA_DQS_DP(5)     I7 @S9S_MB_2U_LIB.S9S_MB_2U(SCH_1):PAGE55
  EK55 M_E_CPU1_SA_DQS_DP<4> @S9S_MB_2U_LIB.S9S_MB_2U(SCH_1):M_E_CPU1_SA_DQS_DP(4)     I7 @S9S_MB_2U_LIB.S9S_MB_2U(SCH_1):PAGE55
  EM61 M_E_CPU1_SA_DQS_DP<3> @S9S_MB_2U_LIB.S9S_MB_2U(SCH_1):M_E_CPU1_SA_DQS_DP(3)     I7 @S9S_MB_2U_LIB.S9S_MB_2U(SCH_1):PAGE55
  EL68 M_E_CPU1_SA_DQS_DP<2> @S9S_MB_2U_LIB.S9S_MB_2U(SCH_1):M_E_CPU1_SA_DQS_DP(2)     I7 @S9S_MB_2U_LIB.S9S_MB_2U(SCH_1):PAGE55
  EE70 M_E_CPU1_SA_DQS_DP<1> @S9S_MB_2U_LIB.S9S_MB_2U(SCH_1):M_E_CPU1_SA_DQS_DP(1)     I7 @S9S_MB_2U_LIB.S9S_MB_2U(SCH_1):PAGE55
  EN76 M_E_CPU1_SA_DQS_DP<0> @S9S_MB_2U_LIB.S9S_MB_2U(SCH_1):M_E_CPU1_SA_DQS_DP(0)     I7 @S9S_MB_2U_LIB.S9S_MB_2U(SCH_1):PAGE55
  EP53 M_E_CPU1_SA_CB<7> @S9S_MB_2U_LIB.S9S_MB_2U(SCH_1):M_E_CPU1_SA_CB(7)     I7 @S9S_MB_2U_LIB.S9S_MB_2U(SCH_1):PAGE55
  ER54 M_E_CPU1_SA_CB<6> @S9S_MB_2U_LIB.S9S_MB_2U(SCH_1):M_E_CPU1_SA_CB(6)     I7 @S9S_MB_2U_LIB.S9S_MB_2U(SCH_1):PAGE55
  EM53 M_E_CPU1_SA_CB<5> @S9S_MB_2U_LIB.S9S_MB_2U(SCH_1):M_E_CPU1_SA_CB(5)     I7 @S9S_MB_2U_LIB.S9S_MB_2U(SCH_1):PAGE55
  EL54 M_E_CPU1_SA_CB<4> @S9S_MB_2U_LIB.S9S_MB_2U(SCH_1):M_E_CPU1_SA_CB(4)     I7 @S9S_MB_2U_LIB.S9S_MB_2U(SCH_1):PAGE55
  ER56 M_E_CPU1_SA_CB<3> @S9S_MB_2U_LIB.S9S_MB_2U(SCH_1):M_E_CPU1_SA_CB(3)     I7 @S9S_MB_2U_LIB.S9S_MB_2U(SCH_1):PAGE55
  EP57 M_E_CPU1_SA_CB<2> @S9S_MB_2U_LIB.S9S_MB_2U(SCH_1):M_E_CPU1_SA_CB(2)     I7 @S9S_MB_2U_LIB.S9S_MB_2U(SCH_1):PAGE55
  EL56 M_E_CPU1_SA_CB<1> @S9S_MB_2U_LIB.S9S_MB_2U(SCH_1):M_E_CPU1_SA_CB(1)     I7 @S9S_MB_2U_LIB.S9S_MB_2U(SCH_1):PAGE55
  EM57 M_E_CPU1_SA_CB<0> @S9S_MB_2U_LIB.S9S_MB_2U(SCH_1):M_E_CPU1_SA_CB(0)     I7 @S9S_MB_2U_LIB.S9S_MB_2U(SCH_1):PAGE55
  EE43 M_E_CPU1_SA_PAR @S9S_MB_2U_LIB.S9S_MB_2U(SCH_1):M_E_CPU1_SA_PAR     I7 @S9S_MB_2U_LIB.S9S_MB_2U(SCH_1):PAGE55
  EK42 M_E_CPU1_SB_CA<6> @S9S_MB_2U_LIB.S9S_MB_2U(SCH_1):M_E_CPU1_SB_CA(6)     I7 @S9S_MB_2U_LIB.S9S_MB_2U(SCH_1):PAGE55
  ET42 M_E_CPU1_SB_CA<5> @S9S_MB_2U_LIB.S9S_MB_2U(SCH_1):M_E_CPU1_SB_CA(5)     I7 @S9S_MB_2U_LIB.S9S_MB_2U(SCH_1):PAGE55
  EL43 M_E_CPU1_SB_CA<4> @S9S_MB_2U_LIB.S9S_MB_2U(SCH_1):M_E_CPU1_SB_CA(4)     I7 @S9S_MB_2U_LIB.S9S_MB_2U(SCH_1):PAGE55
  EP44 M_E_CPU1_SB_CA<3> @S9S_MB_2U_LIB.S9S_MB_2U(SCH_1):M_E_CPU1_SB_CA(3)     I7 @S9S_MB_2U_LIB.S9S_MB_2U(SCH_1):PAGE55
  EM44 M_E_CPU1_SB_CA<2> @S9S_MB_2U_LIB.S9S_MB_2U(SCH_1):M_E_CPU1_SB_CA(2)     I7 @S9S_MB_2U_LIB.S9S_MB_2U(SCH_1):PAGE55
  EH44 M_E_CPU1_SB_CA<1> @S9S_MB_2U_LIB.S9S_MB_2U(SCH_1):M_E_CPU1_SB_CA(1)     I7 @S9S_MB_2U_LIB.S9S_MB_2U(SCH_1):PAGE55
  EG43 M_E_CPU1_SB_CA<0> @S9S_MB_2U_LIB.S9S_MB_2U(SCH_1):M_E_CPU1_SB_CA(0)     I7 @S9S_MB_2U_LIB.S9S_MB_2U(SCH_1):PAGE55
  EL41 M_E_CPU1_SB_CS_N<3> @S9S_MB_2U_LIB.S9S_MB_2U(SCH_1):M_E_CPU1_SB_CS_N(3)     I7 @S9S_MB_2U_LIB.S9S_MB_2U(SCH_1):PAGE55
  EM40 M_E_CPU1_SB_CS_N<2> @S9S_MB_2U_LIB.S9S_MB_2U(SCH_1):M_E_CPU1_SB_CS_N(2)     I7 @S9S_MB_2U_LIB.S9S_MB_2U(SCH_1):PAGE55
  ET40 M_E_CPU1_SB_CS_N<1> @S9S_MB_2U_LIB.S9S_MB_2U(SCH_1):M_E_CPU1_SB_CS_N(1)     I7 @S9S_MB_2U_LIB.S9S_MB_2U(SCH_1):PAGE55
  EP40 M_E_CPU1_SB_CS_N<0> @S9S_MB_2U_LIB.S9S_MB_2U(SCH_1):M_E_CPU1_SB_CS_N(0)     I7 @S9S_MB_2U_LIB.S9S_MB_2U(SCH_1):PAGE55
  EP16 M_E_CPU1_SB_DQ<31> @S9S_MB_2U_LIB.S9S_MB_2U(SCH_1):M_E_CPU1_SB_DQ(31)     I7 @S9S_MB_2U_LIB.S9S_MB_2U(SCH_1):PAGE55
  ER17 M_E_CPU1_SB_DQ<30> @S9S_MB_2U_LIB.S9S_MB_2U(SCH_1):M_E_CPU1_SB_DQ(30)     I7 @S9S_MB_2U_LIB.S9S_MB_2U(SCH_1):PAGE55
  EM16 M_E_CPU1_SB_DQ<29> @S9S_MB_2U_LIB.S9S_MB_2U(SCH_1):M_E_CPU1_SB_DQ(29)     I7 @S9S_MB_2U_LIB.S9S_MB_2U(SCH_1):PAGE55
  EL17 M_E_CPU1_SB_DQ<28> @S9S_MB_2U_LIB.S9S_MB_2U(SCH_1):M_E_CPU1_SB_DQ(28)     I7 @S9S_MB_2U_LIB.S9S_MB_2U(SCH_1):PAGE55
  ER19 M_E_CPU1_SB_DQ<27> @S9S_MB_2U_LIB.S9S_MB_2U(SCH_1):M_E_CPU1_SB_DQ(27)     I7 @S9S_MB_2U_LIB.S9S_MB_2U(SCH_1):PAGE55
  EP20 M_E_CPU1_SB_DQ<26> @S9S_MB_2U_LIB.S9S_MB_2U(SCH_1):M_E_CPU1_SB_DQ(26)     I7 @S9S_MB_2U_LIB.S9S_MB_2U(SCH_1):PAGE55
  EL19 M_E_CPU1_SB_DQ<25> @S9S_MB_2U_LIB.S9S_MB_2U(SCH_1):M_E_CPU1_SB_DQ(25)     I7 @S9S_MB_2U_LIB.S9S_MB_2U(SCH_1):PAGE55
  EM20 M_E_CPU1_SB_DQ<24> @S9S_MB_2U_LIB.S9S_MB_2U(SCH_1):M_E_CPU1_SB_DQ(24)     I7 @S9S_MB_2U_LIB.S9S_MB_2U(SCH_1):PAGE55
  EP22 M_E_CPU1_SB_DQ<23> @S9S_MB_2U_LIB.S9S_MB_2U(SCH_1):M_E_CPU1_SB_DQ(23)     I7 @S9S_MB_2U_LIB.S9S_MB_2U(SCH_1):PAGE55
  ER23 M_E_CPU1_SB_DQ<22> @S9S_MB_2U_LIB.S9S_MB_2U(SCH_1):M_E_CPU1_SB_DQ(22)     I7 @S9S_MB_2U_LIB.S9S_MB_2U(SCH_1):PAGE55
  EM22 M_E_CPU1_SB_DQ<21> @S9S_MB_2U_LIB.S9S_MB_2U(SCH_1):M_E_CPU1_SB_DQ(21)     I7 @S9S_MB_2U_LIB.S9S_MB_2U(SCH_1):PAGE55
  EL23 M_E_CPU1_SB_DQ<20> @S9S_MB_2U_LIB.S9S_MB_2U(SCH_1):M_E_CPU1_SB_DQ(20)     I7 @S9S_MB_2U_LIB.S9S_MB_2U(SCH_1):PAGE55
  ER25 M_E_CPU1_SB_DQ<19> @S9S_MB_2U_LIB.S9S_MB_2U(SCH_1):M_E_CPU1_SB_DQ(19)     I7 @S9S_MB_2U_LIB.S9S_MB_2U(SCH_1):PAGE55
  EP26 M_E_CPU1_SB_DQ<18> @S9S_MB_2U_LIB.S9S_MB_2U(SCH_1):M_E_CPU1_SB_DQ(18)     I7 @S9S_MB_2U_LIB.S9S_MB_2U(SCH_1):PAGE55
  EL25 M_E_CPU1_SB_DQ<17> @S9S_MB_2U_LIB.S9S_MB_2U(SCH_1):M_E_CPU1_SB_DQ(17)     I7 @S9S_MB_2U_LIB.S9S_MB_2U(SCH_1):PAGE55
  EM26 M_E_CPU1_SB_DQ<16> @S9S_MB_2U_LIB.S9S_MB_2U(SCH_1):M_E_CPU1_SB_DQ(16)     I7 @S9S_MB_2U_LIB.S9S_MB_2U(SCH_1):PAGE55
  EP28 M_E_CPU1_SB_DQ<15> @S9S_MB_2U_LIB.S9S_MB_2U(SCH_1):M_E_CPU1_SB_DQ(15)     I7 @S9S_MB_2U_LIB.S9S_MB_2U(SCH_1):PAGE55
  ER29 M_E_CPU1_SB_DQ<14> @S9S_MB_2U_LIB.S9S_MB_2U(SCH_1):M_E_CPU1_SB_DQ(14)     I7 @S9S_MB_2U_LIB.S9S_MB_2U(SCH_1):PAGE55
  EM28 M_E_CPU1_SB_DQ<13> @S9S_MB_2U_LIB.S9S_MB_2U(SCH_1):M_E_CPU1_SB_DQ(13)     I7 @S9S_MB_2U_LIB.S9S_MB_2U(SCH_1):PAGE55
  EL29 M_E_CPU1_SB_DQ<12> @S9S_MB_2U_LIB.S9S_MB_2U(SCH_1):M_E_CPU1_SB_DQ(12)     I7 @S9S_MB_2U_LIB.S9S_MB_2U(SCH_1):PAGE55
  ER31 M_E_CPU1_SB_DQ<11> @S9S_MB_2U_LIB.S9S_MB_2U(SCH_1):M_E_CPU1_SB_DQ(11)     I7 @S9S_MB_2U_LIB.S9S_MB_2U(SCH_1):PAGE55
  EP32 M_E_CPU1_SB_DQ<10> @S9S_MB_2U_LIB.S9S_MB_2U(SCH_1):M_E_CPU1_SB_DQ(10)     I7 @S9S_MB_2U_LIB.S9S_MB_2U(SCH_1):PAGE55
  EL31 M_E_CPU1_SB_DQ<9> @S9S_MB_2U_LIB.S9S_MB_2U(SCH_1):M_E_CPU1_SB_DQ(9)     I7 @S9S_MB_2U_LIB.S9S_MB_2U(SCH_1):PAGE55
  EM32 M_E_CPU1_SB_DQ<8> @S9S_MB_2U_LIB.S9S_MB_2U(SCH_1):M_E_CPU1_SB_DQ(8)     I7 @S9S_MB_2U_LIB.S9S_MB_2U(SCH_1):PAGE55
  EG25 M_E_CPU1_SB_DQ<7> @S9S_MB_2U_LIB.S9S_MB_2U(SCH_1):M_E_CPU1_SB_DQ(7)     I7 @S9S_MB_2U_LIB.S9S_MB_2U(SCH_1):PAGE55
  EH26 M_E_CPU1_SB_DQ<6> @S9S_MB_2U_LIB.S9S_MB_2U(SCH_1):M_E_CPU1_SB_DQ(6)     I7 @S9S_MB_2U_LIB.S9S_MB_2U(SCH_1):PAGE55
  EE25 M_E_CPU1_SB_DQ<5> @S9S_MB_2U_LIB.S9S_MB_2U(SCH_1):M_E_CPU1_SB_DQ(5)     I7 @S9S_MB_2U_LIB.S9S_MB_2U(SCH_1):PAGE55
  ED26 M_E_CPU1_SB_DQ<4> @S9S_MB_2U_LIB.S9S_MB_2U(SCH_1):M_E_CPU1_SB_DQ(4)     I7 @S9S_MB_2U_LIB.S9S_MB_2U(SCH_1):PAGE55
  EH28 M_E_CPU1_SB_DQ<3> @S9S_MB_2U_LIB.S9S_MB_2U(SCH_1):M_E_CPU1_SB_DQ(3)     I7 @S9S_MB_2U_LIB.S9S_MB_2U(SCH_1):PAGE55
  EG29 M_E_CPU1_SB_DQ<2> @S9S_MB_2U_LIB.S9S_MB_2U(SCH_1):M_E_CPU1_SB_DQ(2)     I7 @S9S_MB_2U_LIB.S9S_MB_2U(SCH_1):PAGE55
  ED28 M_E_CPU1_SB_DQ<1> @S9S_MB_2U_LIB.S9S_MB_2U(SCH_1):M_E_CPU1_SB_DQ(1)     I7 @S9S_MB_2U_LIB.S9S_MB_2U(SCH_1):PAGE55
  EE29 M_E_CPU1_SB_DQ<0> @S9S_MB_2U_LIB.S9S_MB_2U(SCH_1):M_E_CPU1_SB_DQ(0)     I7 @S9S_MB_2U_LIB.S9S_MB_2U(SCH_1):PAGE55
  EK36 M_E_CPU1_SB_DQS_DN<9> @S9S_MB_2U_LIB.S9S_MB_2U(SCH_1):M_E_CPU1_SB_DQS_DN(9)     I7 @S9S_MB_2U_LIB.S9S_MB_2U(SCH_1):PAGE55
  ET18 M_E_CPU1_SB_DQS_DN<8> @S9S_MB_2U_LIB.S9S_MB_2U(SCH_1):M_E_CPU1_SB_DQS_DN(8)     I7 @S9S_MB_2U_LIB.S9S_MB_2U(SCH_1):PAGE55
  ET24 M_E_CPU1_SB_DQS_DN<7> @S9S_MB_2U_LIB.S9S_MB_2U(SCH_1):M_E_CPU1_SB_DQS_DN(7)     I7 @S9S_MB_2U_LIB.S9S_MB_2U(SCH_1):PAGE55
  ET30 M_E_CPU1_SB_DQS_DN<6> @S9S_MB_2U_LIB.S9S_MB_2U(SCH_1):M_E_CPU1_SB_DQS_DN(6)     I7 @S9S_MB_2U_LIB.S9S_MB_2U(SCH_1):PAGE55
  EJ27 M_E_CPU1_SB_DQS_DN<5> @S9S_MB_2U_LIB.S9S_MB_2U(SCH_1):M_E_CPU1_SB_DQS_DN(5)     I7 @S9S_MB_2U_LIB.S9S_MB_2U(SCH_1):PAGE55
  ET36 M_E_CPU1_SB_DQS_DN<4> @S9S_MB_2U_LIB.S9S_MB_2U(SCH_1):M_E_CPU1_SB_DQS_DN(4)     I7 @S9S_MB_2U_LIB.S9S_MB_2U(SCH_1):PAGE55
  EK18 M_E_CPU1_SB_DQS_DN<3> @S9S_MB_2U_LIB.S9S_MB_2U(SCH_1):M_E_CPU1_SB_DQS_DN(3)     I7 @S9S_MB_2U_LIB.S9S_MB_2U(SCH_1):PAGE55
  EK24 M_E_CPU1_SB_DQS_DN<2> @S9S_MB_2U_LIB.S9S_MB_2U(SCH_1):M_E_CPU1_SB_DQS_DN(2)     I7 @S9S_MB_2U_LIB.S9S_MB_2U(SCH_1):PAGE55
  EK30 M_E_CPU1_SB_DQS_DN<1> @S9S_MB_2U_LIB.S9S_MB_2U(SCH_1):M_E_CPU1_SB_DQS_DN(1)     I7 @S9S_MB_2U_LIB.S9S_MB_2U(SCH_1):PAGE55
  EE27 M_E_CPU1_SB_DQS_DN<0> @S9S_MB_2U_LIB.S9S_MB_2U(SCH_1):M_E_CPU1_SB_DQS_DN(0)     I7 @S9S_MB_2U_LIB.S9S_MB_2U(SCH_1):PAGE55
  EM36 M_E_CPU1_SB_DQS_DP<9> @S9S_MB_2U_LIB.S9S_MB_2U(SCH_1):M_E_CPU1_SB_DQS_DP(9)     I7 @S9S_MB_2U_LIB.S9S_MB_2U(SCH_1):PAGE55
  EP18 M_E_CPU1_SB_DQS_DP<8> @S9S_MB_2U_LIB.S9S_MB_2U(SCH_1):M_E_CPU1_SB_DQS_DP(8)     I7 @S9S_MB_2U_LIB.S9S_MB_2U(SCH_1):PAGE55
  EP24 M_E_CPU1_SB_DQS_DP<7> @S9S_MB_2U_LIB.S9S_MB_2U(SCH_1):M_E_CPU1_SB_DQS_DP(7)     I7 @S9S_MB_2U_LIB.S9S_MB_2U(SCH_1):PAGE55
  EP30 M_E_CPU1_SB_DQS_DP<6> @S9S_MB_2U_LIB.S9S_MB_2U(SCH_1):M_E_CPU1_SB_DQS_DP(6)     I7 @S9S_MB_2U_LIB.S9S_MB_2U(SCH_1):PAGE55
  EG27 M_E_CPU1_SB_DQS_DP<5> @S9S_MB_2U_LIB.S9S_MB_2U(SCH_1):M_E_CPU1_SB_DQS_DP(5)     I7 @S9S_MB_2U_LIB.S9S_MB_2U(SCH_1):PAGE55
  EP36 M_E_CPU1_SB_DQS_DP<4> @S9S_MB_2U_LIB.S9S_MB_2U(SCH_1):M_E_CPU1_SB_DQS_DP(4)     I7 @S9S_MB_2U_LIB.S9S_MB_2U(SCH_1):PAGE55
  EM18 M_E_CPU1_SB_DQS_DP<3> @S9S_MB_2U_LIB.S9S_MB_2U(SCH_1):M_E_CPU1_SB_DQS_DP(3)     I7 @S9S_MB_2U_LIB.S9S_MB_2U(SCH_1):PAGE55
  EM24 M_E_CPU1_SB_DQS_DP<2> @S9S_MB_2U_LIB.S9S_MB_2U(SCH_1):M_E_CPU1_SB_DQS_DP(2)     I7 @S9S_MB_2U_LIB.S9S_MB_2U(SCH_1):PAGE55
  EM30 M_E_CPU1_SB_DQS_DP<1> @S9S_MB_2U_LIB.S9S_MB_2U(SCH_1):M_E_CPU1_SB_DQS_DP(1)     I7 @S9S_MB_2U_LIB.S9S_MB_2U(SCH_1):PAGE55
  EC27 M_E_CPU1_SB_DQS_DP<0> @S9S_MB_2U_LIB.S9S_MB_2U(SCH_1):M_E_CPU1_SB_DQS_DP(0)     I7 @S9S_MB_2U_LIB.S9S_MB_2U(SCH_1):PAGE55
  ER37 M_E_CPU1_SB_CB<7> @S9S_MB_2U_LIB.S9S_MB_2U(SCH_1):M_E_CPU1_SB_CB(7)     I7 @S9S_MB_2U_LIB.S9S_MB_2U(SCH_1):PAGE55
  EP38 M_E_CPU1_SB_CB<6> @S9S_MB_2U_LIB.S9S_MB_2U(SCH_1):M_E_CPU1_SB_CB(6)     I7 @S9S_MB_2U_LIB.S9S_MB_2U(SCH_1):PAGE55
  EL37 M_E_CPU1_SB_CB<5> @S9S_MB_2U_LIB.S9S_MB_2U(SCH_1):M_E_CPU1_SB_CB(5)     I7 @S9S_MB_2U_LIB.S9S_MB_2U(SCH_1):PAGE55
  EM38 M_E_CPU1_SB_CB<4> @S9S_MB_2U_LIB.S9S_MB_2U(SCH_1):M_E_CPU1_SB_CB(4)     I7 @S9S_MB_2U_LIB.S9S_MB_2U(SCH_1):PAGE55
  EP34 M_E_CPU1_SB_CB<3> @S9S_MB_2U_LIB.S9S_MB_2U(SCH_1):M_E_CPU1_SB_CB(3)     I7 @S9S_MB_2U_LIB.S9S_MB_2U(SCH_1):PAGE55
  ER35 M_E_CPU1_SB_CB<2> @S9S_MB_2U_LIB.S9S_MB_2U(SCH_1):M_E_CPU1_SB_CB(2)     I7 @S9S_MB_2U_LIB.S9S_MB_2U(SCH_1):PAGE55
  EM34 M_E_CPU1_SB_CB<1> @S9S_MB_2U_LIB.S9S_MB_2U(SCH_1):M_E_CPU1_SB_CB(1)     I7 @S9S_MB_2U_LIB.S9S_MB_2U(SCH_1):PAGE55
  EL35 M_E_CPU1_SB_CB<0> @S9S_MB_2U_LIB.S9S_MB_2U(SCH_1):M_E_CPU1_SB_CB(0)     I7 @S9S_MB_2U_LIB.S9S_MB_2U(SCH_1):PAGE55
  EP42 M_E_CPU1_SB_PAR @S9S_MB_2U_LIB.S9S_MB_2U(SCH_1):M_E_CPU1_SB_PAR     I7 @S9S_MB_2U_LIB.S9S_MB_2U(SCH_1):PAGE55
  CW48 M_F_CPU1_ALERT_N @S9S_MB_2U_LIB.S9S_MB_2U(SCH_1):M_F_CPU1_ALERT_N   I168 @S9S_MB_2U_LIB.S9S_MB_2U(SCH_1):PAGE56
  DP47 M_F_CPU1_SA_RSP<1> @S9S_MB_2U_LIB.S9S_MB_2U(SCH_1):M_F_CPU1_SA_RSP(1)   I168 @S9S_MB_2U_LIB.S9S_MB_2U(SCH_1):PAGE56
  DN48 M_F_CPU1_SA_RSP<0> @S9S_MB_2U_LIB.S9S_MB_2U(SCH_1):M_F_CPU1_SA_RSP(0)   I168 @S9S_MB_2U_LIB.S9S_MB_2U(SCH_1):PAGE56
  DK47 M_F_CPU1_SB_RSP<1> @S9S_MB_2U_LIB.S9S_MB_2U(SCH_1):M_F_CPU1_SB_RSP(1)   I168 @S9S_MB_2U_LIB.S9S_MB_2U(SCH_1):PAGE56
  DL48 M_F_CPU1_SB_RSP<0> @S9S_MB_2U_LIB.S9S_MB_2U(SCH_1):M_F_CPU1_SB_RSP(0)   I168 @S9S_MB_2U_LIB.S9S_MB_2U(SCH_1):PAGE56
  DV49 M_F_CPU1_CLK_DN<1> @S9S_MB_2U_LIB.S9S_MB_2U(SCH_1):M_F_CPU1_CLK_DN(1)   I168 @S9S_MB_2U_LIB.S9S_MB_2U(SCH_1):PAGE56
  DY49 M_F_CPU1_CLK_DN<0> @S9S_MB_2U_LIB.S9S_MB_2U(SCH_1):M_F_CPU1_CLK_DN(0)   I168 @S9S_MB_2U_LIB.S9S_MB_2U(SCH_1):PAGE56
  DT49 M_F_CPU1_CLK_DP<1> @S9S_MB_2U_LIB.S9S_MB_2U(SCH_1):M_F_CPU1_CLK_DP(1)   I168 @S9S_MB_2U_LIB.S9S_MB_2U(SCH_1):PAGE56
  EB49 M_F_CPU1_CLK_DP<0> @S9S_MB_2U_LIB.S9S_MB_2U(SCH_1):M_F_CPU1_CLK_DP(0)   I168 @S9S_MB_2U_LIB.S9S_MB_2U(SCH_1):PAGE56
  DY51 M_F_CPU1_SA_CA<6> @S9S_MB_2U_LIB.S9S_MB_2U(SCH_1):M_F_CPU1_SA_CA(6)   I168 @S9S_MB_2U_LIB.S9S_MB_2U(SCH_1):PAGE56
  EG50 M_F_CPU1_SA_CA<5> @S9S_MB_2U_LIB.S9S_MB_2U(SCH_1):M_F_CPU1_SA_CA(5)   I168 @S9S_MB_2U_LIB.S9S_MB_2U(SCH_1):PAGE56
  EE50 M_F_CPU1_SA_CA<4> @S9S_MB_2U_LIB.S9S_MB_2U(SCH_1):M_F_CPU1_SA_CA(4)   I168 @S9S_MB_2U_LIB.S9S_MB_2U(SCH_1):PAGE56
  EH51 M_F_CPU1_SA_CA<3> @S9S_MB_2U_LIB.S9S_MB_2U(SCH_1):M_F_CPU1_SA_CA(3)   I168 @S9S_MB_2U_LIB.S9S_MB_2U(SCH_1):PAGE56
  ED51 M_F_CPU1_SA_CA<2> @S9S_MB_2U_LIB.S9S_MB_2U(SCH_1):M_F_CPU1_SA_CA(2)   I168 @S9S_MB_2U_LIB.S9S_MB_2U(SCH_1):PAGE56
  EJ52 M_F_CPU1_SA_CA<1> @S9S_MB_2U_LIB.S9S_MB_2U(SCH_1):M_F_CPU1_SA_CA(1)   I168 @S9S_MB_2U_LIB.S9S_MB_2U(SCH_1):PAGE56
  EC52 M_F_CPU1_SA_CA<0> @S9S_MB_2U_LIB.S9S_MB_2U(SCH_1):M_F_CPU1_SA_CA(0)   I168 @S9S_MB_2U_LIB.S9S_MB_2U(SCH_1):PAGE56
  ED53 M_F_CPU1_SA_CS_N<3> @S9S_MB_2U_LIB.S9S_MB_2U(SCH_1):M_F_CPU1_SA_CS_N(3)   I168 @S9S_MB_2U_LIB.S9S_MB_2U(SCH_1):PAGE56
  EE54 M_F_CPU1_SA_CS_N<2> @S9S_MB_2U_LIB.S9S_MB_2U(SCH_1):M_F_CPU1_SA_CS_N(2)   I168 @S9S_MB_2U_LIB.S9S_MB_2U(SCH_1):PAGE56
  EH53 M_F_CPU1_SA_CS_N<1> @S9S_MB_2U_LIB.S9S_MB_2U(SCH_1):M_F_CPU1_SA_CS_N(1)   I168 @S9S_MB_2U_LIB.S9S_MB_2U(SCH_1):PAGE56
  EG54 M_F_CPU1_SA_CS_N<0> @S9S_MB_2U_LIB.S9S_MB_2U(SCH_1):M_F_CPU1_SA_CS_N(0)   I168 @S9S_MB_2U_LIB.S9S_MB_2U(SCH_1):PAGE56
  DY53 M_F_CPU1_SA_DQ<31> @S9S_MB_2U_LIB.S9S_MB_2U(SCH_1):M_F_CPU1_SA_DQ(31)   I168 @S9S_MB_2U_LIB.S9S_MB_2U(SCH_1):PAGE56
  EA54 M_F_CPU1_SA_DQ<30> @S9S_MB_2U_LIB.S9S_MB_2U(SCH_1):M_F_CPU1_SA_DQ(30)   I168 @S9S_MB_2U_LIB.S9S_MB_2U(SCH_1):PAGE56
  DV53 M_F_CPU1_SA_DQ<29> @S9S_MB_2U_LIB.S9S_MB_2U(SCH_1):M_F_CPU1_SA_DQ(29)   I168 @S9S_MB_2U_LIB.S9S_MB_2U(SCH_1):PAGE56
  DU54 M_F_CPU1_SA_DQ<28> @S9S_MB_2U_LIB.S9S_MB_2U(SCH_1):M_F_CPU1_SA_DQ(28)   I168 @S9S_MB_2U_LIB.S9S_MB_2U(SCH_1):PAGE56
  EA56 M_F_CPU1_SA_DQ<27> @S9S_MB_2U_LIB.S9S_MB_2U(SCH_1):M_F_CPU1_SA_DQ(27)   I168 @S9S_MB_2U_LIB.S9S_MB_2U(SCH_1):PAGE56
  DY57 M_F_CPU1_SA_DQ<26> @S9S_MB_2U_LIB.S9S_MB_2U(SCH_1):M_F_CPU1_SA_DQ(26)   I168 @S9S_MB_2U_LIB.S9S_MB_2U(SCH_1):PAGE56
  DU56 M_F_CPU1_SA_DQ<25> @S9S_MB_2U_LIB.S9S_MB_2U(SCH_1):M_F_CPU1_SA_DQ(25)   I168 @S9S_MB_2U_LIB.S9S_MB_2U(SCH_1):PAGE56
  DV57 M_F_CPU1_SA_DQ<24> @S9S_MB_2U_LIB.S9S_MB_2U(SCH_1):M_F_CPU1_SA_DQ(24)   I168 @S9S_MB_2U_LIB.S9S_MB_2U(SCH_1):PAGE56
  EG62 M_F_CPU1_SA_DQ<23> @S9S_MB_2U_LIB.S9S_MB_2U(SCH_1):M_F_CPU1_SA_DQ(23)   I168 @S9S_MB_2U_LIB.S9S_MB_2U(SCH_1):PAGE56
  EH63 M_F_CPU1_SA_DQ<22> @S9S_MB_2U_LIB.S9S_MB_2U(SCH_1):M_F_CPU1_SA_DQ(22)   I168 @S9S_MB_2U_LIB.S9S_MB_2U(SCH_1):PAGE56
  EE62 M_F_CPU1_SA_DQ<21> @S9S_MB_2U_LIB.S9S_MB_2U(SCH_1):M_F_CPU1_SA_DQ(21)   I168 @S9S_MB_2U_LIB.S9S_MB_2U(SCH_1):PAGE56
  ED63 M_F_CPU1_SA_DQ<20> @S9S_MB_2U_LIB.S9S_MB_2U(SCH_1):M_F_CPU1_SA_DQ(20)   I168 @S9S_MB_2U_LIB.S9S_MB_2U(SCH_1):PAGE56
  EH65 M_F_CPU1_SA_DQ<19> @S9S_MB_2U_LIB.S9S_MB_2U(SCH_1):M_F_CPU1_SA_DQ(19)   I168 @S9S_MB_2U_LIB.S9S_MB_2U(SCH_1):PAGE56
  EG66 M_F_CPU1_SA_DQ<18> @S9S_MB_2U_LIB.S9S_MB_2U(SCH_1):M_F_CPU1_SA_DQ(18)   I168 @S9S_MB_2U_LIB.S9S_MB_2U(SCH_1):PAGE56
  ED65 M_F_CPU1_SA_DQ<17> @S9S_MB_2U_LIB.S9S_MB_2U(SCH_1):M_F_CPU1_SA_DQ(17)   I168 @S9S_MB_2U_LIB.S9S_MB_2U(SCH_1):PAGE56
  EE66 M_F_CPU1_SA_DQ<16> @S9S_MB_2U_LIB.S9S_MB_2U(SCH_1):M_F_CPU1_SA_DQ(16)   I168 @S9S_MB_2U_LIB.S9S_MB_2U(SCH_1):PAGE56
  DY65 M_F_CPU1_SA_DQ<15> @S9S_MB_2U_LIB.S9S_MB_2U(SCH_1):M_F_CPU1_SA_DQ(15)   I168 @S9S_MB_2U_LIB.S9S_MB_2U(SCH_1):PAGE56
  EA66 M_F_CPU1_SA_DQ<14> @S9S_MB_2U_LIB.S9S_MB_2U(SCH_1):M_F_CPU1_SA_DQ(14)   I168 @S9S_MB_2U_LIB.S9S_MB_2U(SCH_1):PAGE56
  DV65 M_F_CPU1_SA_DQ<13> @S9S_MB_2U_LIB.S9S_MB_2U(SCH_1):M_F_CPU1_SA_DQ(13)   I168 @S9S_MB_2U_LIB.S9S_MB_2U(SCH_1):PAGE56
  DU66 M_F_CPU1_SA_DQ<12> @S9S_MB_2U_LIB.S9S_MB_2U(SCH_1):M_F_CPU1_SA_DQ(12)   I168 @S9S_MB_2U_LIB.S9S_MB_2U(SCH_1):PAGE56
  EA68 M_F_CPU1_SA_DQ<11> @S9S_MB_2U_LIB.S9S_MB_2U(SCH_1):M_F_CPU1_SA_DQ(11)   I168 @S9S_MB_2U_LIB.S9S_MB_2U(SCH_1):PAGE56
  DY69 M_F_CPU1_SA_DQ<10> @S9S_MB_2U_LIB.S9S_MB_2U(SCH_1):M_F_CPU1_SA_DQ(10)   I168 @S9S_MB_2U_LIB.S9S_MB_2U(SCH_1):PAGE56
  DU68 M_F_CPU1_SA_DQ<9> @S9S_MB_2U_LIB.S9S_MB_2U(SCH_1):M_F_CPU1_SA_DQ(9)   I168 @S9S_MB_2U_LIB.S9S_MB_2U(SCH_1):PAGE56
  DV69 M_F_CPU1_SA_DQ<8> @S9S_MB_2U_LIB.S9S_MB_2U(SCH_1):M_F_CPU1_SA_DQ(8)   I168 @S9S_MB_2U_LIB.S9S_MB_2U(SCH_1):PAGE56
  EG74 M_F_CPU1_SA_DQ<7> @S9S_MB_2U_LIB.S9S_MB_2U(SCH_1):M_F_CPU1_SA_DQ(7)   I168 @S9S_MB_2U_LIB.S9S_MB_2U(SCH_1):PAGE56
  EH75 M_F_CPU1_SA_DQ<6> @S9S_MB_2U_LIB.S9S_MB_2U(SCH_1):M_F_CPU1_SA_DQ(6)   I168 @S9S_MB_2U_LIB.S9S_MB_2U(SCH_1):PAGE56
  EE74 M_F_CPU1_SA_DQ<5> @S9S_MB_2U_LIB.S9S_MB_2U(SCH_1):M_F_CPU1_SA_DQ(5)   I168 @S9S_MB_2U_LIB.S9S_MB_2U(SCH_1):PAGE56
  ED75 M_F_CPU1_SA_DQ<4> @S9S_MB_2U_LIB.S9S_MB_2U(SCH_1):M_F_CPU1_SA_DQ(4)   I168 @S9S_MB_2U_LIB.S9S_MB_2U(SCH_1):PAGE56
  EG78 M_F_CPU1_SA_DQ<3> @S9S_MB_2U_LIB.S9S_MB_2U(SCH_1):M_F_CPU1_SA_DQ(3)   I168 @S9S_MB_2U_LIB.S9S_MB_2U(SCH_1):PAGE56
  ED77 M_F_CPU1_SA_DQ<2> @S9S_MB_2U_LIB.S9S_MB_2U(SCH_1):M_F_CPU1_SA_DQ(2)   I168 @S9S_MB_2U_LIB.S9S_MB_2U(SCH_1):PAGE56
  EH77 M_F_CPU1_SA_DQ<1> @S9S_MB_2U_LIB.S9S_MB_2U(SCH_1):M_F_CPU1_SA_DQ(1)   I168 @S9S_MB_2U_LIB.S9S_MB_2U(SCH_1):PAGE56
  EB77 M_F_CPU1_SA_DQ<0> @S9S_MB_2U_LIB.S9S_MB_2U(SCH_1):M_F_CPU1_SA_DQ(0)   I168 @S9S_MB_2U_LIB.S9S_MB_2U(SCH_1):PAGE56
  EJ58 M_F_CPU1_SA_DQS_DN<9> @S9S_MB_2U_LIB.S9S_MB_2U(SCH_1):M_F_CPU1_SA_DQS_DN(9)   I168 @S9S_MB_2U_LIB.S9S_MB_2U(SCH_1):PAGE56
  EB55 M_F_CPU1_SA_DQS_DN<8> @S9S_MB_2U_LIB.S9S_MB_2U(SCH_1):M_F_CPU1_SA_DQS_DN(8)   I168 @S9S_MB_2U_LIB.S9S_MB_2U(SCH_1):PAGE56
  EJ64 M_F_CPU1_SA_DQS_DN<7> @S9S_MB_2U_LIB.S9S_MB_2U(SCH_1):M_F_CPU1_SA_DQS_DN(7)   I168 @S9S_MB_2U_LIB.S9S_MB_2U(SCH_1):PAGE56
  EB67 M_F_CPU1_SA_DQS_DN<6> @S9S_MB_2U_LIB.S9S_MB_2U(SCH_1):M_F_CPU1_SA_DQS_DN(6)   I168 @S9S_MB_2U_LIB.S9S_MB_2U(SCH_1):PAGE56
  EJ76 M_F_CPU1_SA_DQS_DN<5> @S9S_MB_2U_LIB.S9S_MB_2U(SCH_1):M_F_CPU1_SA_DQS_DN(5)   I168 @S9S_MB_2U_LIB.S9S_MB_2U(SCH_1):PAGE56
  EE58 M_F_CPU1_SA_DQS_DN<4> @S9S_MB_2U_LIB.S9S_MB_2U(SCH_1):M_F_CPU1_SA_DQS_DN(4)   I168 @S9S_MB_2U_LIB.S9S_MB_2U(SCH_1):PAGE56
  DV55 M_F_CPU1_SA_DQS_DN<3> @S9S_MB_2U_LIB.S9S_MB_2U(SCH_1):M_F_CPU1_SA_DQS_DN(3)   I168 @S9S_MB_2U_LIB.S9S_MB_2U(SCH_1):PAGE56
  EC64 M_F_CPU1_SA_DQS_DN<2> @S9S_MB_2U_LIB.S9S_MB_2U(SCH_1):M_F_CPU1_SA_DQS_DN(2)   I168 @S9S_MB_2U_LIB.S9S_MB_2U(SCH_1):PAGE56
  DT67 M_F_CPU1_SA_DQS_DN<1> @S9S_MB_2U_LIB.S9S_MB_2U(SCH_1):M_F_CPU1_SA_DQS_DN(1)   I168 @S9S_MB_2U_LIB.S9S_MB_2U(SCH_1):PAGE56
  EE76 M_F_CPU1_SA_DQS_DN<0> @S9S_MB_2U_LIB.S9S_MB_2U(SCH_1):M_F_CPU1_SA_DQS_DN(0)   I168 @S9S_MB_2U_LIB.S9S_MB_2U(SCH_1):PAGE56
  EG58 M_F_CPU1_SA_DQS_DP<9> @S9S_MB_2U_LIB.S9S_MB_2U(SCH_1):M_F_CPU1_SA_DQS_DP(9)   I168 @S9S_MB_2U_LIB.S9S_MB_2U(SCH_1):PAGE56
  DY55 M_F_CPU1_SA_DQS_DP<8> @S9S_MB_2U_LIB.S9S_MB_2U(SCH_1):M_F_CPU1_SA_DQS_DP(8)   I168 @S9S_MB_2U_LIB.S9S_MB_2U(SCH_1):PAGE56
  EG64 M_F_CPU1_SA_DQS_DP<7> @S9S_MB_2U_LIB.S9S_MB_2U(SCH_1):M_F_CPU1_SA_DQS_DP(7)   I168 @S9S_MB_2U_LIB.S9S_MB_2U(SCH_1):PAGE56
  DY67 M_F_CPU1_SA_DQS_DP<6> @S9S_MB_2U_LIB.S9S_MB_2U(SCH_1):M_F_CPU1_SA_DQS_DP(6)   I168 @S9S_MB_2U_LIB.S9S_MB_2U(SCH_1):PAGE56
  EG76 M_F_CPU1_SA_DQS_DP<5> @S9S_MB_2U_LIB.S9S_MB_2U(SCH_1):M_F_CPU1_SA_DQS_DP(5)   I168 @S9S_MB_2U_LIB.S9S_MB_2U(SCH_1):PAGE56
  EC58 M_F_CPU1_SA_DQS_DP<4> @S9S_MB_2U_LIB.S9S_MB_2U(SCH_1):M_F_CPU1_SA_DQS_DP(4)   I168 @S9S_MB_2U_LIB.S9S_MB_2U(SCH_1):PAGE56
  DT55 M_F_CPU1_SA_DQS_DP<3> @S9S_MB_2U_LIB.S9S_MB_2U(SCH_1):M_F_CPU1_SA_DQS_DP(3)   I168 @S9S_MB_2U_LIB.S9S_MB_2U(SCH_1):PAGE56
  EE64 M_F_CPU1_SA_DQS_DP<2> @S9S_MB_2U_LIB.S9S_MB_2U(SCH_1):M_F_CPU1_SA_DQS_DP(2)   I168 @S9S_MB_2U_LIB.S9S_MB_2U(SCH_1):PAGE56
  DV67 M_F_CPU1_SA_DQS_DP<1> @S9S_MB_2U_LIB.S9S_MB_2U(SCH_1):M_F_CPU1_SA_DQS_DP(1)   I168 @S9S_MB_2U_LIB.S9S_MB_2U(SCH_1):PAGE56
  EC76 M_F_CPU1_SA_DQS_DP<0> @S9S_MB_2U_LIB.S9S_MB_2U(SCH_1):M_F_CPU1_SA_DQS_DP(0)   I168 @S9S_MB_2U_LIB.S9S_MB_2U(SCH_1):PAGE56
  EG56 M_F_CPU1_SA_CB<7> @S9S_MB_2U_LIB.S9S_MB_2U(SCH_1):M_F_CPU1_SA_CB(7)   I168 @S9S_MB_2U_LIB.S9S_MB_2U(SCH_1):PAGE56
  EH57 M_F_CPU1_SA_CB<6> @S9S_MB_2U_LIB.S9S_MB_2U(SCH_1):M_F_CPU1_SA_CB(6)   I168 @S9S_MB_2U_LIB.S9S_MB_2U(SCH_1):PAGE56
  EE56 M_F_CPU1_SA_CB<5> @S9S_MB_2U_LIB.S9S_MB_2U(SCH_1):M_F_CPU1_SA_CB(5)   I168 @S9S_MB_2U_LIB.S9S_MB_2U(SCH_1):PAGE56
  ED57 M_F_CPU1_SA_CB<4> @S9S_MB_2U_LIB.S9S_MB_2U(SCH_1):M_F_CPU1_SA_CB(4)   I168 @S9S_MB_2U_LIB.S9S_MB_2U(SCH_1):PAGE56
  EH59 M_F_CPU1_SA_CB<3> @S9S_MB_2U_LIB.S9S_MB_2U(SCH_1):M_F_CPU1_SA_CB(3)   I168 @S9S_MB_2U_LIB.S9S_MB_2U(SCH_1):PAGE56
  EG60 M_F_CPU1_SA_CB<2> @S9S_MB_2U_LIB.S9S_MB_2U(SCH_1):M_F_CPU1_SA_CB(2)   I168 @S9S_MB_2U_LIB.S9S_MB_2U(SCH_1):PAGE56
  ED59 M_F_CPU1_SA_CB<1> @S9S_MB_2U_LIB.S9S_MB_2U(SCH_1):M_F_CPU1_SA_CB(1)   I168 @S9S_MB_2U_LIB.S9S_MB_2U(SCH_1):PAGE56
  EE60 M_F_CPU1_SA_CB<0> @S9S_MB_2U_LIB.S9S_MB_2U(SCH_1):M_F_CPU1_SA_CB(0)   I168 @S9S_MB_2U_LIB.S9S_MB_2U(SCH_1):PAGE56
  EA50 M_F_CPU1_SA_PAR @S9S_MB_2U_LIB.S9S_MB_2U(SCH_1):M_F_CPU1_SA_PAR   I168 @S9S_MB_2U_LIB.S9S_MB_2U(SCH_1):PAGE56
  EC39 M_F_CPU1_SB_CA<6> @S9S_MB_2U_LIB.S9S_MB_2U(SCH_1):M_F_CPU1_SB_CA(6)   I168 @S9S_MB_2U_LIB.S9S_MB_2U(SCH_1):PAGE56
  EH40 M_F_CPU1_SB_CA<5> @S9S_MB_2U_LIB.S9S_MB_2U(SCH_1):M_F_CPU1_SB_CA(5)   I168 @S9S_MB_2U_LIB.S9S_MB_2U(SCH_1):PAGE56
  ED40 M_F_CPU1_SB_CA<4> @S9S_MB_2U_LIB.S9S_MB_2U(SCH_1):M_F_CPU1_SB_CA(4)   I168 @S9S_MB_2U_LIB.S9S_MB_2U(SCH_1):PAGE56
  EG41 M_F_CPU1_SB_CA<3> @S9S_MB_2U_LIB.S9S_MB_2U(SCH_1):M_F_CPU1_SB_CA(3)   I168 @S9S_MB_2U_LIB.S9S_MB_2U(SCH_1):PAGE56
  EE41 M_F_CPU1_SB_CA<2> @S9S_MB_2U_LIB.S9S_MB_2U(SCH_1):M_F_CPU1_SB_CA(2)   I168 @S9S_MB_2U_LIB.S9S_MB_2U(SCH_1):PAGE56
  DU50 M_F_CPU1_SB_CA<1> @S9S_MB_2U_LIB.S9S_MB_2U(SCH_1):M_F_CPU1_SB_CA(1)   I168 @S9S_MB_2U_LIB.S9S_MB_2U(SCH_1):PAGE56
  DV51 M_F_CPU1_SB_CA<0> @S9S_MB_2U_LIB.S9S_MB_2U(SCH_1):M_F_CPU1_SB_CA(0)   I168 @S9S_MB_2U_LIB.S9S_MB_2U(SCH_1):PAGE56
  EE37 M_F_CPU1_SB_CS_N<3> @S9S_MB_2U_LIB.S9S_MB_2U(SCH_1):M_F_CPU1_SB_CS_N(3)   I168 @S9S_MB_2U_LIB.S9S_MB_2U(SCH_1):PAGE56
  ED38 M_F_CPU1_SB_CS_N<2> @S9S_MB_2U_LIB.S9S_MB_2U(SCH_1):M_F_CPU1_SB_CS_N(2)   I168 @S9S_MB_2U_LIB.S9S_MB_2U(SCH_1):PAGE56
  EG37 M_F_CPU1_SB_CS_N<1> @S9S_MB_2U_LIB.S9S_MB_2U(SCH_1):M_F_CPU1_SB_CS_N(1)   I168 @S9S_MB_2U_LIB.S9S_MB_2U(SCH_1):PAGE56
  EH38 M_F_CPU1_SB_CS_N<0> @S9S_MB_2U_LIB.S9S_MB_2U(SCH_1):M_F_CPU1_SB_CS_N(0)   I168 @S9S_MB_2U_LIB.S9S_MB_2U(SCH_1):PAGE56
  DR17 M_F_CPU1_SB_DQ<31> @S9S_MB_2U_LIB.S9S_MB_2U(SCH_1):M_F_CPU1_SB_DQ(31)   I168 @S9S_MB_2U_LIB.S9S_MB_2U(SCH_1):PAGE56
  EC17 M_F_CPU1_SB_DQ<30> @S9S_MB_2U_LIB.S9S_MB_2U(SCH_1):M_F_CPU1_SB_DQ(30)   I168 @S9S_MB_2U_LIB.S9S_MB_2U(SCH_1):PAGE56
  DU17 M_F_CPU1_SB_DQ<29> @S9S_MB_2U_LIB.S9S_MB_2U(SCH_1):M_F_CPU1_SB_DQ(29)   I168 @S9S_MB_2U_LIB.S9S_MB_2U(SCH_1):PAGE56
  EA17 M_F_CPU1_SB_DQ<28> @S9S_MB_2U_LIB.S9S_MB_2U(SCH_1):M_F_CPU1_SB_DQ(28)   I168 @S9S_MB_2U_LIB.S9S_MB_2U(SCH_1):PAGE56
  EA19 M_F_CPU1_SB_DQ<27> @S9S_MB_2U_LIB.S9S_MB_2U(SCH_1):M_F_CPU1_SB_DQ(27)   I168 @S9S_MB_2U_LIB.S9S_MB_2U(SCH_1):PAGE56
  DY20 M_F_CPU1_SB_DQ<26> @S9S_MB_2U_LIB.S9S_MB_2U(SCH_1):M_F_CPU1_SB_DQ(26)   I168 @S9S_MB_2U_LIB.S9S_MB_2U(SCH_1):PAGE56
  DU19 M_F_CPU1_SB_DQ<25> @S9S_MB_2U_LIB.S9S_MB_2U(SCH_1):M_F_CPU1_SB_DQ(25)   I168 @S9S_MB_2U_LIB.S9S_MB_2U(SCH_1):PAGE56
  DV20 M_F_CPU1_SB_DQ<24> @S9S_MB_2U_LIB.S9S_MB_2U(SCH_1):M_F_CPU1_SB_DQ(24)   I168 @S9S_MB_2U_LIB.S9S_MB_2U(SCH_1):PAGE56
  EP10 M_F_CPU1_SB_DQ<23> @S9S_MB_2U_LIB.S9S_MB_2U(SCH_1):M_F_CPU1_SB_DQ(23)   I168 @S9S_MB_2U_LIB.S9S_MB_2U(SCH_1):PAGE56
  ER11 M_F_CPU1_SB_DQ<22> @S9S_MB_2U_LIB.S9S_MB_2U(SCH_1):M_F_CPU1_SB_DQ(22)   I168 @S9S_MB_2U_LIB.S9S_MB_2U(SCH_1):PAGE56
  EM10 M_F_CPU1_SB_DQ<21> @S9S_MB_2U_LIB.S9S_MB_2U(SCH_1):M_F_CPU1_SB_DQ(21)   I168 @S9S_MB_2U_LIB.S9S_MB_2U(SCH_1):PAGE56
  EL11 M_F_CPU1_SB_DQ<20> @S9S_MB_2U_LIB.S9S_MB_2U(SCH_1):M_F_CPU1_SB_DQ(20)   I168 @S9S_MB_2U_LIB.S9S_MB_2U(SCH_1):PAGE56
  ER13 M_F_CPU1_SB_DQ<19> @S9S_MB_2U_LIB.S9S_MB_2U(SCH_1):M_F_CPU1_SB_DQ(19)   I168 @S9S_MB_2U_LIB.S9S_MB_2U(SCH_1):PAGE56
  EP14 M_F_CPU1_SB_DQ<18> @S9S_MB_2U_LIB.S9S_MB_2U(SCH_1):M_F_CPU1_SB_DQ(18)   I168 @S9S_MB_2U_LIB.S9S_MB_2U(SCH_1):PAGE56
  EL13 M_F_CPU1_SB_DQ<17> @S9S_MB_2U_LIB.S9S_MB_2U(SCH_1):M_F_CPU1_SB_DQ(17)   I168 @S9S_MB_2U_LIB.S9S_MB_2U(SCH_1):PAGE56
  EM14 M_F_CPU1_SB_DQ<16> @S9S_MB_2U_LIB.S9S_MB_2U(SCH_1):M_F_CPU1_SB_DQ(16)   I168 @S9S_MB_2U_LIB.S9S_MB_2U(SCH_1):PAGE56
  EG19 M_F_CPU1_SB_DQ<15> @S9S_MB_2U_LIB.S9S_MB_2U(SCH_1):M_F_CPU1_SB_DQ(15)   I168 @S9S_MB_2U_LIB.S9S_MB_2U(SCH_1):PAGE56
  EH20 M_F_CPU1_SB_DQ<14> @S9S_MB_2U_LIB.S9S_MB_2U(SCH_1):M_F_CPU1_SB_DQ(14)   I168 @S9S_MB_2U_LIB.S9S_MB_2U(SCH_1):PAGE56
  EE19 M_F_CPU1_SB_DQ<13> @S9S_MB_2U_LIB.S9S_MB_2U(SCH_1):M_F_CPU1_SB_DQ(13)   I168 @S9S_MB_2U_LIB.S9S_MB_2U(SCH_1):PAGE56
  ED20 M_F_CPU1_SB_DQ<12> @S9S_MB_2U_LIB.S9S_MB_2U(SCH_1):M_F_CPU1_SB_DQ(12)   I168 @S9S_MB_2U_LIB.S9S_MB_2U(SCH_1):PAGE56
  EH22 M_F_CPU1_SB_DQ<11> @S9S_MB_2U_LIB.S9S_MB_2U(SCH_1):M_F_CPU1_SB_DQ(11)   I168 @S9S_MB_2U_LIB.S9S_MB_2U(SCH_1):PAGE56
  EG23 M_F_CPU1_SB_DQ<10> @S9S_MB_2U_LIB.S9S_MB_2U(SCH_1):M_F_CPU1_SB_DQ(10)   I168 @S9S_MB_2U_LIB.S9S_MB_2U(SCH_1):PAGE56
  ED22 M_F_CPU1_SB_DQ<9> @S9S_MB_2U_LIB.S9S_MB_2U(SCH_1):M_F_CPU1_SB_DQ(9)   I168 @S9S_MB_2U_LIB.S9S_MB_2U(SCH_1):PAGE56
  EE23 M_F_CPU1_SB_DQ<8> @S9S_MB_2U_LIB.S9S_MB_2U(SCH_1):M_F_CPU1_SB_DQ(8)   I168 @S9S_MB_2U_LIB.S9S_MB_2U(SCH_1):PAGE56
  DY28 M_F_CPU1_SB_DQ<7> @S9S_MB_2U_LIB.S9S_MB_2U(SCH_1):M_F_CPU1_SB_DQ(7)   I168 @S9S_MB_2U_LIB.S9S_MB_2U(SCH_1):PAGE56
  EA29 M_F_CPU1_SB_DQ<6> @S9S_MB_2U_LIB.S9S_MB_2U(SCH_1):M_F_CPU1_SB_DQ(6)   I168 @S9S_MB_2U_LIB.S9S_MB_2U(SCH_1):PAGE56
  DV28 M_F_CPU1_SB_DQ<5> @S9S_MB_2U_LIB.S9S_MB_2U(SCH_1):M_F_CPU1_SB_DQ(5)   I168 @S9S_MB_2U_LIB.S9S_MB_2U(SCH_1):PAGE56
  DU29 M_F_CPU1_SB_DQ<4> @S9S_MB_2U_LIB.S9S_MB_2U(SCH_1):M_F_CPU1_SB_DQ(4)   I168 @S9S_MB_2U_LIB.S9S_MB_2U(SCH_1):PAGE56
  EA31 M_F_CPU1_SB_DQ<3> @S9S_MB_2U_LIB.S9S_MB_2U(SCH_1):M_F_CPU1_SB_DQ(3)   I168 @S9S_MB_2U_LIB.S9S_MB_2U(SCH_1):PAGE56
  DY32 M_F_CPU1_SB_DQ<2> @S9S_MB_2U_LIB.S9S_MB_2U(SCH_1):M_F_CPU1_SB_DQ(2)   I168 @S9S_MB_2U_LIB.S9S_MB_2U(SCH_1):PAGE56
  DU31 M_F_CPU1_SB_DQ<1> @S9S_MB_2U_LIB.S9S_MB_2U(SCH_1):M_F_CPU1_SB_DQ(1)   I168 @S9S_MB_2U_LIB.S9S_MB_2U(SCH_1):PAGE56
  DV32 M_F_CPU1_SB_DQ<0> @S9S_MB_2U_LIB.S9S_MB_2U(SCH_1):M_F_CPU1_SB_DQ(0)   I168 @S9S_MB_2U_LIB.S9S_MB_2U(SCH_1):PAGE56
  EE33 M_F_CPU1_SB_DQS_DN<9> @S9S_MB_2U_LIB.S9S_MB_2U(SCH_1):M_F_CPU1_SB_DQS_DN(9)   I168 @S9S_MB_2U_LIB.S9S_MB_2U(SCH_1):PAGE56
  DY18 M_F_CPU1_SB_DQS_DN<8> @S9S_MB_2U_LIB.S9S_MB_2U(SCH_1):M_F_CPU1_SB_DQS_DN(8)   I168 @S9S_MB_2U_LIB.S9S_MB_2U(SCH_1):PAGE56
  ET12 M_F_CPU1_SB_DQS_DN<7> @S9S_MB_2U_LIB.S9S_MB_2U(SCH_1):M_F_CPU1_SB_DQS_DN(7)   I168 @S9S_MB_2U_LIB.S9S_MB_2U(SCH_1):PAGE56
  EJ21 M_F_CPU1_SB_DQS_DN<6> @S9S_MB_2U_LIB.S9S_MB_2U(SCH_1):M_F_CPU1_SB_DQS_DN(6)   I168 @S9S_MB_2U_LIB.S9S_MB_2U(SCH_1):PAGE56
  EB30 M_F_CPU1_SB_DQS_DN<5> @S9S_MB_2U_LIB.S9S_MB_2U(SCH_1):M_F_CPU1_SB_DQS_DN(5)   I168 @S9S_MB_2U_LIB.S9S_MB_2U(SCH_1):PAGE56
  EJ33 M_F_CPU1_SB_DQS_DN<4> @S9S_MB_2U_LIB.S9S_MB_2U(SCH_1):M_F_CPU1_SB_DQS_DN(4)   I168 @S9S_MB_2U_LIB.S9S_MB_2U(SCH_1):PAGE56
  DT18 M_F_CPU1_SB_DQS_DN<3> @S9S_MB_2U_LIB.S9S_MB_2U(SCH_1):M_F_CPU1_SB_DQS_DN(3)   I168 @S9S_MB_2U_LIB.S9S_MB_2U(SCH_1):PAGE56
  EM12 M_F_CPU1_SB_DQS_DN<2> @S9S_MB_2U_LIB.S9S_MB_2U(SCH_1):M_F_CPU1_SB_DQS_DN(2)   I168 @S9S_MB_2U_LIB.S9S_MB_2U(SCH_1):PAGE56
  EE21 M_F_CPU1_SB_DQS_DN<1> @S9S_MB_2U_LIB.S9S_MB_2U(SCH_1):M_F_CPU1_SB_DQS_DN(1)   I168 @S9S_MB_2U_LIB.S9S_MB_2U(SCH_1):PAGE56
  DV30 M_F_CPU1_SB_DQS_DN<0> @S9S_MB_2U_LIB.S9S_MB_2U(SCH_1):M_F_CPU1_SB_DQS_DN(0)   I168 @S9S_MB_2U_LIB.S9S_MB_2U(SCH_1):PAGE56
  EC33 M_F_CPU1_SB_DQS_DP<9> @S9S_MB_2U_LIB.S9S_MB_2U(SCH_1):M_F_CPU1_SB_DQS_DP(9)   I168 @S9S_MB_2U_LIB.S9S_MB_2U(SCH_1):PAGE56
  EB18 M_F_CPU1_SB_DQS_DP<8> @S9S_MB_2U_LIB.S9S_MB_2U(SCH_1):M_F_CPU1_SB_DQS_DP(8)   I168 @S9S_MB_2U_LIB.S9S_MB_2U(SCH_1):PAGE56
  EP12 M_F_CPU1_SB_DQS_DP<7> @S9S_MB_2U_LIB.S9S_MB_2U(SCH_1):M_F_CPU1_SB_DQS_DP(7)   I168 @S9S_MB_2U_LIB.S9S_MB_2U(SCH_1):PAGE56
  EG21 M_F_CPU1_SB_DQS_DP<6> @S9S_MB_2U_LIB.S9S_MB_2U(SCH_1):M_F_CPU1_SB_DQS_DP(6)   I168 @S9S_MB_2U_LIB.S9S_MB_2U(SCH_1):PAGE56
  DY30 M_F_CPU1_SB_DQS_DP<5> @S9S_MB_2U_LIB.S9S_MB_2U(SCH_1):M_F_CPU1_SB_DQS_DP(5)   I168 @S9S_MB_2U_LIB.S9S_MB_2U(SCH_1):PAGE56
  EG33 M_F_CPU1_SB_DQS_DP<4> @S9S_MB_2U_LIB.S9S_MB_2U(SCH_1):M_F_CPU1_SB_DQS_DP(4)   I168 @S9S_MB_2U_LIB.S9S_MB_2U(SCH_1):PAGE56
  DV18 M_F_CPU1_SB_DQS_DP<3> @S9S_MB_2U_LIB.S9S_MB_2U(SCH_1):M_F_CPU1_SB_DQS_DP(3)   I168 @S9S_MB_2U_LIB.S9S_MB_2U(SCH_1):PAGE56
  EK12 M_F_CPU1_SB_DQS_DP<2> @S9S_MB_2U_LIB.S9S_MB_2U(SCH_1):M_F_CPU1_SB_DQS_DP(2)   I168 @S9S_MB_2U_LIB.S9S_MB_2U(SCH_1):PAGE56
  EC21 M_F_CPU1_SB_DQS_DP<1> @S9S_MB_2U_LIB.S9S_MB_2U(SCH_1):M_F_CPU1_SB_DQS_DP(1)   I168 @S9S_MB_2U_LIB.S9S_MB_2U(SCH_1):PAGE56
  DT30 M_F_CPU1_SB_DQS_DP<0> @S9S_MB_2U_LIB.S9S_MB_2U(SCH_1):M_F_CPU1_SB_DQS_DP(0)   I168 @S9S_MB_2U_LIB.S9S_MB_2U(SCH_1):PAGE56
  EH34 M_F_CPU1_SB_CB<7> @S9S_MB_2U_LIB.S9S_MB_2U(SCH_1):M_F_CPU1_SB_CB(7)   I168 @S9S_MB_2U_LIB.S9S_MB_2U(SCH_1):PAGE56
  EG35 M_F_CPU1_SB_CB<6> @S9S_MB_2U_LIB.S9S_MB_2U(SCH_1):M_F_CPU1_SB_CB(6)   I168 @S9S_MB_2U_LIB.S9S_MB_2U(SCH_1):PAGE56
  ED34 M_F_CPU1_SB_CB<5> @S9S_MB_2U_LIB.S9S_MB_2U(SCH_1):M_F_CPU1_SB_CB(5)   I168 @S9S_MB_2U_LIB.S9S_MB_2U(SCH_1):PAGE56
  EE35 M_F_CPU1_SB_CB<4> @S9S_MB_2U_LIB.S9S_MB_2U(SCH_1):M_F_CPU1_SB_CB(4)   I168 @S9S_MB_2U_LIB.S9S_MB_2U(SCH_1):PAGE56
  EG31 M_F_CPU1_SB_CB<3> @S9S_MB_2U_LIB.S9S_MB_2U(SCH_1):M_F_CPU1_SB_CB(3)   I168 @S9S_MB_2U_LIB.S9S_MB_2U(SCH_1):PAGE56
  EH32 M_F_CPU1_SB_CB<2> @S9S_MB_2U_LIB.S9S_MB_2U(SCH_1):M_F_CPU1_SB_CB(2)   I168 @S9S_MB_2U_LIB.S9S_MB_2U(SCH_1):PAGE56
  EE31 M_F_CPU1_SB_CB<1> @S9S_MB_2U_LIB.S9S_MB_2U(SCH_1):M_F_CPU1_SB_CB(1)   I168 @S9S_MB_2U_LIB.S9S_MB_2U(SCH_1):PAGE56
  ED32 M_F_CPU1_SB_CB<0> @S9S_MB_2U_LIB.S9S_MB_2U(SCH_1):M_F_CPU1_SB_CB(0)   I168 @S9S_MB_2U_LIB.S9S_MB_2U(SCH_1):PAGE56
  EJ39 M_F_CPU1_SB_PAR @S9S_MB_2U_LIB.S9S_MB_2U(SCH_1):M_F_CPU1_SB_PAR   I168 @S9S_MB_2U_LIB.S9S_MB_2U(SCH_1):PAGE56
  CW50 M_G_CPU1_ALERT_N @S9S_MB_2U_LIB.S9S_MB_2U(SCH_1):M_G_CPU1_ALERT_N   I168 @S9S_MB_2U_LIB.S9S_MB_2U(SCH_1):PAGE57
  DY47 M_G_CPU1_SA_RSP<1> @S9S_MB_2U_LIB.S9S_MB_2U(SCH_1):M_G_CPU1_SA_RSP(1)   I168 @S9S_MB_2U_LIB.S9S_MB_2U(SCH_1):PAGE57
  EA48 M_G_CPU1_SA_RSP<0> @S9S_MB_2U_LIB.S9S_MB_2U(SCH_1):M_G_CPU1_SA_RSP(0)   I168 @S9S_MB_2U_LIB.S9S_MB_2U(SCH_1):PAGE57
  DV47 M_G_CPU1_SB_RSP<1> @S9S_MB_2U_LIB.S9S_MB_2U(SCH_1):M_G_CPU1_SB_RSP(1)   I168 @S9S_MB_2U_LIB.S9S_MB_2U(SCH_1):PAGE57
  DU48 M_G_CPU1_SB_RSP<0> @S9S_MB_2U_LIB.S9S_MB_2U(SCH_1):M_G_CPU1_SB_RSP(0)   I168 @S9S_MB_2U_LIB.S9S_MB_2U(SCH_1):PAGE57
  DL45 M_G_CPU1_CLK_DN<1> @S9S_MB_2U_LIB.S9S_MB_2U(SCH_1):M_G_CPU1_CLK_DN(1)   I168 @S9S_MB_2U_LIB.S9S_MB_2U(SCH_1):PAGE57
  DR45 M_G_CPU1_CLK_DN<0> @S9S_MB_2U_LIB.S9S_MB_2U(SCH_1):M_G_CPU1_CLK_DN(0)   I168 @S9S_MB_2U_LIB.S9S_MB_2U(SCH_1):PAGE57
  DJ45 M_G_CPU1_CLK_DP<1> @S9S_MB_2U_LIB.S9S_MB_2U(SCH_1):M_G_CPU1_CLK_DP(1)   I168 @S9S_MB_2U_LIB.S9S_MB_2U(SCH_1):PAGE57
  DN45 M_G_CPU1_CLK_DP<0> @S9S_MB_2U_LIB.S9S_MB_2U(SCH_1):M_G_CPU1_CLK_DP(0)   I168 @S9S_MB_2U_LIB.S9S_MB_2U(SCH_1):PAGE57
  DK44 M_G_CPU1_SA_CA<6> @S9S_MB_2U_LIB.S9S_MB_2U(SCH_1):M_G_CPU1_SA_CA(6)   I168 @S9S_MB_2U_LIB.S9S_MB_2U(SCH_1):PAGE57
  DN50 M_G_CPU1_SA_CA<5> @S9S_MB_2U_LIB.S9S_MB_2U(SCH_1):M_G_CPU1_SA_CA(5)   I168 @S9S_MB_2U_LIB.S9S_MB_2U(SCH_1):PAGE57
  DL50 M_G_CPU1_SA_CA<4> @S9S_MB_2U_LIB.S9S_MB_2U(SCH_1):M_G_CPU1_SA_CA(4)   I168 @S9S_MB_2U_LIB.S9S_MB_2U(SCH_1):PAGE57
  DP51 M_G_CPU1_SA_CA<3> @S9S_MB_2U_LIB.S9S_MB_2U(SCH_1):M_G_CPU1_SA_CA(3)   I168 @S9S_MB_2U_LIB.S9S_MB_2U(SCH_1):PAGE57
  DK51 M_G_CPU1_SA_CA<2> @S9S_MB_2U_LIB.S9S_MB_2U(SCH_1):M_G_CPU1_SA_CA(2)   I168 @S9S_MB_2U_LIB.S9S_MB_2U(SCH_1):PAGE57
  DR52 M_G_CPU1_SA_CA<1> @S9S_MB_2U_LIB.S9S_MB_2U(SCH_1):M_G_CPU1_SA_CA(1)   I168 @S9S_MB_2U_LIB.S9S_MB_2U(SCH_1):PAGE57
  DJ52 M_G_CPU1_SA_CA<0> @S9S_MB_2U_LIB.S9S_MB_2U(SCH_1):M_G_CPU1_SA_CA(0)   I168 @S9S_MB_2U_LIB.S9S_MB_2U(SCH_1):PAGE57
  DK53 M_G_CPU1_SA_CS_N<3> @S9S_MB_2U_LIB.S9S_MB_2U(SCH_1):M_G_CPU1_SA_CS_N(3)   I168 @S9S_MB_2U_LIB.S9S_MB_2U(SCH_1):PAGE57
  DL54 M_G_CPU1_SA_CS_N<2> @S9S_MB_2U_LIB.S9S_MB_2U(SCH_1):M_G_CPU1_SA_CS_N(2)   I168 @S9S_MB_2U_LIB.S9S_MB_2U(SCH_1):PAGE57
  DP53 M_G_CPU1_SA_CS_N<1> @S9S_MB_2U_LIB.S9S_MB_2U(SCH_1):M_G_CPU1_SA_CS_N(1)   I168 @S9S_MB_2U_LIB.S9S_MB_2U(SCH_1):PAGE57
  DN54 M_G_CPU1_SA_CS_N<0> @S9S_MB_2U_LIB.S9S_MB_2U(SCH_1):M_G_CPU1_SA_CS_N(0)   I168 @S9S_MB_2U_LIB.S9S_MB_2U(SCH_1):PAGE57
  DN62 M_G_CPU1_SA_DQ<31> @S9S_MB_2U_LIB.S9S_MB_2U(SCH_1):M_G_CPU1_SA_DQ(31)   I168 @S9S_MB_2U_LIB.S9S_MB_2U(SCH_1):PAGE57
  DP63 M_G_CPU1_SA_DQ<30> @S9S_MB_2U_LIB.S9S_MB_2U(SCH_1):M_G_CPU1_SA_DQ(30)   I168 @S9S_MB_2U_LIB.S9S_MB_2U(SCH_1):PAGE57
  DL62 M_G_CPU1_SA_DQ<29> @S9S_MB_2U_LIB.S9S_MB_2U(SCH_1):M_G_CPU1_SA_DQ(29)   I168 @S9S_MB_2U_LIB.S9S_MB_2U(SCH_1):PAGE57
  DK63 M_G_CPU1_SA_DQ<28> @S9S_MB_2U_LIB.S9S_MB_2U(SCH_1):M_G_CPU1_SA_DQ(28)   I168 @S9S_MB_2U_LIB.S9S_MB_2U(SCH_1):PAGE57
  DP65 M_G_CPU1_SA_DQ<27> @S9S_MB_2U_LIB.S9S_MB_2U(SCH_1):M_G_CPU1_SA_DQ(27)   I168 @S9S_MB_2U_LIB.S9S_MB_2U(SCH_1):PAGE57
  DN66 M_G_CPU1_SA_DQ<26> @S9S_MB_2U_LIB.S9S_MB_2U(SCH_1):M_G_CPU1_SA_DQ(26)   I168 @S9S_MB_2U_LIB.S9S_MB_2U(SCH_1):PAGE57
  DK65 M_G_CPU1_SA_DQ<25> @S9S_MB_2U_LIB.S9S_MB_2U(SCH_1):M_G_CPU1_SA_DQ(25)   I168 @S9S_MB_2U_LIB.S9S_MB_2U(SCH_1):PAGE57
  DL66 M_G_CPU1_SA_DQ<24> @S9S_MB_2U_LIB.S9S_MB_2U(SCH_1):M_G_CPU1_SA_DQ(24)   I168 @S9S_MB_2U_LIB.S9S_MB_2U(SCH_1):PAGE57
  DY59 M_G_CPU1_SA_DQ<23> @S9S_MB_2U_LIB.S9S_MB_2U(SCH_1):M_G_CPU1_SA_DQ(23)   I168 @S9S_MB_2U_LIB.S9S_MB_2U(SCH_1):PAGE57
  EA60 M_G_CPU1_SA_DQ<22> @S9S_MB_2U_LIB.S9S_MB_2U(SCH_1):M_G_CPU1_SA_DQ(22)   I168 @S9S_MB_2U_LIB.S9S_MB_2U(SCH_1):PAGE57
  DV59 M_G_CPU1_SA_DQ<21> @S9S_MB_2U_LIB.S9S_MB_2U(SCH_1):M_G_CPU1_SA_DQ(21)   I168 @S9S_MB_2U_LIB.S9S_MB_2U(SCH_1):PAGE57
  DU60 M_G_CPU1_SA_DQ<20> @S9S_MB_2U_LIB.S9S_MB_2U(SCH_1):M_G_CPU1_SA_DQ(20)   I168 @S9S_MB_2U_LIB.S9S_MB_2U(SCH_1):PAGE57
  EA62 M_G_CPU1_SA_DQ<19> @S9S_MB_2U_LIB.S9S_MB_2U(SCH_1):M_G_CPU1_SA_DQ(19)   I168 @S9S_MB_2U_LIB.S9S_MB_2U(SCH_1):PAGE57
  DY63 M_G_CPU1_SA_DQ<18> @S9S_MB_2U_LIB.S9S_MB_2U(SCH_1):M_G_CPU1_SA_DQ(18)   I168 @S9S_MB_2U_LIB.S9S_MB_2U(SCH_1):PAGE57
  DU62 M_G_CPU1_SA_DQ<17> @S9S_MB_2U_LIB.S9S_MB_2U(SCH_1):M_G_CPU1_SA_DQ(17)   I168 @S9S_MB_2U_LIB.S9S_MB_2U(SCH_1):PAGE57
  DV63 M_G_CPU1_SA_DQ<16> @S9S_MB_2U_LIB.S9S_MB_2U(SCH_1):M_G_CPU1_SA_DQ(16)   I168 @S9S_MB_2U_LIB.S9S_MB_2U(SCH_1):PAGE57
  DN68 M_G_CPU1_SA_DQ<15> @S9S_MB_2U_LIB.S9S_MB_2U(SCH_1):M_G_CPU1_SA_DQ(15)   I168 @S9S_MB_2U_LIB.S9S_MB_2U(SCH_1):PAGE57
  DP69 M_G_CPU1_SA_DQ<14> @S9S_MB_2U_LIB.S9S_MB_2U(SCH_1):M_G_CPU1_SA_DQ(14)   I168 @S9S_MB_2U_LIB.S9S_MB_2U(SCH_1):PAGE57
  DL68 M_G_CPU1_SA_DQ<13> @S9S_MB_2U_LIB.S9S_MB_2U(SCH_1):M_G_CPU1_SA_DQ(13)   I168 @S9S_MB_2U_LIB.S9S_MB_2U(SCH_1):PAGE57
  DK69 M_G_CPU1_SA_DQ<12> @S9S_MB_2U_LIB.S9S_MB_2U(SCH_1):M_G_CPU1_SA_DQ(12)   I168 @S9S_MB_2U_LIB.S9S_MB_2U(SCH_1):PAGE57
  DP71 M_G_CPU1_SA_DQ<11> @S9S_MB_2U_LIB.S9S_MB_2U(SCH_1):M_G_CPU1_SA_DQ(11)   I168 @S9S_MB_2U_LIB.S9S_MB_2U(SCH_1):PAGE57
  DN72 M_G_CPU1_SA_DQ<10> @S9S_MB_2U_LIB.S9S_MB_2U(SCH_1):M_G_CPU1_SA_DQ(10)   I168 @S9S_MB_2U_LIB.S9S_MB_2U(SCH_1):PAGE57
  DK71 M_G_CPU1_SA_DQ<9> @S9S_MB_2U_LIB.S9S_MB_2U(SCH_1):M_G_CPU1_SA_DQ(9)   I168 @S9S_MB_2U_LIB.S9S_MB_2U(SCH_1):PAGE57
  DL72 M_G_CPU1_SA_DQ<8> @S9S_MB_2U_LIB.S9S_MB_2U(SCH_1):M_G_CPU1_SA_DQ(8)   I168 @S9S_MB_2U_LIB.S9S_MB_2U(SCH_1):PAGE57
  DY71 M_G_CPU1_SA_DQ<7> @S9S_MB_2U_LIB.S9S_MB_2U(SCH_1):M_G_CPU1_SA_DQ(7)   I168 @S9S_MB_2U_LIB.S9S_MB_2U(SCH_1):PAGE57
  EA72 M_G_CPU1_SA_DQ<6> @S9S_MB_2U_LIB.S9S_MB_2U(SCH_1):M_G_CPU1_SA_DQ(6)   I168 @S9S_MB_2U_LIB.S9S_MB_2U(SCH_1):PAGE57
  DV71 M_G_CPU1_SA_DQ<5> @S9S_MB_2U_LIB.S9S_MB_2U(SCH_1):M_G_CPU1_SA_DQ(5)   I168 @S9S_MB_2U_LIB.S9S_MB_2U(SCH_1):PAGE57
  DU72 M_G_CPU1_SA_DQ<4> @S9S_MB_2U_LIB.S9S_MB_2U(SCH_1):M_G_CPU1_SA_DQ(4)   I168 @S9S_MB_2U_LIB.S9S_MB_2U(SCH_1):PAGE57
  EA74 M_G_CPU1_SA_DQ<3> @S9S_MB_2U_LIB.S9S_MB_2U(SCH_1):M_G_CPU1_SA_DQ(3)   I168 @S9S_MB_2U_LIB.S9S_MB_2U(SCH_1):PAGE57
  DY75 M_G_CPU1_SA_DQ<2> @S9S_MB_2U_LIB.S9S_MB_2U(SCH_1):M_G_CPU1_SA_DQ(2)   I168 @S9S_MB_2U_LIB.S9S_MB_2U(SCH_1):PAGE57
  DU74 M_G_CPU1_SA_DQ<1> @S9S_MB_2U_LIB.S9S_MB_2U(SCH_1):M_G_CPU1_SA_DQ(1)   I168 @S9S_MB_2U_LIB.S9S_MB_2U(SCH_1):PAGE57
  DV75 M_G_CPU1_SA_DQ<0> @S9S_MB_2U_LIB.S9S_MB_2U(SCH_1):M_G_CPU1_SA_DQ(0)   I168 @S9S_MB_2U_LIB.S9S_MB_2U(SCH_1):PAGE57
  DR58 M_G_CPU1_SA_DQS_DN<9> @S9S_MB_2U_LIB.S9S_MB_2U(SCH_1):M_G_CPU1_SA_DQS_DN(9)   I168 @S9S_MB_2U_LIB.S9S_MB_2U(SCH_1):PAGE57
  DR64 M_G_CPU1_SA_DQS_DN<8> @S9S_MB_2U_LIB.S9S_MB_2U(SCH_1):M_G_CPU1_SA_DQS_DN(8)   I168 @S9S_MB_2U_LIB.S9S_MB_2U(SCH_1):PAGE57
  EB61 M_G_CPU1_SA_DQS_DN<7> @S9S_MB_2U_LIB.S9S_MB_2U(SCH_1):M_G_CPU1_SA_DQS_DN(7)   I168 @S9S_MB_2U_LIB.S9S_MB_2U(SCH_1):PAGE57
  DR70 M_G_CPU1_SA_DQS_DN<6> @S9S_MB_2U_LIB.S9S_MB_2U(SCH_1):M_G_CPU1_SA_DQS_DN(6)   I168 @S9S_MB_2U_LIB.S9S_MB_2U(SCH_1):PAGE57
  EB73 M_G_CPU1_SA_DQS_DN<5> @S9S_MB_2U_LIB.S9S_MB_2U(SCH_1):M_G_CPU1_SA_DQS_DN(5)   I168 @S9S_MB_2U_LIB.S9S_MB_2U(SCH_1):PAGE57
  DL58 M_G_CPU1_SA_DQS_DN<4> @S9S_MB_2U_LIB.S9S_MB_2U(SCH_1):M_G_CPU1_SA_DQS_DN(4)   I168 @S9S_MB_2U_LIB.S9S_MB_2U(SCH_1):PAGE57
  DL64 M_G_CPU1_SA_DQS_DN<3> @S9S_MB_2U_LIB.S9S_MB_2U(SCH_1):M_G_CPU1_SA_DQS_DN(3)   I168 @S9S_MB_2U_LIB.S9S_MB_2U(SCH_1):PAGE57
  DT61 M_G_CPU1_SA_DQS_DN<2> @S9S_MB_2U_LIB.S9S_MB_2U(SCH_1):M_G_CPU1_SA_DQS_DN(2)   I168 @S9S_MB_2U_LIB.S9S_MB_2U(SCH_1):PAGE57
  DJ70 M_G_CPU1_SA_DQS_DN<1> @S9S_MB_2U_LIB.S9S_MB_2U(SCH_1):M_G_CPU1_SA_DQS_DN(1)   I168 @S9S_MB_2U_LIB.S9S_MB_2U(SCH_1):PAGE57
  DV73 M_G_CPU1_SA_DQS_DN<0> @S9S_MB_2U_LIB.S9S_MB_2U(SCH_1):M_G_CPU1_SA_DQS_DN(0)   I168 @S9S_MB_2U_LIB.S9S_MB_2U(SCH_1):PAGE57
  DN58 M_G_CPU1_SA_DQS_DP<9> @S9S_MB_2U_LIB.S9S_MB_2U(SCH_1):M_G_CPU1_SA_DQS_DP(9)   I168 @S9S_MB_2U_LIB.S9S_MB_2U(SCH_1):PAGE57
  DN64 M_G_CPU1_SA_DQS_DP<8> @S9S_MB_2U_LIB.S9S_MB_2U(SCH_1):M_G_CPU1_SA_DQS_DP(8)   I168 @S9S_MB_2U_LIB.S9S_MB_2U(SCH_1):PAGE57
  DY61 M_G_CPU1_SA_DQS_DP<7> @S9S_MB_2U_LIB.S9S_MB_2U(SCH_1):M_G_CPU1_SA_DQS_DP(7)   I168 @S9S_MB_2U_LIB.S9S_MB_2U(SCH_1):PAGE57
  DN70 M_G_CPU1_SA_DQS_DP<6> @S9S_MB_2U_LIB.S9S_MB_2U(SCH_1):M_G_CPU1_SA_DQS_DP(6)   I168 @S9S_MB_2U_LIB.S9S_MB_2U(SCH_1):PAGE57
  DY73 M_G_CPU1_SA_DQS_DP<5> @S9S_MB_2U_LIB.S9S_MB_2U(SCH_1):M_G_CPU1_SA_DQS_DP(5)   I168 @S9S_MB_2U_LIB.S9S_MB_2U(SCH_1):PAGE57
  DJ58 M_G_CPU1_SA_DQS_DP<4> @S9S_MB_2U_LIB.S9S_MB_2U(SCH_1):M_G_CPU1_SA_DQS_DP(4)   I168 @S9S_MB_2U_LIB.S9S_MB_2U(SCH_1):PAGE57
  DJ64 M_G_CPU1_SA_DQS_DP<3> @S9S_MB_2U_LIB.S9S_MB_2U(SCH_1):M_G_CPU1_SA_DQS_DP(3)   I168 @S9S_MB_2U_LIB.S9S_MB_2U(SCH_1):PAGE57
  DV61 M_G_CPU1_SA_DQS_DP<2> @S9S_MB_2U_LIB.S9S_MB_2U(SCH_1):M_G_CPU1_SA_DQS_DP(2)   I168 @S9S_MB_2U_LIB.S9S_MB_2U(SCH_1):PAGE57
  DL70 M_G_CPU1_SA_DQS_DP<1> @S9S_MB_2U_LIB.S9S_MB_2U(SCH_1):M_G_CPU1_SA_DQS_DP(1)   I168 @S9S_MB_2U_LIB.S9S_MB_2U(SCH_1):PAGE57
  DT73 M_G_CPU1_SA_DQS_DP<0> @S9S_MB_2U_LIB.S9S_MB_2U(SCH_1):M_G_CPU1_SA_DQS_DP(0)   I168 @S9S_MB_2U_LIB.S9S_MB_2U(SCH_1):PAGE57
  DN56 M_G_CPU1_SA_CB<7> @S9S_MB_2U_LIB.S9S_MB_2U(SCH_1):M_G_CPU1_SA_CB(7)   I168 @S9S_MB_2U_LIB.S9S_MB_2U(SCH_1):PAGE57
  DP57 M_G_CPU1_SA_CB<6> @S9S_MB_2U_LIB.S9S_MB_2U(SCH_1):M_G_CPU1_SA_CB(6)   I168 @S9S_MB_2U_LIB.S9S_MB_2U(SCH_1):PAGE57
  DL56 M_G_CPU1_SA_CB<5> @S9S_MB_2U_LIB.S9S_MB_2U(SCH_1):M_G_CPU1_SA_CB(5)   I168 @S9S_MB_2U_LIB.S9S_MB_2U(SCH_1):PAGE57
  DK57 M_G_CPU1_SA_CB<4> @S9S_MB_2U_LIB.S9S_MB_2U(SCH_1):M_G_CPU1_SA_CB(4)   I168 @S9S_MB_2U_LIB.S9S_MB_2U(SCH_1):PAGE57
  DP59 M_G_CPU1_SA_CB<3> @S9S_MB_2U_LIB.S9S_MB_2U(SCH_1):M_G_CPU1_SA_CB(3)   I168 @S9S_MB_2U_LIB.S9S_MB_2U(SCH_1):PAGE57
  DN60 M_G_CPU1_SA_CB<2> @S9S_MB_2U_LIB.S9S_MB_2U(SCH_1):M_G_CPU1_SA_CB(2)   I168 @S9S_MB_2U_LIB.S9S_MB_2U(SCH_1):PAGE57
  DK59 M_G_CPU1_SA_CB<1> @S9S_MB_2U_LIB.S9S_MB_2U(SCH_1):M_G_CPU1_SA_CB(1)   I168 @S9S_MB_2U_LIB.S9S_MB_2U(SCH_1):PAGE57
  DL60 M_G_CPU1_SA_CB<0> @S9S_MB_2U_LIB.S9S_MB_2U(SCH_1):M_G_CPU1_SA_CB(0)   I168 @S9S_MB_2U_LIB.S9S_MB_2U(SCH_1):PAGE57
  DL43 M_G_CPU1_SA_PAR @S9S_MB_2U_LIB.S9S_MB_2U(SCH_1):M_G_CPU1_SA_PAR   I168 @S9S_MB_2U_LIB.S9S_MB_2U(SCH_1):PAGE57
  DT42 M_G_CPU1_SB_CA<6> @S9S_MB_2U_LIB.S9S_MB_2U(SCH_1):M_G_CPU1_SB_CA(6)   I168 @S9S_MB_2U_LIB.S9S_MB_2U(SCH_1):PAGE57
  EA43 M_G_CPU1_SB_CA<5> @S9S_MB_2U_LIB.S9S_MB_2U(SCH_1):M_G_CPU1_SB_CA(5)   I168 @S9S_MB_2U_LIB.S9S_MB_2U(SCH_1):PAGE57
  DU43 M_G_CPU1_SB_CA<4> @S9S_MB_2U_LIB.S9S_MB_2U(SCH_1):M_G_CPU1_SB_CA(4)   I168 @S9S_MB_2U_LIB.S9S_MB_2U(SCH_1):PAGE57
  DY44 M_G_CPU1_SB_CA<3> @S9S_MB_2U_LIB.S9S_MB_2U(SCH_1):M_G_CPU1_SB_CA(3)   I168 @S9S_MB_2U_LIB.S9S_MB_2U(SCH_1):PAGE57
  DV44 M_G_CPU1_SB_CA<2> @S9S_MB_2U_LIB.S9S_MB_2U(SCH_1):M_G_CPU1_SB_CA(2)   I168 @S9S_MB_2U_LIB.S9S_MB_2U(SCH_1):PAGE57
  DP44 M_G_CPU1_SB_CA<1> @S9S_MB_2U_LIB.S9S_MB_2U(SCH_1):M_G_CPU1_SB_CA(1)   I168 @S9S_MB_2U_LIB.S9S_MB_2U(SCH_1):PAGE57
  DN43 M_G_CPU1_SB_CA<0> @S9S_MB_2U_LIB.S9S_MB_2U(SCH_1):M_G_CPU1_SB_CA(0)   I168 @S9S_MB_2U_LIB.S9S_MB_2U(SCH_1):PAGE57
  DV40 M_G_CPU1_SB_CS_N<3> @S9S_MB_2U_LIB.S9S_MB_2U(SCH_1):M_G_CPU1_SB_CS_N(3)   I168 @S9S_MB_2U_LIB.S9S_MB_2U(SCH_1):PAGE57
  DU41 M_G_CPU1_SB_CS_N<2> @S9S_MB_2U_LIB.S9S_MB_2U(SCH_1):M_G_CPU1_SB_CS_N(2)   I168 @S9S_MB_2U_LIB.S9S_MB_2U(SCH_1):PAGE57
  DY40 M_G_CPU1_SB_CS_N<1> @S9S_MB_2U_LIB.S9S_MB_2U(SCH_1):M_G_CPU1_SB_CS_N(1)   I168 @S9S_MB_2U_LIB.S9S_MB_2U(SCH_1):PAGE57
  EA41 M_G_CPU1_SB_CS_N<0> @S9S_MB_2U_LIB.S9S_MB_2U(SCH_1):M_G_CPU1_SB_CS_N(0)   I168 @S9S_MB_2U_LIB.S9S_MB_2U(SCH_1):PAGE57
   EM4 M_G_CPU1_SB_DQ<31> @S9S_MB_2U_LIB.S9S_MB_2U(SCH_1):M_G_CPU1_SB_DQ(31)   I168 @S9S_MB_2U_LIB.S9S_MB_2U(SCH_1):PAGE57
   EP4 M_G_CPU1_SB_DQ<30> @S9S_MB_2U_LIB.S9S_MB_2U(SCH_1):M_G_CPU1_SB_DQ(30)   I168 @S9S_MB_2U_LIB.S9S_MB_2U(SCH_1):PAGE57
   EJ5 M_G_CPU1_SB_DQ<29> @S9S_MB_2U_LIB.S9S_MB_2U(SCH_1):M_G_CPU1_SB_DQ(29)   I168 @S9S_MB_2U_LIB.S9S_MB_2U(SCH_1):PAGE57
   EK6 M_G_CPU1_SB_DQ<28> @S9S_MB_2U_LIB.S9S_MB_2U(SCH_1):M_G_CPU1_SB_DQ(28)   I168 @S9S_MB_2U_LIB.S9S_MB_2U(SCH_1):PAGE57
   ET8 M_G_CPU1_SB_DQ<27> @S9S_MB_2U_LIB.S9S_MB_2U(SCH_1):M_G_CPU1_SB_DQ(27)   I168 @S9S_MB_2U_LIB.S9S_MB_2U(SCH_1):PAGE57
   EP8 M_G_CPU1_SB_DQ<26> @S9S_MB_2U_LIB.S9S_MB_2U(SCH_1):M_G_CPU1_SB_DQ(26)   I168 @S9S_MB_2U_LIB.S9S_MB_2U(SCH_1):PAGE57
   EH8 M_G_CPU1_SB_DQ<25> @S9S_MB_2U_LIB.S9S_MB_2U(SCH_1):M_G_CPU1_SB_DQ(25)   I168 @S9S_MB_2U_LIB.S9S_MB_2U(SCH_1):PAGE57
   EK8 M_G_CPU1_SB_DQ<24> @S9S_MB_2U_LIB.S9S_MB_2U(SCH_1):M_G_CPU1_SB_DQ(24)   I168 @S9S_MB_2U_LIB.S9S_MB_2U(SCH_1):PAGE57
  DY22 M_G_CPU1_SB_DQ<23> @S9S_MB_2U_LIB.S9S_MB_2U(SCH_1):M_G_CPU1_SB_DQ(23)   I168 @S9S_MB_2U_LIB.S9S_MB_2U(SCH_1):PAGE57
  EA23 M_G_CPU1_SB_DQ<22> @S9S_MB_2U_LIB.S9S_MB_2U(SCH_1):M_G_CPU1_SB_DQ(22)   I168 @S9S_MB_2U_LIB.S9S_MB_2U(SCH_1):PAGE57
  DV22 M_G_CPU1_SB_DQ<21> @S9S_MB_2U_LIB.S9S_MB_2U(SCH_1):M_G_CPU1_SB_DQ(21)   I168 @S9S_MB_2U_LIB.S9S_MB_2U(SCH_1):PAGE57
  DU23 M_G_CPU1_SB_DQ<20> @S9S_MB_2U_LIB.S9S_MB_2U(SCH_1):M_G_CPU1_SB_DQ(20)   I168 @S9S_MB_2U_LIB.S9S_MB_2U(SCH_1):PAGE57
  EA25 M_G_CPU1_SB_DQ<19> @S9S_MB_2U_LIB.S9S_MB_2U(SCH_1):M_G_CPU1_SB_DQ(19)   I168 @S9S_MB_2U_LIB.S9S_MB_2U(SCH_1):PAGE57
  DY26 M_G_CPU1_SB_DQ<18> @S9S_MB_2U_LIB.S9S_MB_2U(SCH_1):M_G_CPU1_SB_DQ(18)   I168 @S9S_MB_2U_LIB.S9S_MB_2U(SCH_1):PAGE57
  DU25 M_G_CPU1_SB_DQ<17> @S9S_MB_2U_LIB.S9S_MB_2U(SCH_1):M_G_CPU1_SB_DQ(17)   I168 @S9S_MB_2U_LIB.S9S_MB_2U(SCH_1):PAGE57
  DV26 M_G_CPU1_SB_DQ<16> @S9S_MB_2U_LIB.S9S_MB_2U(SCH_1):M_G_CPU1_SB_DQ(16)   I168 @S9S_MB_2U_LIB.S9S_MB_2U(SCH_1):PAGE57
  DN25 M_G_CPU1_SB_DQ<15> @S9S_MB_2U_LIB.S9S_MB_2U(SCH_1):M_G_CPU1_SB_DQ(15)   I168 @S9S_MB_2U_LIB.S9S_MB_2U(SCH_1):PAGE57
  DP26 M_G_CPU1_SB_DQ<14> @S9S_MB_2U_LIB.S9S_MB_2U(SCH_1):M_G_CPU1_SB_DQ(14)   I168 @S9S_MB_2U_LIB.S9S_MB_2U(SCH_1):PAGE57
  DL25 M_G_CPU1_SB_DQ<13> @S9S_MB_2U_LIB.S9S_MB_2U(SCH_1):M_G_CPU1_SB_DQ(13)   I168 @S9S_MB_2U_LIB.S9S_MB_2U(SCH_1):PAGE57
  DK26 M_G_CPU1_SB_DQ<12> @S9S_MB_2U_LIB.S9S_MB_2U(SCH_1):M_G_CPU1_SB_DQ(12)   I168 @S9S_MB_2U_LIB.S9S_MB_2U(SCH_1):PAGE57
  DP28 M_G_CPU1_SB_DQ<11> @S9S_MB_2U_LIB.S9S_MB_2U(SCH_1):M_G_CPU1_SB_DQ(11)   I168 @S9S_MB_2U_LIB.S9S_MB_2U(SCH_1):PAGE57
  DL29 M_G_CPU1_SB_DQ<10> @S9S_MB_2U_LIB.S9S_MB_2U(SCH_1):M_G_CPU1_SB_DQ(10)   I168 @S9S_MB_2U_LIB.S9S_MB_2U(SCH_1):PAGE57
  DK28 M_G_CPU1_SB_DQ<9> @S9S_MB_2U_LIB.S9S_MB_2U(SCH_1):M_G_CPU1_SB_DQ(9)   I168 @S9S_MB_2U_LIB.S9S_MB_2U(SCH_1):PAGE57
  DN29 M_G_CPU1_SB_DQ<8> @S9S_MB_2U_LIB.S9S_MB_2U(SCH_1):M_G_CPU1_SB_DQ(8)   I168 @S9S_MB_2U_LIB.S9S_MB_2U(SCH_1):PAGE57
  DN31 M_G_CPU1_SB_DQ<7> @S9S_MB_2U_LIB.S9S_MB_2U(SCH_1):M_G_CPU1_SB_DQ(7)   I168 @S9S_MB_2U_LIB.S9S_MB_2U(SCH_1):PAGE57
  DP32 M_G_CPU1_SB_DQ<6> @S9S_MB_2U_LIB.S9S_MB_2U(SCH_1):M_G_CPU1_SB_DQ(6)   I168 @S9S_MB_2U_LIB.S9S_MB_2U(SCH_1):PAGE57
  DL31 M_G_CPU1_SB_DQ<5> @S9S_MB_2U_LIB.S9S_MB_2U(SCH_1):M_G_CPU1_SB_DQ(5)   I168 @S9S_MB_2U_LIB.S9S_MB_2U(SCH_1):PAGE57
  DK32 M_G_CPU1_SB_DQ<4> @S9S_MB_2U_LIB.S9S_MB_2U(SCH_1):M_G_CPU1_SB_DQ(4)   I168 @S9S_MB_2U_LIB.S9S_MB_2U(SCH_1):PAGE57
  DP34 M_G_CPU1_SB_DQ<3> @S9S_MB_2U_LIB.S9S_MB_2U(SCH_1):M_G_CPU1_SB_DQ(3)   I168 @S9S_MB_2U_LIB.S9S_MB_2U(SCH_1):PAGE57
  DN35 M_G_CPU1_SB_DQ<2> @S9S_MB_2U_LIB.S9S_MB_2U(SCH_1):M_G_CPU1_SB_DQ(2)   I168 @S9S_MB_2U_LIB.S9S_MB_2U(SCH_1):PAGE57
  DK34 M_G_CPU1_SB_DQ<1> @S9S_MB_2U_LIB.S9S_MB_2U(SCH_1):M_G_CPU1_SB_DQ(1)   I168 @S9S_MB_2U_LIB.S9S_MB_2U(SCH_1):PAGE57
  DL35 M_G_CPU1_SB_DQ<0> @S9S_MB_2U_LIB.S9S_MB_2U(SCH_1):M_G_CPU1_SB_DQ(0)   I168 @S9S_MB_2U_LIB.S9S_MB_2U(SCH_1):PAGE57
  DV36 M_G_CPU1_SB_DQS_DN<9> @S9S_MB_2U_LIB.S9S_MB_2U(SCH_1):M_G_CPU1_SB_DQS_DN(9)   I168 @S9S_MB_2U_LIB.S9S_MB_2U(SCH_1):PAGE57
   EM6 M_G_CPU1_SB_DQS_DN<8> @S9S_MB_2U_LIB.S9S_MB_2U(SCH_1):M_G_CPU1_SB_DQS_DN(8)   I168 @S9S_MB_2U_LIB.S9S_MB_2U(SCH_1):PAGE57
  EB24 M_G_CPU1_SB_DQS_DN<7> @S9S_MB_2U_LIB.S9S_MB_2U(SCH_1):M_G_CPU1_SB_DQS_DN(7)   I168 @S9S_MB_2U_LIB.S9S_MB_2U(SCH_1):PAGE57
  DN27 M_G_CPU1_SB_DQS_DN<6> @S9S_MB_2U_LIB.S9S_MB_2U(SCH_1):M_G_CPU1_SB_DQS_DN(6)   I168 @S9S_MB_2U_LIB.S9S_MB_2U(SCH_1):PAGE57
  DR33 M_G_CPU1_SB_DQS_DN<5> @S9S_MB_2U_LIB.S9S_MB_2U(SCH_1):M_G_CPU1_SB_DQS_DN(5)   I168 @S9S_MB_2U_LIB.S9S_MB_2U(SCH_1):PAGE57
  EB36 M_G_CPU1_SB_DQS_DN<4> @S9S_MB_2U_LIB.S9S_MB_2U(SCH_1):M_G_CPU1_SB_DQS_DN(4)   I168 @S9S_MB_2U_LIB.S9S_MB_2U(SCH_1):PAGE57
   EP6 M_G_CPU1_SB_DQS_DN<3> @S9S_MB_2U_LIB.S9S_MB_2U(SCH_1):M_G_CPU1_SB_DQS_DN(3)   I168 @S9S_MB_2U_LIB.S9S_MB_2U(SCH_1):PAGE57
  DV24 M_G_CPU1_SB_DQS_DN<2> @S9S_MB_2U_LIB.S9S_MB_2U(SCH_1):M_G_CPU1_SB_DQS_DN(2)   I168 @S9S_MB_2U_LIB.S9S_MB_2U(SCH_1):PAGE57
  DJ27 M_G_CPU1_SB_DQS_DN<1> @S9S_MB_2U_LIB.S9S_MB_2U(SCH_1):M_G_CPU1_SB_DQS_DN(1)   I168 @S9S_MB_2U_LIB.S9S_MB_2U(SCH_1):PAGE57
  DJ33 M_G_CPU1_SB_DQS_DN<0> @S9S_MB_2U_LIB.S9S_MB_2U(SCH_1):M_G_CPU1_SB_DQS_DN(0)   I168 @S9S_MB_2U_LIB.S9S_MB_2U(SCH_1):PAGE57
  DT36 M_G_CPU1_SB_DQS_DP<9> @S9S_MB_2U_LIB.S9S_MB_2U(SCH_1):M_G_CPU1_SB_DQS_DP(9)   I168 @S9S_MB_2U_LIB.S9S_MB_2U(SCH_1):PAGE57
   EN5 M_G_CPU1_SB_DQS_DP<8> @S9S_MB_2U_LIB.S9S_MB_2U(SCH_1):M_G_CPU1_SB_DQS_DP(8)   I168 @S9S_MB_2U_LIB.S9S_MB_2U(SCH_1):PAGE57
  DY24 M_G_CPU1_SB_DQS_DP<7> @S9S_MB_2U_LIB.S9S_MB_2U(SCH_1):M_G_CPU1_SB_DQS_DP(7)   I168 @S9S_MB_2U_LIB.S9S_MB_2U(SCH_1):PAGE57
  DR27 M_G_CPU1_SB_DQS_DP<6> @S9S_MB_2U_LIB.S9S_MB_2U(SCH_1):M_G_CPU1_SB_DQS_DP(6)   I168 @S9S_MB_2U_LIB.S9S_MB_2U(SCH_1):PAGE57
  DN33 M_G_CPU1_SB_DQS_DP<5> @S9S_MB_2U_LIB.S9S_MB_2U(SCH_1):M_G_CPU1_SB_DQS_DP(5)   I168 @S9S_MB_2U_LIB.S9S_MB_2U(SCH_1):PAGE57
  DY36 M_G_CPU1_SB_DQS_DP<4> @S9S_MB_2U_LIB.S9S_MB_2U(SCH_1):M_G_CPU1_SB_DQS_DP(4)   I168 @S9S_MB_2U_LIB.S9S_MB_2U(SCH_1):PAGE57
   EN7 M_G_CPU1_SB_DQS_DP<3> @S9S_MB_2U_LIB.S9S_MB_2U(SCH_1):M_G_CPU1_SB_DQS_DP(3)   I168 @S9S_MB_2U_LIB.S9S_MB_2U(SCH_1):PAGE57
  DT24 M_G_CPU1_SB_DQS_DP<2> @S9S_MB_2U_LIB.S9S_MB_2U(SCH_1):M_G_CPU1_SB_DQS_DP(2)   I168 @S9S_MB_2U_LIB.S9S_MB_2U(SCH_1):PAGE57
  DL27 M_G_CPU1_SB_DQS_DP<1> @S9S_MB_2U_LIB.S9S_MB_2U(SCH_1):M_G_CPU1_SB_DQS_DP(1)   I168 @S9S_MB_2U_LIB.S9S_MB_2U(SCH_1):PAGE57
  DL33 M_G_CPU1_SB_DQS_DP<0> @S9S_MB_2U_LIB.S9S_MB_2U(SCH_1):M_G_CPU1_SB_DQS_DP(0)   I168 @S9S_MB_2U_LIB.S9S_MB_2U(SCH_1):PAGE57
  EA37 M_G_CPU1_SB_CB<7> @S9S_MB_2U_LIB.S9S_MB_2U(SCH_1):M_G_CPU1_SB_CB(7)   I168 @S9S_MB_2U_LIB.S9S_MB_2U(SCH_1):PAGE57
  DY38 M_G_CPU1_SB_CB<6> @S9S_MB_2U_LIB.S9S_MB_2U(SCH_1):M_G_CPU1_SB_CB(6)   I168 @S9S_MB_2U_LIB.S9S_MB_2U(SCH_1):PAGE57
  DU37 M_G_CPU1_SB_CB<5> @S9S_MB_2U_LIB.S9S_MB_2U(SCH_1):M_G_CPU1_SB_CB(5)   I168 @S9S_MB_2U_LIB.S9S_MB_2U(SCH_1):PAGE57
  DV38 M_G_CPU1_SB_CB<4> @S9S_MB_2U_LIB.S9S_MB_2U(SCH_1):M_G_CPU1_SB_CB(4)   I168 @S9S_MB_2U_LIB.S9S_MB_2U(SCH_1):PAGE57
  DY34 M_G_CPU1_SB_CB<3> @S9S_MB_2U_LIB.S9S_MB_2U(SCH_1):M_G_CPU1_SB_CB(3)   I168 @S9S_MB_2U_LIB.S9S_MB_2U(SCH_1):PAGE57
  EA35 M_G_CPU1_SB_CB<2> @S9S_MB_2U_LIB.S9S_MB_2U(SCH_1):M_G_CPU1_SB_CB(2)   I168 @S9S_MB_2U_LIB.S9S_MB_2U(SCH_1):PAGE57
  DV34 M_G_CPU1_SB_CB<1> @S9S_MB_2U_LIB.S9S_MB_2U(SCH_1):M_G_CPU1_SB_CB(1)   I168 @S9S_MB_2U_LIB.S9S_MB_2U(SCH_1):PAGE57
  DU35 M_G_CPU1_SB_CB<0> @S9S_MB_2U_LIB.S9S_MB_2U(SCH_1):M_G_CPU1_SB_CB(0)   I168 @S9S_MB_2U_LIB.S9S_MB_2U(SCH_1):PAGE57
  EB42 M_G_CPU1_SB_PAR @S9S_MB_2U_LIB.S9S_MB_2U(SCH_1):M_G_CPU1_SB_PAR   I168 @S9S_MB_2U_LIB.S9S_MB_2U(SCH_1):PAGE57
  CY51 M_H_CPU1_ALERT_N @S9S_MB_2U_LIB.S9S_MB_2U(SCH_1):M_H_CPU1_ALERT_N    I20 @S9S_MB_2U_LIB.S9S_MB_2U(SCH_1):PAGE58
  EH47 M_H_CPU1_SA_RSP<1> @S9S_MB_2U_LIB.S9S_MB_2U(SCH_1):M_H_CPU1_SA_RSP(1)    I20 @S9S_MB_2U_LIB.S9S_MB_2U(SCH_1):PAGE58
  EG48 M_H_CPU1_SA_RSP<0> @S9S_MB_2U_LIB.S9S_MB_2U(SCH_1):M_H_CPU1_SA_RSP(0)    I20 @S9S_MB_2U_LIB.S9S_MB_2U(SCH_1):PAGE58
  ED47 M_H_CPU1_SB_RSP<1> @S9S_MB_2U_LIB.S9S_MB_2U(SCH_1):M_H_CPU1_SB_RSP(1)    I20 @S9S_MB_2U_LIB.S9S_MB_2U(SCH_1):PAGE58
  EE48 M_H_CPU1_SB_RSP<0> @S9S_MB_2U_LIB.S9S_MB_2U(SCH_1):M_H_CPU1_SB_RSP(0)    I20 @S9S_MB_2U_LIB.S9S_MB_2U(SCH_1):PAGE58
  DD42 M_H_CPU1_CLK_DN<1> @S9S_MB_2U_LIB.S9S_MB_2U(SCH_1):M_H_CPU1_CLK_DN(1)    I20 @S9S_MB_2U_LIB.S9S_MB_2U(SCH_1):PAGE58
  DH42 M_H_CPU1_CLK_DN<0> @S9S_MB_2U_LIB.S9S_MB_2U(SCH_1):M_H_CPU1_CLK_DN(0)    I20 @S9S_MB_2U_LIB.S9S_MB_2U(SCH_1):PAGE58
  DB42 M_H_CPU1_CLK_DP<1> @S9S_MB_2U_LIB.S9S_MB_2U(SCH_1):M_H_CPU1_CLK_DP(1)    I20 @S9S_MB_2U_LIB.S9S_MB_2U(SCH_1):PAGE58
  DF42 M_H_CPU1_CLK_DP<0> @S9S_MB_2U_LIB.S9S_MB_2U(SCH_1):M_H_CPU1_CLK_DP(0)    I20 @S9S_MB_2U_LIB.S9S_MB_2U(SCH_1):PAGE58
  DC41 M_H_CPU1_SA_CA<6> @S9S_MB_2U_LIB.S9S_MB_2U(SCH_1):M_H_CPU1_SA_CA(6)    I20 @S9S_MB_2U_LIB.S9S_MB_2U(SCH_1):PAGE58
  DF47 M_H_CPU1_SA_CA<5> @S9S_MB_2U_LIB.S9S_MB_2U(SCH_1):M_H_CPU1_SA_CA(5)    I20 @S9S_MB_2U_LIB.S9S_MB_2U(SCH_1):PAGE58
  DD47 M_H_CPU1_SA_CA<4> @S9S_MB_2U_LIB.S9S_MB_2U(SCH_1):M_H_CPU1_SA_CA(4)    I20 @S9S_MB_2U_LIB.S9S_MB_2U(SCH_1):PAGE58
  DG48 M_H_CPU1_SA_CA<3> @S9S_MB_2U_LIB.S9S_MB_2U(SCH_1):M_H_CPU1_SA_CA(3)    I20 @S9S_MB_2U_LIB.S9S_MB_2U(SCH_1):PAGE58
  DC48 M_H_CPU1_SA_CA<2> @S9S_MB_2U_LIB.S9S_MB_2U(SCH_1):M_H_CPU1_SA_CA(2)    I20 @S9S_MB_2U_LIB.S9S_MB_2U(SCH_1):PAGE58
  DH49 M_H_CPU1_SA_CA<1> @S9S_MB_2U_LIB.S9S_MB_2U(SCH_1):M_H_CPU1_SA_CA(1)    I20 @S9S_MB_2U_LIB.S9S_MB_2U(SCH_1):PAGE58
  DB49 M_H_CPU1_SA_CA<0> @S9S_MB_2U_LIB.S9S_MB_2U(SCH_1):M_H_CPU1_SA_CA(0)    I20 @S9S_MB_2U_LIB.S9S_MB_2U(SCH_1):PAGE58
  DC50 M_H_CPU1_SA_CS_N<3> @S9S_MB_2U_LIB.S9S_MB_2U(SCH_1):M_H_CPU1_SA_CS_N(3)    I20 @S9S_MB_2U_LIB.S9S_MB_2U(SCH_1):PAGE58
  DD51 M_H_CPU1_SA_CS_N<2> @S9S_MB_2U_LIB.S9S_MB_2U(SCH_1):M_H_CPU1_SA_CS_N(2)    I20 @S9S_MB_2U_LIB.S9S_MB_2U(SCH_1):PAGE58
  DG50 M_H_CPU1_SA_CS_N<1> @S9S_MB_2U_LIB.S9S_MB_2U(SCH_1):M_H_CPU1_SA_CS_N(1)    I20 @S9S_MB_2U_LIB.S9S_MB_2U(SCH_1):PAGE58
  DF51 M_H_CPU1_SA_CS_N<0> @S9S_MB_2U_LIB.S9S_MB_2U(SCH_1):M_H_CPU1_SA_CS_N(0)    I20 @S9S_MB_2U_LIB.S9S_MB_2U(SCH_1):PAGE58
  DF59 M_H_CPU1_SA_DQ<31> @S9S_MB_2U_LIB.S9S_MB_2U(SCH_1):M_H_CPU1_SA_DQ(31)    I20 @S9S_MB_2U_LIB.S9S_MB_2U(SCH_1):PAGE58
  DG60 M_H_CPU1_SA_DQ<30> @S9S_MB_2U_LIB.S9S_MB_2U(SCH_1):M_H_CPU1_SA_DQ(30)    I20 @S9S_MB_2U_LIB.S9S_MB_2U(SCH_1):PAGE58
  DD59 M_H_CPU1_SA_DQ<29> @S9S_MB_2U_LIB.S9S_MB_2U(SCH_1):M_H_CPU1_SA_DQ(29)    I20 @S9S_MB_2U_LIB.S9S_MB_2U(SCH_1):PAGE58
  DC60 M_H_CPU1_SA_DQ<28> @S9S_MB_2U_LIB.S9S_MB_2U(SCH_1):M_H_CPU1_SA_DQ(28)    I20 @S9S_MB_2U_LIB.S9S_MB_2U(SCH_1):PAGE58
  DG62 M_H_CPU1_SA_DQ<27> @S9S_MB_2U_LIB.S9S_MB_2U(SCH_1):M_H_CPU1_SA_DQ(27)    I20 @S9S_MB_2U_LIB.S9S_MB_2U(SCH_1):PAGE58
  DF63 M_H_CPU1_SA_DQ<26> @S9S_MB_2U_LIB.S9S_MB_2U(SCH_1):M_H_CPU1_SA_DQ(26)    I20 @S9S_MB_2U_LIB.S9S_MB_2U(SCH_1):PAGE58
  DC62 M_H_CPU1_SA_DQ<25> @S9S_MB_2U_LIB.S9S_MB_2U(SCH_1):M_H_CPU1_SA_DQ(25)    I20 @S9S_MB_2U_LIB.S9S_MB_2U(SCH_1):PAGE58
  DD63 M_H_CPU1_SA_DQ<24> @S9S_MB_2U_LIB.S9S_MB_2U(SCH_1):M_H_CPU1_SA_DQ(24)    I20 @S9S_MB_2U_LIB.S9S_MB_2U(SCH_1):PAGE58
  DF65 M_H_CPU1_SA_DQ<23> @S9S_MB_2U_LIB.S9S_MB_2U(SCH_1):M_H_CPU1_SA_DQ(23)    I20 @S9S_MB_2U_LIB.S9S_MB_2U(SCH_1):PAGE58
  DG66 M_H_CPU1_SA_DQ<22> @S9S_MB_2U_LIB.S9S_MB_2U(SCH_1):M_H_CPU1_SA_DQ(22)    I20 @S9S_MB_2U_LIB.S9S_MB_2U(SCH_1):PAGE58
  DD65 M_H_CPU1_SA_DQ<21> @S9S_MB_2U_LIB.S9S_MB_2U(SCH_1):M_H_CPU1_SA_DQ(21)    I20 @S9S_MB_2U_LIB.S9S_MB_2U(SCH_1):PAGE58
  DC66 M_H_CPU1_SA_DQ<20> @S9S_MB_2U_LIB.S9S_MB_2U(SCH_1):M_H_CPU1_SA_DQ(20)    I20 @S9S_MB_2U_LIB.S9S_MB_2U(SCH_1):PAGE58
  DG68 M_H_CPU1_SA_DQ<19> @S9S_MB_2U_LIB.S9S_MB_2U(SCH_1):M_H_CPU1_SA_DQ(19)    I20 @S9S_MB_2U_LIB.S9S_MB_2U(SCH_1):PAGE58
  DF69 M_H_CPU1_SA_DQ<18> @S9S_MB_2U_LIB.S9S_MB_2U(SCH_1):M_H_CPU1_SA_DQ(18)    I20 @S9S_MB_2U_LIB.S9S_MB_2U(SCH_1):PAGE58
  DC68 M_H_CPU1_SA_DQ<17> @S9S_MB_2U_LIB.S9S_MB_2U(SCH_1):M_H_CPU1_SA_DQ(17)    I20 @S9S_MB_2U_LIB.S9S_MB_2U(SCH_1):PAGE58
  DD69 M_H_CPU1_SA_DQ<16> @S9S_MB_2U_LIB.S9S_MB_2U(SCH_1):M_H_CPU1_SA_DQ(16)    I20 @S9S_MB_2U_LIB.S9S_MB_2U(SCH_1):PAGE58
  DF71 M_H_CPU1_SA_DQ<15> @S9S_MB_2U_LIB.S9S_MB_2U(SCH_1):M_H_CPU1_SA_DQ(15)    I20 @S9S_MB_2U_LIB.S9S_MB_2U(SCH_1):PAGE58
  DG72 M_H_CPU1_SA_DQ<14> @S9S_MB_2U_LIB.S9S_MB_2U(SCH_1):M_H_CPU1_SA_DQ(14)    I20 @S9S_MB_2U_LIB.S9S_MB_2U(SCH_1):PAGE58
  DD71 M_H_CPU1_SA_DQ<13> @S9S_MB_2U_LIB.S9S_MB_2U(SCH_1):M_H_CPU1_SA_DQ(13)    I20 @S9S_MB_2U_LIB.S9S_MB_2U(SCH_1):PAGE58
  DC72 M_H_CPU1_SA_DQ<12> @S9S_MB_2U_LIB.S9S_MB_2U(SCH_1):M_H_CPU1_SA_DQ(12)    I20 @S9S_MB_2U_LIB.S9S_MB_2U(SCH_1):PAGE58
  DG74 M_H_CPU1_SA_DQ<11> @S9S_MB_2U_LIB.S9S_MB_2U(SCH_1):M_H_CPU1_SA_DQ(11)    I20 @S9S_MB_2U_LIB.S9S_MB_2U(SCH_1):PAGE58
  DF75 M_H_CPU1_SA_DQ<10> @S9S_MB_2U_LIB.S9S_MB_2U(SCH_1):M_H_CPU1_SA_DQ(10)    I20 @S9S_MB_2U_LIB.S9S_MB_2U(SCH_1):PAGE58
  DC74 M_H_CPU1_SA_DQ<9> @S9S_MB_2U_LIB.S9S_MB_2U(SCH_1):M_H_CPU1_SA_DQ(9)    I20 @S9S_MB_2U_LIB.S9S_MB_2U(SCH_1):PAGE58
  DD75 M_H_CPU1_SA_DQ<8> @S9S_MB_2U_LIB.S9S_MB_2U(SCH_1):M_H_CPU1_SA_DQ(8)    I20 @S9S_MB_2U_LIB.S9S_MB_2U(SCH_1):PAGE58
  DN74 M_H_CPU1_SA_DQ<7> @S9S_MB_2U_LIB.S9S_MB_2U(SCH_1):M_H_CPU1_SA_DQ(7)    I20 @S9S_MB_2U_LIB.S9S_MB_2U(SCH_1):PAGE58
  DP75 M_H_CPU1_SA_DQ<6> @S9S_MB_2U_LIB.S9S_MB_2U(SCH_1):M_H_CPU1_SA_DQ(6)    I20 @S9S_MB_2U_LIB.S9S_MB_2U(SCH_1):PAGE58
  DL74 M_H_CPU1_SA_DQ<5> @S9S_MB_2U_LIB.S9S_MB_2U(SCH_1):M_H_CPU1_SA_DQ(5)    I20 @S9S_MB_2U_LIB.S9S_MB_2U(SCH_1):PAGE58
  DK75 M_H_CPU1_SA_DQ<4> @S9S_MB_2U_LIB.S9S_MB_2U(SCH_1):M_H_CPU1_SA_DQ(4)    I20 @S9S_MB_2U_LIB.S9S_MB_2U(SCH_1):PAGE58
  DP77 M_H_CPU1_SA_DQ<3> @S9S_MB_2U_LIB.S9S_MB_2U(SCH_1):M_H_CPU1_SA_DQ(3)    I20 @S9S_MB_2U_LIB.S9S_MB_2U(SCH_1):PAGE58
  DW78 M_H_CPU1_SA_DQ<2> @S9S_MB_2U_LIB.S9S_MB_2U(SCH_1):M_H_CPU1_SA_DQ(2)    I20 @S9S_MB_2U_LIB.S9S_MB_2U(SCH_1):PAGE58
  DT77 M_H_CPU1_SA_DQ<1> @S9S_MB_2U_LIB.S9S_MB_2U(SCH_1):M_H_CPU1_SA_DQ(1)    I20 @S9S_MB_2U_LIB.S9S_MB_2U(SCH_1):PAGE58
  DY79 M_H_CPU1_SA_DQ<0> @S9S_MB_2U_LIB.S9S_MB_2U(SCH_1):M_H_CPU1_SA_DQ(0)    I20 @S9S_MB_2U_LIB.S9S_MB_2U(SCH_1):PAGE58
  DH55 M_H_CPU1_SA_DQS_DN<9> @S9S_MB_2U_LIB.S9S_MB_2U(SCH_1):M_H_CPU1_SA_DQS_DN(9)    I20 @S9S_MB_2U_LIB.S9S_MB_2U(SCH_1):PAGE58
  DH61 M_H_CPU1_SA_DQS_DN<8> @S9S_MB_2U_LIB.S9S_MB_2U(SCH_1):M_H_CPU1_SA_DQS_DN(8)    I20 @S9S_MB_2U_LIB.S9S_MB_2U(SCH_1):PAGE58
  DH67 M_H_CPU1_SA_DQS_DN<7> @S9S_MB_2U_LIB.S9S_MB_2U(SCH_1):M_H_CPU1_SA_DQS_DN(7)    I20 @S9S_MB_2U_LIB.S9S_MB_2U(SCH_1):PAGE58
  DH73 M_H_CPU1_SA_DQS_DN<6> @S9S_MB_2U_LIB.S9S_MB_2U(SCH_1):M_H_CPU1_SA_DQS_DN(6)    I20 @S9S_MB_2U_LIB.S9S_MB_2U(SCH_1):PAGE58
  DR76 M_H_CPU1_SA_DQS_DN<5> @S9S_MB_2U_LIB.S9S_MB_2U(SCH_1):M_H_CPU1_SA_DQS_DN(5)    I20 @S9S_MB_2U_LIB.S9S_MB_2U(SCH_1):PAGE58
  DD55 M_H_CPU1_SA_DQS_DN<4> @S9S_MB_2U_LIB.S9S_MB_2U(SCH_1):M_H_CPU1_SA_DQS_DN(4)    I20 @S9S_MB_2U_LIB.S9S_MB_2U(SCH_1):PAGE58
  DD61 M_H_CPU1_SA_DQS_DN<3> @S9S_MB_2U_LIB.S9S_MB_2U(SCH_1):M_H_CPU1_SA_DQS_DN(3)    I20 @S9S_MB_2U_LIB.S9S_MB_2U(SCH_1):PAGE58
  DD67 M_H_CPU1_SA_DQS_DN<2> @S9S_MB_2U_LIB.S9S_MB_2U(SCH_1):M_H_CPU1_SA_DQS_DN(2)    I20 @S9S_MB_2U_LIB.S9S_MB_2U(SCH_1):PAGE58
  DB73 M_H_CPU1_SA_DQS_DN<1> @S9S_MB_2U_LIB.S9S_MB_2U(SCH_1):M_H_CPU1_SA_DQS_DN(1)    I20 @S9S_MB_2U_LIB.S9S_MB_2U(SCH_1):PAGE58
  DJ76 M_H_CPU1_SA_DQS_DN<0> @S9S_MB_2U_LIB.S9S_MB_2U(SCH_1):M_H_CPU1_SA_DQS_DN(0)    I20 @S9S_MB_2U_LIB.S9S_MB_2U(SCH_1):PAGE58
  DF55 M_H_CPU1_SA_DQS_DP<9> @S9S_MB_2U_LIB.S9S_MB_2U(SCH_1):M_H_CPU1_SA_DQS_DP(9)    I20 @S9S_MB_2U_LIB.S9S_MB_2U(SCH_1):PAGE58
  DF61 M_H_CPU1_SA_DQS_DP<8> @S9S_MB_2U_LIB.S9S_MB_2U(SCH_1):M_H_CPU1_SA_DQS_DP(8)    I20 @S9S_MB_2U_LIB.S9S_MB_2U(SCH_1):PAGE58
  DF67 M_H_CPU1_SA_DQS_DP<7> @S9S_MB_2U_LIB.S9S_MB_2U(SCH_1):M_H_CPU1_SA_DQS_DP(7)    I20 @S9S_MB_2U_LIB.S9S_MB_2U(SCH_1):PAGE58
  DF73 M_H_CPU1_SA_DQS_DP<6> @S9S_MB_2U_LIB.S9S_MB_2U(SCH_1):M_H_CPU1_SA_DQS_DP(6)    I20 @S9S_MB_2U_LIB.S9S_MB_2U(SCH_1):PAGE58
  DN76 M_H_CPU1_SA_DQS_DP<5> @S9S_MB_2U_LIB.S9S_MB_2U(SCH_1):M_H_CPU1_SA_DQS_DP(5)    I20 @S9S_MB_2U_LIB.S9S_MB_2U(SCH_1):PAGE58
  DB55 M_H_CPU1_SA_DQS_DP<4> @S9S_MB_2U_LIB.S9S_MB_2U(SCH_1):M_H_CPU1_SA_DQS_DP(4)    I20 @S9S_MB_2U_LIB.S9S_MB_2U(SCH_1):PAGE58
  DB61 M_H_CPU1_SA_DQS_DP<3> @S9S_MB_2U_LIB.S9S_MB_2U(SCH_1):M_H_CPU1_SA_DQS_DP(3)    I20 @S9S_MB_2U_LIB.S9S_MB_2U(SCH_1):PAGE58
  DB67 M_H_CPU1_SA_DQS_DP<2> @S9S_MB_2U_LIB.S9S_MB_2U(SCH_1):M_H_CPU1_SA_DQS_DP(2)    I20 @S9S_MB_2U_LIB.S9S_MB_2U(SCH_1):PAGE58
  DD73 M_H_CPU1_SA_DQS_DP<1> @S9S_MB_2U_LIB.S9S_MB_2U(SCH_1):M_H_CPU1_SA_DQS_DP(1)    I20 @S9S_MB_2U_LIB.S9S_MB_2U(SCH_1):PAGE58
  DL76 M_H_CPU1_SA_DQS_DP<0> @S9S_MB_2U_LIB.S9S_MB_2U(SCH_1):M_H_CPU1_SA_DQS_DP(0)    I20 @S9S_MB_2U_LIB.S9S_MB_2U(SCH_1):PAGE58
  DF53 M_H_CPU1_SA_CB<7> @S9S_MB_2U_LIB.S9S_MB_2U(SCH_1):M_H_CPU1_SA_CB(7)    I20 @S9S_MB_2U_LIB.S9S_MB_2U(SCH_1):PAGE58
  DG54 M_H_CPU1_SA_CB<6> @S9S_MB_2U_LIB.S9S_MB_2U(SCH_1):M_H_CPU1_SA_CB(6)    I20 @S9S_MB_2U_LIB.S9S_MB_2U(SCH_1):PAGE58
  DD53 M_H_CPU1_SA_CB<5> @S9S_MB_2U_LIB.S9S_MB_2U(SCH_1):M_H_CPU1_SA_CB(5)    I20 @S9S_MB_2U_LIB.S9S_MB_2U(SCH_1):PAGE58
  DC54 M_H_CPU1_SA_CB<4> @S9S_MB_2U_LIB.S9S_MB_2U(SCH_1):M_H_CPU1_SA_CB(4)    I20 @S9S_MB_2U_LIB.S9S_MB_2U(SCH_1):PAGE58
  DG56 M_H_CPU1_SA_CB<3> @S9S_MB_2U_LIB.S9S_MB_2U(SCH_1):M_H_CPU1_SA_CB(3)    I20 @S9S_MB_2U_LIB.S9S_MB_2U(SCH_1):PAGE58
  DF57 M_H_CPU1_SA_CB<2> @S9S_MB_2U_LIB.S9S_MB_2U(SCH_1):M_H_CPU1_SA_CB(2)    I20 @S9S_MB_2U_LIB.S9S_MB_2U(SCH_1):PAGE58
  DC56 M_H_CPU1_SA_CB<1> @S9S_MB_2U_LIB.S9S_MB_2U(SCH_1):M_H_CPU1_SA_CB(1)    I20 @S9S_MB_2U_LIB.S9S_MB_2U(SCH_1):PAGE58
  DD57 M_H_CPU1_SA_CB<0> @S9S_MB_2U_LIB.S9S_MB_2U(SCH_1):M_H_CPU1_SA_CB(0)    I20 @S9S_MB_2U_LIB.S9S_MB_2U(SCH_1):PAGE58
  DD40 M_H_CPU1_SA_PAR @S9S_MB_2U_LIB.S9S_MB_2U(SCH_1):M_H_CPU1_SA_PAR    I20 @S9S_MB_2U_LIB.S9S_MB_2U(SCH_1):PAGE58
  DJ39 M_H_CPU1_SB_CA<6> @S9S_MB_2U_LIB.S9S_MB_2U(SCH_1):M_H_CPU1_SB_CA(6)    I20 @S9S_MB_2U_LIB.S9S_MB_2U(SCH_1):PAGE58
  DP40 M_H_CPU1_SB_CA<5> @S9S_MB_2U_LIB.S9S_MB_2U(SCH_1):M_H_CPU1_SB_CA(5)    I20 @S9S_MB_2U_LIB.S9S_MB_2U(SCH_1):PAGE58
  DK40 M_H_CPU1_SB_CA<4> @S9S_MB_2U_LIB.S9S_MB_2U(SCH_1):M_H_CPU1_SB_CA(4)    I20 @S9S_MB_2U_LIB.S9S_MB_2U(SCH_1):PAGE58
  DN41 M_H_CPU1_SB_CA<3> @S9S_MB_2U_LIB.S9S_MB_2U(SCH_1):M_H_CPU1_SB_CA(3)    I20 @S9S_MB_2U_LIB.S9S_MB_2U(SCH_1):PAGE58
  DL41 M_H_CPU1_SB_CA<2> @S9S_MB_2U_LIB.S9S_MB_2U(SCH_1):M_H_CPU1_SB_CA(2)    I20 @S9S_MB_2U_LIB.S9S_MB_2U(SCH_1):PAGE58
  DG41 M_H_CPU1_SB_CA<1> @S9S_MB_2U_LIB.S9S_MB_2U(SCH_1):M_H_CPU1_SB_CA(1)    I20 @S9S_MB_2U_LIB.S9S_MB_2U(SCH_1):PAGE58
  DF40 M_H_CPU1_SB_CA<0> @S9S_MB_2U_LIB.S9S_MB_2U(SCH_1):M_H_CPU1_SB_CA(0)    I20 @S9S_MB_2U_LIB.S9S_MB_2U(SCH_1):PAGE58
  DP38 M_H_CPU1_SB_CS_N<3> @S9S_MB_2U_LIB.S9S_MB_2U(SCH_1):M_H_CPU1_SB_CS_N(3)    I20 @S9S_MB_2U_LIB.S9S_MB_2U(SCH_1):PAGE58
  DK38 M_H_CPU1_SB_CS_N<2> @S9S_MB_2U_LIB.S9S_MB_2U(SCH_1):M_H_CPU1_SB_CS_N(2)    I20 @S9S_MB_2U_LIB.S9S_MB_2U(SCH_1):PAGE58
  DN37 M_H_CPU1_SB_CS_N<1> @S9S_MB_2U_LIB.S9S_MB_2U(SCH_1):M_H_CPU1_SB_CS_N(1)    I20 @S9S_MB_2U_LIB.S9S_MB_2U(SCH_1):PAGE58
  DL37 M_H_CPU1_SB_CS_N<0> @S9S_MB_2U_LIB.S9S_MB_2U(SCH_1):M_H_CPU1_SB_CS_N(0)    I20 @S9S_MB_2U_LIB.S9S_MB_2U(SCH_1):PAGE58
  DC17 M_H_CPU1_SB_DQ<31> @S9S_MB_2U_LIB.S9S_MB_2U(SCH_1):M_H_CPU1_SB_DQ(31)    I20 @S9S_MB_2U_LIB.S9S_MB_2U(SCH_1):PAGE58
  DJ17 M_H_CPU1_SB_DQ<30> @S9S_MB_2U_LIB.S9S_MB_2U(SCH_1):M_H_CPU1_SB_DQ(30)    I20 @S9S_MB_2U_LIB.S9S_MB_2U(SCH_1):PAGE58
  DA17 M_H_CPU1_SB_DQ<29> @S9S_MB_2U_LIB.S9S_MB_2U(SCH_1):M_H_CPU1_SB_DQ(29)    I20 @S9S_MB_2U_LIB.S9S_MB_2U(SCH_1):PAGE58
  DG17 M_H_CPU1_SB_DQ<28> @S9S_MB_2U_LIB.S9S_MB_2U(SCH_1):M_H_CPU1_SB_DQ(28)    I20 @S9S_MB_2U_LIB.S9S_MB_2U(SCH_1):PAGE58
  DG19 M_H_CPU1_SB_DQ<27> @S9S_MB_2U_LIB.S9S_MB_2U(SCH_1):M_H_CPU1_SB_DQ(27)    I20 @S9S_MB_2U_LIB.S9S_MB_2U(SCH_1):PAGE58
  DF20 M_H_CPU1_SB_DQ<26> @S9S_MB_2U_LIB.S9S_MB_2U(SCH_1):M_H_CPU1_SB_DQ(26)    I20 @S9S_MB_2U_LIB.S9S_MB_2U(SCH_1):PAGE58
  DC19 M_H_CPU1_SB_DQ<25> @S9S_MB_2U_LIB.S9S_MB_2U(SCH_1):M_H_CPU1_SB_DQ(25)    I20 @S9S_MB_2U_LIB.S9S_MB_2U(SCH_1):PAGE58
  DD20 M_H_CPU1_SB_DQ<24> @S9S_MB_2U_LIB.S9S_MB_2U(SCH_1):M_H_CPU1_SB_DQ(24)    I20 @S9S_MB_2U_LIB.S9S_MB_2U(SCH_1):PAGE58
  DN19 M_H_CPU1_SB_DQ<23> @S9S_MB_2U_LIB.S9S_MB_2U(SCH_1):M_H_CPU1_SB_DQ(23)    I20 @S9S_MB_2U_LIB.S9S_MB_2U(SCH_1):PAGE58
  DP20 M_H_CPU1_SB_DQ<22> @S9S_MB_2U_LIB.S9S_MB_2U(SCH_1):M_H_CPU1_SB_DQ(22)    I20 @S9S_MB_2U_LIB.S9S_MB_2U(SCH_1):PAGE58
  DL19 M_H_CPU1_SB_DQ<21> @S9S_MB_2U_LIB.S9S_MB_2U(SCH_1):M_H_CPU1_SB_DQ(21)    I20 @S9S_MB_2U_LIB.S9S_MB_2U(SCH_1):PAGE58
  DK20 M_H_CPU1_SB_DQ<20> @S9S_MB_2U_LIB.S9S_MB_2U(SCH_1):M_H_CPU1_SB_DQ(20)    I20 @S9S_MB_2U_LIB.S9S_MB_2U(SCH_1):PAGE58
  DP22 M_H_CPU1_SB_DQ<19> @S9S_MB_2U_LIB.S9S_MB_2U(SCH_1):M_H_CPU1_SB_DQ(19)    I20 @S9S_MB_2U_LIB.S9S_MB_2U(SCH_1):PAGE58
  DN23 M_H_CPU1_SB_DQ<18> @S9S_MB_2U_LIB.S9S_MB_2U(SCH_1):M_H_CPU1_SB_DQ(18)    I20 @S9S_MB_2U_LIB.S9S_MB_2U(SCH_1):PAGE58
  DK22 M_H_CPU1_SB_DQ<17> @S9S_MB_2U_LIB.S9S_MB_2U(SCH_1):M_H_CPU1_SB_DQ(17)    I20 @S9S_MB_2U_LIB.S9S_MB_2U(SCH_1):PAGE58
  DL23 M_H_CPU1_SB_DQ<16> @S9S_MB_2U_LIB.S9S_MB_2U(SCH_1):M_H_CPU1_SB_DQ(16)    I20 @S9S_MB_2U_LIB.S9S_MB_2U(SCH_1):PAGE58
  DF22 M_H_CPU1_SB_DQ<15> @S9S_MB_2U_LIB.S9S_MB_2U(SCH_1):M_H_CPU1_SB_DQ(15)    I20 @S9S_MB_2U_LIB.S9S_MB_2U(SCH_1):PAGE58
  DG23 M_H_CPU1_SB_DQ<14> @S9S_MB_2U_LIB.S9S_MB_2U(SCH_1):M_H_CPU1_SB_DQ(14)    I20 @S9S_MB_2U_LIB.S9S_MB_2U(SCH_1):PAGE58
  DD22 M_H_CPU1_SB_DQ<13> @S9S_MB_2U_LIB.S9S_MB_2U(SCH_1):M_H_CPU1_SB_DQ(13)    I20 @S9S_MB_2U_LIB.S9S_MB_2U(SCH_1):PAGE58
  DC23 M_H_CPU1_SB_DQ<12> @S9S_MB_2U_LIB.S9S_MB_2U(SCH_1):M_H_CPU1_SB_DQ(12)    I20 @S9S_MB_2U_LIB.S9S_MB_2U(SCH_1):PAGE58
  DG25 M_H_CPU1_SB_DQ<11> @S9S_MB_2U_LIB.S9S_MB_2U(SCH_1):M_H_CPU1_SB_DQ(11)    I20 @S9S_MB_2U_LIB.S9S_MB_2U(SCH_1):PAGE58
  DF26 M_H_CPU1_SB_DQ<10> @S9S_MB_2U_LIB.S9S_MB_2U(SCH_1):M_H_CPU1_SB_DQ(10)    I20 @S9S_MB_2U_LIB.S9S_MB_2U(SCH_1):PAGE58
  DC25 M_H_CPU1_SB_DQ<9> @S9S_MB_2U_LIB.S9S_MB_2U(SCH_1):M_H_CPU1_SB_DQ(9)    I20 @S9S_MB_2U_LIB.S9S_MB_2U(SCH_1):PAGE58
  DD26 M_H_CPU1_SB_DQ<8> @S9S_MB_2U_LIB.S9S_MB_2U(SCH_1):M_H_CPU1_SB_DQ(8)    I20 @S9S_MB_2U_LIB.S9S_MB_2U(SCH_1):PAGE58
  DD28 M_H_CPU1_SB_DQ<7> @S9S_MB_2U_LIB.S9S_MB_2U(SCH_1):M_H_CPU1_SB_DQ(7)    I20 @S9S_MB_2U_LIB.S9S_MB_2U(SCH_1):PAGE58
  DG29 M_H_CPU1_SB_DQ<6> @S9S_MB_2U_LIB.S9S_MB_2U(SCH_1):M_H_CPU1_SB_DQ(6)    I20 @S9S_MB_2U_LIB.S9S_MB_2U(SCH_1):PAGE58
  DF28 M_H_CPU1_SB_DQ<5> @S9S_MB_2U_LIB.S9S_MB_2U(SCH_1):M_H_CPU1_SB_DQ(5)    I20 @S9S_MB_2U_LIB.S9S_MB_2U(SCH_1):PAGE58
  DC29 M_H_CPU1_SB_DQ<4> @S9S_MB_2U_LIB.S9S_MB_2U(SCH_1):M_H_CPU1_SB_DQ(4)    I20 @S9S_MB_2U_LIB.S9S_MB_2U(SCH_1):PAGE58
  DG31 M_H_CPU1_SB_DQ<3> @S9S_MB_2U_LIB.S9S_MB_2U(SCH_1):M_H_CPU1_SB_DQ(3)    I20 @S9S_MB_2U_LIB.S9S_MB_2U(SCH_1):PAGE58
  DF32 M_H_CPU1_SB_DQ<2> @S9S_MB_2U_LIB.S9S_MB_2U(SCH_1):M_H_CPU1_SB_DQ(2)    I20 @S9S_MB_2U_LIB.S9S_MB_2U(SCH_1):PAGE58
  DC31 M_H_CPU1_SB_DQ<1> @S9S_MB_2U_LIB.S9S_MB_2U(SCH_1):M_H_CPU1_SB_DQ(1)    I20 @S9S_MB_2U_LIB.S9S_MB_2U(SCH_1):PAGE58
  DD32 M_H_CPU1_SB_DQ<0> @S9S_MB_2U_LIB.S9S_MB_2U(SCH_1):M_H_CPU1_SB_DQ(0)    I20 @S9S_MB_2U_LIB.S9S_MB_2U(SCH_1):PAGE58
  DD36 M_H_CPU1_SB_DQS_DN<9> @S9S_MB_2U_LIB.S9S_MB_2U(SCH_1):M_H_CPU1_SB_DQS_DN(9)    I20 @S9S_MB_2U_LIB.S9S_MB_2U(SCH_1):PAGE58
  DF18 M_H_CPU1_SB_DQS_DN<8> @S9S_MB_2U_LIB.S9S_MB_2U(SCH_1):M_H_CPU1_SB_DQS_DN(8)    I20 @S9S_MB_2U_LIB.S9S_MB_2U(SCH_1):PAGE58
  DR21 M_H_CPU1_SB_DQS_DN<7> @S9S_MB_2U_LIB.S9S_MB_2U(SCH_1):M_H_CPU1_SB_DQS_DN(7)    I20 @S9S_MB_2U_LIB.S9S_MB_2U(SCH_1):PAGE58
  DH24 M_H_CPU1_SB_DQS_DN<6> @S9S_MB_2U_LIB.S9S_MB_2U(SCH_1):M_H_CPU1_SB_DQS_DN(6)    I20 @S9S_MB_2U_LIB.S9S_MB_2U(SCH_1):PAGE58
  DH30 M_H_CPU1_SB_DQS_DN<5> @S9S_MB_2U_LIB.S9S_MB_2U(SCH_1):M_H_CPU1_SB_DQS_DN(5)    I20 @S9S_MB_2U_LIB.S9S_MB_2U(SCH_1):PAGE58
  DH36 M_H_CPU1_SB_DQS_DN<4> @S9S_MB_2U_LIB.S9S_MB_2U(SCH_1):M_H_CPU1_SB_DQS_DN(4)    I20 @S9S_MB_2U_LIB.S9S_MB_2U(SCH_1):PAGE58
  DB18 M_H_CPU1_SB_DQS_DN<3> @S9S_MB_2U_LIB.S9S_MB_2U(SCH_1):M_H_CPU1_SB_DQS_DN(3)    I20 @S9S_MB_2U_LIB.S9S_MB_2U(SCH_1):PAGE58
  DL21 M_H_CPU1_SB_DQS_DN<2> @S9S_MB_2U_LIB.S9S_MB_2U(SCH_1):M_H_CPU1_SB_DQS_DN(2)    I20 @S9S_MB_2U_LIB.S9S_MB_2U(SCH_1):PAGE58
  DD24 M_H_CPU1_SB_DQS_DN<1> @S9S_MB_2U_LIB.S9S_MB_2U(SCH_1):M_H_CPU1_SB_DQS_DN(1)    I20 @S9S_MB_2U_LIB.S9S_MB_2U(SCH_1):PAGE58
  DD30 M_H_CPU1_SB_DQS_DN<0> @S9S_MB_2U_LIB.S9S_MB_2U(SCH_1):M_H_CPU1_SB_DQS_DN(0)    I20 @S9S_MB_2U_LIB.S9S_MB_2U(SCH_1):PAGE58
  DB36 M_H_CPU1_SB_DQS_DP<9> @S9S_MB_2U_LIB.S9S_MB_2U(SCH_1):M_H_CPU1_SB_DQS_DP(9)    I20 @S9S_MB_2U_LIB.S9S_MB_2U(SCH_1):PAGE58
  DH18 M_H_CPU1_SB_DQS_DP<8> @S9S_MB_2U_LIB.S9S_MB_2U(SCH_1):M_H_CPU1_SB_DQS_DP(8)    I20 @S9S_MB_2U_LIB.S9S_MB_2U(SCH_1):PAGE58
  DN21 M_H_CPU1_SB_DQS_DP<7> @S9S_MB_2U_LIB.S9S_MB_2U(SCH_1):M_H_CPU1_SB_DQS_DP(7)    I20 @S9S_MB_2U_LIB.S9S_MB_2U(SCH_1):PAGE58
  DF24 M_H_CPU1_SB_DQS_DP<6> @S9S_MB_2U_LIB.S9S_MB_2U(SCH_1):M_H_CPU1_SB_DQS_DP(6)    I20 @S9S_MB_2U_LIB.S9S_MB_2U(SCH_1):PAGE58
  DF30 M_H_CPU1_SB_DQS_DP<5> @S9S_MB_2U_LIB.S9S_MB_2U(SCH_1):M_H_CPU1_SB_DQS_DP(5)    I20 @S9S_MB_2U_LIB.S9S_MB_2U(SCH_1):PAGE58
  DF36 M_H_CPU1_SB_DQS_DP<4> @S9S_MB_2U_LIB.S9S_MB_2U(SCH_1):M_H_CPU1_SB_DQS_DP(4)    I20 @S9S_MB_2U_LIB.S9S_MB_2U(SCH_1):PAGE58
  DD18 M_H_CPU1_SB_DQS_DP<3> @S9S_MB_2U_LIB.S9S_MB_2U(SCH_1):M_H_CPU1_SB_DQS_DP(3)    I20 @S9S_MB_2U_LIB.S9S_MB_2U(SCH_1):PAGE58
  DJ21 M_H_CPU1_SB_DQS_DP<2> @S9S_MB_2U_LIB.S9S_MB_2U(SCH_1):M_H_CPU1_SB_DQS_DP(2)    I20 @S9S_MB_2U_LIB.S9S_MB_2U(SCH_1):PAGE58
  DB24 M_H_CPU1_SB_DQS_DP<1> @S9S_MB_2U_LIB.S9S_MB_2U(SCH_1):M_H_CPU1_SB_DQS_DP(1)    I20 @S9S_MB_2U_LIB.S9S_MB_2U(SCH_1):PAGE58
  DB30 M_H_CPU1_SB_DQS_DP<0> @S9S_MB_2U_LIB.S9S_MB_2U(SCH_1):M_H_CPU1_SB_DQS_DP(0)    I20 @S9S_MB_2U_LIB.S9S_MB_2U(SCH_1):PAGE58
  DC37 M_H_CPU1_SB_CB<7> @S9S_MB_2U_LIB.S9S_MB_2U(SCH_1):M_H_CPU1_SB_CB(7)    I20 @S9S_MB_2U_LIB.S9S_MB_2U(SCH_1):PAGE58
  DD38 M_H_CPU1_SB_CB<6> @S9S_MB_2U_LIB.S9S_MB_2U(SCH_1):M_H_CPU1_SB_CB(6)    I20 @S9S_MB_2U_LIB.S9S_MB_2U(SCH_1):PAGE58
  DG37 M_H_CPU1_SB_CB<5> @S9S_MB_2U_LIB.S9S_MB_2U(SCH_1):M_H_CPU1_SB_CB(5)    I20 @S9S_MB_2U_LIB.S9S_MB_2U(SCH_1):PAGE58
  DF38 M_H_CPU1_SB_CB<4> @S9S_MB_2U_LIB.S9S_MB_2U(SCH_1):M_H_CPU1_SB_CB(4)    I20 @S9S_MB_2U_LIB.S9S_MB_2U(SCH_1):PAGE58
  DF34 M_H_CPU1_SB_CB<3> @S9S_MB_2U_LIB.S9S_MB_2U(SCH_1):M_H_CPU1_SB_CB(3)    I20 @S9S_MB_2U_LIB.S9S_MB_2U(SCH_1):PAGE58
  DG35 M_H_CPU1_SB_CB<2> @S9S_MB_2U_LIB.S9S_MB_2U(SCH_1):M_H_CPU1_SB_CB(2)    I20 @S9S_MB_2U_LIB.S9S_MB_2U(SCH_1):PAGE58
  DD34 M_H_CPU1_SB_CB<1> @S9S_MB_2U_LIB.S9S_MB_2U(SCH_1):M_H_CPU1_SB_CB(1)    I20 @S9S_MB_2U_LIB.S9S_MB_2U(SCH_1):PAGE58
  DC35 M_H_CPU1_SB_CB<0> @S9S_MB_2U_LIB.S9S_MB_2U(SCH_1):M_H_CPU1_SB_CB(0)    I20 @S9S_MB_2U_LIB.S9S_MB_2U(SCH_1):PAGE58
  DR39 M_H_CPU1_SB_PAR @S9S_MB_2U_LIB.S9S_MB_2U(SCH_1):M_H_CPU1_SB_PAR    I20 @S9S_MB_2U_LIB.S9S_MB_2U(SCH_1):PAGE58
  BU17 TP_DMI_CPU1_PCH_RX_C_DN<7> @S9S_MB_2U_LIB.S9S_MB_2U(SCH_1):TP_DMI_CPU1_PCH_RX_C_DN(7)    I20 @S9S_MB_2U_LIB.S9S_MB_2U(SCH_1):PAGE59
  BP18 TP_DMI_CPU1_PCH_RX_C_DN<6> @S9S_MB_2U_LIB.S9S_MB_2U(SCH_1):TP_DMI_CPU1_PCH_RX_C_DN(6)    I20 @S9S_MB_2U_LIB.S9S_MB_2U(SCH_1):PAGE59
  BN17 TP_DMI_CPU1_PCH_RX_C_DN<5> @S9S_MB_2U_LIB.S9S_MB_2U(SCH_1):TP_DMI_CPU1_PCH_RX_C_DN(5)    I20 @S9S_MB_2U_LIB.S9S_MB_2U(SCH_1):PAGE59
  BK18 TP_DMI_CPU1_PCH_RX_C_DN<4> @S9S_MB_2U_LIB.S9S_MB_2U(SCH_1):TP_DMI_CPU1_PCH_RX_C_DN(4)    I20 @S9S_MB_2U_LIB.S9S_MB_2U(SCH_1):PAGE59
  BJ17 TP_DMI_CPU1_PCH_RX_C_DN<3> @S9S_MB_2U_LIB.S9S_MB_2U(SCH_1):TP_DMI_CPU1_PCH_RX_C_DN(3)    I20 @S9S_MB_2U_LIB.S9S_MB_2U(SCH_1):PAGE59
  BF18 TP_DMI_CPU1_PCH_RX_C_DN<2> @S9S_MB_2U_LIB.S9S_MB_2U(SCH_1):TP_DMI_CPU1_PCH_RX_C_DN(2)    I20 @S9S_MB_2U_LIB.S9S_MB_2U(SCH_1):PAGE59
  BE17 TP_DMI_CPU1_PCH_RX_C_DN<1> @S9S_MB_2U_LIB.S9S_MB_2U(SCH_1):TP_DMI_CPU1_PCH_RX_C_DN(1)    I20 @S9S_MB_2U_LIB.S9S_MB_2U(SCH_1):PAGE59
  BB18 TP_DMI_CPU1_PCH_RX_C_DN<0> @S9S_MB_2U_LIB.S9S_MB_2U(SCH_1):TP_DMI_CPU1_PCH_RX_C_DN(0)    I20 @S9S_MB_2U_LIB.S9S_MB_2U(SCH_1):PAGE59
  BT18 TP_DMI_CPU1_PCH_RX_C_DP<7> @S9S_MB_2U_LIB.S9S_MB_2U(SCH_1):TP_DMI_CPU1_PCH_RX_C_DP(7)    I20 @S9S_MB_2U_LIB.S9S_MB_2U(SCH_1):PAGE59
  BR19 TP_DMI_CPU1_PCH_RX_C_DP<6> @S9S_MB_2U_LIB.S9S_MB_2U(SCH_1):TP_DMI_CPU1_PCH_RX_C_DP(6)    I20 @S9S_MB_2U_LIB.S9S_MB_2U(SCH_1):PAGE59
  BM18 TP_DMI_CPU1_PCH_RX_C_DP<5> @S9S_MB_2U_LIB.S9S_MB_2U(SCH_1):TP_DMI_CPU1_PCH_RX_C_DP(5)    I20 @S9S_MB_2U_LIB.S9S_MB_2U(SCH_1):PAGE59
  BL19 TP_DMI_CPU1_PCH_RX_C_DP<4> @S9S_MB_2U_LIB.S9S_MB_2U(SCH_1):TP_DMI_CPU1_PCH_RX_C_DP(4)    I20 @S9S_MB_2U_LIB.S9S_MB_2U(SCH_1):PAGE59
  BH18 TP_DMI_CPU1_PCH_RX_C_DP<3> @S9S_MB_2U_LIB.S9S_MB_2U(SCH_1):TP_DMI_CPU1_PCH_RX_C_DP(3)    I20 @S9S_MB_2U_LIB.S9S_MB_2U(SCH_1):PAGE59
  BG19 TP_DMI_CPU1_PCH_RX_C_DP<2> @S9S_MB_2U_LIB.S9S_MB_2U(SCH_1):TP_DMI_CPU1_PCH_RX_C_DP(2)    I20 @S9S_MB_2U_LIB.S9S_MB_2U(SCH_1):PAGE59
  BD18 TP_DMI_CPU1_PCH_RX_C_DP<1> @S9S_MB_2U_LIB.S9S_MB_2U(SCH_1):TP_DMI_CPU1_PCH_RX_C_DP(1)    I20 @S9S_MB_2U_LIB.S9S_MB_2U(SCH_1):PAGE59
  BC19 TP_DMI_CPU1_PCH_RX_C_DP<0> @S9S_MB_2U_LIB.S9S_MB_2U(SCH_1):TP_DMI_CPU1_PCH_RX_C_DP(0)    I20 @S9S_MB_2U_LIB.S9S_MB_2U(SCH_1):PAGE59
  CN17 TP_DMI_CPU1_PCH_TX_DN<7> @S9S_MB_2U_LIB.S9S_MB_2U(SCH_1):TP_DMI_CPU1_PCH_TX_DN(7)    I20 @S9S_MB_2U_LIB.S9S_MB_2U(SCH_1):PAGE59
  CK18 TP_DMI_CPU1_PCH_TX_DN<6> @S9S_MB_2U_LIB.S9S_MB_2U(SCH_1):TP_DMI_CPU1_PCH_TX_DN(6)    I20 @S9S_MB_2U_LIB.S9S_MB_2U(SCH_1):PAGE59
  CJ17 TP_DMI_CPU1_PCH_TX_DN<5> @S9S_MB_2U_LIB.S9S_MB_2U(SCH_1):TP_DMI_CPU1_PCH_TX_DN(5)    I20 @S9S_MB_2U_LIB.S9S_MB_2U(SCH_1):PAGE59
  CF18 TP_DMI_CPU1_PCH_TX_DN<4> @S9S_MB_2U_LIB.S9S_MB_2U(SCH_1):TP_DMI_CPU1_PCH_TX_DN(4)    I20 @S9S_MB_2U_LIB.S9S_MB_2U(SCH_1):PAGE59
  CE17 TP_DMI_CPU1_PCH_TX_DN<3> @S9S_MB_2U_LIB.S9S_MB_2U(SCH_1):TP_DMI_CPU1_PCH_TX_DN(3)    I20 @S9S_MB_2U_LIB.S9S_MB_2U(SCH_1):PAGE59
  CB18 TP_DMI_CPU1_PCH_TX_DN<2> @S9S_MB_2U_LIB.S9S_MB_2U(SCH_1):TP_DMI_CPU1_PCH_TX_DN(2)    I20 @S9S_MB_2U_LIB.S9S_MB_2U(SCH_1):PAGE59
  CA17 TP_DMI_CPU1_PCH_TX_DN<1> @S9S_MB_2U_LIB.S9S_MB_2U(SCH_1):TP_DMI_CPU1_PCH_TX_DN(1)    I20 @S9S_MB_2U_LIB.S9S_MB_2U(SCH_1):PAGE59
  BW19 TP_DMI_CPU1_PCH_TX_DN<0> @S9S_MB_2U_LIB.S9S_MB_2U(SCH_1):TP_DMI_CPU1_PCH_TX_DN(0)    I20 @S9S_MB_2U_LIB.S9S_MB_2U(SCH_1):PAGE59
  CM18 TP_DMI_CPU1_PCH_TX_DP<7> @S9S_MB_2U_LIB.S9S_MB_2U(SCH_1):TP_DMI_CPU1_PCH_TX_DP(7)    I20 @S9S_MB_2U_LIB.S9S_MB_2U(SCH_1):PAGE59
  CL19 TP_DMI_CPU1_PCH_TX_DP<6> @S9S_MB_2U_LIB.S9S_MB_2U(SCH_1):TP_DMI_CPU1_PCH_TX_DP(6)    I20 @S9S_MB_2U_LIB.S9S_MB_2U(SCH_1):PAGE59
  CH18 TP_DMI_CPU1_PCH_TX_DP<5> @S9S_MB_2U_LIB.S9S_MB_2U(SCH_1):TP_DMI_CPU1_PCH_TX_DP(5)    I20 @S9S_MB_2U_LIB.S9S_MB_2U(SCH_1):PAGE59
  CG19 TP_DMI_CPU1_PCH_TX_DP<4> @S9S_MB_2U_LIB.S9S_MB_2U(SCH_1):TP_DMI_CPU1_PCH_TX_DP(4)    I20 @S9S_MB_2U_LIB.S9S_MB_2U(SCH_1):PAGE59
  CD18 TP_DMI_CPU1_PCH_TX_DP<3> @S9S_MB_2U_LIB.S9S_MB_2U(SCH_1):TP_DMI_CPU1_PCH_TX_DP(3)    I20 @S9S_MB_2U_LIB.S9S_MB_2U(SCH_1):PAGE59
  CC19 TP_DMI_CPU1_PCH_TX_DP<2> @S9S_MB_2U_LIB.S9S_MB_2U(SCH_1):TP_DMI_CPU1_PCH_TX_DP(2)    I20 @S9S_MB_2U_LIB.S9S_MB_2U(SCH_1):PAGE59
  BY18 TP_DMI_CPU1_PCH_TX_DP<1> @S9S_MB_2U_LIB.S9S_MB_2U(SCH_1):TP_DMI_CPU1_PCH_TX_DP(1)    I20 @S9S_MB_2U_LIB.S9S_MB_2U(SCH_1):PAGE59
  CA19 TP_DMI_CPU1_PCH_TX_DP<0> @S9S_MB_2U_LIB.S9S_MB_2U(SCH_1):TP_DMI_CPU1_PCH_TX_DP(0)    I20 @S9S_MB_2U_LIB.S9S_MB_2U(SCH_1):PAGE59
   BA9 P5E_CPU1_PE0_RX_DN<15> @S9S_MB_2U_LIB.S9S_MB_2U(SCH_1):P5E_CPU1_PE0_RX_DN(15)    I80 @S9S_MB_2U_LIB.S9S_MB_2U(SCH_1):PAGE60
  AV10 P5E_CPU1_PE0_RX_DN<14> @S9S_MB_2U_LIB.S9S_MB_2U(SCH_1):P5E_CPU1_PE0_RX_DN(14)    I80 @S9S_MB_2U_LIB.S9S_MB_2U(SCH_1):PAGE60
   AU9 P5E_CPU1_PE0_RX_DN<13> @S9S_MB_2U_LIB.S9S_MB_2U(SCH_1):P5E_CPU1_PE0_RX_DN(13)    I80 @S9S_MB_2U_LIB.S9S_MB_2U(SCH_1):PAGE60
  AP10 P5E_CPU1_PE0_RX_DN<12> @S9S_MB_2U_LIB.S9S_MB_2U(SCH_1):P5E_CPU1_PE0_RX_DN(12)    I80 @S9S_MB_2U_LIB.S9S_MB_2U(SCH_1):PAGE60
  AM10 P5E_CPU1_PE0_RX_DN<11> @S9S_MB_2U_LIB.S9S_MB_2U(SCH_1):P5E_CPU1_PE0_RX_DN(11)    I80 @S9S_MB_2U_LIB.S9S_MB_2U(SCH_1):PAGE60
  AK10 P5E_CPU1_PE0_RX_DN<10> @S9S_MB_2U_LIB.S9S_MB_2U(SCH_1):P5E_CPU1_PE0_RX_DN(10)    I80 @S9S_MB_2U_LIB.S9S_MB_2U(SCH_1):PAGE60
   AJ9 P5E_CPU1_PE0_RX_DN<9> @S9S_MB_2U_LIB.S9S_MB_2U(SCH_1):P5E_CPU1_PE0_RX_DN(9)    I80 @S9S_MB_2U_LIB.S9S_MB_2U(SCH_1):PAGE60
  AF10 P5E_CPU1_PE0_RX_DN<8> @S9S_MB_2U_LIB.S9S_MB_2U(SCH_1):P5E_CPU1_PE0_RX_DN(8)    I80 @S9S_MB_2U_LIB.S9S_MB_2U(SCH_1):PAGE60
   AE9 P5E_CPU1_PE0_RX_DN<7> @S9S_MB_2U_LIB.S9S_MB_2U(SCH_1):P5E_CPU1_PE0_RX_DN(7)    I80 @S9S_MB_2U_LIB.S9S_MB_2U(SCH_1):PAGE60
  AB10 P5E_CPU1_PE0_RX_DN<6> @S9S_MB_2U_LIB.S9S_MB_2U(SCH_1):P5E_CPU1_PE0_RX_DN(6)    I80 @S9S_MB_2U_LIB.S9S_MB_2U(SCH_1):PAGE60
   AA9 P5E_CPU1_PE0_RX_DN<5> @S9S_MB_2U_LIB.S9S_MB_2U(SCH_1):P5E_CPU1_PE0_RX_DN(5)    I80 @S9S_MB_2U_LIB.S9S_MB_2U(SCH_1):PAGE60
   V10 P5E_CPU1_PE0_RX_DN<4> @S9S_MB_2U_LIB.S9S_MB_2U(SCH_1):P5E_CPU1_PE0_RX_DN(4)    I80 @S9S_MB_2U_LIB.S9S_MB_2U(SCH_1):PAGE60
   T10 P5E_CPU1_PE0_RX_DN<3> @S9S_MB_2U_LIB.S9S_MB_2U(SCH_1):P5E_CPU1_PE0_RX_DN(3)    I80 @S9S_MB_2U_LIB.S9S_MB_2U(SCH_1):PAGE60
   P10 P5E_CPU1_PE0_RX_DN<2> @S9S_MB_2U_LIB.S9S_MB_2U(SCH_1):P5E_CPU1_PE0_RX_DN(2)    I80 @S9S_MB_2U_LIB.S9S_MB_2U(SCH_1):PAGE60
   M10 P5E_CPU1_PE0_RX_DN<1> @S9S_MB_2U_LIB.S9S_MB_2U(SCH_1):P5E_CPU1_PE0_RX_DN(1)    I80 @S9S_MB_2U_LIB.S9S_MB_2U(SCH_1):PAGE60
   K10 P5E_CPU1_PE0_RX_DN<0> @S9S_MB_2U_LIB.S9S_MB_2U(SCH_1):P5E_CPU1_PE0_RX_DN(0)    I80 @S9S_MB_2U_LIB.S9S_MB_2U(SCH_1):PAGE60
  AY10 P5E_CPU1_PE0_RX_DP<15> @S9S_MB_2U_LIB.S9S_MB_2U(SCH_1):P5E_CPU1_PE0_RX_DP(15)    I80 @S9S_MB_2U_LIB.S9S_MB_2U(SCH_1):PAGE60
  AW11 P5E_CPU1_PE0_RX_DP<14> @S9S_MB_2U_LIB.S9S_MB_2U(SCH_1):P5E_CPU1_PE0_RX_DP(14)    I80 @S9S_MB_2U_LIB.S9S_MB_2U(SCH_1):PAGE60
  AT10 P5E_CPU1_PE0_RX_DP<13> @S9S_MB_2U_LIB.S9S_MB_2U(SCH_1):P5E_CPU1_PE0_RX_DP(13)    I80 @S9S_MB_2U_LIB.S9S_MB_2U(SCH_1):PAGE60
  AR11 P5E_CPU1_PE0_RX_DP<12> @S9S_MB_2U_LIB.S9S_MB_2U(SCH_1):P5E_CPU1_PE0_RX_DP(12)    I80 @S9S_MB_2U_LIB.S9S_MB_2U(SCH_1):PAGE60
   AN9 P5E_CPU1_PE0_RX_DP<11> @S9S_MB_2U_LIB.S9S_MB_2U(SCH_1):P5E_CPU1_PE0_RX_DP(11)    I80 @S9S_MB_2U_LIB.S9S_MB_2U(SCH_1):PAGE60
  AL11 P5E_CPU1_PE0_RX_DP<10> @S9S_MB_2U_LIB.S9S_MB_2U(SCH_1):P5E_CPU1_PE0_RX_DP(10)    I80 @S9S_MB_2U_LIB.S9S_MB_2U(SCH_1):PAGE60
  AH10 P5E_CPU1_PE0_RX_DP<9> @S9S_MB_2U_LIB.S9S_MB_2U(SCH_1):P5E_CPU1_PE0_RX_DP(9)    I80 @S9S_MB_2U_LIB.S9S_MB_2U(SCH_1):PAGE60
  AG11 P5E_CPU1_PE0_RX_DP<8> @S9S_MB_2U_LIB.S9S_MB_2U(SCH_1):P5E_CPU1_PE0_RX_DP(8)    I80 @S9S_MB_2U_LIB.S9S_MB_2U(SCH_1):PAGE60
  AD10 P5E_CPU1_PE0_RX_DP<7> @S9S_MB_2U_LIB.S9S_MB_2U(SCH_1):P5E_CPU1_PE0_RX_DP(7)    I80 @S9S_MB_2U_LIB.S9S_MB_2U(SCH_1):PAGE60
  AC11 P5E_CPU1_PE0_RX_DP<6> @S9S_MB_2U_LIB.S9S_MB_2U(SCH_1):P5E_CPU1_PE0_RX_DP(6)    I80 @S9S_MB_2U_LIB.S9S_MB_2U(SCH_1):PAGE60
   Y10 P5E_CPU1_PE0_RX_DP<5> @S9S_MB_2U_LIB.S9S_MB_2U(SCH_1):P5E_CPU1_PE0_RX_DP(5)    I80 @S9S_MB_2U_LIB.S9S_MB_2U(SCH_1):PAGE60
   W11 P5E_CPU1_PE0_RX_DP<4> @S9S_MB_2U_LIB.S9S_MB_2U(SCH_1):P5E_CPU1_PE0_RX_DP(4)    I80 @S9S_MB_2U_LIB.S9S_MB_2U(SCH_1):PAGE60
    U9 P5E_CPU1_PE0_RX_DP<3> @S9S_MB_2U_LIB.S9S_MB_2U(SCH_1):P5E_CPU1_PE0_RX_DP(3)    I80 @S9S_MB_2U_LIB.S9S_MB_2U(SCH_1):PAGE60
   R11 P5E_CPU1_PE0_RX_DP<2> @S9S_MB_2U_LIB.S9S_MB_2U(SCH_1):P5E_CPU1_PE0_RX_DP(2)    I80 @S9S_MB_2U_LIB.S9S_MB_2U(SCH_1):PAGE60
    N9 P5E_CPU1_PE0_RX_DP<1> @S9S_MB_2U_LIB.S9S_MB_2U(SCH_1):P5E_CPU1_PE0_RX_DP(1)    I80 @S9S_MB_2U_LIB.S9S_MB_2U(SCH_1):PAGE60
   L11 P5E_CPU1_PE0_RX_DP<0> @S9S_MB_2U_LIB.S9S_MB_2U(SCH_1):P5E_CPU1_PE0_RX_DP(0)    I80 @S9S_MB_2U_LIB.S9S_MB_2U(SCH_1):PAGE60
  BB14 P5E_CPU1_PE0_TX_DN<15> @S9S_MB_2U_LIB.S9S_MB_2U(SCH_1):P5E_CPU1_PE0_TX_DN(15)    I80 @S9S_MB_2U_LIB.S9S_MB_2U(SCH_1):PAGE60
  BA13 P5E_CPU1_PE0_TX_DN<14> @S9S_MB_2U_LIB.S9S_MB_2U(SCH_1):P5E_CPU1_PE0_TX_DN(14)    I80 @S9S_MB_2U_LIB.S9S_MB_2U(SCH_1):PAGE60
  AV14 P5E_CPU1_PE0_TX_DN<13> @S9S_MB_2U_LIB.S9S_MB_2U(SCH_1):P5E_CPU1_PE0_TX_DN(13)    I80 @S9S_MB_2U_LIB.S9S_MB_2U(SCH_1):PAGE60
  AU13 P5E_CPU1_PE0_TX_DN<12> @S9S_MB_2U_LIB.S9S_MB_2U(SCH_1):P5E_CPU1_PE0_TX_DN(12)    I80 @S9S_MB_2U_LIB.S9S_MB_2U(SCH_1):PAGE60
  AP14 P5E_CPU1_PE0_TX_DN<11> @S9S_MB_2U_LIB.S9S_MB_2U(SCH_1):P5E_CPU1_PE0_TX_DN(11)    I80 @S9S_MB_2U_LIB.S9S_MB_2U(SCH_1):PAGE60
  AN13 P5E_CPU1_PE0_TX_DN<10> @S9S_MB_2U_LIB.S9S_MB_2U(SCH_1):P5E_CPU1_PE0_TX_DN(10)    I80 @S9S_MB_2U_LIB.S9S_MB_2U(SCH_1):PAGE60
  AK14 P5E_CPU1_PE0_TX_DN<9> @S9S_MB_2U_LIB.S9S_MB_2U(SCH_1):P5E_CPU1_PE0_TX_DN(9)    I80 @S9S_MB_2U_LIB.S9S_MB_2U(SCH_1):PAGE60
  AJ13 P5E_CPU1_PE0_TX_DN<8> @S9S_MB_2U_LIB.S9S_MB_2U(SCH_1):P5E_CPU1_PE0_TX_DN(8)    I80 @S9S_MB_2U_LIB.S9S_MB_2U(SCH_1):PAGE60
  AF14 P5E_CPU1_PE0_TX_DN<7> @S9S_MB_2U_LIB.S9S_MB_2U(SCH_1):P5E_CPU1_PE0_TX_DN(7)    I80 @S9S_MB_2U_LIB.S9S_MB_2U(SCH_1):PAGE60
  AE13 P5E_CPU1_PE0_TX_DN<6> @S9S_MB_2U_LIB.S9S_MB_2U(SCH_1):P5E_CPU1_PE0_TX_DN(6)    I80 @S9S_MB_2U_LIB.S9S_MB_2U(SCH_1):PAGE60
  AB14 P5E_CPU1_PE0_TX_DN<5> @S9S_MB_2U_LIB.S9S_MB_2U(SCH_1):P5E_CPU1_PE0_TX_DN(5)    I80 @S9S_MB_2U_LIB.S9S_MB_2U(SCH_1):PAGE60
  AA13 P5E_CPU1_PE0_TX_DN<4> @S9S_MB_2U_LIB.S9S_MB_2U(SCH_1):P5E_CPU1_PE0_TX_DN(4)    I80 @S9S_MB_2U_LIB.S9S_MB_2U(SCH_1):PAGE60
   V14 P5E_CPU1_PE0_TX_DN<3> @S9S_MB_2U_LIB.S9S_MB_2U(SCH_1):P5E_CPU1_PE0_TX_DN(3)    I80 @S9S_MB_2U_LIB.S9S_MB_2U(SCH_1):PAGE60
   U13 P5E_CPU1_PE0_TX_DN<2> @S9S_MB_2U_LIB.S9S_MB_2U(SCH_1):P5E_CPU1_PE0_TX_DN(2)    I80 @S9S_MB_2U_LIB.S9S_MB_2U(SCH_1):PAGE60
   P14 P5E_CPU1_PE0_TX_DN<1> @S9S_MB_2U_LIB.S9S_MB_2U(SCH_1):P5E_CPU1_PE0_TX_DN(1)    I80 @S9S_MB_2U_LIB.S9S_MB_2U(SCH_1):PAGE60
   N13 P5E_CPU1_PE0_TX_DN<0> @S9S_MB_2U_LIB.S9S_MB_2U(SCH_1):P5E_CPU1_PE0_TX_DN(0)    I80 @S9S_MB_2U_LIB.S9S_MB_2U(SCH_1):PAGE60
  BC15 P5E_CPU1_PE0_TX_DP<15> @S9S_MB_2U_LIB.S9S_MB_2U(SCH_1):P5E_CPU1_PE0_TX_DP(15)    I80 @S9S_MB_2U_LIB.S9S_MB_2U(SCH_1):PAGE60
  AY14 P5E_CPU1_PE0_TX_DP<14> @S9S_MB_2U_LIB.S9S_MB_2U(SCH_1):P5E_CPU1_PE0_TX_DP(14)    I80 @S9S_MB_2U_LIB.S9S_MB_2U(SCH_1):PAGE60
  AW15 P5E_CPU1_PE0_TX_DP<13> @S9S_MB_2U_LIB.S9S_MB_2U(SCH_1):P5E_CPU1_PE0_TX_DP(13)    I80 @S9S_MB_2U_LIB.S9S_MB_2U(SCH_1):PAGE60
  AT14 P5E_CPU1_PE0_TX_DP<12> @S9S_MB_2U_LIB.S9S_MB_2U(SCH_1):P5E_CPU1_PE0_TX_DP(12)    I80 @S9S_MB_2U_LIB.S9S_MB_2U(SCH_1):PAGE60
  AR15 P5E_CPU1_PE0_TX_DP<11> @S9S_MB_2U_LIB.S9S_MB_2U(SCH_1):P5E_CPU1_PE0_TX_DP(11)    I80 @S9S_MB_2U_LIB.S9S_MB_2U(SCH_1):PAGE60
  AM14 P5E_CPU1_PE0_TX_DP<10> @S9S_MB_2U_LIB.S9S_MB_2U(SCH_1):P5E_CPU1_PE0_TX_DP(10)    I80 @S9S_MB_2U_LIB.S9S_MB_2U(SCH_1):PAGE60
  AL15 P5E_CPU1_PE0_TX_DP<9> @S9S_MB_2U_LIB.S9S_MB_2U(SCH_1):P5E_CPU1_PE0_TX_DP(9)    I80 @S9S_MB_2U_LIB.S9S_MB_2U(SCH_1):PAGE60
  AH14 P5E_CPU1_PE0_TX_DP<8> @S9S_MB_2U_LIB.S9S_MB_2U(SCH_1):P5E_CPU1_PE0_TX_DP(8)    I80 @S9S_MB_2U_LIB.S9S_MB_2U(SCH_1):PAGE60
  AG15 P5E_CPU1_PE0_TX_DP<7> @S9S_MB_2U_LIB.S9S_MB_2U(SCH_1):P5E_CPU1_PE0_TX_DP(7)    I80 @S9S_MB_2U_LIB.S9S_MB_2U(SCH_1):PAGE60
  AD14 P5E_CPU1_PE0_TX_DP<6> @S9S_MB_2U_LIB.S9S_MB_2U(SCH_1):P5E_CPU1_PE0_TX_DP(6)    I80 @S9S_MB_2U_LIB.S9S_MB_2U(SCH_1):PAGE60
  AC15 P5E_CPU1_PE0_TX_DP<5> @S9S_MB_2U_LIB.S9S_MB_2U(SCH_1):P5E_CPU1_PE0_TX_DP(5)    I80 @S9S_MB_2U_LIB.S9S_MB_2U(SCH_1):PAGE60
   Y14 P5E_CPU1_PE0_TX_DP<4> @S9S_MB_2U_LIB.S9S_MB_2U(SCH_1):P5E_CPU1_PE0_TX_DP(4)    I80 @S9S_MB_2U_LIB.S9S_MB_2U(SCH_1):PAGE60
   W15 P5E_CPU1_PE0_TX_DP<3> @S9S_MB_2U_LIB.S9S_MB_2U(SCH_1):P5E_CPU1_PE0_TX_DP(3)    I80 @S9S_MB_2U_LIB.S9S_MB_2U(SCH_1):PAGE60
   T14 P5E_CPU1_PE0_TX_DP<2> @S9S_MB_2U_LIB.S9S_MB_2U(SCH_1):P5E_CPU1_PE0_TX_DP(2)    I80 @S9S_MB_2U_LIB.S9S_MB_2U(SCH_1):PAGE60
   R15 P5E_CPU1_PE0_TX_DP<1> @S9S_MB_2U_LIB.S9S_MB_2U(SCH_1):P5E_CPU1_PE0_TX_DP(1)    I80 @S9S_MB_2U_LIB.S9S_MB_2U(SCH_1):PAGE60
   M14 P5E_CPU1_PE0_TX_DP<0> @S9S_MB_2U_LIB.S9S_MB_2U(SCH_1):P5E_CPU1_PE0_TX_DP(0)    I80 @S9S_MB_2U_LIB.S9S_MB_2U(SCH_1):PAGE60
  BC11 P5E_CPU1_PE1_RX_DN<15> @S9S_MB_2U_LIB.S9S_MB_2U(SCH_1):P5E_CPU1_PE1_RX_DN(15)    I69 @S9S_MB_2U_LIB.S9S_MB_2U(SCH_1):PAGE60
  BF10 P5E_CPU1_PE1_RX_DN<14> @S9S_MB_2U_LIB.S9S_MB_2U(SCH_1):P5E_CPU1_PE1_RX_DN(14)    I69 @S9S_MB_2U_LIB.S9S_MB_2U(SCH_1):PAGE60
  BG11 P5E_CPU1_PE1_RX_DN<13> @S9S_MB_2U_LIB.S9S_MB_2U(SCH_1):P5E_CPU1_PE1_RX_DN(13)    I69 @S9S_MB_2U_LIB.S9S_MB_2U(SCH_1):PAGE60
  BK10 P5E_CPU1_PE1_RX_DN<12> @S9S_MB_2U_LIB.S9S_MB_2U(SCH_1):P5E_CPU1_PE1_RX_DN(12)    I69 @S9S_MB_2U_LIB.S9S_MB_2U(SCH_1):PAGE60
  BL11 P5E_CPU1_PE1_RX_DN<11> @S9S_MB_2U_LIB.S9S_MB_2U(SCH_1):P5E_CPU1_PE1_RX_DN(11)    I69 @S9S_MB_2U_LIB.S9S_MB_2U(SCH_1):PAGE60
  BP10 P5E_CPU1_PE1_RX_DN<10> @S9S_MB_2U_LIB.S9S_MB_2U(SCH_1):P5E_CPU1_PE1_RX_DN(10)    I69 @S9S_MB_2U_LIB.S9S_MB_2U(SCH_1):PAGE60
  BR11 P5E_CPU1_PE1_RX_DN<9> @S9S_MB_2U_LIB.S9S_MB_2U(SCH_1):P5E_CPU1_PE1_RX_DN(9)    I69 @S9S_MB_2U_LIB.S9S_MB_2U(SCH_1):PAGE60
  BV10 P5E_CPU1_PE1_RX_DN<8> @S9S_MB_2U_LIB.S9S_MB_2U(SCH_1):P5E_CPU1_PE1_RX_DN(8)    I69 @S9S_MB_2U_LIB.S9S_MB_2U(SCH_1):PAGE60
  BW11 P5E_CPU1_PE1_RX_DN<7> @S9S_MB_2U_LIB.S9S_MB_2U(SCH_1):P5E_CPU1_PE1_RX_DN(7)    I69 @S9S_MB_2U_LIB.S9S_MB_2U(SCH_1):PAGE60
  CB10 P5E_CPU1_PE1_RX_DN<6> @S9S_MB_2U_LIB.S9S_MB_2U(SCH_1):P5E_CPU1_PE1_RX_DN(6)    I69 @S9S_MB_2U_LIB.S9S_MB_2U(SCH_1):PAGE60
  CC11 P5E_CPU1_PE1_RX_DN<5> @S9S_MB_2U_LIB.S9S_MB_2U(SCH_1):P5E_CPU1_PE1_RX_DN(5)    I69 @S9S_MB_2U_LIB.S9S_MB_2U(SCH_1):PAGE60
  CF10 P5E_CPU1_PE1_RX_DN<4> @S9S_MB_2U_LIB.S9S_MB_2U(SCH_1):P5E_CPU1_PE1_RX_DN(4)    I69 @S9S_MB_2U_LIB.S9S_MB_2U(SCH_1):PAGE60
  CG11 P5E_CPU1_PE1_RX_DN<3> @S9S_MB_2U_LIB.S9S_MB_2U(SCH_1):P5E_CPU1_PE1_RX_DN(3)    I69 @S9S_MB_2U_LIB.S9S_MB_2U(SCH_1):PAGE60
  CK10 P5E_CPU1_PE1_RX_DN<2> @S9S_MB_2U_LIB.S9S_MB_2U(SCH_1):P5E_CPU1_PE1_RX_DN(2)    I69 @S9S_MB_2U_LIB.S9S_MB_2U(SCH_1):PAGE60
  CL11 P5E_CPU1_PE1_RX_DN<1> @S9S_MB_2U_LIB.S9S_MB_2U(SCH_1):P5E_CPU1_PE1_RX_DN(1)    I69 @S9S_MB_2U_LIB.S9S_MB_2U(SCH_1):PAGE60
  CP10 P5E_CPU1_PE1_RX_DN<0> @S9S_MB_2U_LIB.S9S_MB_2U(SCH_1):P5E_CPU1_PE1_RX_DN(0)    I69 @S9S_MB_2U_LIB.S9S_MB_2U(SCH_1):PAGE60
  BD10 P5E_CPU1_PE1_RX_DP<15> @S9S_MB_2U_LIB.S9S_MB_2U(SCH_1):P5E_CPU1_PE1_RX_DP(15)    I69 @S9S_MB_2U_LIB.S9S_MB_2U(SCH_1):PAGE60
   BE9 P5E_CPU1_PE1_RX_DP<14> @S9S_MB_2U_LIB.S9S_MB_2U(SCH_1):P5E_CPU1_PE1_RX_DP(14)    I69 @S9S_MB_2U_LIB.S9S_MB_2U(SCH_1):PAGE60
  BH10 P5E_CPU1_PE1_RX_DP<13> @S9S_MB_2U_LIB.S9S_MB_2U(SCH_1):P5E_CPU1_PE1_RX_DP(13)    I69 @S9S_MB_2U_LIB.S9S_MB_2U(SCH_1):PAGE60
   BJ9 P5E_CPU1_PE1_RX_DP<12> @S9S_MB_2U_LIB.S9S_MB_2U(SCH_1):P5E_CPU1_PE1_RX_DP(12)    I69 @S9S_MB_2U_LIB.S9S_MB_2U(SCH_1):PAGE60
  BM10 P5E_CPU1_PE1_RX_DP<11> @S9S_MB_2U_LIB.S9S_MB_2U(SCH_1):P5E_CPU1_PE1_RX_DP(11)    I69 @S9S_MB_2U_LIB.S9S_MB_2U(SCH_1):PAGE60
   BN9 P5E_CPU1_PE1_RX_DP<10> @S9S_MB_2U_LIB.S9S_MB_2U(SCH_1):P5E_CPU1_PE1_RX_DP(10)    I69 @S9S_MB_2U_LIB.S9S_MB_2U(SCH_1):PAGE60
  BT10 P5E_CPU1_PE1_RX_DP<9> @S9S_MB_2U_LIB.S9S_MB_2U(SCH_1):P5E_CPU1_PE1_RX_DP(9)    I69 @S9S_MB_2U_LIB.S9S_MB_2U(SCH_1):PAGE60
   BU9 P5E_CPU1_PE1_RX_DP<8> @S9S_MB_2U_LIB.S9S_MB_2U(SCH_1):P5E_CPU1_PE1_RX_DP(8)    I69 @S9S_MB_2U_LIB.S9S_MB_2U(SCH_1):PAGE60
  BY10 P5E_CPU1_PE1_RX_DP<7> @S9S_MB_2U_LIB.S9S_MB_2U(SCH_1):P5E_CPU1_PE1_RX_DP(7)    I69 @S9S_MB_2U_LIB.S9S_MB_2U(SCH_1):PAGE60
   CA9 P5E_CPU1_PE1_RX_DP<6> @S9S_MB_2U_LIB.S9S_MB_2U(SCH_1):P5E_CPU1_PE1_RX_DP(6)    I69 @S9S_MB_2U_LIB.S9S_MB_2U(SCH_1):PAGE60
  CD10 P5E_CPU1_PE1_RX_DP<5> @S9S_MB_2U_LIB.S9S_MB_2U(SCH_1):P5E_CPU1_PE1_RX_DP(5)    I69 @S9S_MB_2U_LIB.S9S_MB_2U(SCH_1):PAGE60
   CE9 P5E_CPU1_PE1_RX_DP<4> @S9S_MB_2U_LIB.S9S_MB_2U(SCH_1):P5E_CPU1_PE1_RX_DP(4)    I69 @S9S_MB_2U_LIB.S9S_MB_2U(SCH_1):PAGE60
  CH10 P5E_CPU1_PE1_RX_DP<3> @S9S_MB_2U_LIB.S9S_MB_2U(SCH_1):P5E_CPU1_PE1_RX_DP(3)    I69 @S9S_MB_2U_LIB.S9S_MB_2U(SCH_1):PAGE60
   CJ9 P5E_CPU1_PE1_RX_DP<2> @S9S_MB_2U_LIB.S9S_MB_2U(SCH_1):P5E_CPU1_PE1_RX_DP(2)    I69 @S9S_MB_2U_LIB.S9S_MB_2U(SCH_1):PAGE60
  CM10 P5E_CPU1_PE1_RX_DP<1> @S9S_MB_2U_LIB.S9S_MB_2U(SCH_1):P5E_CPU1_PE1_RX_DP(1)    I69 @S9S_MB_2U_LIB.S9S_MB_2U(SCH_1):PAGE60
   CN9 P5E_CPU1_PE1_RX_DP<0> @S9S_MB_2U_LIB.S9S_MB_2U(SCH_1):P5E_CPU1_PE1_RX_DP(0)    I69 @S9S_MB_2U_LIB.S9S_MB_2U(SCH_1):PAGE60
  BE13 P5E_CPU1_PE1_TX_DN<15> @S9S_MB_2U_LIB.S9S_MB_2U(SCH_1):P5E_CPU1_PE1_TX_DN(15)    I69 @S9S_MB_2U_LIB.S9S_MB_2U(SCH_1):PAGE60
  BF14 P5E_CPU1_PE1_TX_DN<14> @S9S_MB_2U_LIB.S9S_MB_2U(SCH_1):P5E_CPU1_PE1_TX_DN(14)    I69 @S9S_MB_2U_LIB.S9S_MB_2U(SCH_1):PAGE60
  BJ13 P5E_CPU1_PE1_TX_DN<13> @S9S_MB_2U_LIB.S9S_MB_2U(SCH_1):P5E_CPU1_PE1_TX_DN(13)    I69 @S9S_MB_2U_LIB.S9S_MB_2U(SCH_1):PAGE60
  BK14 P5E_CPU1_PE1_TX_DN<12> @S9S_MB_2U_LIB.S9S_MB_2U(SCH_1):P5E_CPU1_PE1_TX_DN(12)    I69 @S9S_MB_2U_LIB.S9S_MB_2U(SCH_1):PAGE60
  BN13 P5E_CPU1_PE1_TX_DN<11> @S9S_MB_2U_LIB.S9S_MB_2U(SCH_1):P5E_CPU1_PE1_TX_DN(11)    I69 @S9S_MB_2U_LIB.S9S_MB_2U(SCH_1):PAGE60
  BP14 P5E_CPU1_PE1_TX_DN<10> @S9S_MB_2U_LIB.S9S_MB_2U(SCH_1):P5E_CPU1_PE1_TX_DN(10)    I69 @S9S_MB_2U_LIB.S9S_MB_2U(SCH_1):PAGE60
  BU13 P5E_CPU1_PE1_TX_DN<9> @S9S_MB_2U_LIB.S9S_MB_2U(SCH_1):P5E_CPU1_PE1_TX_DN(9)    I69 @S9S_MB_2U_LIB.S9S_MB_2U(SCH_1):PAGE60
  BV14 P5E_CPU1_PE1_TX_DN<8> @S9S_MB_2U_LIB.S9S_MB_2U(SCH_1):P5E_CPU1_PE1_TX_DN(8)    I69 @S9S_MB_2U_LIB.S9S_MB_2U(SCH_1):PAGE60
  CA13 P5E_CPU1_PE1_TX_DN<7> @S9S_MB_2U_LIB.S9S_MB_2U(SCH_1):P5E_CPU1_PE1_TX_DN(7)    I69 @S9S_MB_2U_LIB.S9S_MB_2U(SCH_1):PAGE60
  CB14 P5E_CPU1_PE1_TX_DN<6> @S9S_MB_2U_LIB.S9S_MB_2U(SCH_1):P5E_CPU1_PE1_TX_DN(6)    I69 @S9S_MB_2U_LIB.S9S_MB_2U(SCH_1):PAGE60
  CE13 P5E_CPU1_PE1_TX_DN<5> @S9S_MB_2U_LIB.S9S_MB_2U(SCH_1):P5E_CPU1_PE1_TX_DN(5)    I69 @S9S_MB_2U_LIB.S9S_MB_2U(SCH_1):PAGE60
  CF14 P5E_CPU1_PE1_TX_DN<4> @S9S_MB_2U_LIB.S9S_MB_2U(SCH_1):P5E_CPU1_PE1_TX_DN(4)    I69 @S9S_MB_2U_LIB.S9S_MB_2U(SCH_1):PAGE60
  CJ13 P5E_CPU1_PE1_TX_DN<3> @S9S_MB_2U_LIB.S9S_MB_2U(SCH_1):P5E_CPU1_PE1_TX_DN(3)    I69 @S9S_MB_2U_LIB.S9S_MB_2U(SCH_1):PAGE60
  CK14 P5E_CPU1_PE1_TX_DN<2> @S9S_MB_2U_LIB.S9S_MB_2U(SCH_1):P5E_CPU1_PE1_TX_DN(2)    I69 @S9S_MB_2U_LIB.S9S_MB_2U(SCH_1):PAGE60
  CN13 P5E_CPU1_PE1_TX_DN<1> @S9S_MB_2U_LIB.S9S_MB_2U(SCH_1):P5E_CPU1_PE1_TX_DN(1)    I69 @S9S_MB_2U_LIB.S9S_MB_2U(SCH_1):PAGE60
  CP14 P5E_CPU1_PE1_TX_DN<0> @S9S_MB_2U_LIB.S9S_MB_2U(SCH_1):P5E_CPU1_PE1_TX_DN(0)    I69 @S9S_MB_2U_LIB.S9S_MB_2U(SCH_1):PAGE60
  BD14 P5E_CPU1_PE1_TX_DP<15> @S9S_MB_2U_LIB.S9S_MB_2U(SCH_1):P5E_CPU1_PE1_TX_DP(15)    I69 @S9S_MB_2U_LIB.S9S_MB_2U(SCH_1):PAGE60
  BG15 P5E_CPU1_PE1_TX_DP<14> @S9S_MB_2U_LIB.S9S_MB_2U(SCH_1):P5E_CPU1_PE1_TX_DP(14)    I69 @S9S_MB_2U_LIB.S9S_MB_2U(SCH_1):PAGE60
  BH14 P5E_CPU1_PE1_TX_DP<13> @S9S_MB_2U_LIB.S9S_MB_2U(SCH_1):P5E_CPU1_PE1_TX_DP(13)    I69 @S9S_MB_2U_LIB.S9S_MB_2U(SCH_1):PAGE60
  BL15 P5E_CPU1_PE1_TX_DP<12> @S9S_MB_2U_LIB.S9S_MB_2U(SCH_1):P5E_CPU1_PE1_TX_DP(12)    I69 @S9S_MB_2U_LIB.S9S_MB_2U(SCH_1):PAGE60
  BM14 P5E_CPU1_PE1_TX_DP<11> @S9S_MB_2U_LIB.S9S_MB_2U(SCH_1):P5E_CPU1_PE1_TX_DP(11)    I69 @S9S_MB_2U_LIB.S9S_MB_2U(SCH_1):PAGE60
  BR15 P5E_CPU1_PE1_TX_DP<10> @S9S_MB_2U_LIB.S9S_MB_2U(SCH_1):P5E_CPU1_PE1_TX_DP(10)    I69 @S9S_MB_2U_LIB.S9S_MB_2U(SCH_1):PAGE60
  BT14 P5E_CPU1_PE1_TX_DP<9> @S9S_MB_2U_LIB.S9S_MB_2U(SCH_1):P5E_CPU1_PE1_TX_DP(9)    I69 @S9S_MB_2U_LIB.S9S_MB_2U(SCH_1):PAGE60
  BW15 P5E_CPU1_PE1_TX_DP<8> @S9S_MB_2U_LIB.S9S_MB_2U(SCH_1):P5E_CPU1_PE1_TX_DP(8)    I69 @S9S_MB_2U_LIB.S9S_MB_2U(SCH_1):PAGE60
  BY14 P5E_CPU1_PE1_TX_DP<7> @S9S_MB_2U_LIB.S9S_MB_2U(SCH_1):P5E_CPU1_PE1_TX_DP(7)    I69 @S9S_MB_2U_LIB.S9S_MB_2U(SCH_1):PAGE60
  CC15 P5E_CPU1_PE1_TX_DP<6> @S9S_MB_2U_LIB.S9S_MB_2U(SCH_1):P5E_CPU1_PE1_TX_DP(6)    I69 @S9S_MB_2U_LIB.S9S_MB_2U(SCH_1):PAGE60
  CD14 P5E_CPU1_PE1_TX_DP<5> @S9S_MB_2U_LIB.S9S_MB_2U(SCH_1):P5E_CPU1_PE1_TX_DP(5)    I69 @S9S_MB_2U_LIB.S9S_MB_2U(SCH_1):PAGE60
  CG15 P5E_CPU1_PE1_TX_DP<4> @S9S_MB_2U_LIB.S9S_MB_2U(SCH_1):P5E_CPU1_PE1_TX_DP(4)    I69 @S9S_MB_2U_LIB.S9S_MB_2U(SCH_1):PAGE60
  CH14 P5E_CPU1_PE1_TX_DP<3> @S9S_MB_2U_LIB.S9S_MB_2U(SCH_1):P5E_CPU1_PE1_TX_DP(3)    I69 @S9S_MB_2U_LIB.S9S_MB_2U(SCH_1):PAGE60
  CL15 P5E_CPU1_PE1_TX_DP<2> @S9S_MB_2U_LIB.S9S_MB_2U(SCH_1):P5E_CPU1_PE1_TX_DP(2)    I69 @S9S_MB_2U_LIB.S9S_MB_2U(SCH_1):PAGE60
  CM14 P5E_CPU1_PE1_TX_DP<1> @S9S_MB_2U_LIB.S9S_MB_2U(SCH_1):P5E_CPU1_PE1_TX_DP(1)    I69 @S9S_MB_2U_LIB.S9S_MB_2U(SCH_1):PAGE60
  CR15 P5E_CPU1_PE1_TX_DP<0> @S9S_MB_2U_LIB.S9S_MB_2U(SCH_1):P5E_CPU1_PE1_TX_DP(0)    I69 @S9S_MB_2U_LIB.S9S_MB_2U(SCH_1):PAGE60
  EH10 P5E_CPU1_PE2_RX_DN<15> @S9S_MB_2U_LIB.S9S_MB_2U(SCH_1):P5E_CPU1_PE2_RX_DN(15)    I54 @S9S_MB_2U_LIB.S9S_MB_2U(SCH_1):PAGE61
   EE9 P5E_CPU1_PE2_RX_DN<14> @S9S_MB_2U_LIB.S9S_MB_2U(SCH_1):P5E_CPU1_PE2_RX_DN(14)    I54 @S9S_MB_2U_LIB.S9S_MB_2U(SCH_1):PAGE61
  ED10 P5E_CPU1_PE2_RX_DN<13> @S9S_MB_2U_LIB.S9S_MB_2U(SCH_1):P5E_CPU1_PE2_RX_DN(13)    I54 @S9S_MB_2U_LIB.S9S_MB_2U(SCH_1):PAGE61
   EA9 P5E_CPU1_PE2_RX_DN<12> @S9S_MB_2U_LIB.S9S_MB_2U(SCH_1):P5E_CPU1_PE2_RX_DN(12)    I54 @S9S_MB_2U_LIB.S9S_MB_2U(SCH_1):PAGE61
  DY10 P5E_CPU1_PE2_RX_DN<11> @S9S_MB_2U_LIB.S9S_MB_2U(SCH_1):P5E_CPU1_PE2_RX_DN(11)    I54 @S9S_MB_2U_LIB.S9S_MB_2U(SCH_1):PAGE61
   DU9 P5E_CPU1_PE2_RX_DN<10> @S9S_MB_2U_LIB.S9S_MB_2U(SCH_1):P5E_CPU1_PE2_RX_DN(10)    I54 @S9S_MB_2U_LIB.S9S_MB_2U(SCH_1):PAGE61
  DT10 P5E_CPU1_PE2_RX_DN<9> @S9S_MB_2U_LIB.S9S_MB_2U(SCH_1):P5E_CPU1_PE2_RX_DN(9)    I54 @S9S_MB_2U_LIB.S9S_MB_2U(SCH_1):PAGE61
   DN9 P5E_CPU1_PE2_RX_DN<8> @S9S_MB_2U_LIB.S9S_MB_2U(SCH_1):P5E_CPU1_PE2_RX_DN(8)    I54 @S9S_MB_2U_LIB.S9S_MB_2U(SCH_1):PAGE61
  DM10 P5E_CPU1_PE2_RX_DN<7> @S9S_MB_2U_LIB.S9S_MB_2U(SCH_1):P5E_CPU1_PE2_RX_DN(7)    I54 @S9S_MB_2U_LIB.S9S_MB_2U(SCH_1):PAGE61
   DJ9 P5E_CPU1_PE2_RX_DN<6> @S9S_MB_2U_LIB.S9S_MB_2U(SCH_1):P5E_CPU1_PE2_RX_DN(6)    I54 @S9S_MB_2U_LIB.S9S_MB_2U(SCH_1):PAGE61
  DH10 P5E_CPU1_PE2_RX_DN<5> @S9S_MB_2U_LIB.S9S_MB_2U(SCH_1):P5E_CPU1_PE2_RX_DN(5)    I54 @S9S_MB_2U_LIB.S9S_MB_2U(SCH_1):PAGE61
   DE9 P5E_CPU1_PE2_RX_DN<4> @S9S_MB_2U_LIB.S9S_MB_2U(SCH_1):P5E_CPU1_PE2_RX_DN(4)    I54 @S9S_MB_2U_LIB.S9S_MB_2U(SCH_1):PAGE61
  DD10 P5E_CPU1_PE2_RX_DN<3> @S9S_MB_2U_LIB.S9S_MB_2U(SCH_1):P5E_CPU1_PE2_RX_DN(3)    I54 @S9S_MB_2U_LIB.S9S_MB_2U(SCH_1):PAGE61
   DA9 P5E_CPU1_PE2_RX_DN<2> @S9S_MB_2U_LIB.S9S_MB_2U(SCH_1):P5E_CPU1_PE2_RX_DN(2)    I54 @S9S_MB_2U_LIB.S9S_MB_2U(SCH_1):PAGE61
  CY10 P5E_CPU1_PE2_RX_DN<1> @S9S_MB_2U_LIB.S9S_MB_2U(SCH_1):P5E_CPU1_PE2_RX_DN(1)    I54 @S9S_MB_2U_LIB.S9S_MB_2U(SCH_1):PAGE61
   CU9 P5E_CPU1_PE2_RX_DN<0> @S9S_MB_2U_LIB.S9S_MB_2U(SCH_1):P5E_CPU1_PE2_RX_DN(0)    I54 @S9S_MB_2U_LIB.S9S_MB_2U(SCH_1):PAGE61
  EG11 P5E_CPU1_PE2_RX_DP<15> @S9S_MB_2U_LIB.S9S_MB_2U(SCH_1):P5E_CPU1_PE2_RX_DP(15)    I54 @S9S_MB_2U_LIB.S9S_MB_2U(SCH_1):PAGE61
  EF10 P5E_CPU1_PE2_RX_DP<14> @S9S_MB_2U_LIB.S9S_MB_2U(SCH_1):P5E_CPU1_PE2_RX_DP(14)    I54 @S9S_MB_2U_LIB.S9S_MB_2U(SCH_1):PAGE61
  EC11 P5E_CPU1_PE2_RX_DP<13> @S9S_MB_2U_LIB.S9S_MB_2U(SCH_1):P5E_CPU1_PE2_RX_DP(13)    I54 @S9S_MB_2U_LIB.S9S_MB_2U(SCH_1):PAGE61
  EB10 P5E_CPU1_PE2_RX_DP<12> @S9S_MB_2U_LIB.S9S_MB_2U(SCH_1):P5E_CPU1_PE2_RX_DP(12)    I54 @S9S_MB_2U_LIB.S9S_MB_2U(SCH_1):PAGE61
  DW11 P5E_CPU1_PE2_RX_DP<11> @S9S_MB_2U_LIB.S9S_MB_2U(SCH_1):P5E_CPU1_PE2_RX_DP(11)    I54 @S9S_MB_2U_LIB.S9S_MB_2U(SCH_1):PAGE61
  DV10 P5E_CPU1_PE2_RX_DP<10> @S9S_MB_2U_LIB.S9S_MB_2U(SCH_1):P5E_CPU1_PE2_RX_DP(10)    I54 @S9S_MB_2U_LIB.S9S_MB_2U(SCH_1):PAGE61
  DR11 P5E_CPU1_PE2_RX_DP<9> @S9S_MB_2U_LIB.S9S_MB_2U(SCH_1):P5E_CPU1_PE2_RX_DP(9)    I54 @S9S_MB_2U_LIB.S9S_MB_2U(SCH_1):PAGE61
  DP10 P5E_CPU1_PE2_RX_DP<8> @S9S_MB_2U_LIB.S9S_MB_2U(SCH_1):P5E_CPU1_PE2_RX_DP(8)    I54 @S9S_MB_2U_LIB.S9S_MB_2U(SCH_1):PAGE61
  DL11 P5E_CPU1_PE2_RX_DP<7> @S9S_MB_2U_LIB.S9S_MB_2U(SCH_1):P5E_CPU1_PE2_RX_DP(7)    I54 @S9S_MB_2U_LIB.S9S_MB_2U(SCH_1):PAGE61
  DK10 P5E_CPU1_PE2_RX_DP<6> @S9S_MB_2U_LIB.S9S_MB_2U(SCH_1):P5E_CPU1_PE2_RX_DP(6)    I54 @S9S_MB_2U_LIB.S9S_MB_2U(SCH_1):PAGE61
  DG11 P5E_CPU1_PE2_RX_DP<5> @S9S_MB_2U_LIB.S9S_MB_2U(SCH_1):P5E_CPU1_PE2_RX_DP(5)    I54 @S9S_MB_2U_LIB.S9S_MB_2U(SCH_1):PAGE61
  DF10 P5E_CPU1_PE2_RX_DP<4> @S9S_MB_2U_LIB.S9S_MB_2U(SCH_1):P5E_CPU1_PE2_RX_DP(4)    I54 @S9S_MB_2U_LIB.S9S_MB_2U(SCH_1):PAGE61
  DC11 P5E_CPU1_PE2_RX_DP<3> @S9S_MB_2U_LIB.S9S_MB_2U(SCH_1):P5E_CPU1_PE2_RX_DP(3)    I54 @S9S_MB_2U_LIB.S9S_MB_2U(SCH_1):PAGE61
  DB10 P5E_CPU1_PE2_RX_DP<2> @S9S_MB_2U_LIB.S9S_MB_2U(SCH_1):P5E_CPU1_PE2_RX_DP(2)    I54 @S9S_MB_2U_LIB.S9S_MB_2U(SCH_1):PAGE61
  CW11 P5E_CPU1_PE2_RX_DP<1> @S9S_MB_2U_LIB.S9S_MB_2U(SCH_1):P5E_CPU1_PE2_RX_DP(1)    I54 @S9S_MB_2U_LIB.S9S_MB_2U(SCH_1):PAGE61
  CV10 P5E_CPU1_PE2_RX_DP<0> @S9S_MB_2U_LIB.S9S_MB_2U(SCH_1):P5E_CPU1_PE2_RX_DP(0)    I54 @S9S_MB_2U_LIB.S9S_MB_2U(SCH_1):PAGE61
  EF14 P5E_CPU1_PE2_TX_DN<15> @S9S_MB_2U_LIB.S9S_MB_2U(SCH_1):P5E_CPU1_PE2_TX_DN(15)    I54 @S9S_MB_2U_LIB.S9S_MB_2U(SCH_1):PAGE61
  EE13 P5E_CPU1_PE2_TX_DN<14> @S9S_MB_2U_LIB.S9S_MB_2U(SCH_1):P5E_CPU1_PE2_TX_DN(14)    I54 @S9S_MB_2U_LIB.S9S_MB_2U(SCH_1):PAGE61
  EB14 P5E_CPU1_PE2_TX_DN<13> @S9S_MB_2U_LIB.S9S_MB_2U(SCH_1):P5E_CPU1_PE2_TX_DN(13)    I54 @S9S_MB_2U_LIB.S9S_MB_2U(SCH_1):PAGE61
  EA13 P5E_CPU1_PE2_TX_DN<12> @S9S_MB_2U_LIB.S9S_MB_2U(SCH_1):P5E_CPU1_PE2_TX_DN(12)    I54 @S9S_MB_2U_LIB.S9S_MB_2U(SCH_1):PAGE61
  DV14 P5E_CPU1_PE2_TX_DN<11> @S9S_MB_2U_LIB.S9S_MB_2U(SCH_1):P5E_CPU1_PE2_TX_DN(11)    I54 @S9S_MB_2U_LIB.S9S_MB_2U(SCH_1):PAGE61
  DU13 P5E_CPU1_PE2_TX_DN<10> @S9S_MB_2U_LIB.S9S_MB_2U(SCH_1):P5E_CPU1_PE2_TX_DN(10)    I54 @S9S_MB_2U_LIB.S9S_MB_2U(SCH_1):PAGE61
  DP14 P5E_CPU1_PE2_TX_DN<9> @S9S_MB_2U_LIB.S9S_MB_2U(SCH_1):P5E_CPU1_PE2_TX_DN(9)    I54 @S9S_MB_2U_LIB.S9S_MB_2U(SCH_1):PAGE61
  DN13 P5E_CPU1_PE2_TX_DN<8> @S9S_MB_2U_LIB.S9S_MB_2U(SCH_1):P5E_CPU1_PE2_TX_DN(8)    I54 @S9S_MB_2U_LIB.S9S_MB_2U(SCH_1):PAGE61
  DK14 P5E_CPU1_PE2_TX_DN<7> @S9S_MB_2U_LIB.S9S_MB_2U(SCH_1):P5E_CPU1_PE2_TX_DN(7)    I54 @S9S_MB_2U_LIB.S9S_MB_2U(SCH_1):PAGE61
  DJ13 P5E_CPU1_PE2_TX_DN<6> @S9S_MB_2U_LIB.S9S_MB_2U(SCH_1):P5E_CPU1_PE2_TX_DN(6)    I54 @S9S_MB_2U_LIB.S9S_MB_2U(SCH_1):PAGE61
  DF14 P5E_CPU1_PE2_TX_DN<5> @S9S_MB_2U_LIB.S9S_MB_2U(SCH_1):P5E_CPU1_PE2_TX_DN(5)    I54 @S9S_MB_2U_LIB.S9S_MB_2U(SCH_1):PAGE61
  DE13 P5E_CPU1_PE2_TX_DN<4> @S9S_MB_2U_LIB.S9S_MB_2U(SCH_1):P5E_CPU1_PE2_TX_DN(4)    I54 @S9S_MB_2U_LIB.S9S_MB_2U(SCH_1):PAGE61
  DB14 P5E_CPU1_PE2_TX_DN<3> @S9S_MB_2U_LIB.S9S_MB_2U(SCH_1):P5E_CPU1_PE2_TX_DN(3)    I54 @S9S_MB_2U_LIB.S9S_MB_2U(SCH_1):PAGE61
  DA13 P5E_CPU1_PE2_TX_DN<2> @S9S_MB_2U_LIB.S9S_MB_2U(SCH_1):P5E_CPU1_PE2_TX_DN(2)    I54 @S9S_MB_2U_LIB.S9S_MB_2U(SCH_1):PAGE61
  CV14 P5E_CPU1_PE2_TX_DN<1> @S9S_MB_2U_LIB.S9S_MB_2U(SCH_1):P5E_CPU1_PE2_TX_DN(1)    I54 @S9S_MB_2U_LIB.S9S_MB_2U(SCH_1):PAGE61
  CU13 P5E_CPU1_PE2_TX_DN<0> @S9S_MB_2U_LIB.S9S_MB_2U(SCH_1):P5E_CPU1_PE2_TX_DN(0)    I54 @S9S_MB_2U_LIB.S9S_MB_2U(SCH_1):PAGE61
  EG15 P5E_CPU1_PE2_TX_DP<15> @S9S_MB_2U_LIB.S9S_MB_2U(SCH_1):P5E_CPU1_PE2_TX_DP(15)    I54 @S9S_MB_2U_LIB.S9S_MB_2U(SCH_1):PAGE61
  ED14 P5E_CPU1_PE2_TX_DP<14> @S9S_MB_2U_LIB.S9S_MB_2U(SCH_1):P5E_CPU1_PE2_TX_DP(14)    I54 @S9S_MB_2U_LIB.S9S_MB_2U(SCH_1):PAGE61
  EC15 P5E_CPU1_PE2_TX_DP<13> @S9S_MB_2U_LIB.S9S_MB_2U(SCH_1):P5E_CPU1_PE2_TX_DP(13)    I54 @S9S_MB_2U_LIB.S9S_MB_2U(SCH_1):PAGE61
  DY14 P5E_CPU1_PE2_TX_DP<12> @S9S_MB_2U_LIB.S9S_MB_2U(SCH_1):P5E_CPU1_PE2_TX_DP(12)    I54 @S9S_MB_2U_LIB.S9S_MB_2U(SCH_1):PAGE61
  DW15 P5E_CPU1_PE2_TX_DP<11> @S9S_MB_2U_LIB.S9S_MB_2U(SCH_1):P5E_CPU1_PE2_TX_DP(11)    I54 @S9S_MB_2U_LIB.S9S_MB_2U(SCH_1):PAGE61
  DT14 P5E_CPU1_PE2_TX_DP<10> @S9S_MB_2U_LIB.S9S_MB_2U(SCH_1):P5E_CPU1_PE2_TX_DP(10)    I54 @S9S_MB_2U_LIB.S9S_MB_2U(SCH_1):PAGE61
  DR15 P5E_CPU1_PE2_TX_DP<9> @S9S_MB_2U_LIB.S9S_MB_2U(SCH_1):P5E_CPU1_PE2_TX_DP(9)    I54 @S9S_MB_2U_LIB.S9S_MB_2U(SCH_1):PAGE61
  DM14 P5E_CPU1_PE2_TX_DP<8> @S9S_MB_2U_LIB.S9S_MB_2U(SCH_1):P5E_CPU1_PE2_TX_DP(8)    I54 @S9S_MB_2U_LIB.S9S_MB_2U(SCH_1):PAGE61
  DL15 P5E_CPU1_PE2_TX_DP<7> @S9S_MB_2U_LIB.S9S_MB_2U(SCH_1):P5E_CPU1_PE2_TX_DP(7)    I54 @S9S_MB_2U_LIB.S9S_MB_2U(SCH_1):PAGE61
  DH14 P5E_CPU1_PE2_TX_DP<6> @S9S_MB_2U_LIB.S9S_MB_2U(SCH_1):P5E_CPU1_PE2_TX_DP(6)    I54 @S9S_MB_2U_LIB.S9S_MB_2U(SCH_1):PAGE61
  DG15 P5E_CPU1_PE2_TX_DP<5> @S9S_MB_2U_LIB.S9S_MB_2U(SCH_1):P5E_CPU1_PE2_TX_DP(5)    I54 @S9S_MB_2U_LIB.S9S_MB_2U(SCH_1):PAGE61
  DD14 P5E_CPU1_PE2_TX_DP<4> @S9S_MB_2U_LIB.S9S_MB_2U(SCH_1):P5E_CPU1_PE2_TX_DP(4)    I54 @S9S_MB_2U_LIB.S9S_MB_2U(SCH_1):PAGE61
  DC15 P5E_CPU1_PE2_TX_DP<3> @S9S_MB_2U_LIB.S9S_MB_2U(SCH_1):P5E_CPU1_PE2_TX_DP(3)    I54 @S9S_MB_2U_LIB.S9S_MB_2U(SCH_1):PAGE61
  CY14 P5E_CPU1_PE2_TX_DP<2> @S9S_MB_2U_LIB.S9S_MB_2U(SCH_1):P5E_CPU1_PE2_TX_DP(2)    I54 @S9S_MB_2U_LIB.S9S_MB_2U(SCH_1):PAGE61
  CW15 P5E_CPU1_PE2_TX_DP<1> @S9S_MB_2U_LIB.S9S_MB_2U(SCH_1):P5E_CPU1_PE2_TX_DP(1)    I54 @S9S_MB_2U_LIB.S9S_MB_2U(SCH_1):PAGE61
  CT14 P5E_CPU1_PE2_TX_DP<0> @S9S_MB_2U_LIB.S9S_MB_2U(SCH_1):P5E_CPU1_PE2_TX_DP(0)    I54 @S9S_MB_2U_LIB.S9S_MB_2U(SCH_1):PAGE61
  CU90 P5E_CPU1_PE3_RX_DN<15> @S9S_MB_2U_LIB.S9S_MB_2U(SCH_1):P5E_CPU1_PE3_RX_DN(15)    I12 @S9S_MB_2U_LIB.S9S_MB_2U(SCH_1):PAGE61
  CV89 P5E_CPU1_PE3_RX_DN<14> @S9S_MB_2U_LIB.S9S_MB_2U(SCH_1):P5E_CPU1_PE3_RX_DN(14)    I12 @S9S_MB_2U_LIB.S9S_MB_2U(SCH_1):PAGE61
  DA90 P5E_CPU1_PE3_RX_DN<13> @S9S_MB_2U_LIB.S9S_MB_2U(SCH_1):P5E_CPU1_PE3_RX_DN(13)    I12 @S9S_MB_2U_LIB.S9S_MB_2U(SCH_1):PAGE61
  DB89 P5E_CPU1_PE3_RX_DN<12> @S9S_MB_2U_LIB.S9S_MB_2U(SCH_1):P5E_CPU1_PE3_RX_DN(12)    I12 @S9S_MB_2U_LIB.S9S_MB_2U(SCH_1):PAGE61
  DD91 P5E_CPU1_PE3_RX_DN<11> @S9S_MB_2U_LIB.S9S_MB_2U(SCH_1):P5E_CPU1_PE3_RX_DN(11)    I12 @S9S_MB_2U_LIB.S9S_MB_2U(SCH_1):PAGE61
  DG90 P5E_CPU1_PE3_RX_DN<10> @S9S_MB_2U_LIB.S9S_MB_2U(SCH_1):P5E_CPU1_PE3_RX_DN(10)    I12 @S9S_MB_2U_LIB.S9S_MB_2U(SCH_1):PAGE61
  DH91 P5E_CPU1_PE3_RX_DN<9> @S9S_MB_2U_LIB.S9S_MB_2U(SCH_1):P5E_CPU1_PE3_RX_DN(9)    I12 @S9S_MB_2U_LIB.S9S_MB_2U(SCH_1):PAGE61
  DL90 P5E_CPU1_PE3_RX_DN<8> @S9S_MB_2U_LIB.S9S_MB_2U(SCH_1):P5E_CPU1_PE3_RX_DN(8)    I12 @S9S_MB_2U_LIB.S9S_MB_2U(SCH_1):PAGE61
  DN90 P5E_CPU1_PE3_RX_DN<7> @S9S_MB_2U_LIB.S9S_MB_2U(SCH_1):P5E_CPU1_PE3_RX_DN(7)    I12 @S9S_MB_2U_LIB.S9S_MB_2U(SCH_1):PAGE61
  DP89 P5E_CPU1_PE3_RX_DN<6> @S9S_MB_2U_LIB.S9S_MB_2U(SCH_1):P5E_CPU1_PE3_RX_DN(6)    I12 @S9S_MB_2U_LIB.S9S_MB_2U(SCH_1):PAGE61
  DU90 P5E_CPU1_PE3_RX_DN<5> @S9S_MB_2U_LIB.S9S_MB_2U(SCH_1):P5E_CPU1_PE3_RX_DN(5)    I12 @S9S_MB_2U_LIB.S9S_MB_2U(SCH_1):PAGE61
  DV89 P5E_CPU1_PE3_RX_DN<4> @S9S_MB_2U_LIB.S9S_MB_2U(SCH_1):P5E_CPU1_PE3_RX_DN(4)    I12 @S9S_MB_2U_LIB.S9S_MB_2U(SCH_1):PAGE61
  DY91 P5E_CPU1_PE3_RX_DN<3> @S9S_MB_2U_LIB.S9S_MB_2U(SCH_1):P5E_CPU1_PE3_RX_DN(3)    I12 @S9S_MB_2U_LIB.S9S_MB_2U(SCH_1):PAGE61
  EC90 P5E_CPU1_PE3_RX_DN<2> @S9S_MB_2U_LIB.S9S_MB_2U(SCH_1):P5E_CPU1_PE3_RX_DN(2)    I12 @S9S_MB_2U_LIB.S9S_MB_2U(SCH_1):PAGE61
  ED91 P5E_CPU1_PE3_RX_DN<1> @S9S_MB_2U_LIB.S9S_MB_2U(SCH_1):P5E_CPU1_PE3_RX_DN(1)    I12 @S9S_MB_2U_LIB.S9S_MB_2U(SCH_1):PAGE61
  EH89 P5E_CPU1_PE3_RX_DN<0> @S9S_MB_2U_LIB.S9S_MB_2U(SCH_1):P5E_CPU1_PE3_RX_DN(0)    I12 @S9S_MB_2U_LIB.S9S_MB_2U(SCH_1):PAGE61
  CT91 P5E_CPU1_PE3_RX_DP<15> @S9S_MB_2U_LIB.S9S_MB_2U(SCH_1):P5E_CPU1_PE3_RX_DP(15)    I12 @S9S_MB_2U_LIB.S9S_MB_2U(SCH_1):PAGE61
  CW90 P5E_CPU1_PE3_RX_DP<14> @S9S_MB_2U_LIB.S9S_MB_2U(SCH_1):P5E_CPU1_PE3_RX_DP(14)    I12 @S9S_MB_2U_LIB.S9S_MB_2U(SCH_1):PAGE61
  CY91 P5E_CPU1_PE3_RX_DP<13> @S9S_MB_2U_LIB.S9S_MB_2U(SCH_1):P5E_CPU1_PE3_RX_DP(13)    I12 @S9S_MB_2U_LIB.S9S_MB_2U(SCH_1):PAGE61
  DC90 P5E_CPU1_PE3_RX_DP<12> @S9S_MB_2U_LIB.S9S_MB_2U(SCH_1):P5E_CPU1_PE3_RX_DP(12)    I12 @S9S_MB_2U_LIB.S9S_MB_2U(SCH_1):PAGE61
  DE90 P5E_CPU1_PE3_RX_DP<11> @S9S_MB_2U_LIB.S9S_MB_2U(SCH_1):P5E_CPU1_PE3_RX_DP(11)    I12 @S9S_MB_2U_LIB.S9S_MB_2U(SCH_1):PAGE61
  DF89 P5E_CPU1_PE3_RX_DP<10> @S9S_MB_2U_LIB.S9S_MB_2U(SCH_1):P5E_CPU1_PE3_RX_DP(10)    I12 @S9S_MB_2U_LIB.S9S_MB_2U(SCH_1):PAGE61
  DJ90 P5E_CPU1_PE3_RX_DP<9> @S9S_MB_2U_LIB.S9S_MB_2U(SCH_1):P5E_CPU1_PE3_RX_DP(9)    I12 @S9S_MB_2U_LIB.S9S_MB_2U(SCH_1):PAGE61
  DK89 P5E_CPU1_PE3_RX_DP<8> @S9S_MB_2U_LIB.S9S_MB_2U(SCH_1):P5E_CPU1_PE3_RX_DP(8)    I12 @S9S_MB_2U_LIB.S9S_MB_2U(SCH_1):PAGE61
  DM91 P5E_CPU1_PE3_RX_DP<7> @S9S_MB_2U_LIB.S9S_MB_2U(SCH_1):P5E_CPU1_PE3_RX_DP(7)    I12 @S9S_MB_2U_LIB.S9S_MB_2U(SCH_1):PAGE61
  DR90 P5E_CPU1_PE3_RX_DP<6> @S9S_MB_2U_LIB.S9S_MB_2U(SCH_1):P5E_CPU1_PE3_RX_DP(6)    I12 @S9S_MB_2U_LIB.S9S_MB_2U(SCH_1):PAGE61
  DT91 P5E_CPU1_PE3_RX_DP<5> @S9S_MB_2U_LIB.S9S_MB_2U(SCH_1):P5E_CPU1_PE3_RX_DP(5)    I12 @S9S_MB_2U_LIB.S9S_MB_2U(SCH_1):PAGE61
  DW90 P5E_CPU1_PE3_RX_DP<4> @S9S_MB_2U_LIB.S9S_MB_2U(SCH_1):P5E_CPU1_PE3_RX_DP(4)    I12 @S9S_MB_2U_LIB.S9S_MB_2U(SCH_1):PAGE61
  EA90 P5E_CPU1_PE3_RX_DP<3> @S9S_MB_2U_LIB.S9S_MB_2U(SCH_1):P5E_CPU1_PE3_RX_DP(3)    I12 @S9S_MB_2U_LIB.S9S_MB_2U(SCH_1):PAGE61
  EB89 P5E_CPU1_PE3_RX_DP<2> @S9S_MB_2U_LIB.S9S_MB_2U(SCH_1):P5E_CPU1_PE3_RX_DP(2)    I12 @S9S_MB_2U_LIB.S9S_MB_2U(SCH_1):PAGE61
  EE90 P5E_CPU1_PE3_RX_DP<1> @S9S_MB_2U_LIB.S9S_MB_2U(SCH_1):P5E_CPU1_PE3_RX_DP(1)    I12 @S9S_MB_2U_LIB.S9S_MB_2U(SCH_1):PAGE61
  EJ90 P5E_CPU1_PE3_RX_DP<0> @S9S_MB_2U_LIB.S9S_MB_2U(SCH_1):P5E_CPU1_PE3_RX_DP(0)    I12 @S9S_MB_2U_LIB.S9S_MB_2U(SCH_1):PAGE61
  CP85 P5E_CPU1_PE3_TX_DN<15> @S9S_MB_2U_LIB.S9S_MB_2U(SCH_1):P5E_CPU1_PE3_TX_DN(15)    I12 @S9S_MB_2U_LIB.S9S_MB_2U(SCH_1):PAGE61
  CT87 P5E_CPU1_PE3_TX_DN<14> @S9S_MB_2U_LIB.S9S_MB_2U(SCH_1):P5E_CPU1_PE3_TX_DN(14)    I12 @S9S_MB_2U_LIB.S9S_MB_2U(SCH_1):PAGE61
  CV85 P5E_CPU1_PE3_TX_DN<13> @S9S_MB_2U_LIB.S9S_MB_2U(SCH_1):P5E_CPU1_PE3_TX_DN(13)    I12 @S9S_MB_2U_LIB.S9S_MB_2U(SCH_1):PAGE61
  CY87 P5E_CPU1_PE3_TX_DN<12> @S9S_MB_2U_LIB.S9S_MB_2U(SCH_1):P5E_CPU1_PE3_TX_DN(12)    I12 @S9S_MB_2U_LIB.S9S_MB_2U(SCH_1):PAGE61
  DB85 P5E_CPU1_PE3_TX_DN<11> @S9S_MB_2U_LIB.S9S_MB_2U(SCH_1):P5E_CPU1_PE3_TX_DN(11)    I12 @S9S_MB_2U_LIB.S9S_MB_2U(SCH_1):PAGE61
  DD87 P5E_CPU1_PE3_TX_DN<10> @S9S_MB_2U_LIB.S9S_MB_2U(SCH_1):P5E_CPU1_PE3_TX_DN(10)    I12 @S9S_MB_2U_LIB.S9S_MB_2U(SCH_1):PAGE61
  DF85 P5E_CPU1_PE3_TX_DN<9> @S9S_MB_2U_LIB.S9S_MB_2U(SCH_1):P5E_CPU1_PE3_TX_DN(9)    I12 @S9S_MB_2U_LIB.S9S_MB_2U(SCH_1):PAGE61
  DH87 P5E_CPU1_PE3_TX_DN<8> @S9S_MB_2U_LIB.S9S_MB_2U(SCH_1):P5E_CPU1_PE3_TX_DN(8)    I12 @S9S_MB_2U_LIB.S9S_MB_2U(SCH_1):PAGE61
  DK85 P5E_CPU1_PE3_TX_DN<7> @S9S_MB_2U_LIB.S9S_MB_2U(SCH_1):P5E_CPU1_PE3_TX_DN(7)    I12 @S9S_MB_2U_LIB.S9S_MB_2U(SCH_1):PAGE61
  DM87 P5E_CPU1_PE3_TX_DN<6> @S9S_MB_2U_LIB.S9S_MB_2U(SCH_1):P5E_CPU1_PE3_TX_DN(6)    I12 @S9S_MB_2U_LIB.S9S_MB_2U(SCH_1):PAGE61
  DP85 P5E_CPU1_PE3_TX_DN<5> @S9S_MB_2U_LIB.S9S_MB_2U(SCH_1):P5E_CPU1_PE3_TX_DN(5)    I12 @S9S_MB_2U_LIB.S9S_MB_2U(SCH_1):PAGE61
  DT87 P5E_CPU1_PE3_TX_DN<4> @S9S_MB_2U_LIB.S9S_MB_2U(SCH_1):P5E_CPU1_PE3_TX_DN(4)    I12 @S9S_MB_2U_LIB.S9S_MB_2U(SCH_1):PAGE61
  DV85 P5E_CPU1_PE3_TX_DN<3> @S9S_MB_2U_LIB.S9S_MB_2U(SCH_1):P5E_CPU1_PE3_TX_DN(3)    I12 @S9S_MB_2U_LIB.S9S_MB_2U(SCH_1):PAGE61
  DY87 P5E_CPU1_PE3_TX_DN<2> @S9S_MB_2U_LIB.S9S_MB_2U(SCH_1):P5E_CPU1_PE3_TX_DN(2)    I12 @S9S_MB_2U_LIB.S9S_MB_2U(SCH_1):PAGE61
  EB85 P5E_CPU1_PE3_TX_DN<1> @S9S_MB_2U_LIB.S9S_MB_2U(SCH_1):P5E_CPU1_PE3_TX_DN(1)    I12 @S9S_MB_2U_LIB.S9S_MB_2U(SCH_1):PAGE61
  EE86 P5E_CPU1_PE3_TX_DN<0> @S9S_MB_2U_LIB.S9S_MB_2U(SCH_1):P5E_CPU1_PE3_TX_DN(0)    I12 @S9S_MB_2U_LIB.S9S_MB_2U(SCH_1):PAGE61
  CR86 P5E_CPU1_PE3_TX_DP<15> @S9S_MB_2U_LIB.S9S_MB_2U(SCH_1):P5E_CPU1_PE3_TX_DP(15)    I12 @S9S_MB_2U_LIB.S9S_MB_2U(SCH_1):PAGE61
  CU86 P5E_CPU1_PE3_TX_DP<14> @S9S_MB_2U_LIB.S9S_MB_2U(SCH_1):P5E_CPU1_PE3_TX_DP(14)    I12 @S9S_MB_2U_LIB.S9S_MB_2U(SCH_1):PAGE61
  CW86 P5E_CPU1_PE3_TX_DP<13> @S9S_MB_2U_LIB.S9S_MB_2U(SCH_1):P5E_CPU1_PE3_TX_DP(13)    I12 @S9S_MB_2U_LIB.S9S_MB_2U(SCH_1):PAGE61
  DA86 P5E_CPU1_PE3_TX_DP<12> @S9S_MB_2U_LIB.S9S_MB_2U(SCH_1):P5E_CPU1_PE3_TX_DP(12)    I12 @S9S_MB_2U_LIB.S9S_MB_2U(SCH_1):PAGE61
  DC86 P5E_CPU1_PE3_TX_DP<11> @S9S_MB_2U_LIB.S9S_MB_2U(SCH_1):P5E_CPU1_PE3_TX_DP(11)    I12 @S9S_MB_2U_LIB.S9S_MB_2U(SCH_1):PAGE61
  DE86 P5E_CPU1_PE3_TX_DP<10> @S9S_MB_2U_LIB.S9S_MB_2U(SCH_1):P5E_CPU1_PE3_TX_DP(10)    I12 @S9S_MB_2U_LIB.S9S_MB_2U(SCH_1):PAGE61
  DG86 P5E_CPU1_PE3_TX_DP<9> @S9S_MB_2U_LIB.S9S_MB_2U(SCH_1):P5E_CPU1_PE3_TX_DP(9)    I12 @S9S_MB_2U_LIB.S9S_MB_2U(SCH_1):PAGE61
  DJ86 P5E_CPU1_PE3_TX_DP<8> @S9S_MB_2U_LIB.S9S_MB_2U(SCH_1):P5E_CPU1_PE3_TX_DP(8)    I12 @S9S_MB_2U_LIB.S9S_MB_2U(SCH_1):PAGE61
  DL86 P5E_CPU1_PE3_TX_DP<7> @S9S_MB_2U_LIB.S9S_MB_2U(SCH_1):P5E_CPU1_PE3_TX_DP(7)    I12 @S9S_MB_2U_LIB.S9S_MB_2U(SCH_1):PAGE61
  DN86 P5E_CPU1_PE3_TX_DP<6> @S9S_MB_2U_LIB.S9S_MB_2U(SCH_1):P5E_CPU1_PE3_TX_DP(6)    I12 @S9S_MB_2U_LIB.S9S_MB_2U(SCH_1):PAGE61
  DR86 P5E_CPU1_PE3_TX_DP<5> @S9S_MB_2U_LIB.S9S_MB_2U(SCH_1):P5E_CPU1_PE3_TX_DP(5)    I12 @S9S_MB_2U_LIB.S9S_MB_2U(SCH_1):PAGE61
  DU86 P5E_CPU1_PE3_TX_DP<4> @S9S_MB_2U_LIB.S9S_MB_2U(SCH_1):P5E_CPU1_PE3_TX_DP(4)    I12 @S9S_MB_2U_LIB.S9S_MB_2U(SCH_1):PAGE61
  DW86 P5E_CPU1_PE3_TX_DP<3> @S9S_MB_2U_LIB.S9S_MB_2U(SCH_1):P5E_CPU1_PE3_TX_DP(3)    I12 @S9S_MB_2U_LIB.S9S_MB_2U(SCH_1):PAGE61
  EA86 P5E_CPU1_PE3_TX_DP<2> @S9S_MB_2U_LIB.S9S_MB_2U(SCH_1):P5E_CPU1_PE3_TX_DP(2)    I12 @S9S_MB_2U_LIB.S9S_MB_2U(SCH_1):PAGE61
  EC86 P5E_CPU1_PE3_TX_DP<1> @S9S_MB_2U_LIB.S9S_MB_2U(SCH_1):P5E_CPU1_PE3_TX_DP(1)    I12 @S9S_MB_2U_LIB.S9S_MB_2U(SCH_1):PAGE61
  ED87 P5E_CPU1_PE3_TX_DP<0> @S9S_MB_2U_LIB.S9S_MB_2U(SCH_1):P5E_CPU1_PE3_TX_DP(0)    I12 @S9S_MB_2U_LIB.S9S_MB_2U(SCH_1):PAGE61
  BB89 P5E_CPU1_PE4_RX_DN<15> @S9S_MB_2U_LIB.S9S_MB_2U(SCH_1):P5E_CPU1_PE4_RX_DN(15)    I18 @S9S_MB_2U_LIB.S9S_MB_2U(SCH_1):PAGE62
  AY91 P5E_CPU1_PE4_RX_DN<14> @S9S_MB_2U_LIB.S9S_MB_2U(SCH_1):P5E_CPU1_PE4_RX_DN(14)    I18 @S9S_MB_2U_LIB.S9S_MB_2U(SCH_1):PAGE62
  AV89 P5E_CPU1_PE4_RX_DN<13> @S9S_MB_2U_LIB.S9S_MB_2U(SCH_1):P5E_CPU1_PE4_RX_DN(13)    I18 @S9S_MB_2U_LIB.S9S_MB_2U(SCH_1):PAGE62
  AT91 P5E_CPU1_PE4_RX_DN<12> @S9S_MB_2U_LIB.S9S_MB_2U(SCH_1):P5E_CPU1_PE4_RX_DN(12)    I18 @S9S_MB_2U_LIB.S9S_MB_2U(SCH_1):PAGE62
  AP89 P5E_CPU1_PE4_RX_DN<11> @S9S_MB_2U_LIB.S9S_MB_2U(SCH_1):P5E_CPU1_PE4_RX_DN(11)    I18 @S9S_MB_2U_LIB.S9S_MB_2U(SCH_1):PAGE62
  AM91 P5E_CPU1_PE4_RX_DN<10> @S9S_MB_2U_LIB.S9S_MB_2U(SCH_1):P5E_CPU1_PE4_RX_DN(10)    I18 @S9S_MB_2U_LIB.S9S_MB_2U(SCH_1):PAGE62
  AK89 P5E_CPU1_PE4_RX_DN<9> @S9S_MB_2U_LIB.S9S_MB_2U(SCH_1):P5E_CPU1_PE4_RX_DN(9)    I18 @S9S_MB_2U_LIB.S9S_MB_2U(SCH_1):PAGE62
  AH91 P5E_CPU1_PE4_RX_DN<8> @S9S_MB_2U_LIB.S9S_MB_2U(SCH_1):P5E_CPU1_PE4_RX_DN(8)    I18 @S9S_MB_2U_LIB.S9S_MB_2U(SCH_1):PAGE62
  AF89 P5E_CPU1_PE4_RX_DN<7> @S9S_MB_2U_LIB.S9S_MB_2U(SCH_1):P5E_CPU1_PE4_RX_DN(7)    I18 @S9S_MB_2U_LIB.S9S_MB_2U(SCH_1):PAGE62
  AD91 P5E_CPU1_PE4_RX_DN<6> @S9S_MB_2U_LIB.S9S_MB_2U(SCH_1):P5E_CPU1_PE4_RX_DN(6)    I18 @S9S_MB_2U_LIB.S9S_MB_2U(SCH_1):PAGE62
  AB89 P5E_CPU1_PE4_RX_DN<5> @S9S_MB_2U_LIB.S9S_MB_2U(SCH_1):P5E_CPU1_PE4_RX_DN(5)    I18 @S9S_MB_2U_LIB.S9S_MB_2U(SCH_1):PAGE62
   Y91 P5E_CPU1_PE4_RX_DN<4> @S9S_MB_2U_LIB.S9S_MB_2U(SCH_1):P5E_CPU1_PE4_RX_DN(4)    I18 @S9S_MB_2U_LIB.S9S_MB_2U(SCH_1):PAGE62
   V89 P5E_CPU1_PE4_RX_DN<3> @S9S_MB_2U_LIB.S9S_MB_2U(SCH_1):P5E_CPU1_PE4_RX_DN(3)    I18 @S9S_MB_2U_LIB.S9S_MB_2U(SCH_1):PAGE62
   T91 P5E_CPU1_PE4_RX_DN<2> @S9S_MB_2U_LIB.S9S_MB_2U(SCH_1):P5E_CPU1_PE4_RX_DN(2)    I18 @S9S_MB_2U_LIB.S9S_MB_2U(SCH_1):PAGE62
   P89 P5E_CPU1_PE4_RX_DN<1> @S9S_MB_2U_LIB.S9S_MB_2U(SCH_1):P5E_CPU1_PE4_RX_DN(1)    I18 @S9S_MB_2U_LIB.S9S_MB_2U(SCH_1):PAGE62
   J90 P5E_CPU1_PE4_RX_DN<0> @S9S_MB_2U_LIB.S9S_MB_2U(SCH_1):P5E_CPU1_PE4_RX_DN(0)    I18 @S9S_MB_2U_LIB.S9S_MB_2U(SCH_1):PAGE62
  BA90 P5E_CPU1_PE4_RX_DP<15> @S9S_MB_2U_LIB.S9S_MB_2U(SCH_1):P5E_CPU1_PE4_RX_DP(15)    I18 @S9S_MB_2U_LIB.S9S_MB_2U(SCH_1):PAGE62
  AW90 P5E_CPU1_PE4_RX_DP<14> @S9S_MB_2U_LIB.S9S_MB_2U(SCH_1):P5E_CPU1_PE4_RX_DP(14)    I18 @S9S_MB_2U_LIB.S9S_MB_2U(SCH_1):PAGE62
  AU90 P5E_CPU1_PE4_RX_DP<13> @S9S_MB_2U_LIB.S9S_MB_2U(SCH_1):P5E_CPU1_PE4_RX_DP(13)    I18 @S9S_MB_2U_LIB.S9S_MB_2U(SCH_1):PAGE62
  AR90 P5E_CPU1_PE4_RX_DP<12> @S9S_MB_2U_LIB.S9S_MB_2U(SCH_1):P5E_CPU1_PE4_RX_DP(12)    I18 @S9S_MB_2U_LIB.S9S_MB_2U(SCH_1):PAGE62
  AN90 P5E_CPU1_PE4_RX_DP<11> @S9S_MB_2U_LIB.S9S_MB_2U(SCH_1):P5E_CPU1_PE4_RX_DP(11)    I18 @S9S_MB_2U_LIB.S9S_MB_2U(SCH_1):PAGE62
  AL90 P5E_CPU1_PE4_RX_DP<10> @S9S_MB_2U_LIB.S9S_MB_2U(SCH_1):P5E_CPU1_PE4_RX_DP(10)    I18 @S9S_MB_2U_LIB.S9S_MB_2U(SCH_1):PAGE62
  AJ90 P5E_CPU1_PE4_RX_DP<9> @S9S_MB_2U_LIB.S9S_MB_2U(SCH_1):P5E_CPU1_PE4_RX_DP(9)    I18 @S9S_MB_2U_LIB.S9S_MB_2U(SCH_1):PAGE62
  AG90 P5E_CPU1_PE4_RX_DP<8> @S9S_MB_2U_LIB.S9S_MB_2U(SCH_1):P5E_CPU1_PE4_RX_DP(8)    I18 @S9S_MB_2U_LIB.S9S_MB_2U(SCH_1):PAGE62
  AE90 P5E_CPU1_PE4_RX_DP<7> @S9S_MB_2U_LIB.S9S_MB_2U(SCH_1):P5E_CPU1_PE4_RX_DP(7)    I18 @S9S_MB_2U_LIB.S9S_MB_2U(SCH_1):PAGE62
  AC90 P5E_CPU1_PE4_RX_DP<6> @S9S_MB_2U_LIB.S9S_MB_2U(SCH_1):P5E_CPU1_PE4_RX_DP(6)    I18 @S9S_MB_2U_LIB.S9S_MB_2U(SCH_1):PAGE62
  AA90 P5E_CPU1_PE4_RX_DP<5> @S9S_MB_2U_LIB.S9S_MB_2U(SCH_1):P5E_CPU1_PE4_RX_DP(5)    I18 @S9S_MB_2U_LIB.S9S_MB_2U(SCH_1):PAGE62
   W90 P5E_CPU1_PE4_RX_DP<4> @S9S_MB_2U_LIB.S9S_MB_2U(SCH_1):P5E_CPU1_PE4_RX_DP(4)    I18 @S9S_MB_2U_LIB.S9S_MB_2U(SCH_1):PAGE62
   U90 P5E_CPU1_PE4_RX_DP<3> @S9S_MB_2U_LIB.S9S_MB_2U(SCH_1):P5E_CPU1_PE4_RX_DP(3)    I18 @S9S_MB_2U_LIB.S9S_MB_2U(SCH_1):PAGE62
   R90 P5E_CPU1_PE4_RX_DP<2> @S9S_MB_2U_LIB.S9S_MB_2U(SCH_1):P5E_CPU1_PE4_RX_DP(2)    I18 @S9S_MB_2U_LIB.S9S_MB_2U(SCH_1):PAGE62
   N90 P5E_CPU1_PE4_RX_DP<1> @S9S_MB_2U_LIB.S9S_MB_2U(SCH_1):P5E_CPU1_PE4_RX_DP(1)    I18 @S9S_MB_2U_LIB.S9S_MB_2U(SCH_1):PAGE62
   K89 P5E_CPU1_PE4_RX_DP<0> @S9S_MB_2U_LIB.S9S_MB_2U(SCH_1):P5E_CPU1_PE4_RX_DP(0)    I18 @S9S_MB_2U_LIB.S9S_MB_2U(SCH_1):PAGE62
  BA86 P5E_CPU1_PE4_TX_DN<15> @S9S_MB_2U_LIB.S9S_MB_2U(SCH_1):P5E_CPU1_PE4_TX_DN(15)    I18 @S9S_MB_2U_LIB.S9S_MB_2U(SCH_1):PAGE62
  AW86 P5E_CPU1_PE4_TX_DN<14> @S9S_MB_2U_LIB.S9S_MB_2U(SCH_1):P5E_CPU1_PE4_TX_DN(14)    I18 @S9S_MB_2U_LIB.S9S_MB_2U(SCH_1):PAGE62
  AU86 P5E_CPU1_PE4_TX_DN<13> @S9S_MB_2U_LIB.S9S_MB_2U(SCH_1):P5E_CPU1_PE4_TX_DN(13)    I18 @S9S_MB_2U_LIB.S9S_MB_2U(SCH_1):PAGE62
  AR86 P5E_CPU1_PE4_TX_DN<12> @S9S_MB_2U_LIB.S9S_MB_2U(SCH_1):P5E_CPU1_PE4_TX_DN(12)    I18 @S9S_MB_2U_LIB.S9S_MB_2U(SCH_1):PAGE62
  AP85 P5E_CPU1_PE4_TX_DN<11> @S9S_MB_2U_LIB.S9S_MB_2U(SCH_1):P5E_CPU1_PE4_TX_DN(11)    I18 @S9S_MB_2U_LIB.S9S_MB_2U(SCH_1):PAGE62
  AL86 P5E_CPU1_PE4_TX_DN<10> @S9S_MB_2U_LIB.S9S_MB_2U(SCH_1):P5E_CPU1_PE4_TX_DN(10)    I18 @S9S_MB_2U_LIB.S9S_MB_2U(SCH_1):PAGE62
  AJ86 P5E_CPU1_PE4_TX_DN<9> @S9S_MB_2U_LIB.S9S_MB_2U(SCH_1):P5E_CPU1_PE4_TX_DN(9)    I18 @S9S_MB_2U_LIB.S9S_MB_2U(SCH_1):PAGE62
  AG86 P5E_CPU1_PE4_TX_DN<8> @S9S_MB_2U_LIB.S9S_MB_2U(SCH_1):P5E_CPU1_PE4_TX_DN(8)    I18 @S9S_MB_2U_LIB.S9S_MB_2U(SCH_1):PAGE62
  AE86 P5E_CPU1_PE4_TX_DN<7> @S9S_MB_2U_LIB.S9S_MB_2U(SCH_1):P5E_CPU1_PE4_TX_DN(7)    I18 @S9S_MB_2U_LIB.S9S_MB_2U(SCH_1):PAGE62
  AC86 P5E_CPU1_PE4_TX_DN<6> @S9S_MB_2U_LIB.S9S_MB_2U(SCH_1):P5E_CPU1_PE4_TX_DN(6)    I18 @S9S_MB_2U_LIB.S9S_MB_2U(SCH_1):PAGE62
  AA86 P5E_CPU1_PE4_TX_DN<5> @S9S_MB_2U_LIB.S9S_MB_2U(SCH_1):P5E_CPU1_PE4_TX_DN(5)    I18 @S9S_MB_2U_LIB.S9S_MB_2U(SCH_1):PAGE62
   W86 P5E_CPU1_PE4_TX_DN<4> @S9S_MB_2U_LIB.S9S_MB_2U(SCH_1):P5E_CPU1_PE4_TX_DN(4)    I18 @S9S_MB_2U_LIB.S9S_MB_2U(SCH_1):PAGE62
   U86 P5E_CPU1_PE4_TX_DN<3> @S9S_MB_2U_LIB.S9S_MB_2U(SCH_1):P5E_CPU1_PE4_TX_DN(3)    I18 @S9S_MB_2U_LIB.S9S_MB_2U(SCH_1):PAGE62
   R86 P5E_CPU1_PE4_TX_DN<2> @S9S_MB_2U_LIB.S9S_MB_2U(SCH_1):P5E_CPU1_PE4_TX_DN(2)    I18 @S9S_MB_2U_LIB.S9S_MB_2U(SCH_1):PAGE62
   P85 P5E_CPU1_PE4_TX_DN<1> @S9S_MB_2U_LIB.S9S_MB_2U(SCH_1):P5E_CPU1_PE4_TX_DN(1)    I18 @S9S_MB_2U_LIB.S9S_MB_2U(SCH_1):PAGE62
   L86 P5E_CPU1_PE4_TX_DN<0> @S9S_MB_2U_LIB.S9S_MB_2U(SCH_1):P5E_CPU1_PE4_TX_DN(0)    I18 @S9S_MB_2U_LIB.S9S_MB_2U(SCH_1):PAGE62
  BB85 P5E_CPU1_PE4_TX_DP<15> @S9S_MB_2U_LIB.S9S_MB_2U(SCH_1):P5E_CPU1_PE4_TX_DP(15)    I18 @S9S_MB_2U_LIB.S9S_MB_2U(SCH_1):PAGE62
  AY87 P5E_CPU1_PE4_TX_DP<14> @S9S_MB_2U_LIB.S9S_MB_2U(SCH_1):P5E_CPU1_PE4_TX_DP(14)    I18 @S9S_MB_2U_LIB.S9S_MB_2U(SCH_1):PAGE62
  AV85 P5E_CPU1_PE4_TX_DP<13> @S9S_MB_2U_LIB.S9S_MB_2U(SCH_1):P5E_CPU1_PE4_TX_DP(13)    I18 @S9S_MB_2U_LIB.S9S_MB_2U(SCH_1):PAGE62
  AT87 P5E_CPU1_PE4_TX_DP<12> @S9S_MB_2U_LIB.S9S_MB_2U(SCH_1):P5E_CPU1_PE4_TX_DP(12)    I18 @S9S_MB_2U_LIB.S9S_MB_2U(SCH_1):PAGE62
  AN86 P5E_CPU1_PE4_TX_DP<11> @S9S_MB_2U_LIB.S9S_MB_2U(SCH_1):P5E_CPU1_PE4_TX_DP(11)    I18 @S9S_MB_2U_LIB.S9S_MB_2U(SCH_1):PAGE62
  AM87 P5E_CPU1_PE4_TX_DP<10> @S9S_MB_2U_LIB.S9S_MB_2U(SCH_1):P5E_CPU1_PE4_TX_DP(10)    I18 @S9S_MB_2U_LIB.S9S_MB_2U(SCH_1):PAGE62
  AK85 P5E_CPU1_PE4_TX_DP<9> @S9S_MB_2U_LIB.S9S_MB_2U(SCH_1):P5E_CPU1_PE4_TX_DP(9)    I18 @S9S_MB_2U_LIB.S9S_MB_2U(SCH_1):PAGE62
  AH87 P5E_CPU1_PE4_TX_DP<8> @S9S_MB_2U_LIB.S9S_MB_2U(SCH_1):P5E_CPU1_PE4_TX_DP(8)    I18 @S9S_MB_2U_LIB.S9S_MB_2U(SCH_1):PAGE62
  AF85 P5E_CPU1_PE4_TX_DP<7> @S9S_MB_2U_LIB.S9S_MB_2U(SCH_1):P5E_CPU1_PE4_TX_DP(7)    I18 @S9S_MB_2U_LIB.S9S_MB_2U(SCH_1):PAGE62
  AD87 P5E_CPU1_PE4_TX_DP<6> @S9S_MB_2U_LIB.S9S_MB_2U(SCH_1):P5E_CPU1_PE4_TX_DP(6)    I18 @S9S_MB_2U_LIB.S9S_MB_2U(SCH_1):PAGE62
  AB85 P5E_CPU1_PE4_TX_DP<5> @S9S_MB_2U_LIB.S9S_MB_2U(SCH_1):P5E_CPU1_PE4_TX_DP(5)    I18 @S9S_MB_2U_LIB.S9S_MB_2U(SCH_1):PAGE62
   Y87 P5E_CPU1_PE4_TX_DP<4> @S9S_MB_2U_LIB.S9S_MB_2U(SCH_1):P5E_CPU1_PE4_TX_DP(4)    I18 @S9S_MB_2U_LIB.S9S_MB_2U(SCH_1):PAGE62
   V85 P5E_CPU1_PE4_TX_DP<3> @S9S_MB_2U_LIB.S9S_MB_2U(SCH_1):P5E_CPU1_PE4_TX_DP(3)    I18 @S9S_MB_2U_LIB.S9S_MB_2U(SCH_1):PAGE62
   T87 P5E_CPU1_PE4_TX_DP<2> @S9S_MB_2U_LIB.S9S_MB_2U(SCH_1):P5E_CPU1_PE4_TX_DP(2)    I18 @S9S_MB_2U_LIB.S9S_MB_2U(SCH_1):PAGE62
   N86 P5E_CPU1_PE4_TX_DP<1> @S9S_MB_2U_LIB.S9S_MB_2U(SCH_1):P5E_CPU1_PE4_TX_DP(1)    I18 @S9S_MB_2U_LIB.S9S_MB_2U(SCH_1):PAGE62
   M87 P5E_CPU1_PE4_TX_DP<0> @S9S_MB_2U_LIB.S9S_MB_2U(SCH_1):P5E_CPU1_PE4_TX_DP(0)    I18 @S9S_MB_2U_LIB.S9S_MB_2U(SCH_1):PAGE62
   BU5 UPI_CPU0_CPU1_P1P0_DN<23> @S9S_MB_2U_LIB.S9S_MB_2U(SCH_1):UPI_CPU0_CPU1_P1P0_DN(23)    I51 @S9S_MB_2U_LIB.S9S_MB_2U(SCH_1):PAGE63
   BR7 UPI_CPU0_CPU1_P1P0_DN<22> @S9S_MB_2U_LIB.S9S_MB_2U(SCH_1):UPI_CPU0_CPU1_P1P0_DN(22)    I51 @S9S_MB_2U_LIB.S9S_MB_2U(SCH_1):PAGE63
   BN5 UPI_CPU0_CPU1_P1P0_DN<21> @S9S_MB_2U_LIB.S9S_MB_2U(SCH_1):UPI_CPU0_CPU1_P1P0_DN(21)    I51 @S9S_MB_2U_LIB.S9S_MB_2U(SCH_1):PAGE63
   BK6 UPI_CPU0_CPU1_P1P0_DN<20> @S9S_MB_2U_LIB.S9S_MB_2U(SCH_1):UPI_CPU0_CPU1_P1P0_DN(20)    I51 @S9S_MB_2U_LIB.S9S_MB_2U(SCH_1):PAGE63
   BJ5 UPI_CPU0_CPU1_P1P0_DN<19> @S9S_MB_2U_LIB.S9S_MB_2U(SCH_1):UPI_CPU0_CPU1_P1P0_DN(19)    I51 @S9S_MB_2U_LIB.S9S_MB_2U(SCH_1):PAGE63
   BF6 UPI_CPU0_CPU1_P1P0_DN<18> @S9S_MB_2U_LIB.S9S_MB_2U(SCH_1):UPI_CPU0_CPU1_P1P0_DN(18)    I51 @S9S_MB_2U_LIB.S9S_MB_2U(SCH_1):PAGE63
   BE5 UPI_CPU0_CPU1_P1P0_DN<17> @S9S_MB_2U_LIB.S9S_MB_2U(SCH_1):UPI_CPU0_CPU1_P1P0_DN(17)    I51 @S9S_MB_2U_LIB.S9S_MB_2U(SCH_1):PAGE63
   BB6 UPI_CPU0_CPU1_P1P0_DN<16> @S9S_MB_2U_LIB.S9S_MB_2U(SCH_1):UPI_CPU0_CPU1_P1P0_DN(16)    I51 @S9S_MB_2U_LIB.S9S_MB_2U(SCH_1):PAGE63
   BA5 UPI_CPU0_CPU1_P1P0_DN<15> @S9S_MB_2U_LIB.S9S_MB_2U(SCH_1):UPI_CPU0_CPU1_P1P0_DN(15)    I51 @S9S_MB_2U_LIB.S9S_MB_2U(SCH_1):PAGE63
   AV6 UPI_CPU0_CPU1_P1P0_DN<14> @S9S_MB_2U_LIB.S9S_MB_2U(SCH_1):UPI_CPU0_CPU1_P1P0_DN(14)    I51 @S9S_MB_2U_LIB.S9S_MB_2U(SCH_1):PAGE63
   AU5 UPI_CPU0_CPU1_P1P0_DN<13> @S9S_MB_2U_LIB.S9S_MB_2U(SCH_1):UPI_CPU0_CPU1_P1P0_DN(13)    I51 @S9S_MB_2U_LIB.S9S_MB_2U(SCH_1):PAGE63
   AP6 UPI_CPU0_CPU1_P1P0_DN<12> @S9S_MB_2U_LIB.S9S_MB_2U(SCH_1):UPI_CPU0_CPU1_P1P0_DN(12)    I51 @S9S_MB_2U_LIB.S9S_MB_2U(SCH_1):PAGE63
   AN5 UPI_CPU0_CPU1_P1P0_DN<11> @S9S_MB_2U_LIB.S9S_MB_2U(SCH_1):UPI_CPU0_CPU1_P1P0_DN(11)    I51 @S9S_MB_2U_LIB.S9S_MB_2U(SCH_1):PAGE63
   AK6 UPI_CPU0_CPU1_P1P0_DN<10> @S9S_MB_2U_LIB.S9S_MB_2U(SCH_1):UPI_CPU0_CPU1_P1P0_DN(10)    I51 @S9S_MB_2U_LIB.S9S_MB_2U(SCH_1):PAGE63
   AH6 UPI_CPU0_CPU1_P1P0_DN<9> @S9S_MB_2U_LIB.S9S_MB_2U(SCH_1):UPI_CPU0_CPU1_P1P0_DN(9)    I51 @S9S_MB_2U_LIB.S9S_MB_2U(SCH_1):PAGE63
   AF6 UPI_CPU0_CPU1_P1P0_DN<8> @S9S_MB_2U_LIB.S9S_MB_2U(SCH_1):UPI_CPU0_CPU1_P1P0_DN(8)    I51 @S9S_MB_2U_LIB.S9S_MB_2U(SCH_1):PAGE63
   AE5 UPI_CPU0_CPU1_P1P0_DN<7> @S9S_MB_2U_LIB.S9S_MB_2U(SCH_1):UPI_CPU0_CPU1_P1P0_DN(7)    I51 @S9S_MB_2U_LIB.S9S_MB_2U(SCH_1):PAGE63
   AB6 UPI_CPU0_CPU1_P1P0_DN<6> @S9S_MB_2U_LIB.S9S_MB_2U(SCH_1):UPI_CPU0_CPU1_P1P0_DN(6)    I51 @S9S_MB_2U_LIB.S9S_MB_2U(SCH_1):PAGE63
   AA5 UPI_CPU0_CPU1_P1P0_DN<5> @S9S_MB_2U_LIB.S9S_MB_2U(SCH_1):UPI_CPU0_CPU1_P1P0_DN(5)    I51 @S9S_MB_2U_LIB.S9S_MB_2U(SCH_1):PAGE63
    V6 UPI_CPU0_CPU1_P1P0_DN<4> @S9S_MB_2U_LIB.S9S_MB_2U(SCH_1):UPI_CPU0_CPU1_P1P0_DN(4)    I51 @S9S_MB_2U_LIB.S9S_MB_2U(SCH_1):PAGE63
    U5 UPI_CPU0_CPU1_P1P0_DN<3> @S9S_MB_2U_LIB.S9S_MB_2U(SCH_1):UPI_CPU0_CPU1_P1P0_DN(3)    I51 @S9S_MB_2U_LIB.S9S_MB_2U(SCH_1):PAGE63
    P6 UPI_CPU0_CPU1_P1P0_DN<2> @S9S_MB_2U_LIB.S9S_MB_2U(SCH_1):UPI_CPU0_CPU1_P1P0_DN(2)    I51 @S9S_MB_2U_LIB.S9S_MB_2U(SCH_1):PAGE63
    N5 UPI_CPU0_CPU1_P1P0_DN<1> @S9S_MB_2U_LIB.S9S_MB_2U(SCH_1):UPI_CPU0_CPU1_P1P0_DN(1)    I51 @S9S_MB_2U_LIB.S9S_MB_2U(SCH_1):PAGE63
    K6 UPI_CPU0_CPU1_P1P0_DN<0> @S9S_MB_2U_LIB.S9S_MB_2U(SCH_1):UPI_CPU0_CPU1_P1P0_DN(0)    I51 @S9S_MB_2U_LIB.S9S_MB_2U(SCH_1):PAGE63
   BT6 UPI_CPU0_CPU1_P1P0_DP<23> @S9S_MB_2U_LIB.S9S_MB_2U(SCH_1):UPI_CPU0_CPU1_P1P0_DP(23)    I51 @S9S_MB_2U_LIB.S9S_MB_2U(SCH_1):PAGE63
   BP6 UPI_CPU0_CPU1_P1P0_DP<22> @S9S_MB_2U_LIB.S9S_MB_2U(SCH_1):UPI_CPU0_CPU1_P1P0_DP(22)    I51 @S9S_MB_2U_LIB.S9S_MB_2U(SCH_1):PAGE63
   BM6 UPI_CPU0_CPU1_P1P0_DP<21> @S9S_MB_2U_LIB.S9S_MB_2U(SCH_1):UPI_CPU0_CPU1_P1P0_DP(21)    I51 @S9S_MB_2U_LIB.S9S_MB_2U(SCH_1):PAGE63
   BL7 UPI_CPU0_CPU1_P1P0_DP<20> @S9S_MB_2U_LIB.S9S_MB_2U(SCH_1):UPI_CPU0_CPU1_P1P0_DP(20)    I51 @S9S_MB_2U_LIB.S9S_MB_2U(SCH_1):PAGE63
   BH6 UPI_CPU0_CPU1_P1P0_DP<19> @S9S_MB_2U_LIB.S9S_MB_2U(SCH_1):UPI_CPU0_CPU1_P1P0_DP(19)    I51 @S9S_MB_2U_LIB.S9S_MB_2U(SCH_1):PAGE63
   BG7 UPI_CPU0_CPU1_P1P0_DP<18> @S9S_MB_2U_LIB.S9S_MB_2U(SCH_1):UPI_CPU0_CPU1_P1P0_DP(18)    I51 @S9S_MB_2U_LIB.S9S_MB_2U(SCH_1):PAGE63
   BD6 UPI_CPU0_CPU1_P1P0_DP<17> @S9S_MB_2U_LIB.S9S_MB_2U(SCH_1):UPI_CPU0_CPU1_P1P0_DP(17)    I51 @S9S_MB_2U_LIB.S9S_MB_2U(SCH_1):PAGE63
   BC7 UPI_CPU0_CPU1_P1P0_DP<16> @S9S_MB_2U_LIB.S9S_MB_2U(SCH_1):UPI_CPU0_CPU1_P1P0_DP(16)    I51 @S9S_MB_2U_LIB.S9S_MB_2U(SCH_1):PAGE63
   AY6 UPI_CPU0_CPU1_P1P0_DP<15> @S9S_MB_2U_LIB.S9S_MB_2U(SCH_1):UPI_CPU0_CPU1_P1P0_DP(15)    I51 @S9S_MB_2U_LIB.S9S_MB_2U(SCH_1):PAGE63
   AW7 UPI_CPU0_CPU1_P1P0_DP<14> @S9S_MB_2U_LIB.S9S_MB_2U(SCH_1):UPI_CPU0_CPU1_P1P0_DP(14)    I51 @S9S_MB_2U_LIB.S9S_MB_2U(SCH_1):PAGE63
   AT6 UPI_CPU0_CPU1_P1P0_DP<13> @S9S_MB_2U_LIB.S9S_MB_2U(SCH_1):UPI_CPU0_CPU1_P1P0_DP(13)    I51 @S9S_MB_2U_LIB.S9S_MB_2U(SCH_1):PAGE63
   AR7 UPI_CPU0_CPU1_P1P0_DP<12> @S9S_MB_2U_LIB.S9S_MB_2U(SCH_1):UPI_CPU0_CPU1_P1P0_DP(12)    I51 @S9S_MB_2U_LIB.S9S_MB_2U(SCH_1):PAGE63
   AM6 UPI_CPU0_CPU1_P1P0_DP<11> @S9S_MB_2U_LIB.S9S_MB_2U(SCH_1):UPI_CPU0_CPU1_P1P0_DP(11)    I51 @S9S_MB_2U_LIB.S9S_MB_2U(SCH_1):PAGE63
   AL7 UPI_CPU0_CPU1_P1P0_DP<10> @S9S_MB_2U_LIB.S9S_MB_2U(SCH_1):UPI_CPU0_CPU1_P1P0_DP(10)    I51 @S9S_MB_2U_LIB.S9S_MB_2U(SCH_1):PAGE63
   AJ5 UPI_CPU0_CPU1_P1P0_DP<9> @S9S_MB_2U_LIB.S9S_MB_2U(SCH_1):UPI_CPU0_CPU1_P1P0_DP(9)    I51 @S9S_MB_2U_LIB.S9S_MB_2U(SCH_1):PAGE63
   AG7 UPI_CPU0_CPU1_P1P0_DP<8> @S9S_MB_2U_LIB.S9S_MB_2U(SCH_1):UPI_CPU0_CPU1_P1P0_DP(8)    I51 @S9S_MB_2U_LIB.S9S_MB_2U(SCH_1):PAGE63
   AD6 UPI_CPU0_CPU1_P1P0_DP<7> @S9S_MB_2U_LIB.S9S_MB_2U(SCH_1):UPI_CPU0_CPU1_P1P0_DP(7)    I51 @S9S_MB_2U_LIB.S9S_MB_2U(SCH_1):PAGE63
   AC7 UPI_CPU0_CPU1_P1P0_DP<6> @S9S_MB_2U_LIB.S9S_MB_2U(SCH_1):UPI_CPU0_CPU1_P1P0_DP(6)    I51 @S9S_MB_2U_LIB.S9S_MB_2U(SCH_1):PAGE63
    Y6 UPI_CPU0_CPU1_P1P0_DP<5> @S9S_MB_2U_LIB.S9S_MB_2U(SCH_1):UPI_CPU0_CPU1_P1P0_DP(5)    I51 @S9S_MB_2U_LIB.S9S_MB_2U(SCH_1):PAGE63
    W7 UPI_CPU0_CPU1_P1P0_DP<4> @S9S_MB_2U_LIB.S9S_MB_2U(SCH_1):UPI_CPU0_CPU1_P1P0_DP(4)    I51 @S9S_MB_2U_LIB.S9S_MB_2U(SCH_1):PAGE63
    T6 UPI_CPU0_CPU1_P1P0_DP<3> @S9S_MB_2U_LIB.S9S_MB_2U(SCH_1):UPI_CPU0_CPU1_P1P0_DP(3)    I51 @S9S_MB_2U_LIB.S9S_MB_2U(SCH_1):PAGE63
    R7 UPI_CPU0_CPU1_P1P0_DP<2> @S9S_MB_2U_LIB.S9S_MB_2U(SCH_1):UPI_CPU0_CPU1_P1P0_DP(2)    I51 @S9S_MB_2U_LIB.S9S_MB_2U(SCH_1):PAGE63
    M6 UPI_CPU0_CPU1_P1P0_DP<1> @S9S_MB_2U_LIB.S9S_MB_2U(SCH_1):UPI_CPU0_CPU1_P1P0_DP(1)    I51 @S9S_MB_2U_LIB.S9S_MB_2U(SCH_1):PAGE63
    L7 UPI_CPU0_CPU1_P1P0_DP<0> @S9S_MB_2U_LIB.S9S_MB_2U(SCH_1):UPI_CPU0_CPU1_P1P0_DP(0)    I51 @S9S_MB_2U_LIB.S9S_MB_2U(SCH_1):PAGE63
   BT2 UPI_CPU1_CPU0_P0P1_DN<23> @S9S_MB_2U_LIB.S9S_MB_2U(SCH_1):UPI_CPU1_CPU0_P0P1_DN(23)    I51 @S9S_MB_2U_LIB.S9S_MB_2U(SCH_1):PAGE63
   BR3 UPI_CPU1_CPU0_P0P1_DN<22> @S9S_MB_2U_LIB.S9S_MB_2U(SCH_1):UPI_CPU1_CPU0_P0P1_DN(22)    I51 @S9S_MB_2U_LIB.S9S_MB_2U(SCH_1):PAGE63
   BM2 UPI_CPU1_CPU0_P0P1_DN<21> @S9S_MB_2U_LIB.S9S_MB_2U(SCH_1):UPI_CPU1_CPU0_P0P1_DN(21)    I51 @S9S_MB_2U_LIB.S9S_MB_2U(SCH_1):PAGE63
   BK2 UPI_CPU1_CPU0_P0P1_DN<20> @S9S_MB_2U_LIB.S9S_MB_2U(SCH_1):UPI_CPU1_CPU0_P0P1_DN(20)    I51 @S9S_MB_2U_LIB.S9S_MB_2U(SCH_1):PAGE63
   BH2 UPI_CPU1_CPU0_P0P1_DN<19> @S9S_MB_2U_LIB.S9S_MB_2U(SCH_1):UPI_CPU1_CPU0_P0P1_DN(19)    I51 @S9S_MB_2U_LIB.S9S_MB_2U(SCH_1):PAGE63
   BF2 UPI_CPU1_CPU0_P0P1_DN<18> @S9S_MB_2U_LIB.S9S_MB_2U(SCH_1):UPI_CPU1_CPU0_P0P1_DN(18)    I51 @S9S_MB_2U_LIB.S9S_MB_2U(SCH_1):PAGE63
   BD2 UPI_CPU1_CPU0_P0P1_DN<17> @S9S_MB_2U_LIB.S9S_MB_2U(SCH_1):UPI_CPU1_CPU0_P0P1_DN(17)    I51 @S9S_MB_2U_LIB.S9S_MB_2U(SCH_1):PAGE63
   BB2 UPI_CPU1_CPU0_P0P1_DN<16> @S9S_MB_2U_LIB.S9S_MB_2U(SCH_1):UPI_CPU1_CPU0_P0P1_DN(16)    I51 @S9S_MB_2U_LIB.S9S_MB_2U(SCH_1):PAGE63
   AY2 UPI_CPU1_CPU0_P0P1_DN<15> @S9S_MB_2U_LIB.S9S_MB_2U(SCH_1):UPI_CPU1_CPU0_P0P1_DN(15)    I51 @S9S_MB_2U_LIB.S9S_MB_2U(SCH_1):PAGE63
   AU1 UPI_CPU1_CPU0_P0P1_DN<14> @S9S_MB_2U_LIB.S9S_MB_2U(SCH_1):UPI_CPU1_CPU0_P0P1_DN(14)    I51 @S9S_MB_2U_LIB.S9S_MB_2U(SCH_1):PAGE63
   AT2 UPI_CPU1_CPU0_P0P1_DN<13> @S9S_MB_2U_LIB.S9S_MB_2U(SCH_1):UPI_CPU1_CPU0_P0P1_DN(13)    I51 @S9S_MB_2U_LIB.S9S_MB_2U(SCH_1):PAGE63
   AP2 UPI_CPU1_CPU0_P0P1_DN<12> @S9S_MB_2U_LIB.S9S_MB_2U(SCH_1):UPI_CPU1_CPU0_P0P1_DN(12)    I51 @S9S_MB_2U_LIB.S9S_MB_2U(SCH_1):PAGE63
   AM2 UPI_CPU1_CPU0_P0P1_DN<11> @S9S_MB_2U_LIB.S9S_MB_2U(SCH_1):UPI_CPU1_CPU0_P0P1_DN(11)    I51 @S9S_MB_2U_LIB.S9S_MB_2U(SCH_1):PAGE63
   AK2 UPI_CPU1_CPU0_P0P1_DN<10> @S9S_MB_2U_LIB.S9S_MB_2U(SCH_1):UPI_CPU1_CPU0_P0P1_DN(10)    I51 @S9S_MB_2U_LIB.S9S_MB_2U(SCH_1):PAGE63
   AH2 UPI_CPU1_CPU0_P0P1_DN<9> @S9S_MB_2U_LIB.S9S_MB_2U(SCH_1):UPI_CPU1_CPU0_P0P1_DN(9)    I51 @S9S_MB_2U_LIB.S9S_MB_2U(SCH_1):PAGE63
   AF2 UPI_CPU1_CPU0_P0P1_DN<8> @S9S_MB_2U_LIB.S9S_MB_2U(SCH_1):UPI_CPU1_CPU0_P0P1_DN(8)    I51 @S9S_MB_2U_LIB.S9S_MB_2U(SCH_1):PAGE63
   AD2 UPI_CPU1_CPU0_P0P1_DN<7> @S9S_MB_2U_LIB.S9S_MB_2U(SCH_1):UPI_CPU1_CPU0_P0P1_DN(7)    I51 @S9S_MB_2U_LIB.S9S_MB_2U(SCH_1):PAGE63
   AA1 UPI_CPU1_CPU0_P0P1_DN<6> @S9S_MB_2U_LIB.S9S_MB_2U(SCH_1):UPI_CPU1_CPU0_P0P1_DN(6)    I51 @S9S_MB_2U_LIB.S9S_MB_2U(SCH_1):PAGE63
    Y2 UPI_CPU1_CPU0_P0P1_DN<5> @S9S_MB_2U_LIB.S9S_MB_2U(SCH_1):UPI_CPU1_CPU0_P0P1_DN(5)    I51 @S9S_MB_2U_LIB.S9S_MB_2U(SCH_1):PAGE63
    U1 UPI_CPU1_CPU0_P0P1_DN<4> @S9S_MB_2U_LIB.S9S_MB_2U(SCH_1):UPI_CPU1_CPU0_P0P1_DN(4)    I51 @S9S_MB_2U_LIB.S9S_MB_2U(SCH_1):PAGE63
    T2 UPI_CPU1_CPU0_P0P1_DN<3> @S9S_MB_2U_LIB.S9S_MB_2U(SCH_1):UPI_CPU1_CPU0_P0P1_DN(3)    I51 @S9S_MB_2U_LIB.S9S_MB_2U(SCH_1):PAGE63
    N1 UPI_CPU1_CPU0_P0P1_DN<2> @S9S_MB_2U_LIB.S9S_MB_2U(SCH_1):UPI_CPU1_CPU0_P0P1_DN(2)    I51 @S9S_MB_2U_LIB.S9S_MB_2U(SCH_1):PAGE63
    M2 UPI_CPU1_CPU0_P0P1_DN<1> @S9S_MB_2U_LIB.S9S_MB_2U(SCH_1):UPI_CPU1_CPU0_P0P1_DN(1)    I51 @S9S_MB_2U_LIB.S9S_MB_2U(SCH_1):PAGE63
    K4 UPI_CPU1_CPU0_P0P1_DN<0> @S9S_MB_2U_LIB.S9S_MB_2U(SCH_1):UPI_CPU1_CPU0_P0P1_DN(0)    I51 @S9S_MB_2U_LIB.S9S_MB_2U(SCH_1):PAGE63
   BU3 UPI_CPU1_CPU0_P0P1_DP<23> @S9S_MB_2U_LIB.S9S_MB_2U(SCH_1):UPI_CPU1_CPU0_P0P1_DP(23)    I51 @S9S_MB_2U_LIB.S9S_MB_2U(SCH_1):PAGE63
   BN3 UPI_CPU1_CPU0_P0P1_DP<22> @S9S_MB_2U_LIB.S9S_MB_2U(SCH_1):UPI_CPU1_CPU0_P0P1_DP(22)    I51 @S9S_MB_2U_LIB.S9S_MB_2U(SCH_1):PAGE63
   BL3 UPI_CPU1_CPU0_P0P1_DP<21> @S9S_MB_2U_LIB.S9S_MB_2U(SCH_1):UPI_CPU1_CPU0_P0P1_DP(21)    I51 @S9S_MB_2U_LIB.S9S_MB_2U(SCH_1):PAGE63
   BJ1 UPI_CPU1_CPU0_P0P1_DP<20> @S9S_MB_2U_LIB.S9S_MB_2U(SCH_1):UPI_CPU1_CPU0_P0P1_DP(20)    I51 @S9S_MB_2U_LIB.S9S_MB_2U(SCH_1):PAGE63
   BG3 UPI_CPU1_CPU0_P0P1_DP<19> @S9S_MB_2U_LIB.S9S_MB_2U(SCH_1):UPI_CPU1_CPU0_P0P1_DP(19)    I51 @S9S_MB_2U_LIB.S9S_MB_2U(SCH_1):PAGE63
   BE1 UPI_CPU1_CPU0_P0P1_DP<18> @S9S_MB_2U_LIB.S9S_MB_2U(SCH_1):UPI_CPU1_CPU0_P0P1_DP(18)    I51 @S9S_MB_2U_LIB.S9S_MB_2U(SCH_1):PAGE63
   BC3 UPI_CPU1_CPU0_P0P1_DP<17> @S9S_MB_2U_LIB.S9S_MB_2U(SCH_1):UPI_CPU1_CPU0_P0P1_DP(17)    I51 @S9S_MB_2U_LIB.S9S_MB_2U(SCH_1):PAGE63
   BA1 UPI_CPU1_CPU0_P0P1_DP<16> @S9S_MB_2U_LIB.S9S_MB_2U(SCH_1):UPI_CPU1_CPU0_P0P1_DP(16)    I51 @S9S_MB_2U_LIB.S9S_MB_2U(SCH_1):PAGE63
   AW3 UPI_CPU1_CPU0_P0P1_DP<15> @S9S_MB_2U_LIB.S9S_MB_2U(SCH_1):UPI_CPU1_CPU0_P0P1_DP(15)    I51 @S9S_MB_2U_LIB.S9S_MB_2U(SCH_1):PAGE63
   AV2 UPI_CPU1_CPU0_P0P1_DP<14> @S9S_MB_2U_LIB.S9S_MB_2U(SCH_1):UPI_CPU1_CPU0_P0P1_DP(14)    I51 @S9S_MB_2U_LIB.S9S_MB_2U(SCH_1):PAGE63
   AR3 UPI_CPU1_CPU0_P0P1_DP<13> @S9S_MB_2U_LIB.S9S_MB_2U(SCH_1):UPI_CPU1_CPU0_P0P1_DP(13)    I51 @S9S_MB_2U_LIB.S9S_MB_2U(SCH_1):PAGE63
   AN1 UPI_CPU1_CPU0_P0P1_DP<12> @S9S_MB_2U_LIB.S9S_MB_2U(SCH_1):UPI_CPU1_CPU0_P0P1_DP(12)    I51 @S9S_MB_2U_LIB.S9S_MB_2U(SCH_1):PAGE63
   AL3 UPI_CPU1_CPU0_P0P1_DP<11> @S9S_MB_2U_LIB.S9S_MB_2U(SCH_1):UPI_CPU1_CPU0_P0P1_DP(11)    I51 @S9S_MB_2U_LIB.S9S_MB_2U(SCH_1):PAGE63
   AJ1 UPI_CPU1_CPU0_P0P1_DP<10> @S9S_MB_2U_LIB.S9S_MB_2U(SCH_1):UPI_CPU1_CPU0_P0P1_DP(10)    I51 @S9S_MB_2U_LIB.S9S_MB_2U(SCH_1):PAGE63
   AG3 UPI_CPU1_CPU0_P0P1_DP<9> @S9S_MB_2U_LIB.S9S_MB_2U(SCH_1):UPI_CPU1_CPU0_P0P1_DP(9)    I51 @S9S_MB_2U_LIB.S9S_MB_2U(SCH_1):PAGE63
   AE1 UPI_CPU1_CPU0_P0P1_DP<8> @S9S_MB_2U_LIB.S9S_MB_2U(SCH_1):UPI_CPU1_CPU0_P0P1_DP(8)    I51 @S9S_MB_2U_LIB.S9S_MB_2U(SCH_1):PAGE63
   AC3 UPI_CPU1_CPU0_P0P1_DP<7> @S9S_MB_2U_LIB.S9S_MB_2U(SCH_1):UPI_CPU1_CPU0_P0P1_DP(7)    I51 @S9S_MB_2U_LIB.S9S_MB_2U(SCH_1):PAGE63
   AB2 UPI_CPU1_CPU0_P0P1_DP<6> @S9S_MB_2U_LIB.S9S_MB_2U(SCH_1):UPI_CPU1_CPU0_P0P1_DP(6)    I51 @S9S_MB_2U_LIB.S9S_MB_2U(SCH_1):PAGE63
    W3 UPI_CPU1_CPU0_P0P1_DP<5> @S9S_MB_2U_LIB.S9S_MB_2U(SCH_1):UPI_CPU1_CPU0_P0P1_DP(5)    I51 @S9S_MB_2U_LIB.S9S_MB_2U(SCH_1):PAGE63
    V2 UPI_CPU1_CPU0_P0P1_DP<4> @S9S_MB_2U_LIB.S9S_MB_2U(SCH_1):UPI_CPU1_CPU0_P0P1_DP(4)    I51 @S9S_MB_2U_LIB.S9S_MB_2U(SCH_1):PAGE63
    R3 UPI_CPU1_CPU0_P0P1_DP<3> @S9S_MB_2U_LIB.S9S_MB_2U(SCH_1):UPI_CPU1_CPU0_P0P1_DP(3)    I51 @S9S_MB_2U_LIB.S9S_MB_2U(SCH_1):PAGE63
    P2 UPI_CPU1_CPU0_P0P1_DP<2> @S9S_MB_2U_LIB.S9S_MB_2U(SCH_1):UPI_CPU1_CPU0_P0P1_DP(2)    I51 @S9S_MB_2U_LIB.S9S_MB_2U(SCH_1):PAGE63
    L3 UPI_CPU1_CPU0_P0P1_DP<1> @S9S_MB_2U_LIB.S9S_MB_2U(SCH_1):UPI_CPU1_CPU0_P0P1_DP(1)    I51 @S9S_MB_2U_LIB.S9S_MB_2U(SCH_1):PAGE63
    J3 UPI_CPU1_CPU0_P0P1_DP<0> @S9S_MB_2U_LIB.S9S_MB_2U(SCH_1):UPI_CPU1_CPU0_P0P1_DP(0)    I51 @S9S_MB_2U_LIB.S9S_MB_2U(SCH_1):PAGE63
   CB2 UPI_CPU0_CPU1_P0P1_DN<23> @S9S_MB_2U_LIB.S9S_MB_2U(SCH_1):UPI_CPU0_CPU1_P0P1_DN(23)    I21 @S9S_MB_2U_LIB.S9S_MB_2U(SCH_1):PAGE64
   CD2 UPI_CPU0_CPU1_P0P1_DN<22> @S9S_MB_2U_LIB.S9S_MB_2U(SCH_1):UPI_CPU0_CPU1_P0P1_DN(22)    I21 @S9S_MB_2U_LIB.S9S_MB_2U(SCH_1):PAGE64
   CF2 UPI_CPU0_CPU1_P0P1_DN<21> @S9S_MB_2U_LIB.S9S_MB_2U(SCH_1):UPI_CPU0_CPU1_P0P1_DN(21)    I21 @S9S_MB_2U_LIB.S9S_MB_2U(SCH_1):PAGE64
   CH2 UPI_CPU0_CPU1_P0P1_DN<20> @S9S_MB_2U_LIB.S9S_MB_2U(SCH_1):UPI_CPU0_CPU1_P0P1_DN(20)    I21 @S9S_MB_2U_LIB.S9S_MB_2U(SCH_1):PAGE64
   CJ1 UPI_CPU0_CPU1_P0P1_DN<19> @S9S_MB_2U_LIB.S9S_MB_2U(SCH_1):UPI_CPU0_CPU1_P0P1_DN(19)    I21 @S9S_MB_2U_LIB.S9S_MB_2U(SCH_1):PAGE64
   CL3 UPI_CPU0_CPU1_P0P1_DN<18> @S9S_MB_2U_LIB.S9S_MB_2U(SCH_1):UPI_CPU0_CPU1_P0P1_DN(18)    I21 @S9S_MB_2U_LIB.S9S_MB_2U(SCH_1):PAGE64
   CN1 UPI_CPU0_CPU1_P0P1_DN<17> @S9S_MB_2U_LIB.S9S_MB_2U(SCH_1):UPI_CPU0_CPU1_P0P1_DN(17)    I21 @S9S_MB_2U_LIB.S9S_MB_2U(SCH_1):PAGE64
   CR3 UPI_CPU0_CPU1_P0P1_DN<16> @S9S_MB_2U_LIB.S9S_MB_2U(SCH_1):UPI_CPU0_CPU1_P0P1_DN(16)    I21 @S9S_MB_2U_LIB.S9S_MB_2U(SCH_1):PAGE64
   CV2 UPI_CPU0_CPU1_P0P1_DN<15> @S9S_MB_2U_LIB.S9S_MB_2U(SCH_1):UPI_CPU0_CPU1_P0P1_DN(15)    I21 @S9S_MB_2U_LIB.S9S_MB_2U(SCH_1):PAGE64
   CY2 UPI_CPU0_CPU1_P0P1_DN<14> @S9S_MB_2U_LIB.S9S_MB_2U(SCH_1):UPI_CPU0_CPU1_P0P1_DN(14)    I21 @S9S_MB_2U_LIB.S9S_MB_2U(SCH_1):PAGE64
   DB2 UPI_CPU0_CPU1_P0P1_DN<13> @S9S_MB_2U_LIB.S9S_MB_2U(SCH_1):UPI_CPU0_CPU1_P0P1_DN(13)    I21 @S9S_MB_2U_LIB.S9S_MB_2U(SCH_1):PAGE64
   DD2 UPI_CPU0_CPU1_P0P1_DN<12> @S9S_MB_2U_LIB.S9S_MB_2U(SCH_1):UPI_CPU0_CPU1_P0P1_DN(12)    I21 @S9S_MB_2U_LIB.S9S_MB_2U(SCH_1):PAGE64
   DE1 UPI_CPU0_CPU1_P0P1_DN<11> @S9S_MB_2U_LIB.S9S_MB_2U(SCH_1):UPI_CPU0_CPU1_P0P1_DN(11)    I21 @S9S_MB_2U_LIB.S9S_MB_2U(SCH_1):PAGE64
   DG3 UPI_CPU0_CPU1_P0P1_DN<10> @S9S_MB_2U_LIB.S9S_MB_2U(SCH_1):UPI_CPU0_CPU1_P0P1_DN(10)    I21 @S9S_MB_2U_LIB.S9S_MB_2U(SCH_1):PAGE64
   DJ1 UPI_CPU0_CPU1_P0P1_DN<9> @S9S_MB_2U_LIB.S9S_MB_2U(SCH_1):UPI_CPU0_CPU1_P0P1_DN(9)    I21 @S9S_MB_2U_LIB.S9S_MB_2U(SCH_1):PAGE64
   DL3 UPI_CPU0_CPU1_P0P1_DN<8> @S9S_MB_2U_LIB.S9S_MB_2U(SCH_1):UPI_CPU0_CPU1_P0P1_DN(8)    I21 @S9S_MB_2U_LIB.S9S_MB_2U(SCH_1):PAGE64
   DN1 UPI_CPU0_CPU1_P0P1_DN<7> @S9S_MB_2U_LIB.S9S_MB_2U(SCH_1):UPI_CPU0_CPU1_P0P1_DN(7)    I21 @S9S_MB_2U_LIB.S9S_MB_2U(SCH_1):PAGE64
   DT2 UPI_CPU0_CPU1_P0P1_DN<6> @S9S_MB_2U_LIB.S9S_MB_2U(SCH_1):UPI_CPU0_CPU1_P0P1_DN(6)    I21 @S9S_MB_2U_LIB.S9S_MB_2U(SCH_1):PAGE64
   DU1 UPI_CPU0_CPU1_P0P1_DN<5> @S9S_MB_2U_LIB.S9S_MB_2U(SCH_1):UPI_CPU0_CPU1_P0P1_DN(5)    I21 @S9S_MB_2U_LIB.S9S_MB_2U(SCH_1):PAGE64
   DY2 UPI_CPU0_CPU1_P0P1_DN<4> @S9S_MB_2U_LIB.S9S_MB_2U(SCH_1):UPI_CPU0_CPU1_P0P1_DN(4)    I21 @S9S_MB_2U_LIB.S9S_MB_2U(SCH_1):PAGE64
   EA1 UPI_CPU0_CPU1_P0P1_DN<3> @S9S_MB_2U_LIB.S9S_MB_2U(SCH_1):UPI_CPU0_CPU1_P0P1_DN(3)    I21 @S9S_MB_2U_LIB.S9S_MB_2U(SCH_1):PAGE64
   ED2 UPI_CPU0_CPU1_P0P1_DN<2> @S9S_MB_2U_LIB.S9S_MB_2U(SCH_1):UPI_CPU0_CPU1_P0P1_DN(2)    I21 @S9S_MB_2U_LIB.S9S_MB_2U(SCH_1):PAGE64
   EE3 UPI_CPU0_CPU1_P0P1_DN<1> @S9S_MB_2U_LIB.S9S_MB_2U(SCH_1):UPI_CPU0_CPU1_P0P1_DN(1)    I21 @S9S_MB_2U_LIB.S9S_MB_2U(SCH_1):PAGE64
   EH2 UPI_CPU0_CPU1_P0P1_DN<0> @S9S_MB_2U_LIB.S9S_MB_2U(SCH_1):UPI_CPU0_CPU1_P0P1_DN(0)    I21 @S9S_MB_2U_LIB.S9S_MB_2U(SCH_1):PAGE64
   BY2 UPI_CPU0_CPU1_P0P1_DP<23> @S9S_MB_2U_LIB.S9S_MB_2U(SCH_1):UPI_CPU0_CPU1_P0P1_DP(23)    I21 @S9S_MB_2U_LIB.S9S_MB_2U(SCH_1):PAGE64
   CC3 UPI_CPU0_CPU1_P0P1_DP<22> @S9S_MB_2U_LIB.S9S_MB_2U(SCH_1):UPI_CPU0_CPU1_P0P1_DP(22)    I21 @S9S_MB_2U_LIB.S9S_MB_2U(SCH_1):PAGE64
   CE1 UPI_CPU0_CPU1_P0P1_DP<21> @S9S_MB_2U_LIB.S9S_MB_2U(SCH_1):UPI_CPU0_CPU1_P0P1_DP(21)    I21 @S9S_MB_2U_LIB.S9S_MB_2U(SCH_1):PAGE64
   CG3 UPI_CPU0_CPU1_P0P1_DP<20> @S9S_MB_2U_LIB.S9S_MB_2U(SCH_1):UPI_CPU0_CPU1_P0P1_DP(20)    I21 @S9S_MB_2U_LIB.S9S_MB_2U(SCH_1):PAGE64
   CK2 UPI_CPU0_CPU1_P0P1_DP<19> @S9S_MB_2U_LIB.S9S_MB_2U(SCH_1):UPI_CPU0_CPU1_P0P1_DP(19)    I21 @S9S_MB_2U_LIB.S9S_MB_2U(SCH_1):PAGE64
   CM2 UPI_CPU0_CPU1_P0P1_DP<18> @S9S_MB_2U_LIB.S9S_MB_2U(SCH_1):UPI_CPU0_CPU1_P0P1_DP(18)    I21 @S9S_MB_2U_LIB.S9S_MB_2U(SCH_1):PAGE64
   CP2 UPI_CPU0_CPU1_P0P1_DP<17> @S9S_MB_2U_LIB.S9S_MB_2U(SCH_1):UPI_CPU0_CPU1_P0P1_DP(17)    I21 @S9S_MB_2U_LIB.S9S_MB_2U(SCH_1):PAGE64
   CT2 UPI_CPU0_CPU1_P0P1_DP<16> @S9S_MB_2U_LIB.S9S_MB_2U(SCH_1):UPI_CPU0_CPU1_P0P1_DP(16)    I21 @S9S_MB_2U_LIB.S9S_MB_2U(SCH_1):PAGE64
   CU1 UPI_CPU0_CPU1_P0P1_DP<15> @S9S_MB_2U_LIB.S9S_MB_2U(SCH_1):UPI_CPU0_CPU1_P0P1_DP(15)    I21 @S9S_MB_2U_LIB.S9S_MB_2U(SCH_1):PAGE64
   CW3 UPI_CPU0_CPU1_P0P1_DP<14> @S9S_MB_2U_LIB.S9S_MB_2U(SCH_1):UPI_CPU0_CPU1_P0P1_DP(14)    I21 @S9S_MB_2U_LIB.S9S_MB_2U(SCH_1):PAGE64
   DA1 UPI_CPU0_CPU1_P0P1_DP<13> @S9S_MB_2U_LIB.S9S_MB_2U(SCH_1):UPI_CPU0_CPU1_P0P1_DP(13)    I21 @S9S_MB_2U_LIB.S9S_MB_2U(SCH_1):PAGE64
   DC3 UPI_CPU0_CPU1_P0P1_DP<12> @S9S_MB_2U_LIB.S9S_MB_2U(SCH_1):UPI_CPU0_CPU1_P0P1_DP(12)    I21 @S9S_MB_2U_LIB.S9S_MB_2U(SCH_1):PAGE64
   DF2 UPI_CPU0_CPU1_P0P1_DP<11> @S9S_MB_2U_LIB.S9S_MB_2U(SCH_1):UPI_CPU0_CPU1_P0P1_DP(11)    I21 @S9S_MB_2U_LIB.S9S_MB_2U(SCH_1):PAGE64
   DH2 UPI_CPU0_CPU1_P0P1_DP<10> @S9S_MB_2U_LIB.S9S_MB_2U(SCH_1):UPI_CPU0_CPU1_P0P1_DP(10)    I21 @S9S_MB_2U_LIB.S9S_MB_2U(SCH_1):PAGE64
   DK2 UPI_CPU0_CPU1_P0P1_DP<9> @S9S_MB_2U_LIB.S9S_MB_2U(SCH_1):UPI_CPU0_CPU1_P0P1_DP(9)    I21 @S9S_MB_2U_LIB.S9S_MB_2U(SCH_1):PAGE64
   DM2 UPI_CPU0_CPU1_P0P1_DP<8> @S9S_MB_2U_LIB.S9S_MB_2U(SCH_1):UPI_CPU0_CPU1_P0P1_DP(8)    I21 @S9S_MB_2U_LIB.S9S_MB_2U(SCH_1):PAGE64
   DP2 UPI_CPU0_CPU1_P0P1_DP<7> @S9S_MB_2U_LIB.S9S_MB_2U(SCH_1):UPI_CPU0_CPU1_P0P1_DP(7)    I21 @S9S_MB_2U_LIB.S9S_MB_2U(SCH_1):PAGE64
   DR3 UPI_CPU0_CPU1_P0P1_DP<6> @S9S_MB_2U_LIB.S9S_MB_2U(SCH_1):UPI_CPU0_CPU1_P0P1_DP(6)    I21 @S9S_MB_2U_LIB.S9S_MB_2U(SCH_1):PAGE64
   DV2 UPI_CPU0_CPU1_P0P1_DP<5> @S9S_MB_2U_LIB.S9S_MB_2U(SCH_1):UPI_CPU0_CPU1_P0P1_DP(5)    I21 @S9S_MB_2U_LIB.S9S_MB_2U(SCH_1):PAGE64
   DW3 UPI_CPU0_CPU1_P0P1_DP<4> @S9S_MB_2U_LIB.S9S_MB_2U(SCH_1):UPI_CPU0_CPU1_P0P1_DP(4)    I21 @S9S_MB_2U_LIB.S9S_MB_2U(SCH_1):PAGE64
   EB2 UPI_CPU0_CPU1_P0P1_DP<3> @S9S_MB_2U_LIB.S9S_MB_2U(SCH_1):UPI_CPU0_CPU1_P0P1_DP(3)    I21 @S9S_MB_2U_LIB.S9S_MB_2U(SCH_1):PAGE64
   EC3 UPI_CPU0_CPU1_P0P1_DP<2> @S9S_MB_2U_LIB.S9S_MB_2U(SCH_1):UPI_CPU0_CPU1_P0P1_DP(2)    I21 @S9S_MB_2U_LIB.S9S_MB_2U(SCH_1):PAGE64
   EG3 UPI_CPU0_CPU1_P0P1_DP<1> @S9S_MB_2U_LIB.S9S_MB_2U(SCH_1):UPI_CPU0_CPU1_P0P1_DP(1)    I21 @S9S_MB_2U_LIB.S9S_MB_2U(SCH_1):PAGE64
   EJ3 UPI_CPU0_CPU1_P0P1_DP<0> @S9S_MB_2U_LIB.S9S_MB_2U(SCH_1):UPI_CPU0_CPU1_P0P1_DP(0)    I21 @S9S_MB_2U_LIB.S9S_MB_2U(SCH_1):PAGE64
   BY6 UPI_CPU1_CPU0_P1P0_DN<23> @S9S_MB_2U_LIB.S9S_MB_2U(SCH_1):UPI_CPU1_CPU0_P1P0_DN(23)    I21 @S9S_MB_2U_LIB.S9S_MB_2U(SCH_1):PAGE64
   CA5 UPI_CPU1_CPU0_P1P0_DN<22> @S9S_MB_2U_LIB.S9S_MB_2U(SCH_1):UPI_CPU1_CPU0_P1P0_DN(22)    I21 @S9S_MB_2U_LIB.S9S_MB_2U(SCH_1):PAGE64
   CD6 UPI_CPU1_CPU0_P1P0_DN<21> @S9S_MB_2U_LIB.S9S_MB_2U(SCH_1):UPI_CPU1_CPU0_P1P0_DN(21)    I21 @S9S_MB_2U_LIB.S9S_MB_2U(SCH_1):PAGE64
   CE5 UPI_CPU1_CPU0_P1P0_DN<20> @S9S_MB_2U_LIB.S9S_MB_2U(SCH_1):UPI_CPU1_CPU0_P1P0_DN(20)    I21 @S9S_MB_2U_LIB.S9S_MB_2U(SCH_1):PAGE64
   CH6 UPI_CPU1_CPU0_P1P0_DN<19> @S9S_MB_2U_LIB.S9S_MB_2U(SCH_1):UPI_CPU1_CPU0_P1P0_DN(19)    I21 @S9S_MB_2U_LIB.S9S_MB_2U(SCH_1):PAGE64
   CJ5 UPI_CPU1_CPU0_P1P0_DN<18> @S9S_MB_2U_LIB.S9S_MB_2U(SCH_1):UPI_CPU1_CPU0_P1P0_DN(18)    I21 @S9S_MB_2U_LIB.S9S_MB_2U(SCH_1):PAGE64
   CM6 UPI_CPU1_CPU0_P1P0_DN<17> @S9S_MB_2U_LIB.S9S_MB_2U(SCH_1):UPI_CPU1_CPU0_P1P0_DN(17)    I21 @S9S_MB_2U_LIB.S9S_MB_2U(SCH_1):PAGE64
   CN5 UPI_CPU1_CPU0_P1P0_DN<16> @S9S_MB_2U_LIB.S9S_MB_2U(SCH_1):UPI_CPU1_CPU0_P1P0_DN(16)    I21 @S9S_MB_2U_LIB.S9S_MB_2U(SCH_1):PAGE64
   CT6 UPI_CPU1_CPU0_P1P0_DN<15> @S9S_MB_2U_LIB.S9S_MB_2U(SCH_1):UPI_CPU1_CPU0_P1P0_DN(15)    I21 @S9S_MB_2U_LIB.S9S_MB_2U(SCH_1):PAGE64
   CU5 UPI_CPU1_CPU0_P1P0_DN<14> @S9S_MB_2U_LIB.S9S_MB_2U(SCH_1):UPI_CPU1_CPU0_P1P0_DN(14)    I21 @S9S_MB_2U_LIB.S9S_MB_2U(SCH_1):PAGE64
   CY6 UPI_CPU1_CPU0_P1P0_DN<13> @S9S_MB_2U_LIB.S9S_MB_2U(SCH_1):UPI_CPU1_CPU0_P1P0_DN(13)    I21 @S9S_MB_2U_LIB.S9S_MB_2U(SCH_1):PAGE64
   DA5 UPI_CPU1_CPU0_P1P0_DN<12> @S9S_MB_2U_LIB.S9S_MB_2U(SCH_1):UPI_CPU1_CPU0_P1P0_DN(12)    I21 @S9S_MB_2U_LIB.S9S_MB_2U(SCH_1):PAGE64
   DD6 UPI_CPU1_CPU0_P1P0_DN<11> @S9S_MB_2U_LIB.S9S_MB_2U(SCH_1):UPI_CPU1_CPU0_P1P0_DN(11)    I21 @S9S_MB_2U_LIB.S9S_MB_2U(SCH_1):PAGE64
   DE5 UPI_CPU1_CPU0_P1P0_DN<10> @S9S_MB_2U_LIB.S9S_MB_2U(SCH_1):UPI_CPU1_CPU0_P1P0_DN(10)    I21 @S9S_MB_2U_LIB.S9S_MB_2U(SCH_1):PAGE64
   DH6 UPI_CPU1_CPU0_P1P0_DN<9> @S9S_MB_2U_LIB.S9S_MB_2U(SCH_1):UPI_CPU1_CPU0_P1P0_DN(9)    I21 @S9S_MB_2U_LIB.S9S_MB_2U(SCH_1):PAGE64
   DK6 UPI_CPU1_CPU0_P1P0_DN<8> @S9S_MB_2U_LIB.S9S_MB_2U(SCH_1):UPI_CPU1_CPU0_P1P0_DN(8)    I21 @S9S_MB_2U_LIB.S9S_MB_2U(SCH_1):PAGE64
   DL7 UPI_CPU1_CPU0_P1P0_DN<7> @S9S_MB_2U_LIB.S9S_MB_2U(SCH_1):UPI_CPU1_CPU0_P1P0_DN(7)    I21 @S9S_MB_2U_LIB.S9S_MB_2U(SCH_1):PAGE64
   DP6 UPI_CPU1_CPU0_P1P0_DN<6> @S9S_MB_2U_LIB.S9S_MB_2U(SCH_1):UPI_CPU1_CPU0_P1P0_DN(6)    I21 @S9S_MB_2U_LIB.S9S_MB_2U(SCH_1):PAGE64
   DT6 UPI_CPU1_CPU0_P1P0_DN<5> @S9S_MB_2U_LIB.S9S_MB_2U(SCH_1):UPI_CPU1_CPU0_P1P0_DN(5)    I21 @S9S_MB_2U_LIB.S9S_MB_2U(SCH_1):PAGE64
   DV6 UPI_CPU1_CPU0_P1P0_DN<4> @S9S_MB_2U_LIB.S9S_MB_2U(SCH_1):UPI_CPU1_CPU0_P1P0_DN(4)    I21 @S9S_MB_2U_LIB.S9S_MB_2U(SCH_1):PAGE64
   DY6 UPI_CPU1_CPU0_P1P0_DN<3> @S9S_MB_2U_LIB.S9S_MB_2U(SCH_1):UPI_CPU1_CPU0_P1P0_DN(3)    I21 @S9S_MB_2U_LIB.S9S_MB_2U(SCH_1):PAGE64
   EB6 UPI_CPU1_CPU0_P1P0_DN<2> @S9S_MB_2U_LIB.S9S_MB_2U(SCH_1):UPI_CPU1_CPU0_P1P0_DN(2)    I21 @S9S_MB_2U_LIB.S9S_MB_2U(SCH_1):PAGE64
   EC7 UPI_CPU1_CPU0_P1P0_DN<1> @S9S_MB_2U_LIB.S9S_MB_2U(SCH_1):UPI_CPU1_CPU0_P1P0_DN(1)    I21 @S9S_MB_2U_LIB.S9S_MB_2U(SCH_1):PAGE64
   EF6 UPI_CPU1_CPU0_P1P0_DN<0> @S9S_MB_2U_LIB.S9S_MB_2U(SCH_1):UPI_CPU1_CPU0_P1P0_DN(0)    I21 @S9S_MB_2U_LIB.S9S_MB_2U(SCH_1):PAGE64
   BW7 UPI_CPU1_CPU0_P1P0_DP<23> @S9S_MB_2U_LIB.S9S_MB_2U(SCH_1):UPI_CPU1_CPU0_P1P0_DP(23)    I21 @S9S_MB_2U_LIB.S9S_MB_2U(SCH_1):PAGE64
   CB6 UPI_CPU1_CPU0_P1P0_DP<22> @S9S_MB_2U_LIB.S9S_MB_2U(SCH_1):UPI_CPU1_CPU0_P1P0_DP(22)    I21 @S9S_MB_2U_LIB.S9S_MB_2U(SCH_1):PAGE64
   CC7 UPI_CPU1_CPU0_P1P0_DP<21> @S9S_MB_2U_LIB.S9S_MB_2U(SCH_1):UPI_CPU1_CPU0_P1P0_DP(21)    I21 @S9S_MB_2U_LIB.S9S_MB_2U(SCH_1):PAGE64
   CF6 UPI_CPU1_CPU0_P1P0_DP<20> @S9S_MB_2U_LIB.S9S_MB_2U(SCH_1):UPI_CPU1_CPU0_P1P0_DP(20)    I21 @S9S_MB_2U_LIB.S9S_MB_2U(SCH_1):PAGE64
   CG7 UPI_CPU1_CPU0_P1P0_DP<19> @S9S_MB_2U_LIB.S9S_MB_2U(SCH_1):UPI_CPU1_CPU0_P1P0_DP(19)    I21 @S9S_MB_2U_LIB.S9S_MB_2U(SCH_1):PAGE64
   CK6 UPI_CPU1_CPU0_P1P0_DP<18> @S9S_MB_2U_LIB.S9S_MB_2U(SCH_1):UPI_CPU1_CPU0_P1P0_DP(18)    I21 @S9S_MB_2U_LIB.S9S_MB_2U(SCH_1):PAGE64
   CL7 UPI_CPU1_CPU0_P1P0_DP<17> @S9S_MB_2U_LIB.S9S_MB_2U(SCH_1):UPI_CPU1_CPU0_P1P0_DP(17)    I21 @S9S_MB_2U_LIB.S9S_MB_2U(SCH_1):PAGE64
   CP6 UPI_CPU1_CPU0_P1P0_DP<16> @S9S_MB_2U_LIB.S9S_MB_2U(SCH_1):UPI_CPU1_CPU0_P1P0_DP(16)    I21 @S9S_MB_2U_LIB.S9S_MB_2U(SCH_1):PAGE64
   CR7 UPI_CPU1_CPU0_P1P0_DP<15> @S9S_MB_2U_LIB.S9S_MB_2U(SCH_1):UPI_CPU1_CPU0_P1P0_DP(15)    I21 @S9S_MB_2U_LIB.S9S_MB_2U(SCH_1):PAGE64
   CV6 UPI_CPU1_CPU0_P1P0_DP<14> @S9S_MB_2U_LIB.S9S_MB_2U(SCH_1):UPI_CPU1_CPU0_P1P0_DP(14)    I21 @S9S_MB_2U_LIB.S9S_MB_2U(SCH_1):PAGE64
   CW7 UPI_CPU1_CPU0_P1P0_DP<13> @S9S_MB_2U_LIB.S9S_MB_2U(SCH_1):UPI_CPU1_CPU0_P1P0_DP(13)    I21 @S9S_MB_2U_LIB.S9S_MB_2U(SCH_1):PAGE64
   DB6 UPI_CPU1_CPU0_P1P0_DP<12> @S9S_MB_2U_LIB.S9S_MB_2U(SCH_1):UPI_CPU1_CPU0_P1P0_DP(12)    I21 @S9S_MB_2U_LIB.S9S_MB_2U(SCH_1):PAGE64
   DC7 UPI_CPU1_CPU0_P1P0_DP<11> @S9S_MB_2U_LIB.S9S_MB_2U(SCH_1):UPI_CPU1_CPU0_P1P0_DP(11)    I21 @S9S_MB_2U_LIB.S9S_MB_2U(SCH_1):PAGE64
   DF6 UPI_CPU1_CPU0_P1P0_DP<10> @S9S_MB_2U_LIB.S9S_MB_2U(SCH_1):UPI_CPU1_CPU0_P1P0_DP(10)    I21 @S9S_MB_2U_LIB.S9S_MB_2U(SCH_1):PAGE64
   DG7 UPI_CPU1_CPU0_P1P0_DP<9> @S9S_MB_2U_LIB.S9S_MB_2U(SCH_1):UPI_CPU1_CPU0_P1P0_DP(9)    I21 @S9S_MB_2U_LIB.S9S_MB_2U(SCH_1):PAGE64
   DJ5 UPI_CPU1_CPU0_P1P0_DP<8> @S9S_MB_2U_LIB.S9S_MB_2U(SCH_1):UPI_CPU1_CPU0_P1P0_DP(8)    I21 @S9S_MB_2U_LIB.S9S_MB_2U(SCH_1):PAGE64
   DM6 UPI_CPU1_CPU0_P1P0_DP<7> @S9S_MB_2U_LIB.S9S_MB_2U(SCH_1):UPI_CPU1_CPU0_P1P0_DP(7)    I21 @S9S_MB_2U_LIB.S9S_MB_2U(SCH_1):PAGE64
   DN5 UPI_CPU1_CPU0_P1P0_DP<6> @S9S_MB_2U_LIB.S9S_MB_2U(SCH_1):UPI_CPU1_CPU0_P1P0_DP(6)    I21 @S9S_MB_2U_LIB.S9S_MB_2U(SCH_1):PAGE64
   DR7 UPI_CPU1_CPU0_P1P0_DP<5> @S9S_MB_2U_LIB.S9S_MB_2U(SCH_1):UPI_CPU1_CPU0_P1P0_DP(5)    I21 @S9S_MB_2U_LIB.S9S_MB_2U(SCH_1):PAGE64
   DU5 UPI_CPU1_CPU0_P1P0_DP<4> @S9S_MB_2U_LIB.S9S_MB_2U(SCH_1):UPI_CPU1_CPU0_P1P0_DP(4)    I21 @S9S_MB_2U_LIB.S9S_MB_2U(SCH_1):PAGE64
   DW7 UPI_CPU1_CPU0_P1P0_DP<3> @S9S_MB_2U_LIB.S9S_MB_2U(SCH_1):UPI_CPU1_CPU0_P1P0_DP(3)    I21 @S9S_MB_2U_LIB.S9S_MB_2U(SCH_1):PAGE64
   EA5 UPI_CPU1_CPU0_P1P0_DP<2> @S9S_MB_2U_LIB.S9S_MB_2U(SCH_1):UPI_CPU1_CPU0_P1P0_DP(2)    I21 @S9S_MB_2U_LIB.S9S_MB_2U(SCH_1):PAGE64
   ED6 UPI_CPU1_CPU0_P1P0_DP<1> @S9S_MB_2U_LIB.S9S_MB_2U(SCH_1):UPI_CPU1_CPU0_P1P0_DP(1)    I21 @S9S_MB_2U_LIB.S9S_MB_2U(SCH_1):PAGE64
   EE5 UPI_CPU1_CPU0_P1P0_DP<0> @S9S_MB_2U_LIB.S9S_MB_2U(SCH_1):UPI_CPU1_CPU0_P1P0_DP(0)    I21 @S9S_MB_2U_LIB.S9S_MB_2U(SCH_1):PAGE64
  BD73 UPI_CPU0_CPU1_P2P2_DN<23> @S9S_MB_2U_LIB.S9S_MB_2U(SCH_1):UPI_CPU0_CPU1_P2P2_DN(23)    I16 @S9S_MB_2U_LIB.S9S_MB_2U(SCH_1):PAGE65
  BK73 UPI_CPU0_CPU1_P2P2_DN<22> @S9S_MB_2U_LIB.S9S_MB_2U(SCH_1):UPI_CPU0_CPU1_P2P2_DN(22)    I16 @S9S_MB_2U_LIB.S9S_MB_2U(SCH_1):PAGE65
  BN74 UPI_CPU0_CPU1_P2P2_DN<21> @S9S_MB_2U_LIB.S9S_MB_2U(SCH_1):UPI_CPU0_CPU1_P2P2_DN(21)    I16 @S9S_MB_2U_LIB.S9S_MB_2U(SCH_1):PAGE65
  BG74 UPI_CPU0_CPU1_P2P2_DN<20> @S9S_MB_2U_LIB.S9S_MB_2U(SCH_1):UPI_CPU0_CPU1_P2P2_DN(20)    I16 @S9S_MB_2U_LIB.S9S_MB_2U(SCH_1):PAGE65
  BL76 UPI_CPU0_CPU1_P2P2_DN<19> @S9S_MB_2U_LIB.S9S_MB_2U(SCH_1):UPI_CPU0_CPU1_P2P2_DN(19)    I16 @S9S_MB_2U_LIB.S9S_MB_2U(SCH_1):PAGE65
  BJ76 UPI_CPU0_CPU1_P2P2_DN<18> @S9S_MB_2U_LIB.S9S_MB_2U(SCH_1):UPI_CPU0_CPU1_P2P2_DN(18)    I16 @S9S_MB_2U_LIB.S9S_MB_2U(SCH_1):PAGE65
  BH75 UPI_CPU0_CPU1_P2P2_DN<17> @S9S_MB_2U_LIB.S9S_MB_2U(SCH_1):UPI_CPU0_CPU1_P2P2_DN(17)    I16 @S9S_MB_2U_LIB.S9S_MB_2U(SCH_1):PAGE65
  AW74 UPI_CPU0_CPU1_P2P2_DN<16> @S9S_MB_2U_LIB.S9S_MB_2U(SCH_1):UPI_CPU0_CPU1_P2P2_DN(16)    I16 @S9S_MB_2U_LIB.S9S_MB_2U(SCH_1):PAGE65
  BB75 UPI_CPU0_CPU1_P2P2_DN<15> @S9S_MB_2U_LIB.S9S_MB_2U(SCH_1):UPI_CPU0_CPU1_P2P2_DN(15)    I16 @S9S_MB_2U_LIB.S9S_MB_2U(SCH_1):PAGE65
  AY75 UPI_CPU0_CPU1_P2P2_DN<14> @S9S_MB_2U_LIB.S9S_MB_2U(SCH_1):UPI_CPU0_CPU1_P2P2_DN(14)    I16 @S9S_MB_2U_LIB.S9S_MB_2U(SCH_1):PAGE65
  AV73 UPI_CPU0_CPU1_P2P2_DN<13> @S9S_MB_2U_LIB.S9S_MB_2U(SCH_1):UPI_CPU0_CPU1_P2P2_DN(13)    I16 @S9S_MB_2U_LIB.S9S_MB_2U(SCH_1):PAGE65
  BA72 UPI_CPU0_CPU1_P2P2_DN<12> @S9S_MB_2U_LIB.S9S_MB_2U(SCH_1):UPI_CPU0_CPU1_P2P2_DN(12)    I16 @S9S_MB_2U_LIB.S9S_MB_2U(SCH_1):PAGE65
  AG82 UPI_CPU0_CPU1_P2P2_DN<11> @S9S_MB_2U_LIB.S9S_MB_2U(SCH_1):UPI_CPU0_CPU1_P2P2_DN(11)    I16 @S9S_MB_2U_LIB.S9S_MB_2U(SCH_1):PAGE65
  AJ80 UPI_CPU0_CPU1_P2P2_DN<10> @S9S_MB_2U_LIB.S9S_MB_2U(SCH_1):UPI_CPU0_CPU1_P2P2_DN(10)    I16 @S9S_MB_2U_LIB.S9S_MB_2U(SCH_1):PAGE65
  AE82 UPI_CPU0_CPU1_P2P2_DN<9> @S9S_MB_2U_LIB.S9S_MB_2U(SCH_1):UPI_CPU0_CPU1_P2P2_DN(9)    I16 @S9S_MB_2U_LIB.S9S_MB_2U(SCH_1):PAGE65
  AF79 UPI_CPU0_CPU1_P2P2_DN<8> @S9S_MB_2U_LIB.S9S_MB_2U(SCH_1):UPI_CPU0_CPU1_P2P2_DN(8)    I16 @S9S_MB_2U_LIB.S9S_MB_2U(SCH_1):PAGE65
  AD81 UPI_CPU0_CPU1_P2P2_DN<7> @S9S_MB_2U_LIB.S9S_MB_2U(SCH_1):UPI_CPU0_CPU1_P2P2_DN(7)    I16 @S9S_MB_2U_LIB.S9S_MB_2U(SCH_1):PAGE65
  AC80 UPI_CPU0_CPU1_P2P2_DN<6> @S9S_MB_2U_LIB.S9S_MB_2U(SCH_1):UPI_CPU0_CPU1_P2P2_DN(6)    I16 @S9S_MB_2U_LIB.S9S_MB_2U(SCH_1):PAGE65
   L80 UPI_CPU0_CPU1_P2P2_DN<5> @S9S_MB_2U_LIB.S9S_MB_2U(SCH_1):UPI_CPU0_CPU1_P2P2_DN(5)    I16 @S9S_MB_2U_LIB.S9S_MB_2U(SCH_1):PAGE65
   J82 UPI_CPU0_CPU1_P2P2_DN<4> @S9S_MB_2U_LIB.S9S_MB_2U(SCH_1):UPI_CPU0_CPU1_P2P2_DN(4)    I16 @S9S_MB_2U_LIB.S9S_MB_2U(SCH_1):PAGE65
   K79 UPI_CPU0_CPU1_P2P2_DN<3> @S9S_MB_2U_LIB.S9S_MB_2U(SCH_1):UPI_CPU0_CPU1_P2P2_DN(3)    I16 @S9S_MB_2U_LIB.S9S_MB_2U(SCH_1):PAGE65
   G82 UPI_CPU0_CPU1_P2P2_DN<2> @S9S_MB_2U_LIB.S9S_MB_2U(SCH_1):UPI_CPU0_CPU1_P2P2_DN(2)    I16 @S9S_MB_2U_LIB.S9S_MB_2U(SCH_1):PAGE65
   F81 UPI_CPU0_CPU1_P2P2_DN<1> @S9S_MB_2U_LIB.S9S_MB_2U(SCH_1):UPI_CPU0_CPU1_P2P2_DN(1)    I16 @S9S_MB_2U_LIB.S9S_MB_2U(SCH_1):PAGE65
   E80 UPI_CPU0_CPU1_P2P2_DN<0> @S9S_MB_2U_LIB.S9S_MB_2U(SCH_1):UPI_CPU0_CPU1_P2P2_DN(0)    I16 @S9S_MB_2U_LIB.S9S_MB_2U(SCH_1):PAGE65
  BC74 UPI_CPU0_CPU1_P2P2_DP<23> @S9S_MB_2U_LIB.S9S_MB_2U(SCH_1):UPI_CPU0_CPU1_P2P2_DP(23)    I16 @S9S_MB_2U_LIB.S9S_MB_2U(SCH_1):PAGE65
  BL74 UPI_CPU0_CPU1_P2P2_DP<22> @S9S_MB_2U_LIB.S9S_MB_2U(SCH_1):UPI_CPU0_CPU1_P2P2_DP(22)    I16 @S9S_MB_2U_LIB.S9S_MB_2U(SCH_1):PAGE65
  BM75 UPI_CPU0_CPU1_P2P2_DP<21> @S9S_MB_2U_LIB.S9S_MB_2U(SCH_1):UPI_CPU0_CPU1_P2P2_DP(21)    I16 @S9S_MB_2U_LIB.S9S_MB_2U(SCH_1):PAGE65
  BJ74 UPI_CPU0_CPU1_P2P2_DP<20> @S9S_MB_2U_LIB.S9S_MB_2U(SCH_1):UPI_CPU0_CPU1_P2P2_DP(20)    I16 @S9S_MB_2U_LIB.S9S_MB_2U(SCH_1):PAGE65
  BN76 UPI_CPU0_CPU1_P2P2_DP<19> @S9S_MB_2U_LIB.S9S_MB_2U(SCH_1):UPI_CPU0_CPU1_P2P2_DP(19)    I16 @S9S_MB_2U_LIB.S9S_MB_2U(SCH_1):PAGE65
  BK77 UPI_CPU0_CPU1_P2P2_DP<18> @S9S_MB_2U_LIB.S9S_MB_2U(SCH_1):UPI_CPU0_CPU1_P2P2_DP(18)    I16 @S9S_MB_2U_LIB.S9S_MB_2U(SCH_1):PAGE65
  BG76 UPI_CPU0_CPU1_P2P2_DP<17> @S9S_MB_2U_LIB.S9S_MB_2U(SCH_1):UPI_CPU0_CPU1_P2P2_DP(17)    I16 @S9S_MB_2U_LIB.S9S_MB_2U(SCH_1):PAGE65
  AV75 UPI_CPU0_CPU1_P2P2_DP<16> @S9S_MB_2U_LIB.S9S_MB_2U(SCH_1):UPI_CPU0_CPU1_P2P2_DP(16)    I16 @S9S_MB_2U_LIB.S9S_MB_2U(SCH_1):PAGE65
  BD75 UPI_CPU0_CPU1_P2P2_DP<15> @S9S_MB_2U_LIB.S9S_MB_2U(SCH_1):UPI_CPU0_CPU1_P2P2_DP(15)    I16 @S9S_MB_2U_LIB.S9S_MB_2U(SCH_1):PAGE65
  BA76 UPI_CPU0_CPU1_P2P2_DP<14> @S9S_MB_2U_LIB.S9S_MB_2U(SCH_1):UPI_CPU0_CPU1_P2P2_DP(14)    I16 @S9S_MB_2U_LIB.S9S_MB_2U(SCH_1):PAGE65
  AY73 UPI_CPU0_CPU1_P2P2_DP<13> @S9S_MB_2U_LIB.S9S_MB_2U(SCH_1):UPI_CPU0_CPU1_P2P2_DP(13)    I16 @S9S_MB_2U_LIB.S9S_MB_2U(SCH_1):PAGE65
  BB73 UPI_CPU0_CPU1_P2P2_DP<12> @S9S_MB_2U_LIB.S9S_MB_2U(SCH_1):UPI_CPU0_CPU1_P2P2_DP(12)    I16 @S9S_MB_2U_LIB.S9S_MB_2U(SCH_1):PAGE65
  AJ82 UPI_CPU0_CPU1_P2P2_DP<11> @S9S_MB_2U_LIB.S9S_MB_2U(SCH_1):UPI_CPU0_CPU1_P2P2_DP(11)    I16 @S9S_MB_2U_LIB.S9S_MB_2U(SCH_1):PAGE65
  AH81 UPI_CPU0_CPU1_P2P2_DP<10> @S9S_MB_2U_LIB.S9S_MB_2U(SCH_1):UPI_CPU0_CPU1_P2P2_DP(10)    I16 @S9S_MB_2U_LIB.S9S_MB_2U(SCH_1):PAGE65
  AF83 UPI_CPU0_CPU1_P2P2_DP<9> @S9S_MB_2U_LIB.S9S_MB_2U(SCH_1):UPI_CPU0_CPU1_P2P2_DP(9)    I16 @S9S_MB_2U_LIB.S9S_MB_2U(SCH_1):PAGE65
  AG80 UPI_CPU0_CPU1_P2P2_DP<8> @S9S_MB_2U_LIB.S9S_MB_2U(SCH_1):UPI_CPU0_CPU1_P2P2_DP(8)    I16 @S9S_MB_2U_LIB.S9S_MB_2U(SCH_1):PAGE65
  AC82 UPI_CPU0_CPU1_P2P2_DP<7> @S9S_MB_2U_LIB.S9S_MB_2U(SCH_1):UPI_CPU0_CPU1_P2P2_DP(7)    I16 @S9S_MB_2U_LIB.S9S_MB_2U(SCH_1):PAGE65
  AE80 UPI_CPU0_CPU1_P2P2_DP<6> @S9S_MB_2U_LIB.S9S_MB_2U(SCH_1):UPI_CPU0_CPU1_P2P2_DP(6)    I16 @S9S_MB_2U_LIB.S9S_MB_2U(SCH_1):PAGE65
   K81 UPI_CPU0_CPU1_P2P2_DP<5> @S9S_MB_2U_LIB.S9S_MB_2U(SCH_1):UPI_CPU0_CPU1_P2P2_DP(5)    I16 @S9S_MB_2U_LIB.S9S_MB_2U(SCH_1):PAGE65
   L82 UPI_CPU0_CPU1_P2P2_DP<4> @S9S_MB_2U_LIB.S9S_MB_2U(SCH_1):UPI_CPU0_CPU1_P2P2_DP(4)    I16 @S9S_MB_2U_LIB.S9S_MB_2U(SCH_1):PAGE65
   M79 UPI_CPU0_CPU1_P2P2_DP<3> @S9S_MB_2U_LIB.S9S_MB_2U(SCH_1):UPI_CPU0_CPU1_P2P2_DP(3)    I16 @S9S_MB_2U_LIB.S9S_MB_2U(SCH_1):PAGE65
   H83 UPI_CPU0_CPU1_P2P2_DP<2> @S9S_MB_2U_LIB.S9S_MB_2U(SCH_1):UPI_CPU0_CPU1_P2P2_DP(2)    I16 @S9S_MB_2U_LIB.S9S_MB_2U(SCH_1):PAGE65
   E82 UPI_CPU0_CPU1_P2P2_DP<1> @S9S_MB_2U_LIB.S9S_MB_2U(SCH_1):UPI_CPU0_CPU1_P2P2_DP(1)    I16 @S9S_MB_2U_LIB.S9S_MB_2U(SCH_1):PAGE65
   G80 UPI_CPU0_CPU1_P2P2_DP<0> @S9S_MB_2U_LIB.S9S_MB_2U(SCH_1):UPI_CPU0_CPU1_P2P2_DP(0)    I16 @S9S_MB_2U_LIB.S9S_MB_2U(SCH_1):PAGE65
  BM71 UPI_CPU1_CPU0_P2P2_DN<23> @S9S_MB_2U_LIB.S9S_MB_2U(SCH_1):UPI_CPU1_CPU0_P2P2_DN(23)    I16 @S9S_MB_2U_LIB.S9S_MB_2U(SCH_1):PAGE65
  BG80 UPI_CPU1_CPU0_P2P2_DN<22> @S9S_MB_2U_LIB.S9S_MB_2U(SCH_1):UPI_CPU1_CPU0_P2P2_DN(22)    I16 @S9S_MB_2U_LIB.S9S_MB_2U(SCH_1):PAGE65
  BF81 UPI_CPU1_CPU0_P2P2_DN<21> @S9S_MB_2U_LIB.S9S_MB_2U(SCH_1):UPI_CPU1_CPU0_P2P2_DN(21)    I16 @S9S_MB_2U_LIB.S9S_MB_2U(SCH_1):PAGE65
  BD79 UPI_CPU1_CPU0_P2P2_DN<20> @S9S_MB_2U_LIB.S9S_MB_2U(SCH_1):UPI_CPU1_CPU0_P2P2_DN(20)    I16 @S9S_MB_2U_LIB.S9S_MB_2U(SCH_1):PAGE65
  BE82 UPI_CPU1_CPU0_P2P2_DN<19> @S9S_MB_2U_LIB.S9S_MB_2U(SCH_1):UPI_CPU1_CPU0_P2P2_DN(19)    I16 @S9S_MB_2U_LIB.S9S_MB_2U(SCH_1):PAGE65
  BC82 UPI_CPU1_CPU0_P2P2_DN<18> @S9S_MB_2U_LIB.S9S_MB_2U(SCH_1):UPI_CPU1_CPU0_P2P2_DN(18)    I16 @S9S_MB_2U_LIB.S9S_MB_2U(SCH_1):PAGE65
  BA80 UPI_CPU1_CPU0_P2P2_DN<17> @S9S_MB_2U_LIB.S9S_MB_2U(SCH_1):UPI_CPU1_CPU0_P2P2_DN(17)    I16 @S9S_MB_2U_LIB.S9S_MB_2U(SCH_1):PAGE65
  AV81 UPI_CPU1_CPU0_P2P2_DN<16> @S9S_MB_2U_LIB.S9S_MB_2U(SCH_1):UPI_CPU1_CPU0_P2P2_DN(16)    I16 @S9S_MB_2U_LIB.S9S_MB_2U(SCH_1):PAGE65
  AT83 UPI_CPU1_CPU0_P2P2_DN<15> @S9S_MB_2U_LIB.S9S_MB_2U(SCH_1):UPI_CPU1_CPU0_P2P2_DN(15)    I16 @S9S_MB_2U_LIB.S9S_MB_2U(SCH_1):PAGE65
  AR80 UPI_CPU1_CPU0_P2P2_DN<14> @S9S_MB_2U_LIB.S9S_MB_2U(SCH_1):UPI_CPU1_CPU0_P2P2_DN(14)    I16 @S9S_MB_2U_LIB.S9S_MB_2U(SCH_1):PAGE65
  AN82 UPI_CPU1_CPU0_P2P2_DN<13> @S9S_MB_2U_LIB.S9S_MB_2U(SCH_1):UPI_CPU1_CPU0_P2P2_DN(13)    I16 @S9S_MB_2U_LIB.S9S_MB_2U(SCH_1):PAGE65
  AM81 UPI_CPU1_CPU0_P2P2_DN<12> @S9S_MB_2U_LIB.S9S_MB_2U(SCH_1):UPI_CPU1_CPU0_P2P2_DN(12)    I16 @S9S_MB_2U_LIB.S9S_MB_2U(SCH_1):PAGE65
  AU78 UPI_CPU1_CPU0_P2P2_DN<11> @S9S_MB_2U_LIB.S9S_MB_2U(SCH_1):UPI_CPU1_CPU0_P2P2_DN(11)    I16 @S9S_MB_2U_LIB.S9S_MB_2U(SCH_1):PAGE65
  AW78 UPI_CPU1_CPU0_P2P2_DN<10> @S9S_MB_2U_LIB.S9S_MB_2U(SCH_1):UPI_CPU1_CPU0_P2P2_DN(10)    I16 @S9S_MB_2U_LIB.S9S_MB_2U(SCH_1):PAGE65
   Y81 UPI_CPU1_CPU0_P2P2_DN<9> @S9S_MB_2U_LIB.S9S_MB_2U(SCH_1):UPI_CPU1_CPU0_P2P2_DN(9)    I16 @S9S_MB_2U_LIB.S9S_MB_2U(SCH_1):PAGE65
   V83 UPI_CPU1_CPU0_P2P2_DN<8> @S9S_MB_2U_LIB.S9S_MB_2U(SCH_1):UPI_CPU1_CPU0_P2P2_DN(8)    I16 @S9S_MB_2U_LIB.S9S_MB_2U(SCH_1):PAGE65
   U80 UPI_CPU1_CPU0_P2P2_DN<7> @S9S_MB_2U_LIB.S9S_MB_2U(SCH_1):UPI_CPU1_CPU0_P2P2_DN(7)    I16 @S9S_MB_2U_LIB.S9S_MB_2U(SCH_1):PAGE65
   R82 UPI_CPU1_CPU0_P2P2_DN<6> @S9S_MB_2U_LIB.S9S_MB_2U(SCH_1):UPI_CPU1_CPU0_P2P2_DN(6)    I16 @S9S_MB_2U_LIB.S9S_MB_2U(SCH_1):PAGE65
   P81 UPI_CPU1_CPU0_P2P2_DN<5> @S9S_MB_2U_LIB.S9S_MB_2U(SCH_1):UPI_CPU1_CPU0_P2P2_DN(5)    I16 @S9S_MB_2U_LIB.S9S_MB_2U(SCH_1):PAGE65
   H85 UPI_CPU1_CPU0_P2P2_DN<4> @S9S_MB_2U_LIB.S9S_MB_2U(SCH_1):UPI_CPU1_CPU0_P2P2_DN(4)    I16 @S9S_MB_2U_LIB.S9S_MB_2U(SCH_1):PAGE65
   F87 UPI_CPU1_CPU0_P2P2_DN<3> @S9S_MB_2U_LIB.S9S_MB_2U(SCH_1):UPI_CPU1_CPU0_P2P2_DN(3)    I16 @S9S_MB_2U_LIB.S9S_MB_2U(SCH_1):PAGE65
   D87 UPI_CPU1_CPU0_P2P2_DN<2> @S9S_MB_2U_LIB.S9S_MB_2U(SCH_1):UPI_CPU1_CPU0_P2P2_DN(2)    I16 @S9S_MB_2U_LIB.S9S_MB_2U(SCH_1):PAGE65
   E84 UPI_CPU1_CPU0_P2P2_DN<1> @S9S_MB_2U_LIB.S9S_MB_2U(SCH_1):UPI_CPU1_CPU0_P2P2_DN(1)    I16 @S9S_MB_2U_LIB.S9S_MB_2U(SCH_1):PAGE65
   B85 UPI_CPU1_CPU0_P2P2_DN<0> @S9S_MB_2U_LIB.S9S_MB_2U(SCH_1):UPI_CPU1_CPU0_P2P2_DN(0)    I16 @S9S_MB_2U_LIB.S9S_MB_2U(SCH_1):PAGE65
  BN72 UPI_CPU1_CPU0_P2P2_DP<23> @S9S_MB_2U_LIB.S9S_MB_2U(SCH_1):UPI_CPU1_CPU0_P2P2_DP(23)    I16 @S9S_MB_2U_LIB.S9S_MB_2U(SCH_1):PAGE65
  BE80 UPI_CPU1_CPU0_P2P2_DP<22> @S9S_MB_2U_LIB.S9S_MB_2U(SCH_1):UPI_CPU1_CPU0_P2P2_DP(22)    I16 @S9S_MB_2U_LIB.S9S_MB_2U(SCH_1):PAGE65
  BG82 UPI_CPU1_CPU0_P2P2_DP<21> @S9S_MB_2U_LIB.S9S_MB_2U(SCH_1):UPI_CPU1_CPU0_P2P2_DP(21)    I16 @S9S_MB_2U_LIB.S9S_MB_2U(SCH_1):PAGE65
  BC80 UPI_CPU1_CPU0_P2P2_DP<20> @S9S_MB_2U_LIB.S9S_MB_2U(SCH_1):UPI_CPU1_CPU0_P2P2_DP(20)    I16 @S9S_MB_2U_LIB.S9S_MB_2U(SCH_1):PAGE65
  BD83 UPI_CPU1_CPU0_P2P2_DP<19> @S9S_MB_2U_LIB.S9S_MB_2U(SCH_1):UPI_CPU1_CPU0_P2P2_DP(19)    I16 @S9S_MB_2U_LIB.S9S_MB_2U(SCH_1):PAGE65
  BA82 UPI_CPU1_CPU0_P2P2_DP<18> @S9S_MB_2U_LIB.S9S_MB_2U(SCH_1):UPI_CPU1_CPU0_P2P2_DP(18)    I16 @S9S_MB_2U_LIB.S9S_MB_2U(SCH_1):PAGE65
  BB81 UPI_CPU1_CPU0_P2P2_DP<17> @S9S_MB_2U_LIB.S9S_MB_2U(SCH_1):UPI_CPU1_CPU0_P2P2_DP(17)    I16 @S9S_MB_2U_LIB.S9S_MB_2U(SCH_1):PAGE65
  AU82 UPI_CPU1_CPU0_P2P2_DP<16> @S9S_MB_2U_LIB.S9S_MB_2U(SCH_1):UPI_CPU1_CPU0_P2P2_DP(16)    I16 @S9S_MB_2U_LIB.S9S_MB_2U(SCH_1):PAGE65
  AV83 UPI_CPU1_CPU0_P2P2_DP<15> @S9S_MB_2U_LIB.S9S_MB_2U(SCH_1):UPI_CPU1_CPU0_P2P2_DP(15)    I16 @S9S_MB_2U_LIB.S9S_MB_2U(SCH_1):PAGE65
  AT81 UPI_CPU1_CPU0_P2P2_DP<14> @S9S_MB_2U_LIB.S9S_MB_2U(SCH_1):UPI_CPU1_CPU0_P2P2_DP(14)    I16 @S9S_MB_2U_LIB.S9S_MB_2U(SCH_1):PAGE65
  AM83 UPI_CPU1_CPU0_P2P2_DP<13> @S9S_MB_2U_LIB.S9S_MB_2U(SCH_1):UPI_CPU1_CPU0_P2P2_DP(13)    I16 @S9S_MB_2U_LIB.S9S_MB_2U(SCH_1):PAGE65
  AP81 UPI_CPU1_CPU0_P2P2_DP<12> @S9S_MB_2U_LIB.S9S_MB_2U(SCH_1):UPI_CPU1_CPU0_P2P2_DP(12)    I16 @S9S_MB_2U_LIB.S9S_MB_2U(SCH_1):PAGE65
  AV79 UPI_CPU1_CPU0_P2P2_DP<11> @S9S_MB_2U_LIB.S9S_MB_2U(SCH_1):UPI_CPU1_CPU0_P2P2_DP(11)    I16 @S9S_MB_2U_LIB.S9S_MB_2U(SCH_1):PAGE65
  BA78 UPI_CPU1_CPU0_P2P2_DP<10> @S9S_MB_2U_LIB.S9S_MB_2U(SCH_1):UPI_CPU1_CPU0_P2P2_DP(10)    I16 @S9S_MB_2U_LIB.S9S_MB_2U(SCH_1):PAGE65
   W82 UPI_CPU1_CPU0_P2P2_DP<9> @S9S_MB_2U_LIB.S9S_MB_2U(SCH_1):UPI_CPU1_CPU0_P2P2_DP(9)    I16 @S9S_MB_2U_LIB.S9S_MB_2U(SCH_1):PAGE65
   Y83 UPI_CPU1_CPU0_P2P2_DP<8> @S9S_MB_2U_LIB.S9S_MB_2U(SCH_1):UPI_CPU1_CPU0_P2P2_DP(8)    I16 @S9S_MB_2U_LIB.S9S_MB_2U(SCH_1):PAGE65
   V81 UPI_CPU1_CPU0_P2P2_DP<7> @S9S_MB_2U_LIB.S9S_MB_2U(SCH_1):UPI_CPU1_CPU0_P2P2_DP(7)    I16 @S9S_MB_2U_LIB.S9S_MB_2U(SCH_1):PAGE65
   P83 UPI_CPU1_CPU0_P2P2_DP<6> @S9S_MB_2U_LIB.S9S_MB_2U(SCH_1):UPI_CPU1_CPU0_P2P2_DP(6)    I16 @S9S_MB_2U_LIB.S9S_MB_2U(SCH_1):PAGE65
   T81 UPI_CPU1_CPU0_P2P2_DP<5> @S9S_MB_2U_LIB.S9S_MB_2U(SCH_1):UPI_CPU1_CPU0_P2P2_DP(5)    I16 @S9S_MB_2U_LIB.S9S_MB_2U(SCH_1):PAGE65
   G86 UPI_CPU1_CPU0_P2P2_DP<4> @S9S_MB_2U_LIB.S9S_MB_2U(SCH_1):UPI_CPU1_CPU0_P2P2_DP(4)    I16 @S9S_MB_2U_LIB.S9S_MB_2U(SCH_1):PAGE65
   H87 UPI_CPU1_CPU0_P2P2_DP<3> @S9S_MB_2U_LIB.S9S_MB_2U(SCH_1):UPI_CPU1_CPU0_P2P2_DP(3)    I16 @S9S_MB_2U_LIB.S9S_MB_2U(SCH_1):PAGE65
   E88 UPI_CPU1_CPU0_P2P2_DP<2> @S9S_MB_2U_LIB.S9S_MB_2U(SCH_1):UPI_CPU1_CPU0_P2P2_DP(2)    I16 @S9S_MB_2U_LIB.S9S_MB_2U(SCH_1):PAGE65
   F85 UPI_CPU1_CPU0_P2P2_DP<1> @S9S_MB_2U_LIB.S9S_MB_2U(SCH_1):UPI_CPU1_CPU0_P2P2_DP(1)    I16 @S9S_MB_2U_LIB.S9S_MB_2U(SCH_1):PAGE65
   D85 UPI_CPU1_CPU0_P2P2_DP<0> @S9S_MB_2U_LIB.S9S_MB_2U(SCH_1):UPI_CPU1_CPU0_P2P2_DP(0)    I16 @S9S_MB_2U_LIB.S9S_MB_2U(SCH_1):PAGE65
  DA78    GND @S9S_MB_2U_LIB.S9S_MB_2U(SCH_1):GND    I16 @S9S_MB_2U_LIB.S9S_MB_2U(SCH_1):PAGE66
  CT79    GND @S9S_MB_2U_LIB.S9S_MB_2U(SCH_1):GND    I16 @S9S_MB_2U_LIB.S9S_MB_2U(SCH_1):PAGE66
  CN80    GND @S9S_MB_2U_LIB.S9S_MB_2U(SCH_1):GND    I16 @S9S_MB_2U_LIB.S9S_MB_2U(SCH_1):PAGE66
  CP81    GND @S9S_MB_2U_LIB.S9S_MB_2U(SCH_1):GND    I16 @S9S_MB_2U_LIB.S9S_MB_2U(SCH_1):PAGE66
  CW80    GND @S9S_MB_2U_LIB.S9S_MB_2U(SCH_1):GND    I16 @S9S_MB_2U_LIB.S9S_MB_2U(SCH_1):PAGE66
  CR82    GND @S9S_MB_2U_LIB.S9S_MB_2U(SCH_1):GND    I16 @S9S_MB_2U_LIB.S9S_MB_2U(SCH_1):PAGE66
  CU82    GND @S9S_MB_2U_LIB.S9S_MB_2U(SCH_1):GND    I16 @S9S_MB_2U_LIB.S9S_MB_2U(SCH_1):PAGE66
  DF77    GND @S9S_MB_2U_LIB.S9S_MB_2U(SCH_1):GND    I16 @S9S_MB_2U_LIB.S9S_MB_2U(SCH_1):PAGE66
  DB81    GND @S9S_MB_2U_LIB.S9S_MB_2U(SCH_1):GND    I16 @S9S_MB_2U_LIB.S9S_MB_2U(SCH_1):PAGE66
  DC82    GND @S9S_MB_2U_LIB.S9S_MB_2U(SCH_1):GND    I16 @S9S_MB_2U_LIB.S9S_MB_2U(SCH_1):PAGE66
  DE80    GND @S9S_MB_2U_LIB.S9S_MB_2U(SCH_1):GND    I16 @S9S_MB_2U_LIB.S9S_MB_2U(SCH_1):PAGE66
  DF83    GND @S9S_MB_2U_LIB.S9S_MB_2U(SCH_1):GND    I16 @S9S_MB_2U_LIB.S9S_MB_2U(SCH_1):PAGE66
  DH81    GND @S9S_MB_2U_LIB.S9S_MB_2U(SCH_1):GND    I16 @S9S_MB_2U_LIB.S9S_MB_2U(SCH_1):PAGE66
  DG78    GND @S9S_MB_2U_LIB.S9S_MB_2U(SCH_1):GND    I16 @S9S_MB_2U_LIB.S9S_MB_2U(SCH_1):PAGE66
  DJ78    GND @S9S_MB_2U_LIB.S9S_MB_2U(SCH_1):GND    I16 @S9S_MB_2U_LIB.S9S_MB_2U(SCH_1):PAGE66
  DY81    GND @S9S_MB_2U_LIB.S9S_MB_2U(SCH_1):GND    I16 @S9S_MB_2U_LIB.S9S_MB_2U(SCH_1):PAGE66
  EA82    GND @S9S_MB_2U_LIB.S9S_MB_2U(SCH_1):GND    I16 @S9S_MB_2U_LIB.S9S_MB_2U(SCH_1):PAGE66
  EC80    GND @S9S_MB_2U_LIB.S9S_MB_2U(SCH_1):GND    I16 @S9S_MB_2U_LIB.S9S_MB_2U(SCH_1):PAGE66
  ED83    GND @S9S_MB_2U_LIB.S9S_MB_2U(SCH_1):GND    I16 @S9S_MB_2U_LIB.S9S_MB_2U(SCH_1):PAGE66
  EF81    GND @S9S_MB_2U_LIB.S9S_MB_2U(SCH_1):GND    I16 @S9S_MB_2U_LIB.S9S_MB_2U(SCH_1):PAGE66
  EK81    GND @S9S_MB_2U_LIB.S9S_MB_2U(SCH_1):GND    I16 @S9S_MB_2U_LIB.S9S_MB_2U(SCH_1):PAGE66
  EL82    GND @S9S_MB_2U_LIB.S9S_MB_2U(SCH_1):GND    I16 @S9S_MB_2U_LIB.S9S_MB_2U(SCH_1):PAGE66
  EP81    GND @S9S_MB_2U_LIB.S9S_MB_2U(SCH_1):GND    I16 @S9S_MB_2U_LIB.S9S_MB_2U(SCH_1):PAGE66
  EJ80    GND @S9S_MB_2U_LIB.S9S_MB_2U(SCH_1):GND    I16 @S9S_MB_2U_LIB.S9S_MB_2U(SCH_1):PAGE66
  DB79    GND @S9S_MB_2U_LIB.S9S_MB_2U(SCH_1):GND    I16 @S9S_MB_2U_LIB.S9S_MB_2U(SCH_1):PAGE66
  CU80    GND @S9S_MB_2U_LIB.S9S_MB_2U(SCH_1):GND    I16 @S9S_MB_2U_LIB.S9S_MB_2U(SCH_1):PAGE66
  CR80    GND @S9S_MB_2U_LIB.S9S_MB_2U(SCH_1):GND    I16 @S9S_MB_2U_LIB.S9S_MB_2U(SCH_1):PAGE66
  CN82    GND @S9S_MB_2U_LIB.S9S_MB_2U(SCH_1):GND    I16 @S9S_MB_2U_LIB.S9S_MB_2U(SCH_1):PAGE66
  CV81    GND @S9S_MB_2U_LIB.S9S_MB_2U(SCH_1):GND    I16 @S9S_MB_2U_LIB.S9S_MB_2U(SCH_1):PAGE66
  CT83    GND @S9S_MB_2U_LIB.S9S_MB_2U(SCH_1):GND    I16 @S9S_MB_2U_LIB.S9S_MB_2U(SCH_1):PAGE66
  CW82    GND @S9S_MB_2U_LIB.S9S_MB_2U(SCH_1):GND    I16 @S9S_MB_2U_LIB.S9S_MB_2U(SCH_1):PAGE66
  DE78    GND @S9S_MB_2U_LIB.S9S_MB_2U(SCH_1):GND    I16 @S9S_MB_2U_LIB.S9S_MB_2U(SCH_1):PAGE66
  DD81    GND @S9S_MB_2U_LIB.S9S_MB_2U(SCH_1):GND    I16 @S9S_MB_2U_LIB.S9S_MB_2U(SCH_1):PAGE66
  DB83    GND @S9S_MB_2U_LIB.S9S_MB_2U(SCH_1):GND    I16 @S9S_MB_2U_LIB.S9S_MB_2U(SCH_1):PAGE66
  DF81    GND @S9S_MB_2U_LIB.S9S_MB_2U(SCH_1):GND    I16 @S9S_MB_2U_LIB.S9S_MB_2U(SCH_1):PAGE66
  DH83    GND @S9S_MB_2U_LIB.S9S_MB_2U(SCH_1):GND    I16 @S9S_MB_2U_LIB.S9S_MB_2U(SCH_1):PAGE66
  DG82    GND @S9S_MB_2U_LIB.S9S_MB_2U(SCH_1):GND    I16 @S9S_MB_2U_LIB.S9S_MB_2U(SCH_1):PAGE66
  DH79    GND @S9S_MB_2U_LIB.S9S_MB_2U(SCH_1):GND    I16 @S9S_MB_2U_LIB.S9S_MB_2U(SCH_1):PAGE66
  DL78    GND @S9S_MB_2U_LIB.S9S_MB_2U(SCH_1):GND    I16 @S9S_MB_2U_LIB.S9S_MB_2U(SCH_1):PAGE66
  EB81    GND @S9S_MB_2U_LIB.S9S_MB_2U(SCH_1):GND    I16 @S9S_MB_2U_LIB.S9S_MB_2U(SCH_1):PAGE66
  DY83    GND @S9S_MB_2U_LIB.S9S_MB_2U(SCH_1):GND    I16 @S9S_MB_2U_LIB.S9S_MB_2U(SCH_1):PAGE66
  ED81    GND @S9S_MB_2U_LIB.S9S_MB_2U(SCH_1):GND    I16 @S9S_MB_2U_LIB.S9S_MB_2U(SCH_1):PAGE66
  EF83    GND @S9S_MB_2U_LIB.S9S_MB_2U(SCH_1):GND    I16 @S9S_MB_2U_LIB.S9S_MB_2U(SCH_1):PAGE66
  EE82    GND @S9S_MB_2U_LIB.S9S_MB_2U(SCH_1):GND    I16 @S9S_MB_2U_LIB.S9S_MB_2U(SCH_1):PAGE66
  EJ82    GND @S9S_MB_2U_LIB.S9S_MB_2U(SCH_1):GND    I16 @S9S_MB_2U_LIB.S9S_MB_2U(SCH_1):PAGE66
  EN82    GND @S9S_MB_2U_LIB.S9S_MB_2U(SCH_1):GND    I16 @S9S_MB_2U_LIB.S9S_MB_2U(SCH_1):PAGE66
  ER82    GND @S9S_MB_2U_LIB.S9S_MB_2U(SCH_1):GND    I16 @S9S_MB_2U_LIB.S9S_MB_2U(SCH_1):PAGE66
  EL80    GND @S9S_MB_2U_LIB.S9S_MB_2U(SCH_1):GND    I16 @S9S_MB_2U_LIB.S9S_MB_2U(SCH_1):PAGE66
  CF73     NC     NC    I16 @S9S_MB_2U_LIB.S9S_MB_2U(SCH_1):PAGE66
  CV73     NC     NC    I16 @S9S_MB_2U_LIB.S9S_MB_2U(SCH_1):PAGE66
  CJ74     NC     NC    I16 @S9S_MB_2U_LIB.S9S_MB_2U(SCH_1):PAGE66
  CF75     NC     NC    I16 @S9S_MB_2U_LIB.S9S_MB_2U(SCH_1):PAGE66
  CG76     NC     NC    I16 @S9S_MB_2U_LIB.S9S_MB_2U(SCH_1):PAGE66
  CM75     NC     NC    I16 @S9S_MB_2U_LIB.S9S_MB_2U(SCH_1):PAGE66
  CH77     NC     NC    I16 @S9S_MB_2U_LIB.S9S_MB_2U(SCH_1):PAGE66
  CK77     NC     NC    I16 @S9S_MB_2U_LIB.S9S_MB_2U(SCH_1):PAGE66
  CR74     NC     NC    I16 @S9S_MB_2U_LIB.S9S_MB_2U(SCH_1):PAGE66
  CT75     NC     NC    I16 @S9S_MB_2U_LIB.S9S_MB_2U(SCH_1):PAGE66
  CU76     NC     NC    I16 @S9S_MB_2U_LIB.S9S_MB_2U(SCH_1):PAGE66
  CW76     NC     NC    I16 @S9S_MB_2U_LIB.S9S_MB_2U(SCH_1):PAGE66
  DL80     NC     NC    I16 @S9S_MB_2U_LIB.S9S_MB_2U(SCH_1):PAGE66
  DM81     NC     NC    I16 @S9S_MB_2U_LIB.S9S_MB_2U(SCH_1):PAGE66
  DN82     NC     NC    I16 @S9S_MB_2U_LIB.S9S_MB_2U(SCH_1):PAGE66
  DP79     NC     NC    I16 @S9S_MB_2U_LIB.S9S_MB_2U(SCH_1):PAGE66
  DR82     NC     NC    I16 @S9S_MB_2U_LIB.S9S_MB_2U(SCH_1):PAGE66
  DU80     NC     NC    I16 @S9S_MB_2U_LIB.S9S_MB_2U(SCH_1):PAGE66
  EK87     NC     NC    I16 @S9S_MB_2U_LIB.S9S_MB_2U(SCH_1):PAGE66
  EJ86     NC     NC    I16 @S9S_MB_2U_LIB.S9S_MB_2U(SCH_1):PAGE66
  EM87     NC     NC    I16 @S9S_MB_2U_LIB.S9S_MB_2U(SCH_1):PAGE66
  EP85     NC     NC    I16 @S9S_MB_2U_LIB.S9S_MB_2U(SCH_1):PAGE66
  EL84     NC     NC    I16 @S9S_MB_2U_LIB.S9S_MB_2U(SCH_1):PAGE66
  EH85     NC     NC    I16 @S9S_MB_2U_LIB.S9S_MB_2U(SCH_1):PAGE66
  CD73     NC     NC    I16 @S9S_MB_2U_LIB.S9S_MB_2U(SCH_1):PAGE66
  CW74     NC     NC    I16 @S9S_MB_2U_LIB.S9S_MB_2U(SCH_1):PAGE66
  CK75     NC     NC    I16 @S9S_MB_2U_LIB.S9S_MB_2U(SCH_1):PAGE66
  CH75     NC     NC    I16 @S9S_MB_2U_LIB.S9S_MB_2U(SCH_1):PAGE66
  CF77     NC     NC    I16 @S9S_MB_2U_LIB.S9S_MB_2U(SCH_1):PAGE66
  CL76     NC     NC    I16 @S9S_MB_2U_LIB.S9S_MB_2U(SCH_1):PAGE66
  CJ78     NC     NC    I16 @S9S_MB_2U_LIB.S9S_MB_2U(SCH_1):PAGE66
  CM77     NC     NC    I16 @S9S_MB_2U_LIB.S9S_MB_2U(SCH_1):PAGE66
  CU74     NC     NC    I16 @S9S_MB_2U_LIB.S9S_MB_2U(SCH_1):PAGE66
  CR76     NC     NC    I16 @S9S_MB_2U_LIB.S9S_MB_2U(SCH_1):PAGE66
  CV77     NC     NC    I16 @S9S_MB_2U_LIB.S9S_MB_2U(SCH_1):PAGE66
  DA76     NC     NC    I16 @S9S_MB_2U_LIB.S9S_MB_2U(SCH_1):PAGE66
  DN80     NC     NC    I16 @S9S_MB_2U_LIB.S9S_MB_2U(SCH_1):PAGE66
  DL82     NC     NC    I16 @S9S_MB_2U_LIB.S9S_MB_2U(SCH_1):PAGE66
  DP83     NC     NC    I16 @S9S_MB_2U_LIB.S9S_MB_2U(SCH_1):PAGE66
  DR80     NC     NC    I16 @S9S_MB_2U_LIB.S9S_MB_2U(SCH_1):PAGE66
  DU82     NC     NC    I16 @S9S_MB_2U_LIB.S9S_MB_2U(SCH_1):PAGE66
  DT81     NC     NC    I16 @S9S_MB_2U_LIB.S9S_MB_2U(SCH_1):PAGE66
  EL88     NC     NC    I16 @S9S_MB_2U_LIB.S9S_MB_2U(SCH_1):PAGE66
  EH87     NC     NC    I16 @S9S_MB_2U_LIB.S9S_MB_2U(SCH_1):PAGE66
  EP87     NC     NC    I16 @S9S_MB_2U_LIB.S9S_MB_2U(SCH_1):PAGE66
  EN86     NC     NC    I16 @S9S_MB_2U_LIB.S9S_MB_2U(SCH_1):PAGE66
  EM85     NC     NC    I16 @S9S_MB_2U_LIB.S9S_MB_2U(SCH_1):PAGE66
  EK85     NC     NC    I16 @S9S_MB_2U_LIB.S9S_MB_2U(SCH_1):PAGE66
  CM89 PVCCIN_CPU1 @S9S_MB_2U_LIB.S9S_MB_2U(SCH_1):PVCCIN_CPU1     I1 @S9S_MB_2U_LIB.S9S_MB_2U(SCH_1):PAGE67
  CP89 PVCCIN_CPU1 @S9S_MB_2U_LIB.S9S_MB_2U(SCH_1):PVCCIN_CPU1     I1 @S9S_MB_2U_LIB.S9S_MB_2U(SCH_1):PAGE67
  CN90 PVCCIN_CPU1 @S9S_MB_2U_LIB.S9S_MB_2U(SCH_1):PVCCIN_CPU1     I1 @S9S_MB_2U_LIB.S9S_MB_2U(SCH_1):PAGE67
  CN88 PVCCIN_CPU1 @S9S_MB_2U_LIB.S9S_MB_2U(SCH_1):PVCCIN_CPU1     I1 @S9S_MB_2U_LIB.S9S_MB_2U(SCH_1):PAGE67
  CM91 PVCCIN_CPU1 @S9S_MB_2U_LIB.S9S_MB_2U(SCH_1):PVCCIN_CPU1     I1 @S9S_MB_2U_LIB.S9S_MB_2U(SCH_1):PAGE67
  CM87 PVCCIN_CPU1 @S9S_MB_2U_LIB.S9S_MB_2U(SCH_1):PVCCIN_CPU1     I1 @S9S_MB_2U_LIB.S9S_MB_2U(SCH_1):PAGE67
  CL90 PVCCIN_CPU1 @S9S_MB_2U_LIB.S9S_MB_2U(SCH_1):PVCCIN_CPU1     I1 @S9S_MB_2U_LIB.S9S_MB_2U(SCH_1):PAGE67
  CL88 PVCCIN_CPU1 @S9S_MB_2U_LIB.S9S_MB_2U(SCH_1):PVCCIN_CPU1     I1 @S9S_MB_2U_LIB.S9S_MB_2U(SCH_1):PAGE67
  CL86 PVCCIN_CPU1 @S9S_MB_2U_LIB.S9S_MB_2U(SCH_1):PVCCIN_CPU1     I1 @S9S_MB_2U_LIB.S9S_MB_2U(SCH_1):PAGE67
  CL84 PVCCIN_CPU1 @S9S_MB_2U_LIB.S9S_MB_2U(SCH_1):PVCCIN_CPU1     I1 @S9S_MB_2U_LIB.S9S_MB_2U(SCH_1):PAGE67
  CK91 PVCCIN_CPU1 @S9S_MB_2U_LIB.S9S_MB_2U(SCH_1):PVCCIN_CPU1     I1 @S9S_MB_2U_LIB.S9S_MB_2U(SCH_1):PAGE67
  CK89 PVCCIN_CPU1 @S9S_MB_2U_LIB.S9S_MB_2U(SCH_1):PVCCIN_CPU1     I1 @S9S_MB_2U_LIB.S9S_MB_2U(SCH_1):PAGE67
  CK87 PVCCIN_CPU1 @S9S_MB_2U_LIB.S9S_MB_2U(SCH_1):PVCCIN_CPU1     I1 @S9S_MB_2U_LIB.S9S_MB_2U(SCH_1):PAGE67
  CK85 PVCCIN_CPU1 @S9S_MB_2U_LIB.S9S_MB_2U(SCH_1):PVCCIN_CPU1     I1 @S9S_MB_2U_LIB.S9S_MB_2U(SCH_1):PAGE67
  CK83 PVCCIN_CPU1 @S9S_MB_2U_LIB.S9S_MB_2U(SCH_1):PVCCIN_CPU1     I1 @S9S_MB_2U_LIB.S9S_MB_2U(SCH_1):PAGE67
  CJ90 PVCCIN_CPU1 @S9S_MB_2U_LIB.S9S_MB_2U(SCH_1):PVCCIN_CPU1     I1 @S9S_MB_2U_LIB.S9S_MB_2U(SCH_1):PAGE67
  CJ88 PVCCIN_CPU1 @S9S_MB_2U_LIB.S9S_MB_2U(SCH_1):PVCCIN_CPU1     I1 @S9S_MB_2U_LIB.S9S_MB_2U(SCH_1):PAGE67
  CJ86 PVCCIN_CPU1 @S9S_MB_2U_LIB.S9S_MB_2U(SCH_1):PVCCIN_CPU1     I1 @S9S_MB_2U_LIB.S9S_MB_2U(SCH_1):PAGE67
  CJ84 PVCCIN_CPU1 @S9S_MB_2U_LIB.S9S_MB_2U(SCH_1):PVCCIN_CPU1     I1 @S9S_MB_2U_LIB.S9S_MB_2U(SCH_1):PAGE67
  CJ82 PVCCIN_CPU1 @S9S_MB_2U_LIB.S9S_MB_2U(SCH_1):PVCCIN_CPU1     I1 @S9S_MB_2U_LIB.S9S_MB_2U(SCH_1):PAGE67
  CH91 PVCCIN_CPU1 @S9S_MB_2U_LIB.S9S_MB_2U(SCH_1):PVCCIN_CPU1     I1 @S9S_MB_2U_LIB.S9S_MB_2U(SCH_1):PAGE67
  CH81 PVCCIN_CPU1 @S9S_MB_2U_LIB.S9S_MB_2U(SCH_1):PVCCIN_CPU1     I1 @S9S_MB_2U_LIB.S9S_MB_2U(SCH_1):PAGE67
  CG90 PVCCIN_CPU1 @S9S_MB_2U_LIB.S9S_MB_2U(SCH_1):PVCCIN_CPU1     I1 @S9S_MB_2U_LIB.S9S_MB_2U(SCH_1):PAGE67
  CG88 PVCCIN_CPU1 @S9S_MB_2U_LIB.S9S_MB_2U(SCH_1):PVCCIN_CPU1     I1 @S9S_MB_2U_LIB.S9S_MB_2U(SCH_1):PAGE67
  CG86 PVCCIN_CPU1 @S9S_MB_2U_LIB.S9S_MB_2U(SCH_1):PVCCIN_CPU1     I1 @S9S_MB_2U_LIB.S9S_MB_2U(SCH_1):PAGE67
  CG84 PVCCIN_CPU1 @S9S_MB_2U_LIB.S9S_MB_2U(SCH_1):PVCCIN_CPU1     I1 @S9S_MB_2U_LIB.S9S_MB_2U(SCH_1):PAGE67
  CG82 PVCCIN_CPU1 @S9S_MB_2U_LIB.S9S_MB_2U(SCH_1):PVCCIN_CPU1     I1 @S9S_MB_2U_LIB.S9S_MB_2U(SCH_1):PAGE67
  CG80 PVCCIN_CPU1 @S9S_MB_2U_LIB.S9S_MB_2U(SCH_1):PVCCIN_CPU1     I1 @S9S_MB_2U_LIB.S9S_MB_2U(SCH_1):PAGE67
  CF91 PVCCIN_CPU1 @S9S_MB_2U_LIB.S9S_MB_2U(SCH_1):PVCCIN_CPU1     I1 @S9S_MB_2U_LIB.S9S_MB_2U(SCH_1):PAGE67
  CF89 PVCCIN_CPU1 @S9S_MB_2U_LIB.S9S_MB_2U(SCH_1):PVCCIN_CPU1     I1 @S9S_MB_2U_LIB.S9S_MB_2U(SCH_1):PAGE67
  CF87 PVCCIN_CPU1 @S9S_MB_2U_LIB.S9S_MB_2U(SCH_1):PVCCIN_CPU1     I1 @S9S_MB_2U_LIB.S9S_MB_2U(SCH_1):PAGE67
  CF85 PVCCIN_CPU1 @S9S_MB_2U_LIB.S9S_MB_2U(SCH_1):PVCCIN_CPU1     I1 @S9S_MB_2U_LIB.S9S_MB_2U(SCH_1):PAGE67
  CF83 PVCCIN_CPU1 @S9S_MB_2U_LIB.S9S_MB_2U(SCH_1):PVCCIN_CPU1     I1 @S9S_MB_2U_LIB.S9S_MB_2U(SCH_1):PAGE67
  CF81 PVCCIN_CPU1 @S9S_MB_2U_LIB.S9S_MB_2U(SCH_1):PVCCIN_CPU1     I1 @S9S_MB_2U_LIB.S9S_MB_2U(SCH_1):PAGE67
  CF79 PVCCIN_CPU1 @S9S_MB_2U_LIB.S9S_MB_2U(SCH_1):PVCCIN_CPU1     I1 @S9S_MB_2U_LIB.S9S_MB_2U(SCH_1):PAGE67
  CE90 PVCCIN_CPU1 @S9S_MB_2U_LIB.S9S_MB_2U(SCH_1):PVCCIN_CPU1     I1 @S9S_MB_2U_LIB.S9S_MB_2U(SCH_1):PAGE67
  CE88 PVCCIN_CPU1 @S9S_MB_2U_LIB.S9S_MB_2U(SCH_1):PVCCIN_CPU1     I1 @S9S_MB_2U_LIB.S9S_MB_2U(SCH_1):PAGE67
  CE86 PVCCIN_CPU1 @S9S_MB_2U_LIB.S9S_MB_2U(SCH_1):PVCCIN_CPU1     I1 @S9S_MB_2U_LIB.S9S_MB_2U(SCH_1):PAGE67
  CE84 PVCCIN_CPU1 @S9S_MB_2U_LIB.S9S_MB_2U(SCH_1):PVCCIN_CPU1     I1 @S9S_MB_2U_LIB.S9S_MB_2U(SCH_1):PAGE67
  CE82 PVCCIN_CPU1 @S9S_MB_2U_LIB.S9S_MB_2U(SCH_1):PVCCIN_CPU1     I1 @S9S_MB_2U_LIB.S9S_MB_2U(SCH_1):PAGE67
  CE80 PVCCIN_CPU1 @S9S_MB_2U_LIB.S9S_MB_2U(SCH_1):PVCCIN_CPU1     I1 @S9S_MB_2U_LIB.S9S_MB_2U(SCH_1):PAGE67
  CD89 PVCCIN_CPU1 @S9S_MB_2U_LIB.S9S_MB_2U(SCH_1):PVCCIN_CPU1     I1 @S9S_MB_2U_LIB.S9S_MB_2U(SCH_1):PAGE67
  CD87 PVCCIN_CPU1 @S9S_MB_2U_LIB.S9S_MB_2U(SCH_1):PVCCIN_CPU1     I1 @S9S_MB_2U_LIB.S9S_MB_2U(SCH_1):PAGE67
  CD85 PVCCIN_CPU1 @S9S_MB_2U_LIB.S9S_MB_2U(SCH_1):PVCCIN_CPU1     I1 @S9S_MB_2U_LIB.S9S_MB_2U(SCH_1):PAGE67
  CD83 PVCCIN_CPU1 @S9S_MB_2U_LIB.S9S_MB_2U(SCH_1):PVCCIN_CPU1     I1 @S9S_MB_2U_LIB.S9S_MB_2U(SCH_1):PAGE67
  CD81 PVCCIN_CPU1 @S9S_MB_2U_LIB.S9S_MB_2U(SCH_1):PVCCIN_CPU1     I1 @S9S_MB_2U_LIB.S9S_MB_2U(SCH_1):PAGE67
  CD79 PVCCIN_CPU1 @S9S_MB_2U_LIB.S9S_MB_2U(SCH_1):PVCCIN_CPU1     I1 @S9S_MB_2U_LIB.S9S_MB_2U(SCH_1):PAGE67
  CD59 PVCCIN_CPU1 @S9S_MB_2U_LIB.S9S_MB_2U(SCH_1):PVCCIN_CPU1     I1 @S9S_MB_2U_LIB.S9S_MB_2U(SCH_1):PAGE67
  CD57 PVCCIN_CPU1 @S9S_MB_2U_LIB.S9S_MB_2U(SCH_1):PVCCIN_CPU1     I1 @S9S_MB_2U_LIB.S9S_MB_2U(SCH_1):PAGE67
  CD55 PVCCIN_CPU1 @S9S_MB_2U_LIB.S9S_MB_2U(SCH_1):PVCCIN_CPU1     I1 @S9S_MB_2U_LIB.S9S_MB_2U(SCH_1):PAGE67
  CD53 PVCCIN_CPU1 @S9S_MB_2U_LIB.S9S_MB_2U(SCH_1):PVCCIN_CPU1     I1 @S9S_MB_2U_LIB.S9S_MB_2U(SCH_1):PAGE67
  CD51 PVCCIN_CPU1 @S9S_MB_2U_LIB.S9S_MB_2U(SCH_1):PVCCIN_CPU1     I1 @S9S_MB_2U_LIB.S9S_MB_2U(SCH_1):PAGE67
  CD49 PVCCIN_CPU1 @S9S_MB_2U_LIB.S9S_MB_2U(SCH_1):PVCCIN_CPU1     I1 @S9S_MB_2U_LIB.S9S_MB_2U(SCH_1):PAGE67
  CD47 PVCCIN_CPU1 @S9S_MB_2U_LIB.S9S_MB_2U(SCH_1):PVCCIN_CPU1     I1 @S9S_MB_2U_LIB.S9S_MB_2U(SCH_1):PAGE67
  CD44 PVCCIN_CPU1 @S9S_MB_2U_LIB.S9S_MB_2U(SCH_1):PVCCIN_CPU1     I1 @S9S_MB_2U_LIB.S9S_MB_2U(SCH_1):PAGE67
  CD42 PVCCIN_CPU1 @S9S_MB_2U_LIB.S9S_MB_2U(SCH_1):PVCCIN_CPU1     I1 @S9S_MB_2U_LIB.S9S_MB_2U(SCH_1):PAGE67
  CD40 PVCCIN_CPU1 @S9S_MB_2U_LIB.S9S_MB_2U(SCH_1):PVCCIN_CPU1     I1 @S9S_MB_2U_LIB.S9S_MB_2U(SCH_1):PAGE67
  CD38 PVCCIN_CPU1 @S9S_MB_2U_LIB.S9S_MB_2U(SCH_1):PVCCIN_CPU1     I1 @S9S_MB_2U_LIB.S9S_MB_2U(SCH_1):PAGE67
  CD36 PVCCIN_CPU1 @S9S_MB_2U_LIB.S9S_MB_2U(SCH_1):PVCCIN_CPU1     I1 @S9S_MB_2U_LIB.S9S_MB_2U(SCH_1):PAGE67
  CD34 PVCCIN_CPU1 @S9S_MB_2U_LIB.S9S_MB_2U(SCH_1):PVCCIN_CPU1     I1 @S9S_MB_2U_LIB.S9S_MB_2U(SCH_1):PAGE67
  CD32 PVCCIN_CPU1 @S9S_MB_2U_LIB.S9S_MB_2U(SCH_1):PVCCIN_CPU1     I1 @S9S_MB_2U_LIB.S9S_MB_2U(SCH_1):PAGE67
  CC90 PVCCIN_CPU1 @S9S_MB_2U_LIB.S9S_MB_2U(SCH_1):PVCCIN_CPU1     I1 @S9S_MB_2U_LIB.S9S_MB_2U(SCH_1):PAGE67
  CC88 PVCCIN_CPU1 @S9S_MB_2U_LIB.S9S_MB_2U(SCH_1):PVCCIN_CPU1     I1 @S9S_MB_2U_LIB.S9S_MB_2U(SCH_1):PAGE67
  CC86 PVCCIN_CPU1 @S9S_MB_2U_LIB.S9S_MB_2U(SCH_1):PVCCIN_CPU1     I1 @S9S_MB_2U_LIB.S9S_MB_2U(SCH_1):PAGE67
  CC84 PVCCIN_CPU1 @S9S_MB_2U_LIB.S9S_MB_2U(SCH_1):PVCCIN_CPU1     I1 @S9S_MB_2U_LIB.S9S_MB_2U(SCH_1):PAGE67
  CC82 PVCCIN_CPU1 @S9S_MB_2U_LIB.S9S_MB_2U(SCH_1):PVCCIN_CPU1     I1 @S9S_MB_2U_LIB.S9S_MB_2U(SCH_1):PAGE67
  CC80 PVCCIN_CPU1 @S9S_MB_2U_LIB.S9S_MB_2U(SCH_1):PVCCIN_CPU1     I1 @S9S_MB_2U_LIB.S9S_MB_2U(SCH_1):PAGE67
  CC78 PVCCIN_CPU1 @S9S_MB_2U_LIB.S9S_MB_2U(SCH_1):PVCCIN_CPU1     I1 @S9S_MB_2U_LIB.S9S_MB_2U(SCH_1):PAGE67
  CC76 PVCCIN_CPU1 @S9S_MB_2U_LIB.S9S_MB_2U(SCH_1):PVCCIN_CPU1     I1 @S9S_MB_2U_LIB.S9S_MB_2U(SCH_1):PAGE67
  CC60 PVCCIN_CPU1 @S9S_MB_2U_LIB.S9S_MB_2U(SCH_1):PVCCIN_CPU1     I1 @S9S_MB_2U_LIB.S9S_MB_2U(SCH_1):PAGE67
  CC58 PVCCIN_CPU1 @S9S_MB_2U_LIB.S9S_MB_2U(SCH_1):PVCCIN_CPU1     I1 @S9S_MB_2U_LIB.S9S_MB_2U(SCH_1):PAGE67
  CC56 PVCCIN_CPU1 @S9S_MB_2U_LIB.S9S_MB_2U(SCH_1):PVCCIN_CPU1     I1 @S9S_MB_2U_LIB.S9S_MB_2U(SCH_1):PAGE67
  CC54 PVCCIN_CPU1 @S9S_MB_2U_LIB.S9S_MB_2U(SCH_1):PVCCIN_CPU1     I1 @S9S_MB_2U_LIB.S9S_MB_2U(SCH_1):PAGE67
  CC52 PVCCIN_CPU1 @S9S_MB_2U_LIB.S9S_MB_2U(SCH_1):PVCCIN_CPU1     I1 @S9S_MB_2U_LIB.S9S_MB_2U(SCH_1):PAGE67
  CC50 PVCCIN_CPU1 @S9S_MB_2U_LIB.S9S_MB_2U(SCH_1):PVCCIN_CPU1     I1 @S9S_MB_2U_LIB.S9S_MB_2U(SCH_1):PAGE67
  CC48 PVCCIN_CPU1 @S9S_MB_2U_LIB.S9S_MB_2U(SCH_1):PVCCIN_CPU1     I1 @S9S_MB_2U_LIB.S9S_MB_2U(SCH_1):PAGE67
  CC45 PVCCIN_CPU1 @S9S_MB_2U_LIB.S9S_MB_2U(SCH_1):PVCCIN_CPU1     I1 @S9S_MB_2U_LIB.S9S_MB_2U(SCH_1):PAGE67
  CC43 PVCCIN_CPU1 @S9S_MB_2U_LIB.S9S_MB_2U(SCH_1):PVCCIN_CPU1     I1 @S9S_MB_2U_LIB.S9S_MB_2U(SCH_1):PAGE67
  CC41 PVCCIN_CPU1 @S9S_MB_2U_LIB.S9S_MB_2U(SCH_1):PVCCIN_CPU1     I1 @S9S_MB_2U_LIB.S9S_MB_2U(SCH_1):PAGE67
  CC39 PVCCIN_CPU1 @S9S_MB_2U_LIB.S9S_MB_2U(SCH_1):PVCCIN_CPU1     I1 @S9S_MB_2U_LIB.S9S_MB_2U(SCH_1):PAGE67
  CC37 PVCCIN_CPU1 @S9S_MB_2U_LIB.S9S_MB_2U(SCH_1):PVCCIN_CPU1     I1 @S9S_MB_2U_LIB.S9S_MB_2U(SCH_1):PAGE67
  CC35 PVCCIN_CPU1 @S9S_MB_2U_LIB.S9S_MB_2U(SCH_1):PVCCIN_CPU1     I1 @S9S_MB_2U_LIB.S9S_MB_2U(SCH_1):PAGE67
  CC33 PVCCIN_CPU1 @S9S_MB_2U_LIB.S9S_MB_2U(SCH_1):PVCCIN_CPU1     I1 @S9S_MB_2U_LIB.S9S_MB_2U(SCH_1):PAGE67
  CB77 PVCCIN_CPU1 @S9S_MB_2U_LIB.S9S_MB_2U(SCH_1):PVCCIN_CPU1     I1 @S9S_MB_2U_LIB.S9S_MB_2U(SCH_1):PAGE67
  CB75 PVCCIN_CPU1 @S9S_MB_2U_LIB.S9S_MB_2U(SCH_1):PVCCIN_CPU1     I1 @S9S_MB_2U_LIB.S9S_MB_2U(SCH_1):PAGE67
  CB61 PVCCIN_CPU1 @S9S_MB_2U_LIB.S9S_MB_2U(SCH_1):PVCCIN_CPU1     I1 @S9S_MB_2U_LIB.S9S_MB_2U(SCH_1):PAGE67
  CA90 PVCCIN_CPU1 @S9S_MB_2U_LIB.S9S_MB_2U(SCH_1):PVCCIN_CPU1     I1 @S9S_MB_2U_LIB.S9S_MB_2U(SCH_1):PAGE67
  CA88 PVCCIN_CPU1 @S9S_MB_2U_LIB.S9S_MB_2U(SCH_1):PVCCIN_CPU1     I1 @S9S_MB_2U_LIB.S9S_MB_2U(SCH_1):PAGE67
  CA86 PVCCIN_CPU1 @S9S_MB_2U_LIB.S9S_MB_2U(SCH_1):PVCCIN_CPU1     I1 @S9S_MB_2U_LIB.S9S_MB_2U(SCH_1):PAGE67
  CA84 PVCCIN_CPU1 @S9S_MB_2U_LIB.S9S_MB_2U(SCH_1):PVCCIN_CPU1     I1 @S9S_MB_2U_LIB.S9S_MB_2U(SCH_1):PAGE67
  CA82 PVCCIN_CPU1 @S9S_MB_2U_LIB.S9S_MB_2U(SCH_1):PVCCIN_CPU1     I1 @S9S_MB_2U_LIB.S9S_MB_2U(SCH_1):PAGE67
  CA80 PVCCIN_CPU1 @S9S_MB_2U_LIB.S9S_MB_2U(SCH_1):PVCCIN_CPU1     I1 @S9S_MB_2U_LIB.S9S_MB_2U(SCH_1):PAGE67
  CA78 PVCCIN_CPU1 @S9S_MB_2U_LIB.S9S_MB_2U(SCH_1):PVCCIN_CPU1     I1 @S9S_MB_2U_LIB.S9S_MB_2U(SCH_1):PAGE67
  CA76 PVCCIN_CPU1 @S9S_MB_2U_LIB.S9S_MB_2U(SCH_1):PVCCIN_CPU1     I1 @S9S_MB_2U_LIB.S9S_MB_2U(SCH_1):PAGE67
  CA74 PVCCIN_CPU1 @S9S_MB_2U_LIB.S9S_MB_2U(SCH_1):PVCCIN_CPU1     I1 @S9S_MB_2U_LIB.S9S_MB_2U(SCH_1):PAGE67
  CA72 PVCCIN_CPU1 @S9S_MB_2U_LIB.S9S_MB_2U(SCH_1):PVCCIN_CPU1     I1 @S9S_MB_2U_LIB.S9S_MB_2U(SCH_1):PAGE67
  CA70 PVCCIN_CPU1 @S9S_MB_2U_LIB.S9S_MB_2U(SCH_1):PVCCIN_CPU1     I1 @S9S_MB_2U_LIB.S9S_MB_2U(SCH_1):PAGE67
  CA68 PVCCIN_CPU1 @S9S_MB_2U_LIB.S9S_MB_2U(SCH_1):PVCCIN_CPU1     I1 @S9S_MB_2U_LIB.S9S_MB_2U(SCH_1):PAGE67
  CA66 PVCCIN_CPU1 @S9S_MB_2U_LIB.S9S_MB_2U(SCH_1):PVCCIN_CPU1     I1 @S9S_MB_2U_LIB.S9S_MB_2U(SCH_1):PAGE67
  CA64 PVCCIN_CPU1 @S9S_MB_2U_LIB.S9S_MB_2U(SCH_1):PVCCIN_CPU1     I1 @S9S_MB_2U_LIB.S9S_MB_2U(SCH_1):PAGE67
  CA62 PVCCIN_CPU1 @S9S_MB_2U_LIB.S9S_MB_2U(SCH_1):PVCCIN_CPU1     I1 @S9S_MB_2U_LIB.S9S_MB_2U(SCH_1):PAGE67
  CA60 PVCCIN_CPU1 @S9S_MB_2U_LIB.S9S_MB_2U(SCH_1):PVCCIN_CPU1     I1 @S9S_MB_2U_LIB.S9S_MB_2U(SCH_1):PAGE67
  CA58 PVCCIN_CPU1 @S9S_MB_2U_LIB.S9S_MB_2U(SCH_1):PVCCIN_CPU1     I1 @S9S_MB_2U_LIB.S9S_MB_2U(SCH_1):PAGE67
  CA56 PVCCIN_CPU1 @S9S_MB_2U_LIB.S9S_MB_2U(SCH_1):PVCCIN_CPU1     I1 @S9S_MB_2U_LIB.S9S_MB_2U(SCH_1):PAGE67
  CA54 PVCCIN_CPU1 @S9S_MB_2U_LIB.S9S_MB_2U(SCH_1):PVCCIN_CPU1     I1 @S9S_MB_2U_LIB.S9S_MB_2U(SCH_1):PAGE67
  CA52 PVCCIN_CPU1 @S9S_MB_2U_LIB.S9S_MB_2U(SCH_1):PVCCIN_CPU1     I1 @S9S_MB_2U_LIB.S9S_MB_2U(SCH_1):PAGE67
  CA50 PVCCIN_CPU1 @S9S_MB_2U_LIB.S9S_MB_2U(SCH_1):PVCCIN_CPU1     I1 @S9S_MB_2U_LIB.S9S_MB_2U(SCH_1):PAGE67
  CA48 PVCCIN_CPU1 @S9S_MB_2U_LIB.S9S_MB_2U(SCH_1):PVCCIN_CPU1     I1 @S9S_MB_2U_LIB.S9S_MB_2U(SCH_1):PAGE67
  CA45 PVCCIN_CPU1 @S9S_MB_2U_LIB.S9S_MB_2U(SCH_1):PVCCIN_CPU1     I1 @S9S_MB_2U_LIB.S9S_MB_2U(SCH_1):PAGE67
  CA43 PVCCIN_CPU1 @S9S_MB_2U_LIB.S9S_MB_2U(SCH_1):PVCCIN_CPU1     I1 @S9S_MB_2U_LIB.S9S_MB_2U(SCH_1):PAGE67
  CA41 PVCCIN_CPU1 @S9S_MB_2U_LIB.S9S_MB_2U(SCH_1):PVCCIN_CPU1     I1 @S9S_MB_2U_LIB.S9S_MB_2U(SCH_1):PAGE67
  CA39 PVCCIN_CPU1 @S9S_MB_2U_LIB.S9S_MB_2U(SCH_1):PVCCIN_CPU1     I1 @S9S_MB_2U_LIB.S9S_MB_2U(SCH_1):PAGE67
  CA37 PVCCIN_CPU1 @S9S_MB_2U_LIB.S9S_MB_2U(SCH_1):PVCCIN_CPU1     I1 @S9S_MB_2U_LIB.S9S_MB_2U(SCH_1):PAGE67
  CA35 PVCCIN_CPU1 @S9S_MB_2U_LIB.S9S_MB_2U(SCH_1):PVCCIN_CPU1     I1 @S9S_MB_2U_LIB.S9S_MB_2U(SCH_1):PAGE67
  CA33 PVCCIN_CPU1 @S9S_MB_2U_LIB.S9S_MB_2U(SCH_1):PVCCIN_CPU1     I1 @S9S_MB_2U_LIB.S9S_MB_2U(SCH_1):PAGE67
  BY89 PVCCIN_CPU1 @S9S_MB_2U_LIB.S9S_MB_2U(SCH_1):PVCCIN_CPU1     I1 @S9S_MB_2U_LIB.S9S_MB_2U(SCH_1):PAGE67
  BY87 PVCCIN_CPU1 @S9S_MB_2U_LIB.S9S_MB_2U(SCH_1):PVCCIN_CPU1     I1 @S9S_MB_2U_LIB.S9S_MB_2U(SCH_1):PAGE67
  BY85 PVCCIN_CPU1 @S9S_MB_2U_LIB.S9S_MB_2U(SCH_1):PVCCIN_CPU1     I1 @S9S_MB_2U_LIB.S9S_MB_2U(SCH_1):PAGE67
  BY83 PVCCIN_CPU1 @S9S_MB_2U_LIB.S9S_MB_2U(SCH_1):PVCCIN_CPU1     I1 @S9S_MB_2U_LIB.S9S_MB_2U(SCH_1):PAGE67
  BY81 PVCCIN_CPU1 @S9S_MB_2U_LIB.S9S_MB_2U(SCH_1):PVCCIN_CPU1     I1 @S9S_MB_2U_LIB.S9S_MB_2U(SCH_1):PAGE67
  BY79 PVCCIN_CPU1 @S9S_MB_2U_LIB.S9S_MB_2U(SCH_1):PVCCIN_CPU1     I1 @S9S_MB_2U_LIB.S9S_MB_2U(SCH_1):PAGE67
  BY77 PVCCIN_CPU1 @S9S_MB_2U_LIB.S9S_MB_2U(SCH_1):PVCCIN_CPU1     I1 @S9S_MB_2U_LIB.S9S_MB_2U(SCH_1):PAGE67
  BY75 PVCCIN_CPU1 @S9S_MB_2U_LIB.S9S_MB_2U(SCH_1):PVCCIN_CPU1     I1 @S9S_MB_2U_LIB.S9S_MB_2U(SCH_1):PAGE67
  BY73 PVCCIN_CPU1 @S9S_MB_2U_LIB.S9S_MB_2U(SCH_1):PVCCIN_CPU1     I1 @S9S_MB_2U_LIB.S9S_MB_2U(SCH_1):PAGE67
  BY71 PVCCIN_CPU1 @S9S_MB_2U_LIB.S9S_MB_2U(SCH_1):PVCCIN_CPU1     I1 @S9S_MB_2U_LIB.S9S_MB_2U(SCH_1):PAGE67
  BY69 PVCCIN_CPU1 @S9S_MB_2U_LIB.S9S_MB_2U(SCH_1):PVCCIN_CPU1     I1 @S9S_MB_2U_LIB.S9S_MB_2U(SCH_1):PAGE67
  BY67 PVCCIN_CPU1 @S9S_MB_2U_LIB.S9S_MB_2U(SCH_1):PVCCIN_CPU1     I1 @S9S_MB_2U_LIB.S9S_MB_2U(SCH_1):PAGE67
  BY65 PVCCIN_CPU1 @S9S_MB_2U_LIB.S9S_MB_2U(SCH_1):PVCCIN_CPU1     I1 @S9S_MB_2U_LIB.S9S_MB_2U(SCH_1):PAGE67
  BY63 PVCCIN_CPU1 @S9S_MB_2U_LIB.S9S_MB_2U(SCH_1):PVCCIN_CPU1     I1 @S9S_MB_2U_LIB.S9S_MB_2U(SCH_1):PAGE67
  BY61 PVCCIN_CPU1 @S9S_MB_2U_LIB.S9S_MB_2U(SCH_1):PVCCIN_CPU1     I1 @S9S_MB_2U_LIB.S9S_MB_2U(SCH_1):PAGE67
  BY59 PVCCIN_CPU1 @S9S_MB_2U_LIB.S9S_MB_2U(SCH_1):PVCCIN_CPU1     I1 @S9S_MB_2U_LIB.S9S_MB_2U(SCH_1):PAGE67
  BY57 PVCCIN_CPU1 @S9S_MB_2U_LIB.S9S_MB_2U(SCH_1):PVCCIN_CPU1     I1 @S9S_MB_2U_LIB.S9S_MB_2U(SCH_1):PAGE67
  BY55 PVCCIN_CPU1 @S9S_MB_2U_LIB.S9S_MB_2U(SCH_1):PVCCIN_CPU1     I1 @S9S_MB_2U_LIB.S9S_MB_2U(SCH_1):PAGE67
  BY53 PVCCIN_CPU1 @S9S_MB_2U_LIB.S9S_MB_2U(SCH_1):PVCCIN_CPU1     I1 @S9S_MB_2U_LIB.S9S_MB_2U(SCH_1):PAGE67
  BY51 PVCCIN_CPU1 @S9S_MB_2U_LIB.S9S_MB_2U(SCH_1):PVCCIN_CPU1     I1 @S9S_MB_2U_LIB.S9S_MB_2U(SCH_1):PAGE67
  BY49 PVCCIN_CPU1 @S9S_MB_2U_LIB.S9S_MB_2U(SCH_1):PVCCIN_CPU1     I1 @S9S_MB_2U_LIB.S9S_MB_2U(SCH_1):PAGE67
  BY47 PVCCIN_CPU1 @S9S_MB_2U_LIB.S9S_MB_2U(SCH_1):PVCCIN_CPU1     I1 @S9S_MB_2U_LIB.S9S_MB_2U(SCH_1):PAGE67
  BY44 PVCCIN_CPU1 @S9S_MB_2U_LIB.S9S_MB_2U(SCH_1):PVCCIN_CPU1     I1 @S9S_MB_2U_LIB.S9S_MB_2U(SCH_1):PAGE67
  BY42 PVCCIN_CPU1 @S9S_MB_2U_LIB.S9S_MB_2U(SCH_1):PVCCIN_CPU1     I1 @S9S_MB_2U_LIB.S9S_MB_2U(SCH_1):PAGE67
  BY40 PVCCIN_CPU1 @S9S_MB_2U_LIB.S9S_MB_2U(SCH_1):PVCCIN_CPU1     I1 @S9S_MB_2U_LIB.S9S_MB_2U(SCH_1):PAGE67
  BY38 PVCCIN_CPU1 @S9S_MB_2U_LIB.S9S_MB_2U(SCH_1):PVCCIN_CPU1     I1 @S9S_MB_2U_LIB.S9S_MB_2U(SCH_1):PAGE67
  BY36 PVCCIN_CPU1 @S9S_MB_2U_LIB.S9S_MB_2U(SCH_1):PVCCIN_CPU1     I1 @S9S_MB_2U_LIB.S9S_MB_2U(SCH_1):PAGE67
  BY34 PVCCIN_CPU1 @S9S_MB_2U_LIB.S9S_MB_2U(SCH_1):PVCCIN_CPU1     I1 @S9S_MB_2U_LIB.S9S_MB_2U(SCH_1):PAGE67
  BY32 PVCCIN_CPU1 @S9S_MB_2U_LIB.S9S_MB_2U(SCH_1):PVCCIN_CPU1     I1 @S9S_MB_2U_LIB.S9S_MB_2U(SCH_1):PAGE67
  BW90 PVCCIN_CPU1 @S9S_MB_2U_LIB.S9S_MB_2U(SCH_1):PVCCIN_CPU1     I1 @S9S_MB_2U_LIB.S9S_MB_2U(SCH_1):PAGE67
  BW88 PVCCIN_CPU1 @S9S_MB_2U_LIB.S9S_MB_2U(SCH_1):PVCCIN_CPU1     I1 @S9S_MB_2U_LIB.S9S_MB_2U(SCH_1):PAGE67
  BW86 PVCCIN_CPU1 @S9S_MB_2U_LIB.S9S_MB_2U(SCH_1):PVCCIN_CPU1     I1 @S9S_MB_2U_LIB.S9S_MB_2U(SCH_1):PAGE67
  BW84 PVCCIN_CPU1 @S9S_MB_2U_LIB.S9S_MB_2U(SCH_1):PVCCIN_CPU1     I1 @S9S_MB_2U_LIB.S9S_MB_2U(SCH_1):PAGE67
  BW82 PVCCIN_CPU1 @S9S_MB_2U_LIB.S9S_MB_2U(SCH_1):PVCCIN_CPU1     I1 @S9S_MB_2U_LIB.S9S_MB_2U(SCH_1):PAGE67
  BW80 PVCCIN_CPU1 @S9S_MB_2U_LIB.S9S_MB_2U(SCH_1):PVCCIN_CPU1     I1 @S9S_MB_2U_LIB.S9S_MB_2U(SCH_1):PAGE67
  BW78 PVCCIN_CPU1 @S9S_MB_2U_LIB.S9S_MB_2U(SCH_1):PVCCIN_CPU1     I3 @S9S_MB_2U_LIB.S9S_MB_2U(SCH_1):PAGE67
  BW76 PVCCIN_CPU1 @S9S_MB_2U_LIB.S9S_MB_2U(SCH_1):PVCCIN_CPU1     I3 @S9S_MB_2U_LIB.S9S_MB_2U(SCH_1):PAGE67
  BW74 PVCCIN_CPU1 @S9S_MB_2U_LIB.S9S_MB_2U(SCH_1):PVCCIN_CPU1     I3 @S9S_MB_2U_LIB.S9S_MB_2U(SCH_1):PAGE67
  BW72 PVCCIN_CPU1 @S9S_MB_2U_LIB.S9S_MB_2U(SCH_1):PVCCIN_CPU1     I3 @S9S_MB_2U_LIB.S9S_MB_2U(SCH_1):PAGE67
  BW70 PVCCIN_CPU1 @S9S_MB_2U_LIB.S9S_MB_2U(SCH_1):PVCCIN_CPU1     I3 @S9S_MB_2U_LIB.S9S_MB_2U(SCH_1):PAGE67
  BW68 PVCCIN_CPU1 @S9S_MB_2U_LIB.S9S_MB_2U(SCH_1):PVCCIN_CPU1     I3 @S9S_MB_2U_LIB.S9S_MB_2U(SCH_1):PAGE67
  BW66 PVCCIN_CPU1 @S9S_MB_2U_LIB.S9S_MB_2U(SCH_1):PVCCIN_CPU1     I3 @S9S_MB_2U_LIB.S9S_MB_2U(SCH_1):PAGE67
  BW64 PVCCIN_CPU1 @S9S_MB_2U_LIB.S9S_MB_2U(SCH_1):PVCCIN_CPU1     I3 @S9S_MB_2U_LIB.S9S_MB_2U(SCH_1):PAGE67
  BW62 PVCCIN_CPU1 @S9S_MB_2U_LIB.S9S_MB_2U(SCH_1):PVCCIN_CPU1     I3 @S9S_MB_2U_LIB.S9S_MB_2U(SCH_1):PAGE67
  BW60 PVCCIN_CPU1 @S9S_MB_2U_LIB.S9S_MB_2U(SCH_1):PVCCIN_CPU1     I3 @S9S_MB_2U_LIB.S9S_MB_2U(SCH_1):PAGE67
  BW58 PVCCIN_CPU1 @S9S_MB_2U_LIB.S9S_MB_2U(SCH_1):PVCCIN_CPU1     I3 @S9S_MB_2U_LIB.S9S_MB_2U(SCH_1):PAGE67
  BW56 PVCCIN_CPU1 @S9S_MB_2U_LIB.S9S_MB_2U(SCH_1):PVCCIN_CPU1     I3 @S9S_MB_2U_LIB.S9S_MB_2U(SCH_1):PAGE67
  BW54 PVCCIN_CPU1 @S9S_MB_2U_LIB.S9S_MB_2U(SCH_1):PVCCIN_CPU1     I3 @S9S_MB_2U_LIB.S9S_MB_2U(SCH_1):PAGE67
  BW52 PVCCIN_CPU1 @S9S_MB_2U_LIB.S9S_MB_2U(SCH_1):PVCCIN_CPU1     I3 @S9S_MB_2U_LIB.S9S_MB_2U(SCH_1):PAGE67
  BW50 PVCCIN_CPU1 @S9S_MB_2U_LIB.S9S_MB_2U(SCH_1):PVCCIN_CPU1     I3 @S9S_MB_2U_LIB.S9S_MB_2U(SCH_1):PAGE67
  BW48 PVCCIN_CPU1 @S9S_MB_2U_LIB.S9S_MB_2U(SCH_1):PVCCIN_CPU1     I3 @S9S_MB_2U_LIB.S9S_MB_2U(SCH_1):PAGE67
  BW45 PVCCIN_CPU1 @S9S_MB_2U_LIB.S9S_MB_2U(SCH_1):PVCCIN_CPU1     I3 @S9S_MB_2U_LIB.S9S_MB_2U(SCH_1):PAGE67
  BW43 PVCCIN_CPU1 @S9S_MB_2U_LIB.S9S_MB_2U(SCH_1):PVCCIN_CPU1     I3 @S9S_MB_2U_LIB.S9S_MB_2U(SCH_1):PAGE67
  BW41 PVCCIN_CPU1 @S9S_MB_2U_LIB.S9S_MB_2U(SCH_1):PVCCIN_CPU1     I3 @S9S_MB_2U_LIB.S9S_MB_2U(SCH_1):PAGE67
  BW39 PVCCIN_CPU1 @S9S_MB_2U_LIB.S9S_MB_2U(SCH_1):PVCCIN_CPU1     I3 @S9S_MB_2U_LIB.S9S_MB_2U(SCH_1):PAGE67
  BW37 PVCCIN_CPU1 @S9S_MB_2U_LIB.S9S_MB_2U(SCH_1):PVCCIN_CPU1     I3 @S9S_MB_2U_LIB.S9S_MB_2U(SCH_1):PAGE67
  BW35 PVCCIN_CPU1 @S9S_MB_2U_LIB.S9S_MB_2U(SCH_1):PVCCIN_CPU1     I3 @S9S_MB_2U_LIB.S9S_MB_2U(SCH_1):PAGE67
  BW33 PVCCIN_CPU1 @S9S_MB_2U_LIB.S9S_MB_2U(SCH_1):PVCCIN_CPU1     I3 @S9S_MB_2U_LIB.S9S_MB_2U(SCH_1):PAGE67
  BV89 PVCCIN_CPU1 @S9S_MB_2U_LIB.S9S_MB_2U(SCH_1):PVCCIN_CPU1     I3 @S9S_MB_2U_LIB.S9S_MB_2U(SCH_1):PAGE67
  BV87 PVCCIN_CPU1 @S9S_MB_2U_LIB.S9S_MB_2U(SCH_1):PVCCIN_CPU1     I3 @S9S_MB_2U_LIB.S9S_MB_2U(SCH_1):PAGE67
  BV85 PVCCIN_CPU1 @S9S_MB_2U_LIB.S9S_MB_2U(SCH_1):PVCCIN_CPU1     I3 @S9S_MB_2U_LIB.S9S_MB_2U(SCH_1):PAGE67
  BV83 PVCCIN_CPU1 @S9S_MB_2U_LIB.S9S_MB_2U(SCH_1):PVCCIN_CPU1     I3 @S9S_MB_2U_LIB.S9S_MB_2U(SCH_1):PAGE67
  BV81 PVCCIN_CPU1 @S9S_MB_2U_LIB.S9S_MB_2U(SCH_1):PVCCIN_CPU1     I3 @S9S_MB_2U_LIB.S9S_MB_2U(SCH_1):PAGE67
  BV79 PVCCIN_CPU1 @S9S_MB_2U_LIB.S9S_MB_2U(SCH_1):PVCCIN_CPU1     I3 @S9S_MB_2U_LIB.S9S_MB_2U(SCH_1):PAGE67
  BV77 PVCCIN_CPU1 @S9S_MB_2U_LIB.S9S_MB_2U(SCH_1):PVCCIN_CPU1     I3 @S9S_MB_2U_LIB.S9S_MB_2U(SCH_1):PAGE67
  BV75 PVCCIN_CPU1 @S9S_MB_2U_LIB.S9S_MB_2U(SCH_1):PVCCIN_CPU1     I3 @S9S_MB_2U_LIB.S9S_MB_2U(SCH_1):PAGE67
  BV73 PVCCIN_CPU1 @S9S_MB_2U_LIB.S9S_MB_2U(SCH_1):PVCCIN_CPU1     I3 @S9S_MB_2U_LIB.S9S_MB_2U(SCH_1):PAGE67
  BV71 PVCCIN_CPU1 @S9S_MB_2U_LIB.S9S_MB_2U(SCH_1):PVCCIN_CPU1     I3 @S9S_MB_2U_LIB.S9S_MB_2U(SCH_1):PAGE67
  BV69 PVCCIN_CPU1 @S9S_MB_2U_LIB.S9S_MB_2U(SCH_1):PVCCIN_CPU1     I3 @S9S_MB_2U_LIB.S9S_MB_2U(SCH_1):PAGE67
  BV67 PVCCIN_CPU1 @S9S_MB_2U_LIB.S9S_MB_2U(SCH_1):PVCCIN_CPU1     I3 @S9S_MB_2U_LIB.S9S_MB_2U(SCH_1):PAGE67
  BV65 PVCCIN_CPU1 @S9S_MB_2U_LIB.S9S_MB_2U(SCH_1):PVCCIN_CPU1     I3 @S9S_MB_2U_LIB.S9S_MB_2U(SCH_1):PAGE67
  BV63 PVCCIN_CPU1 @S9S_MB_2U_LIB.S9S_MB_2U(SCH_1):PVCCIN_CPU1     I3 @S9S_MB_2U_LIB.S9S_MB_2U(SCH_1):PAGE67
  BV61 PVCCIN_CPU1 @S9S_MB_2U_LIB.S9S_MB_2U(SCH_1):PVCCIN_CPU1     I3 @S9S_MB_2U_LIB.S9S_MB_2U(SCH_1):PAGE67
  BV59 PVCCIN_CPU1 @S9S_MB_2U_LIB.S9S_MB_2U(SCH_1):PVCCIN_CPU1     I3 @S9S_MB_2U_LIB.S9S_MB_2U(SCH_1):PAGE67
  BV57 PVCCIN_CPU1 @S9S_MB_2U_LIB.S9S_MB_2U(SCH_1):PVCCIN_CPU1     I3 @S9S_MB_2U_LIB.S9S_MB_2U(SCH_1):PAGE67
  BV55 PVCCIN_CPU1 @S9S_MB_2U_LIB.S9S_MB_2U(SCH_1):PVCCIN_CPU1     I3 @S9S_MB_2U_LIB.S9S_MB_2U(SCH_1):PAGE67
  BV53 PVCCIN_CPU1 @S9S_MB_2U_LIB.S9S_MB_2U(SCH_1):PVCCIN_CPU1     I3 @S9S_MB_2U_LIB.S9S_MB_2U(SCH_1):PAGE67
  BV51 PVCCIN_CPU1 @S9S_MB_2U_LIB.S9S_MB_2U(SCH_1):PVCCIN_CPU1     I3 @S9S_MB_2U_LIB.S9S_MB_2U(SCH_1):PAGE67
  BV49 PVCCIN_CPU1 @S9S_MB_2U_LIB.S9S_MB_2U(SCH_1):PVCCIN_CPU1     I3 @S9S_MB_2U_LIB.S9S_MB_2U(SCH_1):PAGE67
  BV47 PVCCIN_CPU1 @S9S_MB_2U_LIB.S9S_MB_2U(SCH_1):PVCCIN_CPU1     I3 @S9S_MB_2U_LIB.S9S_MB_2U(SCH_1):PAGE67
  BV44 PVCCIN_CPU1 @S9S_MB_2U_LIB.S9S_MB_2U(SCH_1):PVCCIN_CPU1     I3 @S9S_MB_2U_LIB.S9S_MB_2U(SCH_1):PAGE67
  BV42 PVCCIN_CPU1 @S9S_MB_2U_LIB.S9S_MB_2U(SCH_1):PVCCIN_CPU1     I3 @S9S_MB_2U_LIB.S9S_MB_2U(SCH_1):PAGE67
  BV40 PVCCIN_CPU1 @S9S_MB_2U_LIB.S9S_MB_2U(SCH_1):PVCCIN_CPU1     I3 @S9S_MB_2U_LIB.S9S_MB_2U(SCH_1):PAGE67
  BV38 PVCCIN_CPU1 @S9S_MB_2U_LIB.S9S_MB_2U(SCH_1):PVCCIN_CPU1     I3 @S9S_MB_2U_LIB.S9S_MB_2U(SCH_1):PAGE67
  BV36 PVCCIN_CPU1 @S9S_MB_2U_LIB.S9S_MB_2U(SCH_1):PVCCIN_CPU1     I3 @S9S_MB_2U_LIB.S9S_MB_2U(SCH_1):PAGE67
  BV34 PVCCIN_CPU1 @S9S_MB_2U_LIB.S9S_MB_2U(SCH_1):PVCCIN_CPU1     I3 @S9S_MB_2U_LIB.S9S_MB_2U(SCH_1):PAGE67
  BV32 PVCCIN_CPU1 @S9S_MB_2U_LIB.S9S_MB_2U(SCH_1):PVCCIN_CPU1     I3 @S9S_MB_2U_LIB.S9S_MB_2U(SCH_1):PAGE67
  BU90 PVCCIN_CPU1 @S9S_MB_2U_LIB.S9S_MB_2U(SCH_1):PVCCIN_CPU1     I3 @S9S_MB_2U_LIB.S9S_MB_2U(SCH_1):PAGE67
  BU88 PVCCIN_CPU1 @S9S_MB_2U_LIB.S9S_MB_2U(SCH_1):PVCCIN_CPU1     I3 @S9S_MB_2U_LIB.S9S_MB_2U(SCH_1):PAGE67
  BU86 PVCCIN_CPU1 @S9S_MB_2U_LIB.S9S_MB_2U(SCH_1):PVCCIN_CPU1     I3 @S9S_MB_2U_LIB.S9S_MB_2U(SCH_1):PAGE67
  BU84 PVCCIN_CPU1 @S9S_MB_2U_LIB.S9S_MB_2U(SCH_1):PVCCIN_CPU1     I3 @S9S_MB_2U_LIB.S9S_MB_2U(SCH_1):PAGE67
  BU82 PVCCIN_CPU1 @S9S_MB_2U_LIB.S9S_MB_2U(SCH_1):PVCCIN_CPU1     I3 @S9S_MB_2U_LIB.S9S_MB_2U(SCH_1):PAGE67
  BU80 PVCCIN_CPU1 @S9S_MB_2U_LIB.S9S_MB_2U(SCH_1):PVCCIN_CPU1     I3 @S9S_MB_2U_LIB.S9S_MB_2U(SCH_1):PAGE67
  BU78 PVCCIN_CPU1 @S9S_MB_2U_LIB.S9S_MB_2U(SCH_1):PVCCIN_CPU1     I3 @S9S_MB_2U_LIB.S9S_MB_2U(SCH_1):PAGE67
  BU76 PVCCIN_CPU1 @S9S_MB_2U_LIB.S9S_MB_2U(SCH_1):PVCCIN_CPU1     I3 @S9S_MB_2U_LIB.S9S_MB_2U(SCH_1):PAGE67
  BU74 PVCCIN_CPU1 @S9S_MB_2U_LIB.S9S_MB_2U(SCH_1):PVCCIN_CPU1     I3 @S9S_MB_2U_LIB.S9S_MB_2U(SCH_1):PAGE67
  BU72 PVCCIN_CPU1 @S9S_MB_2U_LIB.S9S_MB_2U(SCH_1):PVCCIN_CPU1     I3 @S9S_MB_2U_LIB.S9S_MB_2U(SCH_1):PAGE67
  BU70 PVCCIN_CPU1 @S9S_MB_2U_LIB.S9S_MB_2U(SCH_1):PVCCIN_CPU1     I3 @S9S_MB_2U_LIB.S9S_MB_2U(SCH_1):PAGE67
  BU68 PVCCIN_CPU1 @S9S_MB_2U_LIB.S9S_MB_2U(SCH_1):PVCCIN_CPU1     I3 @S9S_MB_2U_LIB.S9S_MB_2U(SCH_1):PAGE67
  BU66 PVCCIN_CPU1 @S9S_MB_2U_LIB.S9S_MB_2U(SCH_1):PVCCIN_CPU1     I3 @S9S_MB_2U_LIB.S9S_MB_2U(SCH_1):PAGE67
  BU64 PVCCIN_CPU1 @S9S_MB_2U_LIB.S9S_MB_2U(SCH_1):PVCCIN_CPU1     I3 @S9S_MB_2U_LIB.S9S_MB_2U(SCH_1):PAGE67
  BU62 PVCCIN_CPU1 @S9S_MB_2U_LIB.S9S_MB_2U(SCH_1):PVCCIN_CPU1     I3 @S9S_MB_2U_LIB.S9S_MB_2U(SCH_1):PAGE67
  BU60 PVCCIN_CPU1 @S9S_MB_2U_LIB.S9S_MB_2U(SCH_1):PVCCIN_CPU1     I3 @S9S_MB_2U_LIB.S9S_MB_2U(SCH_1):PAGE67
  BU58 PVCCIN_CPU1 @S9S_MB_2U_LIB.S9S_MB_2U(SCH_1):PVCCIN_CPU1     I3 @S9S_MB_2U_LIB.S9S_MB_2U(SCH_1):PAGE67
  BU56 PVCCIN_CPU1 @S9S_MB_2U_LIB.S9S_MB_2U(SCH_1):PVCCIN_CPU1     I3 @S9S_MB_2U_LIB.S9S_MB_2U(SCH_1):PAGE67
  BU54 PVCCIN_CPU1 @S9S_MB_2U_LIB.S9S_MB_2U(SCH_1):PVCCIN_CPU1     I3 @S9S_MB_2U_LIB.S9S_MB_2U(SCH_1):PAGE67
  BU52 PVCCIN_CPU1 @S9S_MB_2U_LIB.S9S_MB_2U(SCH_1):PVCCIN_CPU1     I3 @S9S_MB_2U_LIB.S9S_MB_2U(SCH_1):PAGE67
  BU50 PVCCIN_CPU1 @S9S_MB_2U_LIB.S9S_MB_2U(SCH_1):PVCCIN_CPU1     I3 @S9S_MB_2U_LIB.S9S_MB_2U(SCH_1):PAGE67
  BU48 PVCCIN_CPU1 @S9S_MB_2U_LIB.S9S_MB_2U(SCH_1):PVCCIN_CPU1     I3 @S9S_MB_2U_LIB.S9S_MB_2U(SCH_1):PAGE67
  BU45 PVCCIN_CPU1 @S9S_MB_2U_LIB.S9S_MB_2U(SCH_1):PVCCIN_CPU1     I3 @S9S_MB_2U_LIB.S9S_MB_2U(SCH_1):PAGE67
  BU43 PVCCIN_CPU1 @S9S_MB_2U_LIB.S9S_MB_2U(SCH_1):PVCCIN_CPU1     I3 @S9S_MB_2U_LIB.S9S_MB_2U(SCH_1):PAGE67
  BU41 PVCCIN_CPU1 @S9S_MB_2U_LIB.S9S_MB_2U(SCH_1):PVCCIN_CPU1     I3 @S9S_MB_2U_LIB.S9S_MB_2U(SCH_1):PAGE67
  BU39 PVCCIN_CPU1 @S9S_MB_2U_LIB.S9S_MB_2U(SCH_1):PVCCIN_CPU1     I3 @S9S_MB_2U_LIB.S9S_MB_2U(SCH_1):PAGE67
  BU37 PVCCIN_CPU1 @S9S_MB_2U_LIB.S9S_MB_2U(SCH_1):PVCCIN_CPU1     I3 @S9S_MB_2U_LIB.S9S_MB_2U(SCH_1):PAGE67
  BU35 PVCCIN_CPU1 @S9S_MB_2U_LIB.S9S_MB_2U(SCH_1):PVCCIN_CPU1     I3 @S9S_MB_2U_LIB.S9S_MB_2U(SCH_1):PAGE67
  BU33 PVCCIN_CPU1 @S9S_MB_2U_LIB.S9S_MB_2U(SCH_1):PVCCIN_CPU1     I3 @S9S_MB_2U_LIB.S9S_MB_2U(SCH_1):PAGE67
  BT89 PVCCIN_CPU1 @S9S_MB_2U_LIB.S9S_MB_2U(SCH_1):PVCCIN_CPU1     I3 @S9S_MB_2U_LIB.S9S_MB_2U(SCH_1):PAGE67
  BT87 PVCCIN_CPU1 @S9S_MB_2U_LIB.S9S_MB_2U(SCH_1):PVCCIN_CPU1     I3 @S9S_MB_2U_LIB.S9S_MB_2U(SCH_1):PAGE67
  BT85 PVCCIN_CPU1 @S9S_MB_2U_LIB.S9S_MB_2U(SCH_1):PVCCIN_CPU1     I3 @S9S_MB_2U_LIB.S9S_MB_2U(SCH_1):PAGE67
  BT83 PVCCIN_CPU1 @S9S_MB_2U_LIB.S9S_MB_2U(SCH_1):PVCCIN_CPU1     I3 @S9S_MB_2U_LIB.S9S_MB_2U(SCH_1):PAGE67
  BT81 PVCCIN_CPU1 @S9S_MB_2U_LIB.S9S_MB_2U(SCH_1):PVCCIN_CPU1     I3 @S9S_MB_2U_LIB.S9S_MB_2U(SCH_1):PAGE67
  BT79 PVCCIN_CPU1 @S9S_MB_2U_LIB.S9S_MB_2U(SCH_1):PVCCIN_CPU1     I3 @S9S_MB_2U_LIB.S9S_MB_2U(SCH_1):PAGE67
  BT77 PVCCIN_CPU1 @S9S_MB_2U_LIB.S9S_MB_2U(SCH_1):PVCCIN_CPU1     I3 @S9S_MB_2U_LIB.S9S_MB_2U(SCH_1):PAGE67
  BT75 PVCCIN_CPU1 @S9S_MB_2U_LIB.S9S_MB_2U(SCH_1):PVCCIN_CPU1     I3 @S9S_MB_2U_LIB.S9S_MB_2U(SCH_1):PAGE67
  BT73 PVCCIN_CPU1 @S9S_MB_2U_LIB.S9S_MB_2U(SCH_1):PVCCIN_CPU1     I3 @S9S_MB_2U_LIB.S9S_MB_2U(SCH_1):PAGE67
  BT71 PVCCIN_CPU1 @S9S_MB_2U_LIB.S9S_MB_2U(SCH_1):PVCCIN_CPU1     I3 @S9S_MB_2U_LIB.S9S_MB_2U(SCH_1):PAGE67
  BT69 PVCCIN_CPU1 @S9S_MB_2U_LIB.S9S_MB_2U(SCH_1):PVCCIN_CPU1     I3 @S9S_MB_2U_LIB.S9S_MB_2U(SCH_1):PAGE67
  BT67 PVCCIN_CPU1 @S9S_MB_2U_LIB.S9S_MB_2U(SCH_1):PVCCIN_CPU1     I3 @S9S_MB_2U_LIB.S9S_MB_2U(SCH_1):PAGE67
  BT65 PVCCIN_CPU1 @S9S_MB_2U_LIB.S9S_MB_2U(SCH_1):PVCCIN_CPU1     I3 @S9S_MB_2U_LIB.S9S_MB_2U(SCH_1):PAGE67
  BT63 PVCCIN_CPU1 @S9S_MB_2U_LIB.S9S_MB_2U(SCH_1):PVCCIN_CPU1     I3 @S9S_MB_2U_LIB.S9S_MB_2U(SCH_1):PAGE67
  BT61 PVCCIN_CPU1 @S9S_MB_2U_LIB.S9S_MB_2U(SCH_1):PVCCIN_CPU1     I3 @S9S_MB_2U_LIB.S9S_MB_2U(SCH_1):PAGE67
  BT59 PVCCIN_CPU1 @S9S_MB_2U_LIB.S9S_MB_2U(SCH_1):PVCCIN_CPU1     I3 @S9S_MB_2U_LIB.S9S_MB_2U(SCH_1):PAGE67
  BT57 PVCCIN_CPU1 @S9S_MB_2U_LIB.S9S_MB_2U(SCH_1):PVCCIN_CPU1     I3 @S9S_MB_2U_LIB.S9S_MB_2U(SCH_1):PAGE67
  BT55 PVCCIN_CPU1 @S9S_MB_2U_LIB.S9S_MB_2U(SCH_1):PVCCIN_CPU1     I3 @S9S_MB_2U_LIB.S9S_MB_2U(SCH_1):PAGE67
  BT53 PVCCIN_CPU1 @S9S_MB_2U_LIB.S9S_MB_2U(SCH_1):PVCCIN_CPU1     I3 @S9S_MB_2U_LIB.S9S_MB_2U(SCH_1):PAGE67
  BT51 PVCCIN_CPU1 @S9S_MB_2U_LIB.S9S_MB_2U(SCH_1):PVCCIN_CPU1     I3 @S9S_MB_2U_LIB.S9S_MB_2U(SCH_1):PAGE67
  BT49 PVCCIN_CPU1 @S9S_MB_2U_LIB.S9S_MB_2U(SCH_1):PVCCIN_CPU1     I3 @S9S_MB_2U_LIB.S9S_MB_2U(SCH_1):PAGE67
  BT47 PVCCIN_CPU1 @S9S_MB_2U_LIB.S9S_MB_2U(SCH_1):PVCCIN_CPU1     I3 @S9S_MB_2U_LIB.S9S_MB_2U(SCH_1):PAGE67
  BT44 PVCCIN_CPU1 @S9S_MB_2U_LIB.S9S_MB_2U(SCH_1):PVCCIN_CPU1     I3 @S9S_MB_2U_LIB.S9S_MB_2U(SCH_1):PAGE67
  BT42 PVCCIN_CPU1 @S9S_MB_2U_LIB.S9S_MB_2U(SCH_1):PVCCIN_CPU1     I3 @S9S_MB_2U_LIB.S9S_MB_2U(SCH_1):PAGE67
  BT40 PVCCIN_CPU1 @S9S_MB_2U_LIB.S9S_MB_2U(SCH_1):PVCCIN_CPU1     I3 @S9S_MB_2U_LIB.S9S_MB_2U(SCH_1):PAGE67
  BT38 PVCCIN_CPU1 @S9S_MB_2U_LIB.S9S_MB_2U(SCH_1):PVCCIN_CPU1     I3 @S9S_MB_2U_LIB.S9S_MB_2U(SCH_1):PAGE67
  BT36 PVCCIN_CPU1 @S9S_MB_2U_LIB.S9S_MB_2U(SCH_1):PVCCIN_CPU1     I3 @S9S_MB_2U_LIB.S9S_MB_2U(SCH_1):PAGE67
  BT34 PVCCIN_CPU1 @S9S_MB_2U_LIB.S9S_MB_2U(SCH_1):PVCCIN_CPU1     I3 @S9S_MB_2U_LIB.S9S_MB_2U(SCH_1):PAGE67
  BT32 PVCCIN_CPU1 @S9S_MB_2U_LIB.S9S_MB_2U(SCH_1):PVCCIN_CPU1     I3 @S9S_MB_2U_LIB.S9S_MB_2U(SCH_1):PAGE67
  BR78 PVCCIN_CPU1 @S9S_MB_2U_LIB.S9S_MB_2U(SCH_1):PVCCIN_CPU1     I3 @S9S_MB_2U_LIB.S9S_MB_2U(SCH_1):PAGE67
  BR62 PVCCIN_CPU1 @S9S_MB_2U_LIB.S9S_MB_2U(SCH_1):PVCCIN_CPU1     I3 @S9S_MB_2U_LIB.S9S_MB_2U(SCH_1):PAGE67
  BR60 PVCCIN_CPU1 @S9S_MB_2U_LIB.S9S_MB_2U(SCH_1):PVCCIN_CPU1     I3 @S9S_MB_2U_LIB.S9S_MB_2U(SCH_1):PAGE67
  BP89 PVCCIN_CPU1 @S9S_MB_2U_LIB.S9S_MB_2U(SCH_1):PVCCIN_CPU1     I3 @S9S_MB_2U_LIB.S9S_MB_2U(SCH_1):PAGE67
  BP87 PVCCIN_CPU1 @S9S_MB_2U_LIB.S9S_MB_2U(SCH_1):PVCCIN_CPU1     I3 @S9S_MB_2U_LIB.S9S_MB_2U(SCH_1):PAGE67
  BP85 PVCCIN_CPU1 @S9S_MB_2U_LIB.S9S_MB_2U(SCH_1):PVCCIN_CPU1     I3 @S9S_MB_2U_LIB.S9S_MB_2U(SCH_1):PAGE67
  BP83 PVCCIN_CPU1 @S9S_MB_2U_LIB.S9S_MB_2U(SCH_1):PVCCIN_CPU1     I3 @S9S_MB_2U_LIB.S9S_MB_2U(SCH_1):PAGE67
  BP81 PVCCIN_CPU1 @S9S_MB_2U_LIB.S9S_MB_2U(SCH_1):PVCCIN_CPU1     I3 @S9S_MB_2U_LIB.S9S_MB_2U(SCH_1):PAGE67
  BP79 PVCCIN_CPU1 @S9S_MB_2U_LIB.S9S_MB_2U(SCH_1):PVCCIN_CPU1     I3 @S9S_MB_2U_LIB.S9S_MB_2U(SCH_1):PAGE67
  BP61 PVCCIN_CPU1 @S9S_MB_2U_LIB.S9S_MB_2U(SCH_1):PVCCIN_CPU1     I3 @S9S_MB_2U_LIB.S9S_MB_2U(SCH_1):PAGE67
  BP59 PVCCIN_CPU1 @S9S_MB_2U_LIB.S9S_MB_2U(SCH_1):PVCCIN_CPU1     I3 @S9S_MB_2U_LIB.S9S_MB_2U(SCH_1):PAGE67
  BP57 PVCCIN_CPU1 @S9S_MB_2U_LIB.S9S_MB_2U(SCH_1):PVCCIN_CPU1     I3 @S9S_MB_2U_LIB.S9S_MB_2U(SCH_1):PAGE67
  BP55 PVCCIN_CPU1 @S9S_MB_2U_LIB.S9S_MB_2U(SCH_1):PVCCIN_CPU1     I3 @S9S_MB_2U_LIB.S9S_MB_2U(SCH_1):PAGE67
  BP53 PVCCIN_CPU1 @S9S_MB_2U_LIB.S9S_MB_2U(SCH_1):PVCCIN_CPU1     I3 @S9S_MB_2U_LIB.S9S_MB_2U(SCH_1):PAGE67
  BP51 PVCCIN_CPU1 @S9S_MB_2U_LIB.S9S_MB_2U(SCH_1):PVCCIN_CPU1     I3 @S9S_MB_2U_LIB.S9S_MB_2U(SCH_1):PAGE67
  BP49 PVCCIN_CPU1 @S9S_MB_2U_LIB.S9S_MB_2U(SCH_1):PVCCIN_CPU1     I3 @S9S_MB_2U_LIB.S9S_MB_2U(SCH_1):PAGE67
  BP47 PVCCIN_CPU1 @S9S_MB_2U_LIB.S9S_MB_2U(SCH_1):PVCCIN_CPU1     I3 @S9S_MB_2U_LIB.S9S_MB_2U(SCH_1):PAGE67
  BP44 PVCCIN_CPU1 @S9S_MB_2U_LIB.S9S_MB_2U(SCH_1):PVCCIN_CPU1     I3 @S9S_MB_2U_LIB.S9S_MB_2U(SCH_1):PAGE67
  BP42 PVCCIN_CPU1 @S9S_MB_2U_LIB.S9S_MB_2U(SCH_1):PVCCIN_CPU1     I3 @S9S_MB_2U_LIB.S9S_MB_2U(SCH_1):PAGE67
  BP40 PVCCIN_CPU1 @S9S_MB_2U_LIB.S9S_MB_2U(SCH_1):PVCCIN_CPU1     I3 @S9S_MB_2U_LIB.S9S_MB_2U(SCH_1):PAGE67
  BP38 PVCCIN_CPU1 @S9S_MB_2U_LIB.S9S_MB_2U(SCH_1):PVCCIN_CPU1     I3 @S9S_MB_2U_LIB.S9S_MB_2U(SCH_1):PAGE67
  BP36 PVCCIN_CPU1 @S9S_MB_2U_LIB.S9S_MB_2U(SCH_1):PVCCIN_CPU1     I3 @S9S_MB_2U_LIB.S9S_MB_2U(SCH_1):PAGE67
  BP34 PVCCIN_CPU1 @S9S_MB_2U_LIB.S9S_MB_2U(SCH_1):PVCCIN_CPU1     I3 @S9S_MB_2U_LIB.S9S_MB_2U(SCH_1):PAGE67
  BP32 PVCCIN_CPU1 @S9S_MB_2U_LIB.S9S_MB_2U(SCH_1):PVCCIN_CPU1     I3 @S9S_MB_2U_LIB.S9S_MB_2U(SCH_1):PAGE67
  BN90 PVCCIN_CPU1 @S9S_MB_2U_LIB.S9S_MB_2U(SCH_1):PVCCIN_CPU1     I3 @S9S_MB_2U_LIB.S9S_MB_2U(SCH_1):PAGE67
  BN88 PVCCIN_CPU1 @S9S_MB_2U_LIB.S9S_MB_2U(SCH_1):PVCCIN_CPU1     I3 @S9S_MB_2U_LIB.S9S_MB_2U(SCH_1):PAGE67
  BN86 PVCCIN_CPU1 @S9S_MB_2U_LIB.S9S_MB_2U(SCH_1):PVCCIN_CPU1     I3 @S9S_MB_2U_LIB.S9S_MB_2U(SCH_1):PAGE67
  BN84 PVCCIN_CPU1 @S9S_MB_2U_LIB.S9S_MB_2U(SCH_1):PVCCIN_CPU1     I3 @S9S_MB_2U_LIB.S9S_MB_2U(SCH_1):PAGE67
  BN82 PVCCIN_CPU1 @S9S_MB_2U_LIB.S9S_MB_2U(SCH_1):PVCCIN_CPU1     I3 @S9S_MB_2U_LIB.S9S_MB_2U(SCH_1):PAGE67
  BN80 PVCCIN_CPU1 @S9S_MB_2U_LIB.S9S_MB_2U(SCH_1):PVCCIN_CPU1     I3 @S9S_MB_2U_LIB.S9S_MB_2U(SCH_1):PAGE67
  BN78 PVCCIN_CPU1 @S9S_MB_2U_LIB.S9S_MB_2U(SCH_1):PVCCIN_CPU1     I3 @S9S_MB_2U_LIB.S9S_MB_2U(SCH_1):PAGE67
  BN60 PVCCIN_CPU1 @S9S_MB_2U_LIB.S9S_MB_2U(SCH_1):PVCCIN_CPU1     I3 @S9S_MB_2U_LIB.S9S_MB_2U(SCH_1):PAGE67
  BN58 PVCCIN_CPU1 @S9S_MB_2U_LIB.S9S_MB_2U(SCH_1):PVCCIN_CPU1     I3 @S9S_MB_2U_LIB.S9S_MB_2U(SCH_1):PAGE67
  BN56 PVCCIN_CPU1 @S9S_MB_2U_LIB.S9S_MB_2U(SCH_1):PVCCIN_CPU1     I3 @S9S_MB_2U_LIB.S9S_MB_2U(SCH_1):PAGE67
  BN54 PVCCIN_CPU1 @S9S_MB_2U_LIB.S9S_MB_2U(SCH_1):PVCCIN_CPU1     I3 @S9S_MB_2U_LIB.S9S_MB_2U(SCH_1):PAGE67
  BN52 PVCCIN_CPU1 @S9S_MB_2U_LIB.S9S_MB_2U(SCH_1):PVCCIN_CPU1     I3 @S9S_MB_2U_LIB.S9S_MB_2U(SCH_1):PAGE67
  BN50 PVCCIN_CPU1 @S9S_MB_2U_LIB.S9S_MB_2U(SCH_1):PVCCIN_CPU1     I3 @S9S_MB_2U_LIB.S9S_MB_2U(SCH_1):PAGE67
  BN48 PVCCIN_CPU1 @S9S_MB_2U_LIB.S9S_MB_2U(SCH_1):PVCCIN_CPU1     I3 @S9S_MB_2U_LIB.S9S_MB_2U(SCH_1):PAGE67
  BN45 PVCCIN_CPU1 @S9S_MB_2U_LIB.S9S_MB_2U(SCH_1):PVCCIN_CPU1     I3 @S9S_MB_2U_LIB.S9S_MB_2U(SCH_1):PAGE67
  BN43 PVCCIN_CPU1 @S9S_MB_2U_LIB.S9S_MB_2U(SCH_1):PVCCIN_CPU1     I3 @S9S_MB_2U_LIB.S9S_MB_2U(SCH_1):PAGE67
  BN41 PVCCIN_CPU1 @S9S_MB_2U_LIB.S9S_MB_2U(SCH_1):PVCCIN_CPU1     I1 @S9S_MB_2U_LIB.S9S_MB_2U(SCH_1):PAGE68
  BN39 PVCCIN_CPU1 @S9S_MB_2U_LIB.S9S_MB_2U(SCH_1):PVCCIN_CPU1     I1 @S9S_MB_2U_LIB.S9S_MB_2U(SCH_1):PAGE68
  BN37 PVCCIN_CPU1 @S9S_MB_2U_LIB.S9S_MB_2U(SCH_1):PVCCIN_CPU1     I1 @S9S_MB_2U_LIB.S9S_MB_2U(SCH_1):PAGE68
  BN35 PVCCIN_CPU1 @S9S_MB_2U_LIB.S9S_MB_2U(SCH_1):PVCCIN_CPU1     I1 @S9S_MB_2U_LIB.S9S_MB_2U(SCH_1):PAGE68
  BN33 PVCCIN_CPU1 @S9S_MB_2U_LIB.S9S_MB_2U(SCH_1):PVCCIN_CPU1     I1 @S9S_MB_2U_LIB.S9S_MB_2U(SCH_1):PAGE68
  BM91 PVCCIN_CPU1 @S9S_MB_2U_LIB.S9S_MB_2U(SCH_1):PVCCIN_CPU1     I1 @S9S_MB_2U_LIB.S9S_MB_2U(SCH_1):PAGE68
  BM89 PVCCIN_CPU1 @S9S_MB_2U_LIB.S9S_MB_2U(SCH_1):PVCCIN_CPU1     I1 @S9S_MB_2U_LIB.S9S_MB_2U(SCH_1):PAGE68
  BM87 PVCCIN_CPU1 @S9S_MB_2U_LIB.S9S_MB_2U(SCH_1):PVCCIN_CPU1     I1 @S9S_MB_2U_LIB.S9S_MB_2U(SCH_1):PAGE68
  BM85 PVCCIN_CPU1 @S9S_MB_2U_LIB.S9S_MB_2U(SCH_1):PVCCIN_CPU1     I1 @S9S_MB_2U_LIB.S9S_MB_2U(SCH_1):PAGE68
  BM83 PVCCIN_CPU1 @S9S_MB_2U_LIB.S9S_MB_2U(SCH_1):PVCCIN_CPU1     I1 @S9S_MB_2U_LIB.S9S_MB_2U(SCH_1):PAGE68
  BM81 PVCCIN_CPU1 @S9S_MB_2U_LIB.S9S_MB_2U(SCH_1):PVCCIN_CPU1     I1 @S9S_MB_2U_LIB.S9S_MB_2U(SCH_1):PAGE68
  BM79 PVCCIN_CPU1 @S9S_MB_2U_LIB.S9S_MB_2U(SCH_1):PVCCIN_CPU1     I1 @S9S_MB_2U_LIB.S9S_MB_2U(SCH_1):PAGE68
  BL90 PVCCIN_CPU1 @S9S_MB_2U_LIB.S9S_MB_2U(SCH_1):PVCCIN_CPU1     I1 @S9S_MB_2U_LIB.S9S_MB_2U(SCH_1):PAGE68
  BL88 PVCCIN_CPU1 @S9S_MB_2U_LIB.S9S_MB_2U(SCH_1):PVCCIN_CPU1     I1 @S9S_MB_2U_LIB.S9S_MB_2U(SCH_1):PAGE68
  BL86 PVCCIN_CPU1 @S9S_MB_2U_LIB.S9S_MB_2U(SCH_1):PVCCIN_CPU1     I1 @S9S_MB_2U_LIB.S9S_MB_2U(SCH_1):PAGE68
  BL84 PVCCIN_CPU1 @S9S_MB_2U_LIB.S9S_MB_2U(SCH_1):PVCCIN_CPU1     I1 @S9S_MB_2U_LIB.S9S_MB_2U(SCH_1):PAGE68
  BL82 PVCCIN_CPU1 @S9S_MB_2U_LIB.S9S_MB_2U(SCH_1):PVCCIN_CPU1     I1 @S9S_MB_2U_LIB.S9S_MB_2U(SCH_1):PAGE68
  BL80 PVCCIN_CPU1 @S9S_MB_2U_LIB.S9S_MB_2U(SCH_1):PVCCIN_CPU1     I1 @S9S_MB_2U_LIB.S9S_MB_2U(SCH_1):PAGE68
  BK91 PVCCIN_CPU1 @S9S_MB_2U_LIB.S9S_MB_2U(SCH_1):PVCCIN_CPU1     I1 @S9S_MB_2U_LIB.S9S_MB_2U(SCH_1):PAGE68
  BK89 PVCCIN_CPU1 @S9S_MB_2U_LIB.S9S_MB_2U(SCH_1):PVCCIN_CPU1     I1 @S9S_MB_2U_LIB.S9S_MB_2U(SCH_1):PAGE68
  BK87 PVCCIN_CPU1 @S9S_MB_2U_LIB.S9S_MB_2U(SCH_1):PVCCIN_CPU1     I1 @S9S_MB_2U_LIB.S9S_MB_2U(SCH_1):PAGE68
  BK85 PVCCIN_CPU1 @S9S_MB_2U_LIB.S9S_MB_2U(SCH_1):PVCCIN_CPU1     I1 @S9S_MB_2U_LIB.S9S_MB_2U(SCH_1):PAGE68
  BK83 PVCCIN_CPU1 @S9S_MB_2U_LIB.S9S_MB_2U(SCH_1):PVCCIN_CPU1     I1 @S9S_MB_2U_LIB.S9S_MB_2U(SCH_1):PAGE68
  BK81 PVCCIN_CPU1 @S9S_MB_2U_LIB.S9S_MB_2U(SCH_1):PVCCIN_CPU1     I1 @S9S_MB_2U_LIB.S9S_MB_2U(SCH_1):PAGE68
  BH91 PVCCIN_CPU1 @S9S_MB_2U_LIB.S9S_MB_2U(SCH_1):PVCCIN_CPU1     I1 @S9S_MB_2U_LIB.S9S_MB_2U(SCH_1):PAGE68
  BH89 PVCCIN_CPU1 @S9S_MB_2U_LIB.S9S_MB_2U(SCH_1):PVCCIN_CPU1     I1 @S9S_MB_2U_LIB.S9S_MB_2U(SCH_1):PAGE68
  BH87 PVCCIN_CPU1 @S9S_MB_2U_LIB.S9S_MB_2U(SCH_1):PVCCIN_CPU1     I1 @S9S_MB_2U_LIB.S9S_MB_2U(SCH_1):PAGE68
  BH85 PVCCIN_CPU1 @S9S_MB_2U_LIB.S9S_MB_2U(SCH_1):PVCCIN_CPU1     I1 @S9S_MB_2U_LIB.S9S_MB_2U(SCH_1):PAGE68
  BG90 PVCCIN_CPU1 @S9S_MB_2U_LIB.S9S_MB_2U(SCH_1):PVCCIN_CPU1     I1 @S9S_MB_2U_LIB.S9S_MB_2U(SCH_1):PAGE68
  BG88 PVCCIN_CPU1 @S9S_MB_2U_LIB.S9S_MB_2U(SCH_1):PVCCIN_CPU1     I1 @S9S_MB_2U_LIB.S9S_MB_2U(SCH_1):PAGE68
  BG86 PVCCIN_CPU1 @S9S_MB_2U_LIB.S9S_MB_2U(SCH_1):PVCCIN_CPU1     I1 @S9S_MB_2U_LIB.S9S_MB_2U(SCH_1):PAGE68
  BG84 PVCCIN_CPU1 @S9S_MB_2U_LIB.S9S_MB_2U(SCH_1):PVCCIN_CPU1     I1 @S9S_MB_2U_LIB.S9S_MB_2U(SCH_1):PAGE68
  BF91 PVCCIN_CPU1 @S9S_MB_2U_LIB.S9S_MB_2U(SCH_1):PVCCIN_CPU1     I1 @S9S_MB_2U_LIB.S9S_MB_2U(SCH_1):PAGE68
  BF89 PVCCIN_CPU1 @S9S_MB_2U_LIB.S9S_MB_2U(SCH_1):PVCCIN_CPU1     I1 @S9S_MB_2U_LIB.S9S_MB_2U(SCH_1):PAGE68
  BF87 PVCCIN_CPU1 @S9S_MB_2U_LIB.S9S_MB_2U(SCH_1):PVCCIN_CPU1     I1 @S9S_MB_2U_LIB.S9S_MB_2U(SCH_1):PAGE68
  BF85 PVCCIN_CPU1 @S9S_MB_2U_LIB.S9S_MB_2U(SCH_1):PVCCIN_CPU1     I1 @S9S_MB_2U_LIB.S9S_MB_2U(SCH_1):PAGE68
  BE90 PVCCIN_CPU1 @S9S_MB_2U_LIB.S9S_MB_2U(SCH_1):PVCCIN_CPU1     I1 @S9S_MB_2U_LIB.S9S_MB_2U(SCH_1):PAGE68
  BE88 PVCCIN_CPU1 @S9S_MB_2U_LIB.S9S_MB_2U(SCH_1):PVCCIN_CPU1     I1 @S9S_MB_2U_LIB.S9S_MB_2U(SCH_1):PAGE68
  BE86 PVCCIN_CPU1 @S9S_MB_2U_LIB.S9S_MB_2U(SCH_1):PVCCIN_CPU1     I1 @S9S_MB_2U_LIB.S9S_MB_2U(SCH_1):PAGE68
  BD91 PVCCIN_CPU1 @S9S_MB_2U_LIB.S9S_MB_2U(SCH_1):PVCCIN_CPU1     I1 @S9S_MB_2U_LIB.S9S_MB_2U(SCH_1):PAGE68
  DA21 PVCCINFAON_CPU1 @S9S_MB_2U_LIB.S9S_MB_2U(SCH_1):PVCCINFAON_CPU1     I1 @S9S_MB_2U_LIB.S9S_MB_2U(SCH_1):PAGE68
  CW62 PVCCINFAON_CPU1 @S9S_MB_2U_LIB.S9S_MB_2U(SCH_1):PVCCINFAON_CPU1     I1 @S9S_MB_2U_LIB.S9S_MB_2U(SCH_1):PAGE68
  CV63 PVCCINFAON_CPU1 @S9S_MB_2U_LIB.S9S_MB_2U(SCH_1):PVCCINFAON_CPU1     I1 @S9S_MB_2U_LIB.S9S_MB_2U(SCH_1):PAGE68
  CV61 PVCCINFAON_CPU1 @S9S_MB_2U_LIB.S9S_MB_2U(SCH_1):PVCCINFAON_CPU1     I1 @S9S_MB_2U_LIB.S9S_MB_2U(SCH_1):PAGE68
  CT63 PVCCINFAON_CPU1 @S9S_MB_2U_LIB.S9S_MB_2U(SCH_1):PVCCINFAON_CPU1     I1 @S9S_MB_2U_LIB.S9S_MB_2U(SCH_1):PAGE68
  CP63 PVCCINFAON_CPU1 @S9S_MB_2U_LIB.S9S_MB_2U(SCH_1):PVCCINFAON_CPU1     I1 @S9S_MB_2U_LIB.S9S_MB_2U(SCH_1):PAGE68
  CN19 PVCCINFAON_CPU1 @S9S_MB_2U_LIB.S9S_MB_2U(SCH_1):PVCCINFAON_CPU1     I1 @S9S_MB_2U_LIB.S9S_MB_2U(SCH_1):PAGE68
  CJ19 PVCCINFAON_CPU1 @S9S_MB_2U_LIB.S9S_MB_2U(SCH_1):PVCCINFAON_CPU1     I1 @S9S_MB_2U_LIB.S9S_MB_2U(SCH_1):PAGE68
  CJ11 PVCCINFAON_CPU1 @S9S_MB_2U_LIB.S9S_MB_2U(SCH_1):PVCCINFAON_CPU1     I1 @S9S_MB_2U_LIB.S9S_MB_2U(SCH_1):PAGE68
  CE19 PVCCINFAON_CPU1 @S9S_MB_2U_LIB.S9S_MB_2U(SCH_1):PVCCINFAON_CPU1     I1 @S9S_MB_2U_LIB.S9S_MB_2U(SCH_1):PAGE68
  CA15 PVCCINFAON_CPU1 @S9S_MB_2U_LIB.S9S_MB_2U(SCH_1):PVCCINFAON_CPU1     I1 @S9S_MB_2U_LIB.S9S_MB_2U(SCH_1):PAGE68
  BN15 PVCCINFAON_CPU1 @S9S_MB_2U_LIB.S9S_MB_2U(SCH_1):PVCCINFAON_CPU1     I1 @S9S_MB_2U_LIB.S9S_MB_2U(SCH_1):PAGE68
  BK61 PVCCINFAON_CPU1 @S9S_MB_2U_LIB.S9S_MB_2U(SCH_1):PVCCINFAON_CPU1     I1 @S9S_MB_2U_LIB.S9S_MB_2U(SCH_1):PAGE68
  BJ60 PVCCINFAON_CPU1 @S9S_MB_2U_LIB.S9S_MB_2U(SCH_1):PVCCINFAON_CPU1     I1 @S9S_MB_2U_LIB.S9S_MB_2U(SCH_1):PAGE68
  BJ15 PVCCINFAON_CPU1 @S9S_MB_2U_LIB.S9S_MB_2U(SCH_1):PVCCINFAON_CPU1     I1 @S9S_MB_2U_LIB.S9S_MB_2U(SCH_1):PAGE68
  BG60 PVCCINFAON_CPU1 @S9S_MB_2U_LIB.S9S_MB_2U(SCH_1):PVCCINFAON_CPU1     I1 @S9S_MB_2U_LIB.S9S_MB_2U(SCH_1):PAGE68
  BE60 PVCCINFAON_CPU1 @S9S_MB_2U_LIB.S9S_MB_2U(SCH_1):PVCCINFAON_CPU1     I1 @S9S_MB_2U_LIB.S9S_MB_2U(SCH_1):PAGE68
  BE15 PVCCINFAON_CPU1 @S9S_MB_2U_LIB.S9S_MB_2U(SCH_1):PVCCINFAON_CPU1     I1 @S9S_MB_2U_LIB.S9S_MB_2U(SCH_1):PAGE68
  BC60 PVCCINFAON_CPU1 @S9S_MB_2U_LIB.S9S_MB_2U(SCH_1):PVCCINFAON_CPU1     I1 @S9S_MB_2U_LIB.S9S_MB_2U(SCH_1):PAGE68
  BA15 PVCCINFAON_CPU1 @S9S_MB_2U_LIB.S9S_MB_2U(SCH_1):PVCCINFAON_CPU1     I1 @S9S_MB_2U_LIB.S9S_MB_2U(SCH_1):PAGE68
  AY18 PVCCINFAON_CPU1 @S9S_MB_2U_LIB.S9S_MB_2U(SCH_1):PVCCINFAON_CPU1     I1 @S9S_MB_2U_LIB.S9S_MB_2U(SCH_1):PAGE68
  BC21 P3V3_AUX @S9S_MB_2U_LIB.S9S_MB_2U(SCH_1):P3V3_AUX     I8 @S9S_MB_2U_LIB.S9S_MB_2U(SCH_1):PAGE68
  BA21 P3V3_AUX @S9S_MB_2U_LIB.S9S_MB_2U(SCH_1):P3V3_AUX     I8 @S9S_MB_2U_LIB.S9S_MB_2U(SCH_1):PAGE68
  CY53 PVCCD_HV_CPU1 @S9S_MB_2U_LIB.S9S_MB_2U(SCH_1):PVCCD_HV_CPU1     I8 @S9S_MB_2U_LIB.S9S_MB_2U(SCH_1):PAGE68
  CY36 PVCCD_HV_CPU1 @S9S_MB_2U_LIB.S9S_MB_2U(SCH_1):PVCCD_HV_CPU1     I8 @S9S_MB_2U_LIB.S9S_MB_2U(SCH_1):PAGE68
  CW54 PVCCD_HV_CPU1 @S9S_MB_2U_LIB.S9S_MB_2U(SCH_1):PVCCD_HV_CPU1     I8 @S9S_MB_2U_LIB.S9S_MB_2U(SCH_1):PAGE68
  CY34 PVCCD_HV_CPU1 @S9S_MB_2U_LIB.S9S_MB_2U(SCH_1):PVCCD_HV_CPU1     I8 @S9S_MB_2U_LIB.S9S_MB_2U(SCH_1):PAGE68
  CW56 PVCCD_HV_CPU1 @S9S_MB_2U_LIB.S9S_MB_2U(SCH_1):PVCCD_HV_CPU1     I8 @S9S_MB_2U_LIB.S9S_MB_2U(SCH_1):PAGE68
  CW52 PVCCD_HV_CPU1 @S9S_MB_2U_LIB.S9S_MB_2U(SCH_1):PVCCD_HV_CPU1     I8 @S9S_MB_2U_LIB.S9S_MB_2U(SCH_1):PAGE68
  CW37 PVCCD_HV_CPU1 @S9S_MB_2U_LIB.S9S_MB_2U(SCH_1):PVCCD_HV_CPU1     I8 @S9S_MB_2U_LIB.S9S_MB_2U(SCH_1):PAGE68
  CW35 PVCCD_HV_CPU1 @S9S_MB_2U_LIB.S9S_MB_2U(SCH_1):PVCCD_HV_CPU1     I8 @S9S_MB_2U_LIB.S9S_MB_2U(SCH_1):PAGE68
   CE7 PVCCD_HV_CPU1 @S9S_MB_2U_LIB.S9S_MB_2U(SCH_1):PVCCD_HV_CPU1     I8 @S9S_MB_2U_LIB.S9S_MB_2U(SCH_1):PAGE68
   CA7 PVCCD_HV_CPU1 @S9S_MB_2U_LIB.S9S_MB_2U(SCH_1):PVCCD_HV_CPU1     I8 @S9S_MB_2U_LIB.S9S_MB_2U(SCH_1):PAGE68
   BN7 PVCCD_HV_CPU1 @S9S_MB_2U_LIB.S9S_MB_2U(SCH_1):PVCCD_HV_CPU1     I8 @S9S_MB_2U_LIB.S9S_MB_2U(SCH_1):PAGE68
   BJ7 PVCCD_HV_CPU1 @S9S_MB_2U_LIB.S9S_MB_2U(SCH_1):PVCCD_HV_CPU1     I8 @S9S_MB_2U_LIB.S9S_MB_2U(SCH_1):PAGE68
   BJ3 PVCCD_HV_CPU1 @S9S_MB_2U_LIB.S9S_MB_2U(SCH_1):PVCCD_HV_CPU1     I8 @S9S_MB_2U_LIB.S9S_MB_2U(SCH_1):PAGE68
  BJ11 PVCCD_HV_CPU1 @S9S_MB_2U_LIB.S9S_MB_2U(SCH_1):PVCCD_HV_CPU1     I8 @S9S_MB_2U_LIB.S9S_MB_2U(SCH_1):PAGE68
   BE7 PVCCD_HV_CPU1 @S9S_MB_2U_LIB.S9S_MB_2U(SCH_1):PVCCD_HV_CPU1     I8 @S9S_MB_2U_LIB.S9S_MB_2U(SCH_1):PAGE68
   BE3 PVCCD_HV_CPU1 @S9S_MB_2U_LIB.S9S_MB_2U(SCH_1):PVCCD_HV_CPU1     I8 @S9S_MB_2U_LIB.S9S_MB_2U(SCH_1):PAGE68
  BE11 PVCCD_HV_CPU1 @S9S_MB_2U_LIB.S9S_MB_2U(SCH_1):PVCCD_HV_CPU1     I8 @S9S_MB_2U_LIB.S9S_MB_2U(SCH_1):PAGE68
   BA7 PVCCD_HV_CPU1 @S9S_MB_2U_LIB.S9S_MB_2U(SCH_1):PVCCD_HV_CPU1     I8 @S9S_MB_2U_LIB.S9S_MB_2U(SCH_1):PAGE68
   BA3 PVCCD_HV_CPU1 @S9S_MB_2U_LIB.S9S_MB_2U(SCH_1):PVCCD_HV_CPU1     I8 @S9S_MB_2U_LIB.S9S_MB_2U(SCH_1):PAGE68
  AV55 PVCCD_HV_CPU1 @S9S_MB_2U_LIB.S9S_MB_2U(SCH_1):PVCCD_HV_CPU1     I8 @S9S_MB_2U_LIB.S9S_MB_2U(SCH_1):PAGE68
  AV53 PVCCD_HV_CPU1 @S9S_MB_2U_LIB.S9S_MB_2U(SCH_1):PVCCD_HV_CPU1     I8 @S9S_MB_2U_LIB.S9S_MB_2U(SCH_1):PAGE68
  AV36 PVCCD_HV_CPU1 @S9S_MB_2U_LIB.S9S_MB_2U(SCH_1):PVCCD_HV_CPU1     I8 @S9S_MB_2U_LIB.S9S_MB_2U(SCH_1):PAGE68
  AV34 PVCCD_HV_CPU1 @S9S_MB_2U_LIB.S9S_MB_2U(SCH_1):PVCCD_HV_CPU1     I8 @S9S_MB_2U_LIB.S9S_MB_2U(SCH_1):PAGE68
   AU7 PVCCD_HV_CPU1 @S9S_MB_2U_LIB.S9S_MB_2U(SCH_1):PVCCD_HV_CPU1     I8 @S9S_MB_2U_LIB.S9S_MB_2U(SCH_1):PAGE68
  AU54 PVCCD_HV_CPU1 @S9S_MB_2U_LIB.S9S_MB_2U(SCH_1):PVCCD_HV_CPU1     I8 @S9S_MB_2U_LIB.S9S_MB_2U(SCH_1):PAGE68
  AU35 PVCCD_HV_CPU1 @S9S_MB_2U_LIB.S9S_MB_2U(SCH_1):PVCCD_HV_CPU1     I8 @S9S_MB_2U_LIB.S9S_MB_2U(SCH_1):PAGE68
   AU3 PVCCD_HV_CPU1 @S9S_MB_2U_LIB.S9S_MB_2U(SCH_1):PVCCD_HV_CPU1     I8 @S9S_MB_2U_LIB.S9S_MB_2U(SCH_1):PAGE68
  AT55 PVCCD_HV_CPU1 @S9S_MB_2U_LIB.S9S_MB_2U(SCH_1):PVCCD_HV_CPU1     I8 @S9S_MB_2U_LIB.S9S_MB_2U(SCH_1):PAGE68
  AT36 PVCCD_HV_CPU1 @S9S_MB_2U_LIB.S9S_MB_2U(SCH_1):PVCCD_HV_CPU1     I8 @S9S_MB_2U_LIB.S9S_MB_2U(SCH_1):PAGE68
    N3 PVCCFA_EHV_CPU1 @S9S_MB_2U_LIB.S9S_MB_2U(SCH_1):PVCCFA_EHV_CPU1     I8 @S9S_MB_2U_LIB.S9S_MB_2U(SCH_1):PAGE68
    U3 PVCCFA_EHV_CPU1 @S9S_MB_2U_LIB.S9S_MB_2U(SCH_1):PVCCFA_EHV_CPU1     I8 @S9S_MB_2U_LIB.S9S_MB_2U(SCH_1):PAGE68
  AW60 PVCCFA_EHV_CPU1 @S9S_MB_2U_LIB.S9S_MB_2U(SCH_1):PVCCFA_EHV_CPU1     I8 @S9S_MB_2U_LIB.S9S_MB_2U(SCH_1):PAGE68
  AV61 PVCCFA_EHV_CPU1 @S9S_MB_2U_LIB.S9S_MB_2U(SCH_1):PVCCFA_EHV_CPU1     I8 @S9S_MB_2U_LIB.S9S_MB_2U(SCH_1):PAGE68
  AU60 PVCCFA_EHV_CPU1 @S9S_MB_2U_LIB.S9S_MB_2U(SCH_1):PVCCFA_EHV_CPU1     I8 @S9S_MB_2U_LIB.S9S_MB_2U(SCH_1):PAGE68
  AT61 PVCCFA_EHV_CPU1 @S9S_MB_2U_LIB.S9S_MB_2U(SCH_1):PVCCFA_EHV_CPU1     I8 @S9S_MB_2U_LIB.S9S_MB_2U(SCH_1):PAGE68
   AN3 PVCCFA_EHV_CPU1 @S9S_MB_2U_LIB.S9S_MB_2U(SCH_1):PVCCFA_EHV_CPU1     I8 @S9S_MB_2U_LIB.S9S_MB_2U(SCH_1):PAGE68
   AJ3 PVCCFA_EHV_CPU1 @S9S_MB_2U_LIB.S9S_MB_2U(SCH_1):PVCCFA_EHV_CPU1     I8 @S9S_MB_2U_LIB.S9S_MB_2U(SCH_1):PAGE68
   AE3 PVCCFA_EHV_CPU1 @S9S_MB_2U_LIB.S9S_MB_2U(SCH_1):PVCCFA_EHV_CPU1     I8 @S9S_MB_2U_LIB.S9S_MB_2U(SCH_1):PAGE68
   AA3 PVCCFA_EHV_CPU1 @S9S_MB_2U_LIB.S9S_MB_2U(SCH_1):PVCCFA_EHV_CPU1     I8 @S9S_MB_2U_LIB.S9S_MB_2U(SCH_1):PAGE68
  DJ11 PVCCINFAON_CPU1 @S9S_MB_2U_LIB.S9S_MB_2U(SCH_1):PVCCINFAON_CPU1     I8 @S9S_MB_2U_LIB.S9S_MB_2U(SCH_1):PAGE68
   DE7 PVCCINFAON_CPU1 @S9S_MB_2U_LIB.S9S_MB_2U(SCH_1):PVCCINFAON_CPU1     I8 @S9S_MB_2U_LIB.S9S_MB_2U(SCH_1):PAGE68
   DA7 PVCCINFAON_CPU1 @S9S_MB_2U_LIB.S9S_MB_2U(SCH_1):PVCCINFAON_CPU1     I8 @S9S_MB_2U_LIB.S9S_MB_2U(SCH_1):PAGE68
   DA3 PVCCINFAON_CPU1 @S9S_MB_2U_LIB.S9S_MB_2U(SCH_1):PVCCINFAON_CPU1     I8 @S9S_MB_2U_LIB.S9S_MB_2U(SCH_1):PAGE68
  CW64 PVCCINFAON_CPU1 @S9S_MB_2U_LIB.S9S_MB_2U(SCH_1):PVCCINFAON_CPU1     I8 @S9S_MB_2U_LIB.S9S_MB_2U(SCH_1):PAGE68
  CR66 PVCCINFAON_CPU1 @S9S_MB_2U_LIB.S9S_MB_2U(SCH_1):PVCCINFAON_CPU1     I8 @S9S_MB_2U_LIB.S9S_MB_2U(SCH_1):PAGE68
   DJ7 PVCCINFAON_CPU1 @S9S_MB_2U_LIB.S9S_MB_2U(SCH_1):PVCCINFAON_CPU1     I8 @S9S_MB_2U_LIB.S9S_MB_2U(SCH_1):PAGE68
   DJ3 PVCCINFAON_CPU1 @S9S_MB_2U_LIB.S9S_MB_2U(SCH_1):PVCCINFAON_CPU1     I8 @S9S_MB_2U_LIB.S9S_MB_2U(SCH_1):PAGE68
  DJ15 PVCCINFAON_CPU1 @S9S_MB_2U_LIB.S9S_MB_2U(SCH_1):PVCCINFAON_CPU1     I8 @S9S_MB_2U_LIB.S9S_MB_2U(SCH_1):PAGE68
   DE3 PVCCINFAON_CPU1 @S9S_MB_2U_LIB.S9S_MB_2U(SCH_1):PVCCINFAON_CPU1     I8 @S9S_MB_2U_LIB.S9S_MB_2U(SCH_1):PAGE68
  DE15 PVCCINFAON_CPU1 @S9S_MB_2U_LIB.S9S_MB_2U(SCH_1):PVCCINFAON_CPU1     I8 @S9S_MB_2U_LIB.S9S_MB_2U(SCH_1):PAGE68
  DE11 PVCCINFAON_CPU1 @S9S_MB_2U_LIB.S9S_MB_2U(SCH_1):PVCCINFAON_CPU1     I8 @S9S_MB_2U_LIB.S9S_MB_2U(SCH_1):PAGE68
  DA64 PVCCINFAON_CPU1 @S9S_MB_2U_LIB.S9S_MB_2U(SCH_1):PVCCINFAON_CPU1     I8 @S9S_MB_2U_LIB.S9S_MB_2U(SCH_1):PAGE68
  DA15 PVCCINFAON_CPU1 @S9S_MB_2U_LIB.S9S_MB_2U(SCH_1):PVCCINFAON_CPU1     I8 @S9S_MB_2U_LIB.S9S_MB_2U(SCH_1):PAGE68
  DA11 PVCCINFAON_CPU1 @S9S_MB_2U_LIB.S9S_MB_2U(SCH_1):PVCCINFAON_CPU1     I8 @S9S_MB_2U_LIB.S9S_MB_2U(SCH_1):PAGE68
  CY67 PVCCINFAON_CPU1 @S9S_MB_2U_LIB.S9S_MB_2U(SCH_1):PVCCINFAON_CPU1     I8 @S9S_MB_2U_LIB.S9S_MB_2U(SCH_1):PAGE68
  CY65 PVCCINFAON_CPU1 @S9S_MB_2U_LIB.S9S_MB_2U(SCH_1):PVCCINFAON_CPU1     I8 @S9S_MB_2U_LIB.S9S_MB_2U(SCH_1):PAGE68
  CW66 PVCCINFAON_CPU1 @S9S_MB_2U_LIB.S9S_MB_2U(SCH_1):PVCCINFAON_CPU1     I8 @S9S_MB_2U_LIB.S9S_MB_2U(SCH_1):PAGE68
  CV67 PVCCINFAON_CPU1 @S9S_MB_2U_LIB.S9S_MB_2U(SCH_1):PVCCINFAON_CPU1     I8 @S9S_MB_2U_LIB.S9S_MB_2U(SCH_1):PAGE68
  CV65 PVCCINFAON_CPU1 @S9S_MB_2U_LIB.S9S_MB_2U(SCH_1):PVCCINFAON_CPU1     I8 @S9S_MB_2U_LIB.S9S_MB_2U(SCH_1):PAGE68
   CU7 PVCCINFAON_CPU1 @S9S_MB_2U_LIB.S9S_MB_2U(SCH_1):PVCCINFAON_CPU1     I8 @S9S_MB_2U_LIB.S9S_MB_2U(SCH_1):PAGE68
  CU64 PVCCINFAON_CPU1 @S9S_MB_2U_LIB.S9S_MB_2U(SCH_1):PVCCINFAON_CPU1     I8 @S9S_MB_2U_LIB.S9S_MB_2U(SCH_1):PAGE68
   CU3 PVCCINFAON_CPU1 @S9S_MB_2U_LIB.S9S_MB_2U(SCH_1):PVCCINFAON_CPU1     I8 @S9S_MB_2U_LIB.S9S_MB_2U(SCH_1):PAGE68
  CU15 PVCCINFAON_CPU1 @S9S_MB_2U_LIB.S9S_MB_2U(SCH_1):PVCCINFAON_CPU1     I8 @S9S_MB_2U_LIB.S9S_MB_2U(SCH_1):PAGE68
  CU11 PVCCINFAON_CPU1 @S9S_MB_2U_LIB.S9S_MB_2U(SCH_1):PVCCINFAON_CPU1     I8 @S9S_MB_2U_LIB.S9S_MB_2U(SCH_1):PAGE68
  CT67 PVCCINFAON_CPU1 @S9S_MB_2U_LIB.S9S_MB_2U(SCH_1):PVCCINFAON_CPU1     I8 @S9S_MB_2U_LIB.S9S_MB_2U(SCH_1):PAGE68
  CT65 PVCCINFAON_CPU1 @S9S_MB_2U_LIB.S9S_MB_2U(SCH_1):PVCCINFAON_CPU1     I8 @S9S_MB_2U_LIB.S9S_MB_2U(SCH_1):PAGE68
  CP67 PVCCINFAON_CPU1 @S9S_MB_2U_LIB.S9S_MB_2U(SCH_1):PVCCINFAON_CPU1     I8 @S9S_MB_2U_LIB.S9S_MB_2U(SCH_1):PAGE68
  CP65 PVCCINFAON_CPU1 @S9S_MB_2U_LIB.S9S_MB_2U(SCH_1):PVCCINFAON_CPU1     I8 @S9S_MB_2U_LIB.S9S_MB_2U(SCH_1):PAGE68
   CN7 PVCCINFAON_CPU1 @S9S_MB_2U_LIB.S9S_MB_2U(SCH_1):PVCCINFAON_CPU1     I8 @S9S_MB_2U_LIB.S9S_MB_2U(SCH_1):PAGE68
  CN66 PVCCINFAON_CPU1 @S9S_MB_2U_LIB.S9S_MB_2U(SCH_1):PVCCINFAON_CPU1     I8 @S9S_MB_2U_LIB.S9S_MB_2U(SCH_1):PAGE68
  CN64 PVCCINFAON_CPU1 @S9S_MB_2U_LIB.S9S_MB_2U(SCH_1):PVCCINFAON_CPU1     I8 @S9S_MB_2U_LIB.S9S_MB_2U(SCH_1):PAGE68
   CN3 PVCCINFAON_CPU1 @S9S_MB_2U_LIB.S9S_MB_2U(SCH_1):PVCCINFAON_CPU1     I8 @S9S_MB_2U_LIB.S9S_MB_2U(SCH_1):PAGE68
  CN15 PVCCINFAON_CPU1 @S9S_MB_2U_LIB.S9S_MB_2U(SCH_1):PVCCINFAON_CPU1     I8 @S9S_MB_2U_LIB.S9S_MB_2U(SCH_1):PAGE68
  CN11 PVCCINFAON_CPU1 @S9S_MB_2U_LIB.S9S_MB_2U(SCH_1):PVCCINFAON_CPU1     I8 @S9S_MB_2U_LIB.S9S_MB_2U(SCH_1):PAGE68
   CJ7 PVCCINFAON_CPU1 @S9S_MB_2U_LIB.S9S_MB_2U(SCH_1):PVCCINFAON_CPU1     I8 @S9S_MB_2U_LIB.S9S_MB_2U(SCH_1):PAGE68
   CJ3 PVCCINFAON_CPU1 @S9S_MB_2U_LIB.S9S_MB_2U(SCH_1):PVCCINFAON_CPU1     I8 @S9S_MB_2U_LIB.S9S_MB_2U(SCH_1):PAGE68
  CJ15 PVCCINFAON_CPU1 @S9S_MB_2U_LIB.S9S_MB_2U(SCH_1):PVCCINFAON_CPU1     I8 @S9S_MB_2U_LIB.S9S_MB_2U(SCH_1):PAGE68
  CE15 PVCCINFAON_CPU1 @S9S_MB_2U_LIB.S9S_MB_2U(SCH_1):PVCCINFAON_CPU1     I8 @S9S_MB_2U_LIB.S9S_MB_2U(SCH_1):PAGE68
  BN19 PVNN_MAIN_CPU1 @S9S_MB_2U_LIB.S9S_MB_2U(SCH_1):PVNN_MAIN_CPU1     I8 @S9S_MB_2U_LIB.S9S_MB_2U(SCH_1):PAGE68
  BJ19 PVNN_MAIN_CPU1 @S9S_MB_2U_LIB.S9S_MB_2U(SCH_1):PVNN_MAIN_CPU1     I8 @S9S_MB_2U_LIB.S9S_MB_2U(SCH_1):PAGE68
  BE19 PVNN_MAIN_CPU1 @S9S_MB_2U_LIB.S9S_MB_2U(SCH_1):PVNN_MAIN_CPU1     I8 @S9S_MB_2U_LIB.S9S_MB_2U(SCH_1):PAGE68
  BA19 PVNN_MAIN_CPU1 @S9S_MB_2U_LIB.S9S_MB_2U(SCH_1):PVNN_MAIN_CPU1     I8 @S9S_MB_2U_LIB.S9S_MB_2U(SCH_1):PAGE68
  CG68 PVPP_HBM_CPU1 @S9S_MB_2U_LIB.S9S_MB_2U(SCH_1):PVPP_HBM_CPU1     I8 @S9S_MB_2U_LIB.S9S_MB_2U(SCH_1):PAGE68
  CF67 PVPP_HBM_CPU1 @S9S_MB_2U_LIB.S9S_MB_2U(SCH_1):PVPP_HBM_CPU1     I8 @S9S_MB_2U_LIB.S9S_MB_2U(SCH_1):PAGE68
  CE68 PVPP_HBM_CPU1 @S9S_MB_2U_LIB.S9S_MB_2U(SCH_1):PVPP_HBM_CPU1     I8 @S9S_MB_2U_LIB.S9S_MB_2U(SCH_1):PAGE68
  CD67 PVPP_HBM_CPU1 @S9S_MB_2U_LIB.S9S_MB_2U(SCH_1):PVPP_HBM_CPU1     I8 @S9S_MB_2U_LIB.S9S_MB_2U(SCH_1):PAGE68
  CC68 PVPP_HBM_CPU1 @S9S_MB_2U_LIB.S9S_MB_2U(SCH_1):PVPP_HBM_CPU1     I8 @S9S_MB_2U_LIB.S9S_MB_2U(SCH_1):PAGE68
   Y89 PVCCFA_EHV_FIVRA_CPU1 @S9S_MB_2U_LIB.S9S_MB_2U(SCH_1):PVCCFA_EHV_FIVRA_CPU1     I1 @S9S_MB_2U_LIB.S9S_MB_2U(SCH_1):PAGE69
   Y85 PVCCFA_EHV_FIVRA_CPU1 @S9S_MB_2U_LIB.S9S_MB_2U(SCH_1):PVCCFA_EHV_FIVRA_CPU1     I1 @S9S_MB_2U_LIB.S9S_MB_2U(SCH_1):PAGE69
   Y79 PVCCFA_EHV_FIVRA_CPU1 @S9S_MB_2U_LIB.S9S_MB_2U(SCH_1):PVCCFA_EHV_FIVRA_CPU1     I1 @S9S_MB_2U_LIB.S9S_MB_2U(SCH_1):PAGE69
   W80 PVCCFA_EHV_FIVRA_CPU1 @S9S_MB_2U_LIB.S9S_MB_2U(SCH_1):PVCCFA_EHV_FIVRA_CPU1     I1 @S9S_MB_2U_LIB.S9S_MB_2U(SCH_1):PAGE69
    U7 PVCCFA_EHV_FIVRA_CPU1 @S9S_MB_2U_LIB.S9S_MB_2U(SCH_1):PVCCFA_EHV_FIVRA_CPU1     I1 @S9S_MB_2U_LIB.S9S_MB_2U(SCH_1):PAGE69
   U15 PVCCFA_EHV_FIVRA_CPU1 @S9S_MB_2U_LIB.S9S_MB_2U(SCH_1):PVCCFA_EHV_FIVRA_CPU1     I1 @S9S_MB_2U_LIB.S9S_MB_2U(SCH_1):PAGE69
   U11 PVCCFA_EHV_FIVRA_CPU1 @S9S_MB_2U_LIB.S9S_MB_2U(SCH_1):PVCCFA_EHV_FIVRA_CPU1     I1 @S9S_MB_2U_LIB.S9S_MB_2U(SCH_1):PAGE69
   T89 PVCCFA_EHV_FIVRA_CPU1 @S9S_MB_2U_LIB.S9S_MB_2U(SCH_1):PVCCFA_EHV_FIVRA_CPU1     I1 @S9S_MB_2U_LIB.S9S_MB_2U(SCH_1):PAGE69
   T85 PVCCFA_EHV_FIVRA_CPU1 @S9S_MB_2U_LIB.S9S_MB_2U(SCH_1):PVCCFA_EHV_FIVRA_CPU1     I1 @S9S_MB_2U_LIB.S9S_MB_2U(SCH_1):PAGE69
   R80 PVCCFA_EHV_FIVRA_CPU1 @S9S_MB_2U_LIB.S9S_MB_2U(SCH_1):PVCCFA_EHV_FIVRA_CPU1     I1 @S9S_MB_2U_LIB.S9S_MB_2U(SCH_1):PAGE69
   P79 PVCCFA_EHV_FIVRA_CPU1 @S9S_MB_2U_LIB.S9S_MB_2U(SCH_1):PVCCFA_EHV_FIVRA_CPU1     I1 @S9S_MB_2U_LIB.S9S_MB_2U(SCH_1):PAGE69
    N7 PVCCFA_EHV_FIVRA_CPU1 @S9S_MB_2U_LIB.S9S_MB_2U(SCH_1):PVCCFA_EHV_FIVRA_CPU1     I1 @S9S_MB_2U_LIB.S9S_MB_2U(SCH_1):PAGE69
   N11 PVCCFA_EHV_FIVRA_CPU1 @S9S_MB_2U_LIB.S9S_MB_2U(SCH_1):PVCCFA_EHV_FIVRA_CPU1     I1 @S9S_MB_2U_LIB.S9S_MB_2U(SCH_1):PAGE69
   M89 PVCCFA_EHV_FIVRA_CPU1 @S9S_MB_2U_LIB.S9S_MB_2U(SCH_1):PVCCFA_EHV_FIVRA_CPU1     I1 @S9S_MB_2U_LIB.S9S_MB_2U(SCH_1):PAGE69
   M85 PVCCFA_EHV_FIVRA_CPU1 @S9S_MB_2U_LIB.S9S_MB_2U(SCH_1):PVCCFA_EHV_FIVRA_CPU1     I1 @S9S_MB_2U_LIB.S9S_MB_2U(SCH_1):PAGE69
   L84 PVCCFA_EHV_FIVRA_CPU1 @S9S_MB_2U_LIB.S9S_MB_2U(SCH_1):PVCCFA_EHV_FIVRA_CPU1     I1 @S9S_MB_2U_LIB.S9S_MB_2U(SCH_1):PAGE69
   K87 PVCCFA_EHV_FIVRA_CPU1 @S9S_MB_2U_LIB.S9S_MB_2U(SCH_1):PVCCFA_EHV_FIVRA_CPU1     I1 @S9S_MB_2U_LIB.S9S_MB_2U(SCH_1):PAGE69
   J80 PVCCFA_EHV_FIVRA_CPU1 @S9S_MB_2U_LIB.S9S_MB_2U(SCH_1):PVCCFA_EHV_FIVRA_CPU1     I1 @S9S_MB_2U_LIB.S9S_MB_2U(SCH_1):PAGE69
    J7 PVCCFA_EHV_FIVRA_CPU1 @S9S_MB_2U_LIB.S9S_MB_2U(SCH_1):PVCCFA_EHV_FIVRA_CPU1     I1 @S9S_MB_2U_LIB.S9S_MB_2U(SCH_1):PAGE69
   J11 PVCCFA_EHV_FIVRA_CPU1 @S9S_MB_2U_LIB.S9S_MB_2U(SCH_1):PVCCFA_EHV_FIVRA_CPU1     I1 @S9S_MB_2U_LIB.S9S_MB_2U(SCH_1):PAGE69
   H89 PVCCFA_EHV_FIVRA_CPU1 @S9S_MB_2U_LIB.S9S_MB_2U(SCH_1):PVCCFA_EHV_FIVRA_CPU1     I1 @S9S_MB_2U_LIB.S9S_MB_2U(SCH_1):PAGE69
  EN84 PVCCFA_EHV_FIVRA_CPU1 @S9S_MB_2U_LIB.S9S_MB_2U(SCH_1):PVCCFA_EHV_FIVRA_CPU1     I1 @S9S_MB_2U_LIB.S9S_MB_2U(SCH_1):PAGE69
  EJ84 PVCCFA_EHV_FIVRA_CPU1 @S9S_MB_2U_LIB.S9S_MB_2U(SCH_1):PVCCFA_EHV_FIVRA_CPU1     I1 @S9S_MB_2U_LIB.S9S_MB_2U(SCH_1):PAGE69
  EJ15 PVCCFA_EHV_FIVRA_CPU1 @S9S_MB_2U_LIB.S9S_MB_2U(SCH_1):PVCCFA_EHV_FIVRA_CPU1     I1 @S9S_MB_2U_LIB.S9S_MB_2U(SCH_1):PAGE69
  EG80 PVCCFA_EHV_FIVRA_CPU1 @S9S_MB_2U_LIB.S9S_MB_2U(SCH_1):PVCCFA_EHV_FIVRA_CPU1     I1 @S9S_MB_2U_LIB.S9S_MB_2U(SCH_1):PAGE69
  EF79 PVCCFA_EHV_FIVRA_CPU1 @S9S_MB_2U_LIB.S9S_MB_2U(SCH_1):PVCCFA_EHV_FIVRA_CPU1     I1 @S9S_MB_2U_LIB.S9S_MB_2U(SCH_1):PAGE69
  EE84 PVCCFA_EHV_FIVRA_CPU1 @S9S_MB_2U_LIB.S9S_MB_2U(SCH_1):PVCCFA_EHV_FIVRA_CPU1     I1 @S9S_MB_2U_LIB.S9S_MB_2U(SCH_1):PAGE69
   EE7 PVCCFA_EHV_FIVRA_CPU1 @S9S_MB_2U_LIB.S9S_MB_2U(SCH_1):PVCCFA_EHV_FIVRA_CPU1     I1 @S9S_MB_2U_LIB.S9S_MB_2U(SCH_1):PAGE69
  EE15 PVCCFA_EHV_FIVRA_CPU1 @S9S_MB_2U_LIB.S9S_MB_2U(SCH_1):PVCCFA_EHV_FIVRA_CPU1     I1 @S9S_MB_2U_LIB.S9S_MB_2U(SCH_1):PAGE69
  EE11 PVCCFA_EHV_FIVRA_CPU1 @S9S_MB_2U_LIB.S9S_MB_2U(SCH_1):PVCCFA_EHV_FIVRA_CPU1     I1 @S9S_MB_2U_LIB.S9S_MB_2U(SCH_1):PAGE69
  ED89 PVCCFA_EHV_FIVRA_CPU1 @S9S_MB_2U_LIB.S9S_MB_2U(SCH_1):PVCCFA_EHV_FIVRA_CPU1     I1 @S9S_MB_2U_LIB.S9S_MB_2U(SCH_1):PAGE69
  ED85 PVCCFA_EHV_FIVRA_CPU1 @S9S_MB_2U_LIB.S9S_MB_2U(SCH_1):PVCCFA_EHV_FIVRA_CPU1     I1 @S9S_MB_2U_LIB.S9S_MB_2U(SCH_1):PAGE69
  ED79 PVCCFA_EHV_FIVRA_CPU1 @S9S_MB_2U_LIB.S9S_MB_2U(SCH_1):PVCCFA_EHV_FIVRA_CPU1     I1 @S9S_MB_2U_LIB.S9S_MB_2U(SCH_1):PAGE69
  EC78 PVCCFA_EHV_FIVRA_CPU1 @S9S_MB_2U_LIB.S9S_MB_2U(SCH_1):PVCCFA_EHV_FIVRA_CPU1     I1 @S9S_MB_2U_LIB.S9S_MB_2U(SCH_1):PAGE69
   EA7 PVCCFA_EHV_FIVRA_CPU1 @S9S_MB_2U_LIB.S9S_MB_2U(SCH_1):PVCCFA_EHV_FIVRA_CPU1     I1 @S9S_MB_2U_LIB.S9S_MB_2U(SCH_1):PAGE69
   EA3 PVCCFA_EHV_FIVRA_CPU1 @S9S_MB_2U_LIB.S9S_MB_2U(SCH_1):PVCCFA_EHV_FIVRA_CPU1     I1 @S9S_MB_2U_LIB.S9S_MB_2U(SCH_1):PAGE69
  EA15 PVCCFA_EHV_FIVRA_CPU1 @S9S_MB_2U_LIB.S9S_MB_2U(SCH_1):PVCCFA_EHV_FIVRA_CPU1     I1 @S9S_MB_2U_LIB.S9S_MB_2U(SCH_1):PAGE69
  EA11 PVCCFA_EHV_FIVRA_CPU1 @S9S_MB_2U_LIB.S9S_MB_2U(SCH_1):PVCCFA_EHV_FIVRA_CPU1     I1 @S9S_MB_2U_LIB.S9S_MB_2U(SCH_1):PAGE69
  DY89 PVCCFA_EHV_FIVRA_CPU1 @S9S_MB_2U_LIB.S9S_MB_2U(SCH_1):PVCCFA_EHV_FIVRA_CPU1     I1 @S9S_MB_2U_LIB.S9S_MB_2U(SCH_1):PAGE69
  DY85 PVCCFA_EHV_FIVRA_CPU1 @S9S_MB_2U_LIB.S9S_MB_2U(SCH_1):PVCCFA_EHV_FIVRA_CPU1     I1 @S9S_MB_2U_LIB.S9S_MB_2U(SCH_1):PAGE69
   DU7 PVCCFA_EHV_FIVRA_CPU1 @S9S_MB_2U_LIB.S9S_MB_2U(SCH_1):PVCCFA_EHV_FIVRA_CPU1     I1 @S9S_MB_2U_LIB.S9S_MB_2U(SCH_1):PAGE69
   DU3 PVCCFA_EHV_FIVRA_CPU1 @S9S_MB_2U_LIB.S9S_MB_2U(SCH_1):PVCCFA_EHV_FIVRA_CPU1     I1 @S9S_MB_2U_LIB.S9S_MB_2U(SCH_1):PAGE69
  DU15 PVCCFA_EHV_FIVRA_CPU1 @S9S_MB_2U_LIB.S9S_MB_2U(SCH_1):PVCCFA_EHV_FIVRA_CPU1     I1 @S9S_MB_2U_LIB.S9S_MB_2U(SCH_1):PAGE69
  DU11 PVCCFA_EHV_FIVRA_CPU1 @S9S_MB_2U_LIB.S9S_MB_2U(SCH_1):PVCCFA_EHV_FIVRA_CPU1     I1 @S9S_MB_2U_LIB.S9S_MB_2U(SCH_1):PAGE69
  DT89 PVCCFA_EHV_FIVRA_CPU1 @S9S_MB_2U_LIB.S9S_MB_2U(SCH_1):PVCCFA_EHV_FIVRA_CPU1     I1 @S9S_MB_2U_LIB.S9S_MB_2U(SCH_1):PAGE69
  DT85 PVCCFA_EHV_FIVRA_CPU1 @S9S_MB_2U_LIB.S9S_MB_2U(SCH_1):PVCCFA_EHV_FIVRA_CPU1     I1 @S9S_MB_2U_LIB.S9S_MB_2U(SCH_1):PAGE69
  DT79 PVCCFA_EHV_FIVRA_CPU1 @S9S_MB_2U_LIB.S9S_MB_2U(SCH_1):PVCCFA_EHV_FIVRA_CPU1     I1 @S9S_MB_2U_LIB.S9S_MB_2U(SCH_1):PAGE69
   DN7 PVCCFA_EHV_FIVRA_CPU1 @S9S_MB_2U_LIB.S9S_MB_2U(SCH_1):PVCCFA_EHV_FIVRA_CPU1     I1 @S9S_MB_2U_LIB.S9S_MB_2U(SCH_1):PAGE69
   DN3 PVCCFA_EHV_FIVRA_CPU1 @S9S_MB_2U_LIB.S9S_MB_2U(SCH_1):PVCCFA_EHV_FIVRA_CPU1     I1 @S9S_MB_2U_LIB.S9S_MB_2U(SCH_1):PAGE69
  DN15 PVCCFA_EHV_FIVRA_CPU1 @S9S_MB_2U_LIB.S9S_MB_2U(SCH_1):PVCCFA_EHV_FIVRA_CPU1     I1 @S9S_MB_2U_LIB.S9S_MB_2U(SCH_1):PAGE69
  DN11 PVCCFA_EHV_FIVRA_CPU1 @S9S_MB_2U_LIB.S9S_MB_2U(SCH_1):PVCCFA_EHV_FIVRA_CPU1     I1 @S9S_MB_2U_LIB.S9S_MB_2U(SCH_1):PAGE69
  DM89 PVCCFA_EHV_FIVRA_CPU1 @S9S_MB_2U_LIB.S9S_MB_2U(SCH_1):PVCCFA_EHV_FIVRA_CPU1     I1 @S9S_MB_2U_LIB.S9S_MB_2U(SCH_1):PAGE69
  DM85 PVCCFA_EHV_FIVRA_CPU1 @S9S_MB_2U_LIB.S9S_MB_2U(SCH_1):PVCCFA_EHV_FIVRA_CPU1     I1 @S9S_MB_2U_LIB.S9S_MB_2U(SCH_1):PAGE69
  DM83 PVCCFA_EHV_FIVRA_CPU1 @S9S_MB_2U_LIB.S9S_MB_2U(SCH_1):PVCCFA_EHV_FIVRA_CPU1     I1 @S9S_MB_2U_LIB.S9S_MB_2U(SCH_1):PAGE69
  DH89 PVCCFA_EHV_FIVRA_CPU1 @S9S_MB_2U_LIB.S9S_MB_2U(SCH_1):PVCCFA_EHV_FIVRA_CPU1     I1 @S9S_MB_2U_LIB.S9S_MB_2U(SCH_1):PAGE69
  DD89 PVCCFA_EHV_FIVRA_CPU1 @S9S_MB_2U_LIB.S9S_MB_2U(SCH_1):PVCCFA_EHV_FIVRA_CPU1     I1 @S9S_MB_2U_LIB.S9S_MB_2U(SCH_1):PAGE69
  DD85 PVCCFA_EHV_FIVRA_CPU1 @S9S_MB_2U_LIB.S9S_MB_2U(SCH_1):PVCCFA_EHV_FIVRA_CPU1     I1 @S9S_MB_2U_LIB.S9S_MB_2U(SCH_1):PAGE69
  DD83 PVCCFA_EHV_FIVRA_CPU1 @S9S_MB_2U_LIB.S9S_MB_2U(SCH_1):PVCCFA_EHV_FIVRA_CPU1     I1 @S9S_MB_2U_LIB.S9S_MB_2U(SCH_1):PAGE69
  DD77 PVCCFA_EHV_FIVRA_CPU1 @S9S_MB_2U_LIB.S9S_MB_2U(SCH_1):PVCCFA_EHV_FIVRA_CPU1     I1 @S9S_MB_2U_LIB.S9S_MB_2U(SCH_1):PAGE69
  CY89 PVCCFA_EHV_FIVRA_CPU1 @S9S_MB_2U_LIB.S9S_MB_2U(SCH_1):PVCCFA_EHV_FIVRA_CPU1     I1 @S9S_MB_2U_LIB.S9S_MB_2U(SCH_1):PAGE69
  CY85 PVCCFA_EHV_FIVRA_CPU1 @S9S_MB_2U_LIB.S9S_MB_2U(SCH_1):PVCCFA_EHV_FIVRA_CPU1     I1 @S9S_MB_2U_LIB.S9S_MB_2U(SCH_1):PAGE69
  CY79 PVCCFA_EHV_FIVRA_CPU1 @S9S_MB_2U_LIB.S9S_MB_2U(SCH_1):PVCCFA_EHV_FIVRA_CPU1     I1 @S9S_MB_2U_LIB.S9S_MB_2U(SCH_1):PAGE69
  CY75 PVCCFA_EHV_FIVRA_CPU1 @S9S_MB_2U_LIB.S9S_MB_2U(SCH_1):PVCCFA_EHV_FIVRA_CPU1     I1 @S9S_MB_2U_LIB.S9S_MB_2U(SCH_1):PAGE69
  CT85 PVCCFA_EHV_FIVRA_CPU1 @S9S_MB_2U_LIB.S9S_MB_2U(SCH_1):PVCCFA_EHV_FIVRA_CPU1     I1 @S9S_MB_2U_LIB.S9S_MB_2U(SCH_1):PAGE69
  CT77 PVCCFA_EHV_FIVRA_CPU1 @S9S_MB_2U_LIB.S9S_MB_2U(SCH_1):PVCCFA_EHV_FIVRA_CPU1     I1 @S9S_MB_2U_LIB.S9S_MB_2U(SCH_1):PAGE69
  CP73 PVCCFA_EHV_FIVRA_CPU1 @S9S_MB_2U_LIB.S9S_MB_2U(SCH_1):PVCCFA_EHV_FIVRA_CPU1     I1 @S9S_MB_2U_LIB.S9S_MB_2U(SCH_1):PAGE69
  CN78 PVCCFA_EHV_FIVRA_CPU1 @S9S_MB_2U_LIB.S9S_MB_2U(SCH_1):PVCCFA_EHV_FIVRA_CPU1     I1 @S9S_MB_2U_LIB.S9S_MB_2U(SCH_1):PAGE69
  CM73 PVCCFA_EHV_FIVRA_CPU1 @S9S_MB_2U_LIB.S9S_MB_2U(SCH_1):PVCCFA_EHV_FIVRA_CPU1     I1 @S9S_MB_2U_LIB.S9S_MB_2U(SCH_1):PAGE69
  CK79 PVCCFA_EHV_FIVRA_CPU1 @S9S_MB_2U_LIB.S9S_MB_2U(SCH_1):PVCCFA_EHV_FIVRA_CPU1     I1 @S9S_MB_2U_LIB.S9S_MB_2U(SCH_1):PAGE69
  CK73 PVCCFA_EHV_FIVRA_CPU1 @S9S_MB_2U_LIB.S9S_MB_2U(SCH_1):PVCCFA_EHV_FIVRA_CPU1     I1 @S9S_MB_2U_LIB.S9S_MB_2U(SCH_1):PAGE69
  CE74 PVCCFA_EHV_FIVRA_CPU1 @S9S_MB_2U_LIB.S9S_MB_2U(SCH_1):PVCCFA_EHV_FIVRA_CPU1     I1 @S9S_MB_2U_LIB.S9S_MB_2U(SCH_1):PAGE69
   C88 PVCCFA_EHV_FIVRA_CPU1 @S9S_MB_2U_LIB.S9S_MB_2U(SCH_1):PVCCFA_EHV_FIVRA_CPU1     I1 @S9S_MB_2U_LIB.S9S_MB_2U(SCH_1):PAGE69
   C84 PVCCFA_EHV_FIVRA_CPU1 @S9S_MB_2U_LIB.S9S_MB_2U(SCH_1):PVCCFA_EHV_FIVRA_CPU1     I1 @S9S_MB_2U_LIB.S9S_MB_2U(SCH_1):PAGE69
  BJ78 PVCCFA_EHV_FIVRA_CPU1 @S9S_MB_2U_LIB.S9S_MB_2U(SCH_1):PVCCFA_EHV_FIVRA_CPU1     I1 @S9S_MB_2U_LIB.S9S_MB_2U(SCH_1):PAGE69
  BJ72 PVCCFA_EHV_FIVRA_CPU1 @S9S_MB_2U_LIB.S9S_MB_2U(SCH_1):PVCCFA_EHV_FIVRA_CPU1     I1 @S9S_MB_2U_LIB.S9S_MB_2U(SCH_1):PAGE69
  BH79 PVCCFA_EHV_FIVRA_CPU1 @S9S_MB_2U_LIB.S9S_MB_2U(SCH_1):PVCCFA_EHV_FIVRA_CPU1     I1 @S9S_MB_2U_LIB.S9S_MB_2U(SCH_1):PAGE69
  BF77 PVCCFA_EHV_FIVRA_CPU1 @S9S_MB_2U_LIB.S9S_MB_2U(SCH_1):PVCCFA_EHV_FIVRA_CPU1     I1 @S9S_MB_2U_LIB.S9S_MB_2U(SCH_1):PAGE69
  BE72 PVCCFA_EHV_FIVRA_CPU1 @S9S_MB_2U_LIB.S9S_MB_2U(SCH_1):PVCCFA_EHV_FIVRA_CPU1     I1 @S9S_MB_2U_LIB.S9S_MB_2U(SCH_1):PAGE69
  AY89 PVCCFA_EHV_FIVRA_CPU1 @S9S_MB_2U_LIB.S9S_MB_2U(SCH_1):PVCCFA_EHV_FIVRA_CPU1     I1 @S9S_MB_2U_LIB.S9S_MB_2U(SCH_1):PAGE69
  AW76 PVCCFA_EHV_FIVRA_CPU1 @S9S_MB_2U_LIB.S9S_MB_2U(SCH_1):PVCCFA_EHV_FIVRA_CPU1     I1 @S9S_MB_2U_LIB.S9S_MB_2U(SCH_1):PAGE69
  AU15 PVCCFA_EHV_FIVRA_CPU1 @S9S_MB_2U_LIB.S9S_MB_2U(SCH_1):PVCCFA_EHV_FIVRA_CPU1     I1 @S9S_MB_2U_LIB.S9S_MB_2U(SCH_1):PAGE69
  AT89 PVCCFA_EHV_FIVRA_CPU1 @S9S_MB_2U_LIB.S9S_MB_2U(SCH_1):PVCCFA_EHV_FIVRA_CPU1     I1 @S9S_MB_2U_LIB.S9S_MB_2U(SCH_1):PAGE69
  AT73 PVCCFA_EHV_FIVRA_CPU1 @S9S_MB_2U_LIB.S9S_MB_2U(SCH_1):PVCCFA_EHV_FIVRA_CPU1     I1 @S9S_MB_2U_LIB.S9S_MB_2U(SCH_1):PAGE69
  AN80 PVCCFA_EHV_FIVRA_CPU1 @S9S_MB_2U_LIB.S9S_MB_2U(SCH_1):PVCCFA_EHV_FIVRA_CPU1     I1 @S9S_MB_2U_LIB.S9S_MB_2U(SCH_1):PAGE69
   AN7 PVCCFA_EHV_FIVRA_CPU1 @S9S_MB_2U_LIB.S9S_MB_2U(SCH_1):PVCCFA_EHV_FIVRA_CPU1     I1 @S9S_MB_2U_LIB.S9S_MB_2U(SCH_1):PAGE69
  AN15 PVCCFA_EHV_FIVRA_CPU1 @S9S_MB_2U_LIB.S9S_MB_2U(SCH_1):PVCCFA_EHV_FIVRA_CPU1     I1 @S9S_MB_2U_LIB.S9S_MB_2U(SCH_1):PAGE69
  AN11 PVCCFA_EHV_FIVRA_CPU1 @S9S_MB_2U_LIB.S9S_MB_2U(SCH_1):PVCCFA_EHV_FIVRA_CPU1     I1 @S9S_MB_2U_LIB.S9S_MB_2U(SCH_1):PAGE69
  AM89 PVCCFA_EHV_FIVRA_CPU1 @S9S_MB_2U_LIB.S9S_MB_2U(SCH_1):PVCCFA_EHV_FIVRA_CPU1     I1 @S9S_MB_2U_LIB.S9S_MB_2U(SCH_1):PAGE69
  AM85 PVCCFA_EHV_FIVRA_CPU1 @S9S_MB_2U_LIB.S9S_MB_2U(SCH_1):PVCCFA_EHV_FIVRA_CPU1     I1 @S9S_MB_2U_LIB.S9S_MB_2U(SCH_1):PAGE69
  AM79 PVCCFA_EHV_FIVRA_CPU1 @S9S_MB_2U_LIB.S9S_MB_2U(SCH_1):PVCCFA_EHV_FIVRA_CPU1     I1 @S9S_MB_2U_LIB.S9S_MB_2U(SCH_1):PAGE69
   AJ7 PVCCFA_EHV_FIVRA_CPU1 @S9S_MB_2U_LIB.S9S_MB_2U(SCH_1):PVCCFA_EHV_FIVRA_CPU1     I1 @S9S_MB_2U_LIB.S9S_MB_2U(SCH_1):PAGE69
  AJ15 PVCCFA_EHV_FIVRA_CPU1 @S9S_MB_2U_LIB.S9S_MB_2U(SCH_1):PVCCFA_EHV_FIVRA_CPU1     I1 @S9S_MB_2U_LIB.S9S_MB_2U(SCH_1):PAGE69
  AJ11 PVCCFA_EHV_FIVRA_CPU1 @S9S_MB_2U_LIB.S9S_MB_2U(SCH_1):PVCCFA_EHV_FIVRA_CPU1     I1 @S9S_MB_2U_LIB.S9S_MB_2U(SCH_1):PAGE69
  AH89 PVCCFA_EHV_FIVRA_CPU1 @S9S_MB_2U_LIB.S9S_MB_2U(SCH_1):PVCCFA_EHV_FIVRA_CPU1     I1 @S9S_MB_2U_LIB.S9S_MB_2U(SCH_1):PAGE69
  AH85 PVCCFA_EHV_FIVRA_CPU1 @S9S_MB_2U_LIB.S9S_MB_2U(SCH_1):PVCCFA_EHV_FIVRA_CPU1     I1 @S9S_MB_2U_LIB.S9S_MB_2U(SCH_1):PAGE69
  AG78 PVCCFA_EHV_FIVRA_CPU1 @S9S_MB_2U_LIB.S9S_MB_2U(SCH_1):PVCCFA_EHV_FIVRA_CPU1     I1 @S9S_MB_2U_LIB.S9S_MB_2U(SCH_1):PAGE69
  AF77 PVCCFA_EHV_FIVRA_CPU1 @S9S_MB_2U_LIB.S9S_MB_2U(SCH_1):PVCCFA_EHV_FIVRA_CPU1     I1 @S9S_MB_2U_LIB.S9S_MB_2U(SCH_1):PAGE69
   AE7 PVCCFA_EHV_FIVRA_CPU1 @S9S_MB_2U_LIB.S9S_MB_2U(SCH_1):PVCCFA_EHV_FIVRA_CPU1     I1 @S9S_MB_2U_LIB.S9S_MB_2U(SCH_1):PAGE69
  AE15 PVCCFA_EHV_FIVRA_CPU1 @S9S_MB_2U_LIB.S9S_MB_2U(SCH_1):PVCCFA_EHV_FIVRA_CPU1     I1 @S9S_MB_2U_LIB.S9S_MB_2U(SCH_1):PAGE69
  AE11 PVCCFA_EHV_FIVRA_CPU1 @S9S_MB_2U_LIB.S9S_MB_2U(SCH_1):PVCCFA_EHV_FIVRA_CPU1     I1 @S9S_MB_2U_LIB.S9S_MB_2U(SCH_1):PAGE69
  AD89 PVCCFA_EHV_FIVRA_CPU1 @S9S_MB_2U_LIB.S9S_MB_2U(SCH_1):PVCCFA_EHV_FIVRA_CPU1     I1 @S9S_MB_2U_LIB.S9S_MB_2U(SCH_1):PAGE69
  AD85 PVCCFA_EHV_FIVRA_CPU1 @S9S_MB_2U_LIB.S9S_MB_2U(SCH_1):PVCCFA_EHV_FIVRA_CPU1     I1 @S9S_MB_2U_LIB.S9S_MB_2U(SCH_1):PAGE69
   AA7 PVCCFA_EHV_FIVRA_CPU1 @S9S_MB_2U_LIB.S9S_MB_2U(SCH_1):PVCCFA_EHV_FIVRA_CPU1     I1 @S9S_MB_2U_LIB.S9S_MB_2U(SCH_1):PAGE69
  AA15 PVCCFA_EHV_FIVRA_CPU1 @S9S_MB_2U_LIB.S9S_MB_2U(SCH_1):PVCCFA_EHV_FIVRA_CPU1     I1 @S9S_MB_2U_LIB.S9S_MB_2U(SCH_1):PAGE69
  AA11 PVCCFA_EHV_FIVRA_CPU1 @S9S_MB_2U_LIB.S9S_MB_2U(SCH_1):PVCCFA_EHV_FIVRA_CPU1     I1 @S9S_MB_2U_LIB.S9S_MB_2U(SCH_1):PAGE69
  ER41    GND @S9S_MB_2U_LIB.S9S_MB_2U(SCH_1):GND     I2 @S9S_MB_2U_LIB.S9S_MB_2U(SCH_1):PAGE70
  ER43    GND @S9S_MB_2U_LIB.S9S_MB_2U(SCH_1):GND     I2 @S9S_MB_2U_LIB.S9S_MB_2U(SCH_1):PAGE70
  ER48    GND @S9S_MB_2U_LIB.S9S_MB_2U(SCH_1):GND     I2 @S9S_MB_2U_LIB.S9S_MB_2U(SCH_1):PAGE70
  ER50    GND @S9S_MB_2U_LIB.S9S_MB_2U(SCH_1):GND     I2 @S9S_MB_2U_LIB.S9S_MB_2U(SCH_1):PAGE70
  ET57    GND @S9S_MB_2U_LIB.S9S_MB_2U(SCH_1):GND     I2 @S9S_MB_2U_LIB.S9S_MB_2U(SCH_1):PAGE70
  ET38    GND @S9S_MB_2U_LIB.S9S_MB_2U(SCH_1):GND     I2 @S9S_MB_2U_LIB.S9S_MB_2U(SCH_1):PAGE70
  ET34    GND @S9S_MB_2U_LIB.S9S_MB_2U(SCH_1):GND     I2 @S9S_MB_2U_LIB.S9S_MB_2U(SCH_1):PAGE70
  ET28    GND @S9S_MB_2U_LIB.S9S_MB_2U(SCH_1):GND     I2 @S9S_MB_2U_LIB.S9S_MB_2U(SCH_1):PAGE70
  ET22    GND @S9S_MB_2U_LIB.S9S_MB_2U(SCH_1):GND     I2 @S9S_MB_2U_LIB.S9S_MB_2U(SCH_1):PAGE70
  ET16    GND @S9S_MB_2U_LIB.S9S_MB_2U(SCH_1):GND     I2 @S9S_MB_2U_LIB.S9S_MB_2U(SCH_1):PAGE70
  ET10    GND @S9S_MB_2U_LIB.S9S_MB_2U(SCH_1):GND     I2 @S9S_MB_2U_LIB.S9S_MB_2U(SCH_1):PAGE70
  ER86    GND @S9S_MB_2U_LIB.S9S_MB_2U(SCH_1):GND     I2 @S9S_MB_2U_LIB.S9S_MB_2U(SCH_1):PAGE70
  ER84    GND @S9S_MB_2U_LIB.S9S_MB_2U(SCH_1):GND     I2 @S9S_MB_2U_LIB.S9S_MB_2U(SCH_1):PAGE70
  ER80    GND @S9S_MB_2U_LIB.S9S_MB_2U(SCH_1):GND     I2 @S9S_MB_2U_LIB.S9S_MB_2U(SCH_1):PAGE70
  ER78    GND @S9S_MB_2U_LIB.S9S_MB_2U(SCH_1):GND     I2 @S9S_MB_2U_LIB.S9S_MB_2U(SCH_1):PAGE70
  ER74    GND @S9S_MB_2U_LIB.S9S_MB_2U(SCH_1):GND     I2 @S9S_MB_2U_LIB.S9S_MB_2U(SCH_1):PAGE70
  ER70    GND @S9S_MB_2U_LIB.S9S_MB_2U(SCH_1):GND     I2 @S9S_MB_2U_LIB.S9S_MB_2U(SCH_1):PAGE70
   ER7    GND @S9S_MB_2U_LIB.S9S_MB_2U(SCH_1):GND     I2 @S9S_MB_2U_LIB.S9S_MB_2U(SCH_1):PAGE70
   ER5    GND @S9S_MB_2U_LIB.S9S_MB_2U(SCH_1):GND     I2 @S9S_MB_2U_LIB.S9S_MB_2U(SCH_1):PAGE70
  ER33    GND @S9S_MB_2U_LIB.S9S_MB_2U(SCH_1):GND     I2 @S9S_MB_2U_LIB.S9S_MB_2U(SCH_1):PAGE70
  ER27    GND @S9S_MB_2U_LIB.S9S_MB_2U(SCH_1):GND     I2 @S9S_MB_2U_LIB.S9S_MB_2U(SCH_1):PAGE70
  EP83    GND @S9S_MB_2U_LIB.S9S_MB_2U(SCH_1):GND     I2 @S9S_MB_2U_LIB.S9S_MB_2U(SCH_1):PAGE70
  EP67    GND @S9S_MB_2U_LIB.S9S_MB_2U(SCH_1):GND     I2 @S9S_MB_2U_LIB.S9S_MB_2U(SCH_1):PAGE70
  EN80    GND @S9S_MB_2U_LIB.S9S_MB_2U(SCH_1):GND     I2 @S9S_MB_2U_LIB.S9S_MB_2U(SCH_1):PAGE70
  EN78    GND @S9S_MB_2U_LIB.S9S_MB_2U(SCH_1):GND     I2 @S9S_MB_2U_LIB.S9S_MB_2U(SCH_1):PAGE70
  EN64    GND @S9S_MB_2U_LIB.S9S_MB_2U(SCH_1):GND     I2 @S9S_MB_2U_LIB.S9S_MB_2U(SCH_1):PAGE70
  EN56    GND @S9S_MB_2U_LIB.S9S_MB_2U(SCH_1):GND     I2 @S9S_MB_2U_LIB.S9S_MB_2U(SCH_1):PAGE70
  EN54    GND @S9S_MB_2U_LIB.S9S_MB_2U(SCH_1):GND     I2 @S9S_MB_2U_LIB.S9S_MB_2U(SCH_1):PAGE70
  EN52    GND @S9S_MB_2U_LIB.S9S_MB_2U(SCH_1):GND     I2 @S9S_MB_2U_LIB.S9S_MB_2U(SCH_1):PAGE70
  EN50    GND @S9S_MB_2U_LIB.S9S_MB_2U(SCH_1):GND     I2 @S9S_MB_2U_LIB.S9S_MB_2U(SCH_1):PAGE70
  EN48    GND @S9S_MB_2U_LIB.S9S_MB_2U(SCH_1):GND     I2 @S9S_MB_2U_LIB.S9S_MB_2U(SCH_1):PAGE70
  EN45    GND @S9S_MB_2U_LIB.S9S_MB_2U(SCH_1):GND     I2 @S9S_MB_2U_LIB.S9S_MB_2U(SCH_1):PAGE70
  EN43    GND @S9S_MB_2U_LIB.S9S_MB_2U(SCH_1):GND     I2 @S9S_MB_2U_LIB.S9S_MB_2U(SCH_1):PAGE70
  EN41    GND @S9S_MB_2U_LIB.S9S_MB_2U(SCH_1):GND     I2 @S9S_MB_2U_LIB.S9S_MB_2U(SCH_1):PAGE70
  EN37    GND @S9S_MB_2U_LIB.S9S_MB_2U(SCH_1):GND     I2 @S9S_MB_2U_LIB.S9S_MB_2U(SCH_1):PAGE70
  EN35    GND @S9S_MB_2U_LIB.S9S_MB_2U(SCH_1):GND     I2 @S9S_MB_2U_LIB.S9S_MB_2U(SCH_1):PAGE70
  EN33    GND @S9S_MB_2U_LIB.S9S_MB_2U(SCH_1):GND     I2 @S9S_MB_2U_LIB.S9S_MB_2U(SCH_1):PAGE70
  EN31    GND @S9S_MB_2U_LIB.S9S_MB_2U(SCH_1):GND     I2 @S9S_MB_2U_LIB.S9S_MB_2U(SCH_1):PAGE70
  EN29    GND @S9S_MB_2U_LIB.S9S_MB_2U(SCH_1):GND     I2 @S9S_MB_2U_LIB.S9S_MB_2U(SCH_1):PAGE70
  EN27    GND @S9S_MB_2U_LIB.S9S_MB_2U(SCH_1):GND     I2 @S9S_MB_2U_LIB.S9S_MB_2U(SCH_1):PAGE70
  EN25    GND @S9S_MB_2U_LIB.S9S_MB_2U(SCH_1):GND     I2 @S9S_MB_2U_LIB.S9S_MB_2U(SCH_1):PAGE70
  EN23    GND @S9S_MB_2U_LIB.S9S_MB_2U(SCH_1):GND     I2 @S9S_MB_2U_LIB.S9S_MB_2U(SCH_1):PAGE70
  EN21    GND @S9S_MB_2U_LIB.S9S_MB_2U(SCH_1):GND     I2 @S9S_MB_2U_LIB.S9S_MB_2U(SCH_1):PAGE70
  EN19    GND @S9S_MB_2U_LIB.S9S_MB_2U(SCH_1):GND     I2 @S9S_MB_2U_LIB.S9S_MB_2U(SCH_1):PAGE70
  EN17    GND @S9S_MB_2U_LIB.S9S_MB_2U(SCH_1):GND     I2 @S9S_MB_2U_LIB.S9S_MB_2U(SCH_1):PAGE70
  EN15    GND @S9S_MB_2U_LIB.S9S_MB_2U(SCH_1):GND     I2 @S9S_MB_2U_LIB.S9S_MB_2U(SCH_1):PAGE70
  EN13    GND @S9S_MB_2U_LIB.S9S_MB_2U(SCH_1):GND     I2 @S9S_MB_2U_LIB.S9S_MB_2U(SCH_1):PAGE70
  EN11    GND @S9S_MB_2U_LIB.S9S_MB_2U(SCH_1):GND     I2 @S9S_MB_2U_LIB.S9S_MB_2U(SCH_1):PAGE70
  EM83    GND @S9S_MB_2U_LIB.S9S_MB_2U(SCH_1):GND     I2 @S9S_MB_2U_LIB.S9S_MB_2U(SCH_1):PAGE70
  EM81    GND @S9S_MB_2U_LIB.S9S_MB_2U(SCH_1):GND     I2 @S9S_MB_2U_LIB.S9S_MB_2U(SCH_1):PAGE70
   EM8    GND @S9S_MB_2U_LIB.S9S_MB_2U(SCH_1):GND     I2 @S9S_MB_2U_LIB.S9S_MB_2U(SCH_1):PAGE70
  EM73    GND @S9S_MB_2U_LIB.S9S_MB_2U(SCH_1):GND     I2 @S9S_MB_2U_LIB.S9S_MB_2U(SCH_1):PAGE70
  ET59    GND @S9S_MB_2U_LIB.S9S_MB_2U(SCH_1):GND     I2 @S9S_MB_2U_LIB.S9S_MB_2U(SCH_1):PAGE70
  EM42    GND @S9S_MB_2U_LIB.S9S_MB_2U(SCH_1):GND     I2 @S9S_MB_2U_LIB.S9S_MB_2U(SCH_1):PAGE70
  ET53    GND @S9S_MB_2U_LIB.S9S_MB_2U(SCH_1):GND     I2 @S9S_MB_2U_LIB.S9S_MB_2U(SCH_1):PAGE70
  EL76    GND @S9S_MB_2U_LIB.S9S_MB_2U(SCH_1):GND     I2 @S9S_MB_2U_LIB.S9S_MB_2U(SCH_1):PAGE70
  EL64    GND @S9S_MB_2U_LIB.S9S_MB_2U(SCH_1):GND     I2 @S9S_MB_2U_LIB.S9S_MB_2U(SCH_1):PAGE70
   EL5    GND @S9S_MB_2U_LIB.S9S_MB_2U(SCH_1):GND     I2 @S9S_MB_2U_LIB.S9S_MB_2U(SCH_1):PAGE70
  EL45    GND @S9S_MB_2U_LIB.S9S_MB_2U(SCH_1):GND     I2 @S9S_MB_2U_LIB.S9S_MB_2U(SCH_1):PAGE70
  ET32    GND @S9S_MB_2U_LIB.S9S_MB_2U(SCH_1):GND     I2 @S9S_MB_2U_LIB.S9S_MB_2U(SCH_1):PAGE70
  EL39    GND @S9S_MB_2U_LIB.S9S_MB_2U(SCH_1):GND     I2 @S9S_MB_2U_LIB.S9S_MB_2U(SCH_1):PAGE70
  ET26    GND @S9S_MB_2U_LIB.S9S_MB_2U(SCH_1):GND     I2 @S9S_MB_2U_LIB.S9S_MB_2U(SCH_1):PAGE70
  EL33    GND @S9S_MB_2U_LIB.S9S_MB_2U(SCH_1):GND     I2 @S9S_MB_2U_LIB.S9S_MB_2U(SCH_1):PAGE70
  ET20    GND @S9S_MB_2U_LIB.S9S_MB_2U(SCH_1):GND     I2 @S9S_MB_2U_LIB.S9S_MB_2U(SCH_1):PAGE70
   EL3    GND @S9S_MB_2U_LIB.S9S_MB_2U(SCH_1):GND     I2 @S9S_MB_2U_LIB.S9S_MB_2U(SCH_1):PAGE70
  ET14    GND @S9S_MB_2U_LIB.S9S_MB_2U(SCH_1):GND     I2 @S9S_MB_2U_LIB.S9S_MB_2U(SCH_1):PAGE70
  EL27    GND @S9S_MB_2U_LIB.S9S_MB_2U(SCH_1):GND     I2 @S9S_MB_2U_LIB.S9S_MB_2U(SCH_1):PAGE70
   ER9    GND @S9S_MB_2U_LIB.S9S_MB_2U(SCH_1):GND     I2 @S9S_MB_2U_LIB.S9S_MB_2U(SCH_1):PAGE70
  EL21    GND @S9S_MB_2U_LIB.S9S_MB_2U(SCH_1):GND     I2 @S9S_MB_2U_LIB.S9S_MB_2U(SCH_1):PAGE70
  EK75    GND @S9S_MB_2U_LIB.S9S_MB_2U(SCH_1):GND     I2 @S9S_MB_2U_LIB.S9S_MB_2U(SCH_1):PAGE70
  EK69    GND @S9S_MB_2U_LIB.S9S_MB_2U(SCH_1):GND     I2 @S9S_MB_2U_LIB.S9S_MB_2U(SCH_1):PAGE70
  EK65    GND @S9S_MB_2U_LIB.S9S_MB_2U(SCH_1):GND     I2 @S9S_MB_2U_LIB.S9S_MB_2U(SCH_1):PAGE70
  EK57    GND @S9S_MB_2U_LIB.S9S_MB_2U(SCH_1):GND     I2 @S9S_MB_2U_LIB.S9S_MB_2U(SCH_1):PAGE70
  EK47    GND @S9S_MB_2U_LIB.S9S_MB_2U(SCH_1):GND     I2 @S9S_MB_2U_LIB.S9S_MB_2U(SCH_1):PAGE70
  EK40    GND @S9S_MB_2U_LIB.S9S_MB_2U(SCH_1):GND     I2 @S9S_MB_2U_LIB.S9S_MB_2U(SCH_1):PAGE70
  ER64    GND @S9S_MB_2U_LIB.S9S_MB_2U(SCH_1):GND     I2 @S9S_MB_2U_LIB.S9S_MB_2U(SCH_1):PAGE70
  ER58    GND @S9S_MB_2U_LIB.S9S_MB_2U(SCH_1):GND     I2 @S9S_MB_2U_LIB.S9S_MB_2U(SCH_1):PAGE70
   EK4    GND @S9S_MB_2U_LIB.S9S_MB_2U(SCH_1):GND     I2 @S9S_MB_2U_LIB.S9S_MB_2U(SCH_1):PAGE70
  EK38    GND @S9S_MB_2U_LIB.S9S_MB_2U(SCH_1):GND     I2 @S9S_MB_2U_LIB.S9S_MB_2U(SCH_1):PAGE70
  ER52    GND @S9S_MB_2U_LIB.S9S_MB_2U(SCH_1):GND     I2 @S9S_MB_2U_LIB.S9S_MB_2U(SCH_1):PAGE70
  EK34    GND @S9S_MB_2U_LIB.S9S_MB_2U(SCH_1):GND     I2 @S9S_MB_2U_LIB.S9S_MB_2U(SCH_1):PAGE70
  ER39    GND @S9S_MB_2U_LIB.S9S_MB_2U(SCH_1):GND     I2 @S9S_MB_2U_LIB.S9S_MB_2U(SCH_1):PAGE70
  EK32    GND @S9S_MB_2U_LIB.S9S_MB_2U(SCH_1):GND     I2 @S9S_MB_2U_LIB.S9S_MB_2U(SCH_1):PAGE70
  EK28    GND @S9S_MB_2U_LIB.S9S_MB_2U(SCH_1):GND     I2 @S9S_MB_2U_LIB.S9S_MB_2U(SCH_1):PAGE70
  EK22    GND @S9S_MB_2U_LIB.S9S_MB_2U(SCH_1):GND     I2 @S9S_MB_2U_LIB.S9S_MB_2U(SCH_1):PAGE70
   EK2    GND @S9S_MB_2U_LIB.S9S_MB_2U(SCH_1):GND     I2 @S9S_MB_2U_LIB.S9S_MB_2U(SCH_1):PAGE70
  ER21    GND @S9S_MB_2U_LIB.S9S_MB_2U(SCH_1):GND     I2 @S9S_MB_2U_LIB.S9S_MB_2U(SCH_1):PAGE70
  ER15    GND @S9S_MB_2U_LIB.S9S_MB_2U(SCH_1):GND     I2 @S9S_MB_2U_LIB.S9S_MB_2U(SCH_1):PAGE70
  EK14    GND @S9S_MB_2U_LIB.S9S_MB_2U(SCH_1):GND     I2 @S9S_MB_2U_LIB.S9S_MB_2U(SCH_1):PAGE70
  EP77    GND @S9S_MB_2U_LIB.S9S_MB_2U(SCH_1):GND     I2 @S9S_MB_2U_LIB.S9S_MB_2U(SCH_1):PAGE70
  EP71    GND @S9S_MB_2U_LIB.S9S_MB_2U(SCH_1):GND     I2 @S9S_MB_2U_LIB.S9S_MB_2U(SCH_1):PAGE70
  EP69    GND @S9S_MB_2U_LIB.S9S_MB_2U(SCH_1):GND     I2 @S9S_MB_2U_LIB.S9S_MB_2U(SCH_1):PAGE70
  EK10    GND @S9S_MB_2U_LIB.S9S_MB_2U(SCH_1):GND     I2 @S9S_MB_2U_LIB.S9S_MB_2U(SCH_1):PAGE70
   EJ9    GND @S9S_MB_2U_LIB.S9S_MB_2U(SCH_1):GND     I2 @S9S_MB_2U_LIB.S9S_MB_2U(SCH_1):PAGE70
  EJ88    GND @S9S_MB_2U_LIB.S9S_MB_2U(SCH_1):GND     I2 @S9S_MB_2U_LIB.S9S_MB_2U(SCH_1):PAGE70
  EJ78    GND @S9S_MB_2U_LIB.S9S_MB_2U(SCH_1):GND     I2 @S9S_MB_2U_LIB.S9S_MB_2U(SCH_1):PAGE70
  EJ74    GND @S9S_MB_2U_LIB.S9S_MB_2U(SCH_1):GND     I2 @S9S_MB_2U_LIB.S9S_MB_2U(SCH_1):PAGE70
   EN9    GND @S9S_MB_2U_LIB.S9S_MB_2U(SCH_1):GND     I2 @S9S_MB_2U_LIB.S9S_MB_2U(SCH_1):PAGE70
  EN88    GND @S9S_MB_2U_LIB.S9S_MB_2U(SCH_1):GND     I2 @S9S_MB_2U_LIB.S9S_MB_2U(SCH_1):PAGE70
   EJ7    GND @S9S_MB_2U_LIB.S9S_MB_2U(SCH_1):GND     I2 @S9S_MB_2U_LIB.S9S_MB_2U(SCH_1):PAGE70
  EJ66    GND @S9S_MB_2U_LIB.S9S_MB_2U(SCH_1):GND     I2 @S9S_MB_2U_LIB.S9S_MB_2U(SCH_1):PAGE70
  EJ60    GND @S9S_MB_2U_LIB.S9S_MB_2U(SCH_1):GND     I2 @S9S_MB_2U_LIB.S9S_MB_2U(SCH_1):PAGE70
  EN72    GND @S9S_MB_2U_LIB.S9S_MB_2U(SCH_1):GND     I2 @S9S_MB_2U_LIB.S9S_MB_2U(SCH_1):PAGE70
  EN66    GND @S9S_MB_2U_LIB.S9S_MB_2U(SCH_1):GND     I2 @S9S_MB_2U_LIB.S9S_MB_2U(SCH_1):PAGE70
  EJ56    GND @S9S_MB_2U_LIB.S9S_MB_2U(SCH_1):GND     I2 @S9S_MB_2U_LIB.S9S_MB_2U(SCH_1):PAGE70
  EN62    GND @S9S_MB_2U_LIB.S9S_MB_2U(SCH_1):GND     I2 @S9S_MB_2U_LIB.S9S_MB_2U(SCH_1):PAGE70
  EN60    GND @S9S_MB_2U_LIB.S9S_MB_2U(SCH_1):GND     I2 @S9S_MB_2U_LIB.S9S_MB_2U(SCH_1):PAGE70
  EN58    GND @S9S_MB_2U_LIB.S9S_MB_2U(SCH_1):GND     I2 @S9S_MB_2U_LIB.S9S_MB_2U(SCH_1):PAGE70
  EJ50    GND @S9S_MB_2U_LIB.S9S_MB_2U(SCH_1):GND     I2 @S9S_MB_2U_LIB.S9S_MB_2U(SCH_1):PAGE70
  EJ48    GND @S9S_MB_2U_LIB.S9S_MB_2U(SCH_1):GND     I2 @S9S_MB_2U_LIB.S9S_MB_2U(SCH_1):PAGE70
  EJ43    GND @S9S_MB_2U_LIB.S9S_MB_2U(SCH_1):GND     I2 @S9S_MB_2U_LIB.S9S_MB_2U(SCH_1):PAGE70
  EJ41    GND @S9S_MB_2U_LIB.S9S_MB_2U(SCH_1):GND     I2 @S9S_MB_2U_LIB.S9S_MB_2U(SCH_1):PAGE70
  EJ37    GND @S9S_MB_2U_LIB.S9S_MB_2U(SCH_1):GND     I2 @S9S_MB_2U_LIB.S9S_MB_2U(SCH_1):PAGE70
  EJ31    GND @S9S_MB_2U_LIB.S9S_MB_2U(SCH_1):GND     I2 @S9S_MB_2U_LIB.S9S_MB_2U(SCH_1):PAGE70
  EJ29    GND @S9S_MB_2U_LIB.S9S_MB_2U(SCH_1):GND     I2 @S9S_MB_2U_LIB.S9S_MB_2U(SCH_1):PAGE70
  EJ23    GND @S9S_MB_2U_LIB.S9S_MB_2U(SCH_1):GND     I2 @S9S_MB_2U_LIB.S9S_MB_2U(SCH_1):PAGE70
  EN39    GND @S9S_MB_2U_LIB.S9S_MB_2U(SCH_1):GND     I2 @S9S_MB_2U_LIB.S9S_MB_2U(SCH_1):PAGE70
  EJ19    GND @S9S_MB_2U_LIB.S9S_MB_2U(SCH_1):GND     I2 @S9S_MB_2U_LIB.S9S_MB_2U(SCH_1):PAGE70
  EJ13    GND @S9S_MB_2U_LIB.S9S_MB_2U(SCH_1):GND     I2 @S9S_MB_2U_LIB.S9S_MB_2U(SCH_1):PAGE70
  EH83    GND @S9S_MB_2U_LIB.S9S_MB_2U(SCH_1):GND     I2 @S9S_MB_2U_LIB.S9S_MB_2U(SCH_1):PAGE70
  EH81    GND @S9S_MB_2U_LIB.S9S_MB_2U(SCH_1):GND     I2 @S9S_MB_2U_LIB.S9S_MB_2U(SCH_1):PAGE70
  EH73    GND @S9S_MB_2U_LIB.S9S_MB_2U(SCH_1):GND     I2 @S9S_MB_2U_LIB.S9S_MB_2U(SCH_1):PAGE70
  EH49    GND @S9S_MB_2U_LIB.S9S_MB_2U(SCH_1):GND     I2 @S9S_MB_2U_LIB.S9S_MB_2U(SCH_1):PAGE70
  EH36    GND @S9S_MB_2U_LIB.S9S_MB_2U(SCH_1):GND     I2 @S9S_MB_2U_LIB.S9S_MB_2U(SCH_1):PAGE70
  EM79    GND @S9S_MB_2U_LIB.S9S_MB_2U(SCH_1):GND     I2 @S9S_MB_2U_LIB.S9S_MB_2U(SCH_1):PAGE70
  EM49    GND @S9S_MB_2U_LIB.S9S_MB_2U(SCH_1):GND     I2 @S9S_MB_2U_LIB.S9S_MB_2U(SCH_1):PAGE70
   EL9    GND @S9S_MB_2U_LIB.S9S_MB_2U(SCH_1):GND     I2 @S9S_MB_2U_LIB.S9S_MB_2U(SCH_1):PAGE70
  EL86    GND @S9S_MB_2U_LIB.S9S_MB_2U(SCH_1):GND     I2 @S9S_MB_2U_LIB.S9S_MB_2U(SCH_1):PAGE70
  EL72    GND @S9S_MB_2U_LIB.S9S_MB_2U(SCH_1):GND     I2 @S9S_MB_2U_LIB.S9S_MB_2U(SCH_1):PAGE70
  EL70    GND @S9S_MB_2U_LIB.S9S_MB_2U(SCH_1):GND     I2 @S9S_MB_2U_LIB.S9S_MB_2U(SCH_1):PAGE70
   EL7    GND @S9S_MB_2U_LIB.S9S_MB_2U(SCH_1):GND     I2 @S9S_MB_2U_LIB.S9S_MB_2U(SCH_1):PAGE70
  EL58    GND @S9S_MB_2U_LIB.S9S_MB_2U(SCH_1):GND     I2 @S9S_MB_2U_LIB.S9S_MB_2U(SCH_1):PAGE70
  EL52    GND @S9S_MB_2U_LIB.S9S_MB_2U(SCH_1):GND     I2 @S9S_MB_2U_LIB.S9S_MB_2U(SCH_1):PAGE70
  EL15    GND @S9S_MB_2U_LIB.S9S_MB_2U(SCH_1):GND     I2 @S9S_MB_2U_LIB.S9S_MB_2U(SCH_1):PAGE70
  EK89    GND @S9S_MB_2U_LIB.S9S_MB_2U(SCH_1):GND     I2 @S9S_MB_2U_LIB.S9S_MB_2U(SCH_1):PAGE70
  EK83    GND @S9S_MB_2U_LIB.S9S_MB_2U(SCH_1):GND     I2 @S9S_MB_2U_LIB.S9S_MB_2U(SCH_1):PAGE70
  EK79    GND @S9S_MB_2U_LIB.S9S_MB_2U(SCH_1):GND     I2 @S9S_MB_2U_LIB.S9S_MB_2U(SCH_1):PAGE70
  EK77    GND @S9S_MB_2U_LIB.S9S_MB_2U(SCH_1):GND     I2 @S9S_MB_2U_LIB.S9S_MB_2U(SCH_1):PAGE70
  EK71    GND @S9S_MB_2U_LIB.S9S_MB_2U(SCH_1):GND     I2 @S9S_MB_2U_LIB.S9S_MB_2U(SCH_1):PAGE70
  EK63    GND @S9S_MB_2U_LIB.S9S_MB_2U(SCH_1):GND     I2 @S9S_MB_2U_LIB.S9S_MB_2U(SCH_1):PAGE70
  EK59    GND @S9S_MB_2U_LIB.S9S_MB_2U(SCH_1):GND     I2 @S9S_MB_2U_LIB.S9S_MB_2U(SCH_1):PAGE70
  EK53    GND @S9S_MB_2U_LIB.S9S_MB_2U(SCH_1):GND     I2 @S9S_MB_2U_LIB.S9S_MB_2U(SCH_1):PAGE70
  EK51    GND @S9S_MB_2U_LIB.S9S_MB_2U(SCH_1):GND     I2 @S9S_MB_2U_LIB.S9S_MB_2U(SCH_1):PAGE70
  EK44    GND @S9S_MB_2U_LIB.S9S_MB_2U(SCH_1):GND     I2 @S9S_MB_2U_LIB.S9S_MB_2U(SCH_1):PAGE70
  EK26    GND @S9S_MB_2U_LIB.S9S_MB_2U(SCH_1):GND     I2 @S9S_MB_2U_LIB.S9S_MB_2U(SCH_1):PAGE70
  EK20    GND @S9S_MB_2U_LIB.S9S_MB_2U(SCH_1):GND     I2 @S9S_MB_2U_LIB.S9S_MB_2U(SCH_1):PAGE70
  EK16    GND @S9S_MB_2U_LIB.S9S_MB_2U(SCH_1):GND     I2 @S9S_MB_2U_LIB.S9S_MB_2U(SCH_1):PAGE70
  EJ72    GND @S9S_MB_2U_LIB.S9S_MB_2U(SCH_1):GND     I2 @S9S_MB_2U_LIB.S9S_MB_2U(SCH_1):PAGE70
  EJ68    GND @S9S_MB_2U_LIB.S9S_MB_2U(SCH_1):GND     I2 @S9S_MB_2U_LIB.S9S_MB_2U(SCH_1):PAGE70
  EJ62    GND @S9S_MB_2U_LIB.S9S_MB_2U(SCH_1):GND     I2 @S9S_MB_2U_LIB.S9S_MB_2U(SCH_1):PAGE70
  EJ54    GND @S9S_MB_2U_LIB.S9S_MB_2U(SCH_1):GND     I2 @S9S_MB_2U_LIB.S9S_MB_2U(SCH_1):PAGE70
  EJ35    GND @S9S_MB_2U_LIB.S9S_MB_2U(SCH_1):GND     I2 @S9S_MB_2U_LIB.S9S_MB_2U(SCH_1):PAGE70
  EJ25    GND @S9S_MB_2U_LIB.S9S_MB_2U(SCH_1):GND     I2 @S9S_MB_2U_LIB.S9S_MB_2U(SCH_1):PAGE70
  EJ17    GND @S9S_MB_2U_LIB.S9S_MB_2U(SCH_1):GND     I2 @S9S_MB_2U_LIB.S9S_MB_2U(SCH_1):PAGE70
  EJ11    GND @S9S_MB_2U_LIB.S9S_MB_2U(SCH_1):GND     I2 @S9S_MB_2U_LIB.S9S_MB_2U(SCH_1):PAGE70
  EH79    GND @S9S_MB_2U_LIB.S9S_MB_2U(SCH_1):GND     I2 @S9S_MB_2U_LIB.S9S_MB_2U(SCH_1):PAGE70
  EH67    GND @S9S_MB_2U_LIB.S9S_MB_2U(SCH_1):GND     I2 @S9S_MB_2U_LIB.S9S_MB_2U(SCH_1):PAGE70
  EH61    GND @S9S_MB_2U_LIB.S9S_MB_2U(SCH_1):GND     I2 @S9S_MB_2U_LIB.S9S_MB_2U(SCH_1):PAGE70
  EH55    GND @S9S_MB_2U_LIB.S9S_MB_2U(SCH_1):GND     I2 @S9S_MB_2U_LIB.S9S_MB_2U(SCH_1):PAGE70
  EH42    GND @S9S_MB_2U_LIB.S9S_MB_2U(SCH_1):GND     I2 @S9S_MB_2U_LIB.S9S_MB_2U(SCH_1):PAGE70
   EH4    GND @S9S_MB_2U_LIB.S9S_MB_2U(SCH_1):GND     I5 @S9S_MB_2U_LIB.S9S_MB_2U(SCH_1):PAGE70
  EH30    GND @S9S_MB_2U_LIB.S9S_MB_2U(SCH_1):GND     I5 @S9S_MB_2U_LIB.S9S_MB_2U(SCH_1):PAGE70
  EH24    GND @S9S_MB_2U_LIB.S9S_MB_2U(SCH_1):GND     I5 @S9S_MB_2U_LIB.S9S_MB_2U(SCH_1):PAGE70
  EH16    GND @S9S_MB_2U_LIB.S9S_MB_2U(SCH_1):GND     I5 @S9S_MB_2U_LIB.S9S_MB_2U(SCH_1):PAGE70
  EG90    GND @S9S_MB_2U_LIB.S9S_MB_2U(SCH_1):GND     I5 @S9S_MB_2U_LIB.S9S_MB_2U(SCH_1):PAGE70
   EG9    GND @S9S_MB_2U_LIB.S9S_MB_2U(SCH_1):GND     I5 @S9S_MB_2U_LIB.S9S_MB_2U(SCH_1):PAGE70
  EG88    GND @S9S_MB_2U_LIB.S9S_MB_2U(SCH_1):GND     I5 @S9S_MB_2U_LIB.S9S_MB_2U(SCH_1):PAGE70
  EG86    GND @S9S_MB_2U_LIB.S9S_MB_2U(SCH_1):GND     I5 @S9S_MB_2U_LIB.S9S_MB_2U(SCH_1):PAGE70
  EG84    GND @S9S_MB_2U_LIB.S9S_MB_2U(SCH_1):GND     I5 @S9S_MB_2U_LIB.S9S_MB_2U(SCH_1):PAGE70
  EG82    GND @S9S_MB_2U_LIB.S9S_MB_2U(SCH_1):GND     I5 @S9S_MB_2U_LIB.S9S_MB_2U(SCH_1):PAGE70
  EG39    GND @S9S_MB_2U_LIB.S9S_MB_2U(SCH_1):GND     I5 @S9S_MB_2U_LIB.S9S_MB_2U(SCH_1):PAGE70
  EF87    GND @S9S_MB_2U_LIB.S9S_MB_2U(SCH_1):GND     I5 @S9S_MB_2U_LIB.S9S_MB_2U(SCH_1):PAGE70
  EF85    GND @S9S_MB_2U_LIB.S9S_MB_2U(SCH_1):GND     I5 @S9S_MB_2U_LIB.S9S_MB_2U(SCH_1):PAGE70
   EF8    GND @S9S_MB_2U_LIB.S9S_MB_2U(SCH_1):GND     I5 @S9S_MB_2U_LIB.S9S_MB_2U(SCH_1):PAGE70
  EF77    GND @S9S_MB_2U_LIB.S9S_MB_2U(SCH_1):GND     I5 @S9S_MB_2U_LIB.S9S_MB_2U(SCH_1):PAGE70
  EF71    GND @S9S_MB_2U_LIB.S9S_MB_2U(SCH_1):GND     I5 @S9S_MB_2U_LIB.S9S_MB_2U(SCH_1):PAGE70
  EF69    GND @S9S_MB_2U_LIB.S9S_MB_2U(SCH_1):GND     I5 @S9S_MB_2U_LIB.S9S_MB_2U(SCH_1):PAGE70
  EF67    GND @S9S_MB_2U_LIB.S9S_MB_2U(SCH_1):GND     I5 @S9S_MB_2U_LIB.S9S_MB_2U(SCH_1):PAGE70
  EF65    GND @S9S_MB_2U_LIB.S9S_MB_2U(SCH_1):GND     I5 @S9S_MB_2U_LIB.S9S_MB_2U(SCH_1):PAGE70
  EF63    GND @S9S_MB_2U_LIB.S9S_MB_2U(SCH_1):GND     I5 @S9S_MB_2U_LIB.S9S_MB_2U(SCH_1):PAGE70
  EF61    GND @S9S_MB_2U_LIB.S9S_MB_2U(SCH_1):GND     I5 @S9S_MB_2U_LIB.S9S_MB_2U(SCH_1):PAGE70
  EF59    GND @S9S_MB_2U_LIB.S9S_MB_2U(SCH_1):GND     I5 @S9S_MB_2U_LIB.S9S_MB_2U(SCH_1):PAGE70
  EF57    GND @S9S_MB_2U_LIB.S9S_MB_2U(SCH_1):GND     I5 @S9S_MB_2U_LIB.S9S_MB_2U(SCH_1):PAGE70
  EF55    GND @S9S_MB_2U_LIB.S9S_MB_2U(SCH_1):GND     I5 @S9S_MB_2U_LIB.S9S_MB_2U(SCH_1):PAGE70
  EF53    GND @S9S_MB_2U_LIB.S9S_MB_2U(SCH_1):GND     I5 @S9S_MB_2U_LIB.S9S_MB_2U(SCH_1):PAGE70
  EF49    GND @S9S_MB_2U_LIB.S9S_MB_2U(SCH_1):GND     I5 @S9S_MB_2U_LIB.S9S_MB_2U(SCH_1):PAGE70
  EF47    GND @S9S_MB_2U_LIB.S9S_MB_2U(SCH_1):GND     I5 @S9S_MB_2U_LIB.S9S_MB_2U(SCH_1):PAGE70
  EF44    GND @S9S_MB_2U_LIB.S9S_MB_2U(SCH_1):GND     I5 @S9S_MB_2U_LIB.S9S_MB_2U(SCH_1):PAGE70
  EF42    GND @S9S_MB_2U_LIB.S9S_MB_2U(SCH_1):GND     I5 @S9S_MB_2U_LIB.S9S_MB_2U(SCH_1):PAGE70
  EF40    GND @S9S_MB_2U_LIB.S9S_MB_2U(SCH_1):GND     I5 @S9S_MB_2U_LIB.S9S_MB_2U(SCH_1):PAGE70
   EF4    GND @S9S_MB_2U_LIB.S9S_MB_2U(SCH_1):GND     I5 @S9S_MB_2U_LIB.S9S_MB_2U(SCH_1):PAGE70
  EF38    GND @S9S_MB_2U_LIB.S9S_MB_2U(SCH_1):GND     I5 @S9S_MB_2U_LIB.S9S_MB_2U(SCH_1):PAGE70
  EF36    GND @S9S_MB_2U_LIB.S9S_MB_2U(SCH_1):GND     I5 @S9S_MB_2U_LIB.S9S_MB_2U(SCH_1):PAGE70
  EF34    GND @S9S_MB_2U_LIB.S9S_MB_2U(SCH_1):GND     I5 @S9S_MB_2U_LIB.S9S_MB_2U(SCH_1):PAGE70
  EF32    GND @S9S_MB_2U_LIB.S9S_MB_2U(SCH_1):GND     I5 @S9S_MB_2U_LIB.S9S_MB_2U(SCH_1):PAGE70
  EF30    GND @S9S_MB_2U_LIB.S9S_MB_2U(SCH_1):GND     I5 @S9S_MB_2U_LIB.S9S_MB_2U(SCH_1):PAGE70
  EF28    GND @S9S_MB_2U_LIB.S9S_MB_2U(SCH_1):GND     I5 @S9S_MB_2U_LIB.S9S_MB_2U(SCH_1):PAGE70
  EF26    GND @S9S_MB_2U_LIB.S9S_MB_2U(SCH_1):GND     I5 @S9S_MB_2U_LIB.S9S_MB_2U(SCH_1):PAGE70
  EF24    GND @S9S_MB_2U_LIB.S9S_MB_2U(SCH_1):GND     I5 @S9S_MB_2U_LIB.S9S_MB_2U(SCH_1):PAGE70
  EF22    GND @S9S_MB_2U_LIB.S9S_MB_2U(SCH_1):GND     I5 @S9S_MB_2U_LIB.S9S_MB_2U(SCH_1):PAGE70
  EF20    GND @S9S_MB_2U_LIB.S9S_MB_2U(SCH_1):GND     I5 @S9S_MB_2U_LIB.S9S_MB_2U(SCH_1):PAGE70
   EF2    GND @S9S_MB_2U_LIB.S9S_MB_2U(SCH_1):GND     I5 @S9S_MB_2U_LIB.S9S_MB_2U(SCH_1):PAGE70
  EF18    GND @S9S_MB_2U_LIB.S9S_MB_2U(SCH_1):GND     I5 @S9S_MB_2U_LIB.S9S_MB_2U(SCH_1):PAGE70
  EF16    GND @S9S_MB_2U_LIB.S9S_MB_2U(SCH_1):GND     I5 @S9S_MB_2U_LIB.S9S_MB_2U(SCH_1):PAGE70
  EF12    GND @S9S_MB_2U_LIB.S9S_MB_2U(SCH_1):GND     I5 @S9S_MB_2U_LIB.S9S_MB_2U(SCH_1):PAGE70
  EE88    GND @S9S_MB_2U_LIB.S9S_MB_2U(SCH_1):GND     I5 @S9S_MB_2U_LIB.S9S_MB_2U(SCH_1):PAGE70
  EE80    GND @S9S_MB_2U_LIB.S9S_MB_2U(SCH_1):GND     I5 @S9S_MB_2U_LIB.S9S_MB_2U(SCH_1):PAGE70
  EE78    GND @S9S_MB_2U_LIB.S9S_MB_2U(SCH_1):GND     I5 @S9S_MB_2U_LIB.S9S_MB_2U(SCH_1):PAGE70
   ED8    GND @S9S_MB_2U_LIB.S9S_MB_2U(SCH_1):GND     I5 @S9S_MB_2U_LIB.S9S_MB_2U(SCH_1):PAGE70
  ED49    GND @S9S_MB_2U_LIB.S9S_MB_2U(SCH_1):GND     I5 @S9S_MB_2U_LIB.S9S_MB_2U(SCH_1):PAGE70
   ED4    GND @S9S_MB_2U_LIB.S9S_MB_2U(SCH_1):GND     I5 @S9S_MB_2U_LIB.S9S_MB_2U(SCH_1):PAGE70
  ED36    GND @S9S_MB_2U_LIB.S9S_MB_2U(SCH_1):GND     I5 @S9S_MB_2U_LIB.S9S_MB_2U(SCH_1):PAGE70
  ED30    GND @S9S_MB_2U_LIB.S9S_MB_2U(SCH_1):GND     I5 @S9S_MB_2U_LIB.S9S_MB_2U(SCH_1):PAGE70
  ED24    GND @S9S_MB_2U_LIB.S9S_MB_2U(SCH_1):GND     I5 @S9S_MB_2U_LIB.S9S_MB_2U(SCH_1):PAGE70
  ED16    GND @S9S_MB_2U_LIB.S9S_MB_2U(SCH_1):GND     I5 @S9S_MB_2U_LIB.S9S_MB_2U(SCH_1):PAGE70
   EC9    GND @S9S_MB_2U_LIB.S9S_MB_2U(SCH_1):GND     I5 @S9S_MB_2U_LIB.S9S_MB_2U(SCH_1):PAGE70
  EC88    GND @S9S_MB_2U_LIB.S9S_MB_2U(SCH_1):GND     I5 @S9S_MB_2U_LIB.S9S_MB_2U(SCH_1):PAGE70
  EC84    GND @S9S_MB_2U_LIB.S9S_MB_2U(SCH_1):GND     I5 @S9S_MB_2U_LIB.S9S_MB_2U(SCH_1):PAGE70
  EC82    GND @S9S_MB_2U_LIB.S9S_MB_2U(SCH_1):GND     I5 @S9S_MB_2U_LIB.S9S_MB_2U(SCH_1):PAGE70
  EC74    GND @S9S_MB_2U_LIB.S9S_MB_2U(SCH_1):GND     I5 @S9S_MB_2U_LIB.S9S_MB_2U(SCH_1):PAGE70
  EC72    GND @S9S_MB_2U_LIB.S9S_MB_2U(SCH_1):GND     I5 @S9S_MB_2U_LIB.S9S_MB_2U(SCH_1):PAGE70
  EC66    GND @S9S_MB_2U_LIB.S9S_MB_2U(SCH_1):GND     I5 @S9S_MB_2U_LIB.S9S_MB_2U(SCH_1):PAGE70
  EC56    GND @S9S_MB_2U_LIB.S9S_MB_2U(SCH_1):GND     I5 @S9S_MB_2U_LIB.S9S_MB_2U(SCH_1):PAGE70
  EC50    GND @S9S_MB_2U_LIB.S9S_MB_2U(SCH_1):GND     I5 @S9S_MB_2U_LIB.S9S_MB_2U(SCH_1):PAGE70
  EC48    GND @S9S_MB_2U_LIB.S9S_MB_2U(SCH_1):GND     I5 @S9S_MB_2U_LIB.S9S_MB_2U(SCH_1):PAGE70
  EC43    GND @S9S_MB_2U_LIB.S9S_MB_2U(SCH_1):GND     I5 @S9S_MB_2U_LIB.S9S_MB_2U(SCH_1):PAGE70
  EC41    GND @S9S_MB_2U_LIB.S9S_MB_2U(SCH_1):GND     I5 @S9S_MB_2U_LIB.S9S_MB_2U(SCH_1):PAGE70
   EH6    GND @S9S_MB_2U_LIB.S9S_MB_2U(SCH_1):GND     I5 @S9S_MB_2U_LIB.S9S_MB_2U(SCH_1):PAGE70
  EC37    GND @S9S_MB_2U_LIB.S9S_MB_2U(SCH_1):GND     I5 @S9S_MB_2U_LIB.S9S_MB_2U(SCH_1):PAGE70
  EC31    GND @S9S_MB_2U_LIB.S9S_MB_2U(SCH_1):GND     I5 @S9S_MB_2U_LIB.S9S_MB_2U(SCH_1):PAGE70
  EC29    GND @S9S_MB_2U_LIB.S9S_MB_2U(SCH_1):GND     I5 @S9S_MB_2U_LIB.S9S_MB_2U(SCH_1):PAGE70
  EC23    GND @S9S_MB_2U_LIB.S9S_MB_2U(SCH_1):GND     I5 @S9S_MB_2U_LIB.S9S_MB_2U(SCH_1):PAGE70
  EC19    GND @S9S_MB_2U_LIB.S9S_MB_2U(SCH_1):GND     I5 @S9S_MB_2U_LIB.S9S_MB_2U(SCH_1):PAGE70
  EC13    GND @S9S_MB_2U_LIB.S9S_MB_2U(SCH_1):GND     I5 @S9S_MB_2U_LIB.S9S_MB_2U(SCH_1):PAGE70
   EC1    GND @S9S_MB_2U_LIB.S9S_MB_2U(SCH_1):GND     I5 @S9S_MB_2U_LIB.S9S_MB_2U(SCH_1):PAGE70
  EB87    GND @S9S_MB_2U_LIB.S9S_MB_2U(SCH_1):GND     I5 @S9S_MB_2U_LIB.S9S_MB_2U(SCH_1):PAGE70
  EB83    GND @S9S_MB_2U_LIB.S9S_MB_2U(SCH_1):GND     I5 @S9S_MB_2U_LIB.S9S_MB_2U(SCH_1):PAGE70
   EB8    GND @S9S_MB_2U_LIB.S9S_MB_2U(SCH_1):GND     I5 @S9S_MB_2U_LIB.S9S_MB_2U(SCH_1):PAGE70
  EH18    GND @S9S_MB_2U_LIB.S9S_MB_2U(SCH_1):GND     I5 @S9S_MB_2U_LIB.S9S_MB_2U(SCH_1):PAGE70
  EB79    GND @S9S_MB_2U_LIB.S9S_MB_2U(SCH_1):GND     I5 @S9S_MB_2U_LIB.S9S_MB_2U(SCH_1):PAGE70
  EH14    GND @S9S_MB_2U_LIB.S9S_MB_2U(SCH_1):GND     I5 @S9S_MB_2U_LIB.S9S_MB_2U(SCH_1):PAGE70
  EH12    GND @S9S_MB_2U_LIB.S9S_MB_2U(SCH_1):GND     I5 @S9S_MB_2U_LIB.S9S_MB_2U(SCH_1):PAGE70
  EB75    GND @S9S_MB_2U_LIB.S9S_MB_2U(SCH_1):GND     I5 @S9S_MB_2U_LIB.S9S_MB_2U(SCH_1):PAGE70
  EB71    GND @S9S_MB_2U_LIB.S9S_MB_2U(SCH_1):GND     I5 @S9S_MB_2U_LIB.S9S_MB_2U(SCH_1):PAGE70
  EB69    GND @S9S_MB_2U_LIB.S9S_MB_2U(SCH_1):GND     I5 @S9S_MB_2U_LIB.S9S_MB_2U(SCH_1):PAGE70
  EB65    GND @S9S_MB_2U_LIB.S9S_MB_2U(SCH_1):GND     I5 @S9S_MB_2U_LIB.S9S_MB_2U(SCH_1):PAGE70
  EB57    GND @S9S_MB_2U_LIB.S9S_MB_2U(SCH_1):GND     I5 @S9S_MB_2U_LIB.S9S_MB_2U(SCH_1):PAGE70
  EB47    GND @S9S_MB_2U_LIB.S9S_MB_2U(SCH_1):GND     I5 @S9S_MB_2U_LIB.S9S_MB_2U(SCH_1):PAGE70
  EB40    GND @S9S_MB_2U_LIB.S9S_MB_2U(SCH_1):GND     I5 @S9S_MB_2U_LIB.S9S_MB_2U(SCH_1):PAGE70
   EG7    GND @S9S_MB_2U_LIB.S9S_MB_2U(SCH_1):GND     I5 @S9S_MB_2U_LIB.S9S_MB_2U(SCH_1):PAGE70
  EB38    GND @S9S_MB_2U_LIB.S9S_MB_2U(SCH_1):GND     I5 @S9S_MB_2U_LIB.S9S_MB_2U(SCH_1):PAGE70
  EB32    GND @S9S_MB_2U_LIB.S9S_MB_2U(SCH_1):GND     I5 @S9S_MB_2U_LIB.S9S_MB_2U(SCH_1):PAGE70
  EG52    GND @S9S_MB_2U_LIB.S9S_MB_2U(SCH_1):GND     I5 @S9S_MB_2U_LIB.S9S_MB_2U(SCH_1):PAGE70
   EG5    GND @S9S_MB_2U_LIB.S9S_MB_2U(SCH_1):GND     I5 @S9S_MB_2U_LIB.S9S_MB_2U(SCH_1):PAGE70
  EB28    GND @S9S_MB_2U_LIB.S9S_MB_2U(SCH_1):GND     I5 @S9S_MB_2U_LIB.S9S_MB_2U(SCH_1):PAGE70
  EB22    GND @S9S_MB_2U_LIB.S9S_MB_2U(SCH_1):GND     I5 @S9S_MB_2U_LIB.S9S_MB_2U(SCH_1):PAGE70
  EB12    GND @S9S_MB_2U_LIB.S9S_MB_2U(SCH_1):GND     I5 @S9S_MB_2U_LIB.S9S_MB_2U(SCH_1):PAGE70
  EA88    GND @S9S_MB_2U_LIB.S9S_MB_2U(SCH_1):GND     I5 @S9S_MB_2U_LIB.S9S_MB_2U(SCH_1):PAGE70
  EA84    GND @S9S_MB_2U_LIB.S9S_MB_2U(SCH_1):GND     I5 @S9S_MB_2U_LIB.S9S_MB_2U(SCH_1):PAGE70
  EG13    GND @S9S_MB_2U_LIB.S9S_MB_2U(SCH_1):GND     I5 @S9S_MB_2U_LIB.S9S_MB_2U(SCH_1):PAGE70
  EF89    GND @S9S_MB_2U_LIB.S9S_MB_2U(SCH_1):GND     I5 @S9S_MB_2U_LIB.S9S_MB_2U(SCH_1):PAGE70
  EA80    GND @S9S_MB_2U_LIB.S9S_MB_2U(SCH_1):GND     I5 @S9S_MB_2U_LIB.S9S_MB_2U(SCH_1):PAGE70
  EA78    GND @S9S_MB_2U_LIB.S9S_MB_2U(SCH_1):GND     I5 @S9S_MB_2U_LIB.S9S_MB_2U(SCH_1):PAGE70
  EA76    GND @S9S_MB_2U_LIB.S9S_MB_2U(SCH_1):GND     I5 @S9S_MB_2U_LIB.S9S_MB_2U(SCH_1):PAGE70
  EA70    GND @S9S_MB_2U_LIB.S9S_MB_2U(SCH_1):GND     I5 @S9S_MB_2U_LIB.S9S_MB_2U(SCH_1):PAGE70
  EA33    GND @S9S_MB_2U_LIB.S9S_MB_2U(SCH_1):GND     I5 @S9S_MB_2U_LIB.S9S_MB_2U(SCH_1):PAGE70
  EF75    GND @S9S_MB_2U_LIB.S9S_MB_2U(SCH_1):GND     I5 @S9S_MB_2U_LIB.S9S_MB_2U(SCH_1):PAGE70
  EF73    GND @S9S_MB_2U_LIB.S9S_MB_2U(SCH_1):GND     I5 @S9S_MB_2U_LIB.S9S_MB_2U(SCH_1):PAGE70
  EA27    GND @S9S_MB_2U_LIB.S9S_MB_2U(SCH_1):GND     I5 @S9S_MB_2U_LIB.S9S_MB_2U(SCH_1):PAGE70
  EA21    GND @S9S_MB_2U_LIB.S9S_MB_2U(SCH_1):GND     I5 @S9S_MB_2U_LIB.S9S_MB_2U(SCH_1):PAGE70
   DY8    GND @S9S_MB_2U_LIB.S9S_MB_2U(SCH_1):GND     I5 @S9S_MB_2U_LIB.S9S_MB_2U(SCH_1):PAGE70
  DY77    GND @S9S_MB_2U_LIB.S9S_MB_2U(SCH_1):GND     I5 @S9S_MB_2U_LIB.S9S_MB_2U(SCH_1):PAGE70
  DW88    GND @S9S_MB_2U_LIB.S9S_MB_2U(SCH_1):GND     I5 @S9S_MB_2U_LIB.S9S_MB_2U(SCH_1):PAGE70
  DW84    GND @S9S_MB_2U_LIB.S9S_MB_2U(SCH_1):GND     I5 @S9S_MB_2U_LIB.S9S_MB_2U(SCH_1):PAGE70
  EF51    GND @S9S_MB_2U_LIB.S9S_MB_2U(SCH_1):GND     I5 @S9S_MB_2U_LIB.S9S_MB_2U(SCH_1):PAGE70
  DW82    GND @S9S_MB_2U_LIB.S9S_MB_2U(SCH_1):GND     I5 @S9S_MB_2U_LIB.S9S_MB_2U(SCH_1):PAGE70
  DW80    GND @S9S_MB_2U_LIB.S9S_MB_2U(SCH_1):GND     I5 @S9S_MB_2U_LIB.S9S_MB_2U(SCH_1):PAGE70
  DW76    GND @S9S_MB_2U_LIB.S9S_MB_2U(SCH_1):GND     I5 @S9S_MB_2U_LIB.S9S_MB_2U(SCH_1):PAGE70
  DW74    GND @S9S_MB_2U_LIB.S9S_MB_2U(SCH_1):GND     I5 @S9S_MB_2U_LIB.S9S_MB_2U(SCH_1):PAGE70
  DW72    GND @S9S_MB_2U_LIB.S9S_MB_2U(SCH_1):GND     I5 @S9S_MB_2U_LIB.S9S_MB_2U(SCH_1):PAGE70
  DW70    GND @S9S_MB_2U_LIB.S9S_MB_2U(SCH_1):GND     I5 @S9S_MB_2U_LIB.S9S_MB_2U(SCH_1):PAGE70
  DW68    GND @S9S_MB_2U_LIB.S9S_MB_2U(SCH_1):GND     I5 @S9S_MB_2U_LIB.S9S_MB_2U(SCH_1):PAGE70
  DW66    GND @S9S_MB_2U_LIB.S9S_MB_2U(SCH_1):GND     I5 @S9S_MB_2U_LIB.S9S_MB_2U(SCH_1):PAGE70
  EE52    GND @S9S_MB_2U_LIB.S9S_MB_2U(SCH_1):GND     I5 @S9S_MB_2U_LIB.S9S_MB_2U(SCH_1):PAGE70
  EE39    GND @S9S_MB_2U_LIB.S9S_MB_2U(SCH_1):GND     I5 @S9S_MB_2U_LIB.S9S_MB_2U(SCH_1):PAGE70
  EE17    GND @S9S_MB_2U_LIB.S9S_MB_2U(SCH_1):GND     I5 @S9S_MB_2U_LIB.S9S_MB_2U(SCH_1):PAGE70
  ED73    GND @S9S_MB_2U_LIB.S9S_MB_2U(SCH_1):GND     I5 @S9S_MB_2U_LIB.S9S_MB_2U(SCH_1):PAGE70
  ED67    GND @S9S_MB_2U_LIB.S9S_MB_2U(SCH_1):GND     I5 @S9S_MB_2U_LIB.S9S_MB_2U(SCH_1):PAGE70
  ED61    GND @S9S_MB_2U_LIB.S9S_MB_2U(SCH_1):GND     I5 @S9S_MB_2U_LIB.S9S_MB_2U(SCH_1):PAGE70
  ED55    GND @S9S_MB_2U_LIB.S9S_MB_2U(SCH_1):GND     I5 @S9S_MB_2U_LIB.S9S_MB_2U(SCH_1):PAGE70
  ED42    GND @S9S_MB_2U_LIB.S9S_MB_2U(SCH_1):GND     I5 @S9S_MB_2U_LIB.S9S_MB_2U(SCH_1):PAGE70
  ED18    GND @S9S_MB_2U_LIB.S9S_MB_2U(SCH_1):GND     I5 @S9S_MB_2U_LIB.S9S_MB_2U(SCH_1):PAGE70
  ED12    GND @S9S_MB_2U_LIB.S9S_MB_2U(SCH_1):GND     I5 @S9S_MB_2U_LIB.S9S_MB_2U(SCH_1):PAGE70
  EC68    GND @S9S_MB_2U_LIB.S9S_MB_2U(SCH_1):GND     I5 @S9S_MB_2U_LIB.S9S_MB_2U(SCH_1):PAGE70
  EC62    GND @S9S_MB_2U_LIB.S9S_MB_2U(SCH_1):GND     I5 @S9S_MB_2U_LIB.S9S_MB_2U(SCH_1):PAGE70
  EC60    GND @S9S_MB_2U_LIB.S9S_MB_2U(SCH_1):GND     I5 @S9S_MB_2U_LIB.S9S_MB_2U(SCH_1):PAGE70
  EC54    GND @S9S_MB_2U_LIB.S9S_MB_2U(SCH_1):GND     I5 @S9S_MB_2U_LIB.S9S_MB_2U(SCH_1):PAGE70
   EC5    GND @S9S_MB_2U_LIB.S9S_MB_2U(SCH_1):GND     I5 @S9S_MB_2U_LIB.S9S_MB_2U(SCH_1):PAGE70
  EC35    GND @S9S_MB_2U_LIB.S9S_MB_2U(SCH_1):GND     I5 @S9S_MB_2U_LIB.S9S_MB_2U(SCH_1):PAGE70
  EC25    GND @S9S_MB_2U_LIB.S9S_MB_2U(SCH_1):GND     I5 @S9S_MB_2U_LIB.S9S_MB_2U(SCH_1):PAGE70
  EB91    GND @S9S_MB_2U_LIB.S9S_MB_2U(SCH_1):GND     I5 @S9S_MB_2U_LIB.S9S_MB_2U(SCH_1):PAGE70
  EB63    GND @S9S_MB_2U_LIB.S9S_MB_2U(SCH_1):GND     I5 @S9S_MB_2U_LIB.S9S_MB_2U(SCH_1):PAGE70
  EB59    GND @S9S_MB_2U_LIB.S9S_MB_2U(SCH_1):GND     I5 @S9S_MB_2U_LIB.S9S_MB_2U(SCH_1):PAGE70
  EB53    GND @S9S_MB_2U_LIB.S9S_MB_2U(SCH_1):GND     I5 @S9S_MB_2U_LIB.S9S_MB_2U(SCH_1):PAGE70
  EB51    GND @S9S_MB_2U_LIB.S9S_MB_2U(SCH_1):GND     I5 @S9S_MB_2U_LIB.S9S_MB_2U(SCH_1):PAGE70
  EB44    GND @S9S_MB_2U_LIB.S9S_MB_2U(SCH_1):GND     I5 @S9S_MB_2U_LIB.S9S_MB_2U(SCH_1):PAGE70
   EB4    GND @S9S_MB_2U_LIB.S9S_MB_2U(SCH_1):GND     I5 @S9S_MB_2U_LIB.S9S_MB_2U(SCH_1):PAGE70
  EB34    GND @S9S_MB_2U_LIB.S9S_MB_2U(SCH_1):GND     I5 @S9S_MB_2U_LIB.S9S_MB_2U(SCH_1):PAGE70
  EB26    GND @S9S_MB_2U_LIB.S9S_MB_2U(SCH_1):GND     I5 @S9S_MB_2U_LIB.S9S_MB_2U(SCH_1):PAGE70
  EB20    GND @S9S_MB_2U_LIB.S9S_MB_2U(SCH_1):GND     I5 @S9S_MB_2U_LIB.S9S_MB_2U(SCH_1):PAGE70
  EB16    GND @S9S_MB_2U_LIB.S9S_MB_2U(SCH_1):GND     I5 @S9S_MB_2U_LIB.S9S_MB_2U(SCH_1):PAGE70
  EA64    GND @S9S_MB_2U_LIB.S9S_MB_2U(SCH_1):GND     I5 @S9S_MB_2U_LIB.S9S_MB_2U(SCH_1):PAGE70
  EA58    GND @S9S_MB_2U_LIB.S9S_MB_2U(SCH_1):GND     I5 @S9S_MB_2U_LIB.S9S_MB_2U(SCH_1):PAGE70
  EA52    GND @S9S_MB_2U_LIB.S9S_MB_2U(SCH_1):GND     I5 @S9S_MB_2U_LIB.S9S_MB_2U(SCH_1):PAGE70
  EA45    GND @S9S_MB_2U_LIB.S9S_MB_2U(SCH_1):GND     I5 @S9S_MB_2U_LIB.S9S_MB_2U(SCH_1):PAGE70
  EA39    GND @S9S_MB_2U_LIB.S9S_MB_2U(SCH_1):GND     I5 @S9S_MB_2U_LIB.S9S_MB_2U(SCH_1):PAGE70
  DY42    GND @S9S_MB_2U_LIB.S9S_MB_2U(SCH_1):GND     I5 @S9S_MB_2U_LIB.S9S_MB_2U(SCH_1):PAGE70
   DY4    GND @S9S_MB_2U_LIB.S9S_MB_2U(SCH_1):GND     I5 @S9S_MB_2U_LIB.S9S_MB_2U(SCH_1):PAGE70
  DY16    GND @S9S_MB_2U_LIB.S9S_MB_2U(SCH_1):GND     I5 @S9S_MB_2U_LIB.S9S_MB_2U(SCH_1):PAGE70
  DY12    GND @S9S_MB_2U_LIB.S9S_MB_2U(SCH_1):GND     I5 @S9S_MB_2U_LIB.S9S_MB_2U(SCH_1):PAGE70
   DW9    GND @S9S_MB_2U_LIB.S9S_MB_2U(SCH_1):GND     I8 @S9S_MB_2U_LIB.S9S_MB_2U(SCH_1):PAGE70
  DW64    GND @S9S_MB_2U_LIB.S9S_MB_2U(SCH_1):GND     I8 @S9S_MB_2U_LIB.S9S_MB_2U(SCH_1):PAGE70
  DW62    GND @S9S_MB_2U_LIB.S9S_MB_2U(SCH_1):GND     I8 @S9S_MB_2U_LIB.S9S_MB_2U(SCH_1):PAGE70
  DW58    GND @S9S_MB_2U_LIB.S9S_MB_2U(SCH_1):GND     I8 @S9S_MB_2U_LIB.S9S_MB_2U(SCH_1):PAGE70
  DW56    GND @S9S_MB_2U_LIB.S9S_MB_2U(SCH_1):GND     I8 @S9S_MB_2U_LIB.S9S_MB_2U(SCH_1):PAGE70
  DW54    GND @S9S_MB_2U_LIB.S9S_MB_2U(SCH_1):GND     I8 @S9S_MB_2U_LIB.S9S_MB_2U(SCH_1):PAGE70
  DW52    GND @S9S_MB_2U_LIB.S9S_MB_2U(SCH_1):GND     I8 @S9S_MB_2U_LIB.S9S_MB_2U(SCH_1):PAGE70
  DW50    GND @S9S_MB_2U_LIB.S9S_MB_2U(SCH_1):GND     I8 @S9S_MB_2U_LIB.S9S_MB_2U(SCH_1):PAGE70
   DW5    GND @S9S_MB_2U_LIB.S9S_MB_2U(SCH_1):GND     I8 @S9S_MB_2U_LIB.S9S_MB_2U(SCH_1):PAGE70
  DW48    GND @S9S_MB_2U_LIB.S9S_MB_2U(SCH_1):GND     I8 @S9S_MB_2U_LIB.S9S_MB_2U(SCH_1):PAGE70
  DW45    GND @S9S_MB_2U_LIB.S9S_MB_2U(SCH_1):GND     I8 @S9S_MB_2U_LIB.S9S_MB_2U(SCH_1):PAGE70
  DW43    GND @S9S_MB_2U_LIB.S9S_MB_2U(SCH_1):GND     I8 @S9S_MB_2U_LIB.S9S_MB_2U(SCH_1):PAGE70
  DW41    GND @S9S_MB_2U_LIB.S9S_MB_2U(SCH_1):GND     I8 @S9S_MB_2U_LIB.S9S_MB_2U(SCH_1):PAGE70
  DW39    GND @S9S_MB_2U_LIB.S9S_MB_2U(SCH_1):GND     I8 @S9S_MB_2U_LIB.S9S_MB_2U(SCH_1):PAGE70
  DW37    GND @S9S_MB_2U_LIB.S9S_MB_2U(SCH_1):GND     I8 @S9S_MB_2U_LIB.S9S_MB_2U(SCH_1):PAGE70
  DW35    GND @S9S_MB_2U_LIB.S9S_MB_2U(SCH_1):GND     I8 @S9S_MB_2U_LIB.S9S_MB_2U(SCH_1):PAGE70
  DW33    GND @S9S_MB_2U_LIB.S9S_MB_2U(SCH_1):GND     I8 @S9S_MB_2U_LIB.S9S_MB_2U(SCH_1):PAGE70
  DW31    GND @S9S_MB_2U_LIB.S9S_MB_2U(SCH_1):GND     I8 @S9S_MB_2U_LIB.S9S_MB_2U(SCH_1):PAGE70
  DW29    GND @S9S_MB_2U_LIB.S9S_MB_2U(SCH_1):GND     I8 @S9S_MB_2U_LIB.S9S_MB_2U(SCH_1):PAGE70
  DW27    GND @S9S_MB_2U_LIB.S9S_MB_2U(SCH_1):GND     I8 @S9S_MB_2U_LIB.S9S_MB_2U(SCH_1):PAGE70
  DW25    GND @S9S_MB_2U_LIB.S9S_MB_2U(SCH_1):GND     I8 @S9S_MB_2U_LIB.S9S_MB_2U(SCH_1):PAGE70
  DW23    GND @S9S_MB_2U_LIB.S9S_MB_2U(SCH_1):GND     I8 @S9S_MB_2U_LIB.S9S_MB_2U(SCH_1):PAGE70
  DW19    GND @S9S_MB_2U_LIB.S9S_MB_2U(SCH_1):GND     I8 @S9S_MB_2U_LIB.S9S_MB_2U(SCH_1):PAGE70
  DW17    GND @S9S_MB_2U_LIB.S9S_MB_2U(SCH_1):GND     I8 @S9S_MB_2U_LIB.S9S_MB_2U(SCH_1):PAGE70
  DW13    GND @S9S_MB_2U_LIB.S9S_MB_2U(SCH_1):GND     I8 @S9S_MB_2U_LIB.S9S_MB_2U(SCH_1):PAGE70
   DW1    GND @S9S_MB_2U_LIB.S9S_MB_2U(SCH_1):GND     I8 @S9S_MB_2U_LIB.S9S_MB_2U(SCH_1):PAGE70
  DV91    GND @S9S_MB_2U_LIB.S9S_MB_2U(SCH_1):GND     I8 @S9S_MB_2U_LIB.S9S_MB_2U(SCH_1):PAGE70
  DV87    GND @S9S_MB_2U_LIB.S9S_MB_2U(SCH_1):GND     I8 @S9S_MB_2U_LIB.S9S_MB_2U(SCH_1):PAGE70
  DV83    GND @S9S_MB_2U_LIB.S9S_MB_2U(SCH_1):GND     I8 @S9S_MB_2U_LIB.S9S_MB_2U(SCH_1):PAGE70
  DV81    GND @S9S_MB_2U_LIB.S9S_MB_2U(SCH_1):GND     I8 @S9S_MB_2U_LIB.S9S_MB_2U(SCH_1):PAGE70
   DV8    GND @S9S_MB_2U_LIB.S9S_MB_2U(SCH_1):GND     I8 @S9S_MB_2U_LIB.S9S_MB_2U(SCH_1):PAGE70
  DV79    GND @S9S_MB_2U_LIB.S9S_MB_2U(SCH_1):GND     I8 @S9S_MB_2U_LIB.S9S_MB_2U(SCH_1):PAGE70
  DV77    GND @S9S_MB_2U_LIB.S9S_MB_2U(SCH_1):GND     I8 @S9S_MB_2U_LIB.S9S_MB_2U(SCH_1):PAGE70
  DU88    GND @S9S_MB_2U_LIB.S9S_MB_2U(SCH_1):GND     I8 @S9S_MB_2U_LIB.S9S_MB_2U(SCH_1):PAGE70
  DU84    GND @S9S_MB_2U_LIB.S9S_MB_2U(SCH_1):GND     I8 @S9S_MB_2U_LIB.S9S_MB_2U(SCH_1):PAGE70
  DU78    GND @S9S_MB_2U_LIB.S9S_MB_2U(SCH_1):GND     I8 @S9S_MB_2U_LIB.S9S_MB_2U(SCH_1):PAGE70
  DU76    GND @S9S_MB_2U_LIB.S9S_MB_2U(SCH_1):GND     I8 @S9S_MB_2U_LIB.S9S_MB_2U(SCH_1):PAGE70
  DU33    GND @S9S_MB_2U_LIB.S9S_MB_2U(SCH_1):GND     I8 @S9S_MB_2U_LIB.S9S_MB_2U(SCH_1):PAGE70
  DU27    GND @S9S_MB_2U_LIB.S9S_MB_2U(SCH_1):GND     I8 @S9S_MB_2U_LIB.S9S_MB_2U(SCH_1):PAGE70
  DU21    GND @S9S_MB_2U_LIB.S9S_MB_2U(SCH_1):GND     I8 @S9S_MB_2U_LIB.S9S_MB_2U(SCH_1):PAGE70
   DT8    GND @S9S_MB_2U_LIB.S9S_MB_2U(SCH_1):GND     I8 @S9S_MB_2U_LIB.S9S_MB_2U(SCH_1):PAGE70
  DT75    GND @S9S_MB_2U_LIB.S9S_MB_2U(SCH_1):GND     I8 @S9S_MB_2U_LIB.S9S_MB_2U(SCH_1):PAGE70
  DT71    GND @S9S_MB_2U_LIB.S9S_MB_2U(SCH_1):GND     I8 @S9S_MB_2U_LIB.S9S_MB_2U(SCH_1):PAGE70
  DT69    GND @S9S_MB_2U_LIB.S9S_MB_2U(SCH_1):GND     I8 @S9S_MB_2U_LIB.S9S_MB_2U(SCH_1):PAGE70
  DT65    GND @S9S_MB_2U_LIB.S9S_MB_2U(SCH_1):GND     I8 @S9S_MB_2U_LIB.S9S_MB_2U(SCH_1):PAGE70
  DT57    GND @S9S_MB_2U_LIB.S9S_MB_2U(SCH_1):GND     I8 @S9S_MB_2U_LIB.S9S_MB_2U(SCH_1):PAGE70
  DT47    GND @S9S_MB_2U_LIB.S9S_MB_2U(SCH_1):GND     I8 @S9S_MB_2U_LIB.S9S_MB_2U(SCH_1):PAGE70
  DT40    GND @S9S_MB_2U_LIB.S9S_MB_2U(SCH_1):GND     I8 @S9S_MB_2U_LIB.S9S_MB_2U(SCH_1):PAGE70
  DT38    GND @S9S_MB_2U_LIB.S9S_MB_2U(SCH_1):GND     I8 @S9S_MB_2U_LIB.S9S_MB_2U(SCH_1):PAGE70
  DT34    GND @S9S_MB_2U_LIB.S9S_MB_2U(SCH_1):GND     I8 @S9S_MB_2U_LIB.S9S_MB_2U(SCH_1):PAGE70
  DT32    GND @S9S_MB_2U_LIB.S9S_MB_2U(SCH_1):GND     I8 @S9S_MB_2U_LIB.S9S_MB_2U(SCH_1):PAGE70
  DT28    GND @S9S_MB_2U_LIB.S9S_MB_2U(SCH_1):GND     I8 @S9S_MB_2U_LIB.S9S_MB_2U(SCH_1):PAGE70
  DT22    GND @S9S_MB_2U_LIB.S9S_MB_2U(SCH_1):GND     I8 @S9S_MB_2U_LIB.S9S_MB_2U(SCH_1):PAGE70
  DT12    GND @S9S_MB_2U_LIB.S9S_MB_2U(SCH_1):GND     I8 @S9S_MB_2U_LIB.S9S_MB_2U(SCH_1):PAGE70
   DR9    GND @S9S_MB_2U_LIB.S9S_MB_2U(SCH_1):GND     I8 @S9S_MB_2U_LIB.S9S_MB_2U(SCH_1):PAGE70
  DR88    GND @S9S_MB_2U_LIB.S9S_MB_2U(SCH_1):GND     I8 @S9S_MB_2U_LIB.S9S_MB_2U(SCH_1):PAGE70
  DR84    GND @S9S_MB_2U_LIB.S9S_MB_2U(SCH_1):GND     I8 @S9S_MB_2U_LIB.S9S_MB_2U(SCH_1):PAGE70
  DR78    GND @S9S_MB_2U_LIB.S9S_MB_2U(SCH_1):GND     I8 @S9S_MB_2U_LIB.S9S_MB_2U(SCH_1):PAGE70
  DR74    GND @S9S_MB_2U_LIB.S9S_MB_2U(SCH_1):GND     I8 @S9S_MB_2U_LIB.S9S_MB_2U(SCH_1):PAGE70
  DR66    GND @S9S_MB_2U_LIB.S9S_MB_2U(SCH_1):GND     I8 @S9S_MB_2U_LIB.S9S_MB_2U(SCH_1):PAGE70
  DR56    GND @S9S_MB_2U_LIB.S9S_MB_2U(SCH_1):GND     I8 @S9S_MB_2U_LIB.S9S_MB_2U(SCH_1):PAGE70
  DR50    GND @S9S_MB_2U_LIB.S9S_MB_2U(SCH_1):GND     I8 @S9S_MB_2U_LIB.S9S_MB_2U(SCH_1):PAGE70
  DR48    GND @S9S_MB_2U_LIB.S9S_MB_2U(SCH_1):GND     I8 @S9S_MB_2U_LIB.S9S_MB_2U(SCH_1):PAGE70
  DR43    GND @S9S_MB_2U_LIB.S9S_MB_2U(SCH_1):GND     I8 @S9S_MB_2U_LIB.S9S_MB_2U(SCH_1):PAGE70
  DR41    GND @S9S_MB_2U_LIB.S9S_MB_2U(SCH_1):GND     I8 @S9S_MB_2U_LIB.S9S_MB_2U(SCH_1):PAGE70
  DR37    GND @S9S_MB_2U_LIB.S9S_MB_2U(SCH_1):GND     I8 @S9S_MB_2U_LIB.S9S_MB_2U(SCH_1):PAGE70
  DR31    GND @S9S_MB_2U_LIB.S9S_MB_2U(SCH_1):GND     I8 @S9S_MB_2U_LIB.S9S_MB_2U(SCH_1):PAGE70
  DR29    GND @S9S_MB_2U_LIB.S9S_MB_2U(SCH_1):GND     I8 @S9S_MB_2U_LIB.S9S_MB_2U(SCH_1):PAGE70
  DR23    GND @S9S_MB_2U_LIB.S9S_MB_2U(SCH_1):GND     I8 @S9S_MB_2U_LIB.S9S_MB_2U(SCH_1):PAGE70
  DR19    GND @S9S_MB_2U_LIB.S9S_MB_2U(SCH_1):GND     I8 @S9S_MB_2U_LIB.S9S_MB_2U(SCH_1):PAGE70
  DR13    GND @S9S_MB_2U_LIB.S9S_MB_2U(SCH_1):GND     I8 @S9S_MB_2U_LIB.S9S_MB_2U(SCH_1):PAGE70
   DR1    GND @S9S_MB_2U_LIB.S9S_MB_2U(SCH_1):GND     I8 @S9S_MB_2U_LIB.S9S_MB_2U(SCH_1):PAGE70
  DP87    GND @S9S_MB_2U_LIB.S9S_MB_2U(SCH_1):GND     I8 @S9S_MB_2U_LIB.S9S_MB_2U(SCH_1):PAGE70
  DP81    GND @S9S_MB_2U_LIB.S9S_MB_2U(SCH_1):GND     I8 @S9S_MB_2U_LIB.S9S_MB_2U(SCH_1):PAGE70
   DP8    GND @S9S_MB_2U_LIB.S9S_MB_2U(SCH_1):GND     I8 @S9S_MB_2U_LIB.S9S_MB_2U(SCH_1):PAGE70
  DP73    GND @S9S_MB_2U_LIB.S9S_MB_2U(SCH_1):GND     I8 @S9S_MB_2U_LIB.S9S_MB_2U(SCH_1):PAGE70
  DP49    GND @S9S_MB_2U_LIB.S9S_MB_2U(SCH_1):GND     I8 @S9S_MB_2U_LIB.S9S_MB_2U(SCH_1):PAGE70
   DP4    GND @S9S_MB_2U_LIB.S9S_MB_2U(SCH_1):GND     I8 @S9S_MB_2U_LIB.S9S_MB_2U(SCH_1):PAGE70
  DP36    GND @S9S_MB_2U_LIB.S9S_MB_2U(SCH_1):GND     I8 @S9S_MB_2U_LIB.S9S_MB_2U(SCH_1):PAGE70
  DP30    GND @S9S_MB_2U_LIB.S9S_MB_2U(SCH_1):GND     I8 @S9S_MB_2U_LIB.S9S_MB_2U(SCH_1):PAGE70
  DP16    GND @S9S_MB_2U_LIB.S9S_MB_2U(SCH_1):GND     I8 @S9S_MB_2U_LIB.S9S_MB_2U(SCH_1):PAGE70
  DN88    GND @S9S_MB_2U_LIB.S9S_MB_2U(SCH_1):GND     I8 @S9S_MB_2U_LIB.S9S_MB_2U(SCH_1):PAGE70
  DN84    GND @S9S_MB_2U_LIB.S9S_MB_2U(SCH_1):GND     I8 @S9S_MB_2U_LIB.S9S_MB_2U(SCH_1):PAGE70
  DN78    GND @S9S_MB_2U_LIB.S9S_MB_2U(SCH_1):GND     I8 @S9S_MB_2U_LIB.S9S_MB_2U(SCH_1):PAGE70
   DM8    GND @S9S_MB_2U_LIB.S9S_MB_2U(SCH_1):GND     I8 @S9S_MB_2U_LIB.S9S_MB_2U(SCH_1):PAGE70
  DM79    GND @S9S_MB_2U_LIB.S9S_MB_2U(SCH_1):GND     I8 @S9S_MB_2U_LIB.S9S_MB_2U(SCH_1):PAGE70
  DM77    GND @S9S_MB_2U_LIB.S9S_MB_2U(SCH_1):GND     I8 @S9S_MB_2U_LIB.S9S_MB_2U(SCH_1):PAGE70
  DM75    GND @S9S_MB_2U_LIB.S9S_MB_2U(SCH_1):GND     I8 @S9S_MB_2U_LIB.S9S_MB_2U(SCH_1):PAGE70
  DM71    GND @S9S_MB_2U_LIB.S9S_MB_2U(SCH_1):GND     I8 @S9S_MB_2U_LIB.S9S_MB_2U(SCH_1):PAGE70
  DM69    GND @S9S_MB_2U_LIB.S9S_MB_2U(SCH_1):GND     I8 @S9S_MB_2U_LIB.S9S_MB_2U(SCH_1):PAGE70
  DM67    GND @S9S_MB_2U_LIB.S9S_MB_2U(SCH_1):GND     I8 @S9S_MB_2U_LIB.S9S_MB_2U(SCH_1):PAGE70
  DM65    GND @S9S_MB_2U_LIB.S9S_MB_2U(SCH_1):GND     I8 @S9S_MB_2U_LIB.S9S_MB_2U(SCH_1):PAGE70
  DM63    GND @S9S_MB_2U_LIB.S9S_MB_2U(SCH_1):GND     I8 @S9S_MB_2U_LIB.S9S_MB_2U(SCH_1):PAGE70
  DM61    GND @S9S_MB_2U_LIB.S9S_MB_2U(SCH_1):GND     I8 @S9S_MB_2U_LIB.S9S_MB_2U(SCH_1):PAGE70
  DM59    GND @S9S_MB_2U_LIB.S9S_MB_2U(SCH_1):GND     I8 @S9S_MB_2U_LIB.S9S_MB_2U(SCH_1):PAGE70
  DM57    GND @S9S_MB_2U_LIB.S9S_MB_2U(SCH_1):GND     I8 @S9S_MB_2U_LIB.S9S_MB_2U(SCH_1):PAGE70
  DM55    GND @S9S_MB_2U_LIB.S9S_MB_2U(SCH_1):GND     I8 @S9S_MB_2U_LIB.S9S_MB_2U(SCH_1):PAGE70
  DM53    GND @S9S_MB_2U_LIB.S9S_MB_2U(SCH_1):GND     I8 @S9S_MB_2U_LIB.S9S_MB_2U(SCH_1):PAGE70
  DM49    GND @S9S_MB_2U_LIB.S9S_MB_2U(SCH_1):GND     I8 @S9S_MB_2U_LIB.S9S_MB_2U(SCH_1):PAGE70
  DM47    GND @S9S_MB_2U_LIB.S9S_MB_2U(SCH_1):GND     I8 @S9S_MB_2U_LIB.S9S_MB_2U(SCH_1):PAGE70
  DM44    GND @S9S_MB_2U_LIB.S9S_MB_2U(SCH_1):GND     I8 @S9S_MB_2U_LIB.S9S_MB_2U(SCH_1):PAGE70
  DM42    GND @S9S_MB_2U_LIB.S9S_MB_2U(SCH_1):GND     I8 @S9S_MB_2U_LIB.S9S_MB_2U(SCH_1):PAGE70
  DM40    GND @S9S_MB_2U_LIB.S9S_MB_2U(SCH_1):GND     I8 @S9S_MB_2U_LIB.S9S_MB_2U(SCH_1):PAGE70
   DM4    GND @S9S_MB_2U_LIB.S9S_MB_2U(SCH_1):GND     I8 @S9S_MB_2U_LIB.S9S_MB_2U(SCH_1):PAGE70
  DM38    GND @S9S_MB_2U_LIB.S9S_MB_2U(SCH_1):GND     I8 @S9S_MB_2U_LIB.S9S_MB_2U(SCH_1):PAGE70
  DM36    GND @S9S_MB_2U_LIB.S9S_MB_2U(SCH_1):GND     I8 @S9S_MB_2U_LIB.S9S_MB_2U(SCH_1):PAGE70
  DM34    GND @S9S_MB_2U_LIB.S9S_MB_2U(SCH_1):GND     I8 @S9S_MB_2U_LIB.S9S_MB_2U(SCH_1):PAGE70
  DM32    GND @S9S_MB_2U_LIB.S9S_MB_2U(SCH_1):GND     I8 @S9S_MB_2U_LIB.S9S_MB_2U(SCH_1):PAGE70
  DM30    GND @S9S_MB_2U_LIB.S9S_MB_2U(SCH_1):GND     I8 @S9S_MB_2U_LIB.S9S_MB_2U(SCH_1):PAGE70
  DM28    GND @S9S_MB_2U_LIB.S9S_MB_2U(SCH_1):GND     I8 @S9S_MB_2U_LIB.S9S_MB_2U(SCH_1):PAGE70
  DM26    GND @S9S_MB_2U_LIB.S9S_MB_2U(SCH_1):GND     I8 @S9S_MB_2U_LIB.S9S_MB_2U(SCH_1):PAGE70
  DM24    GND @S9S_MB_2U_LIB.S9S_MB_2U(SCH_1):GND     I8 @S9S_MB_2U_LIB.S9S_MB_2U(SCH_1):PAGE70
  DM22    GND @S9S_MB_2U_LIB.S9S_MB_2U(SCH_1):GND     I8 @S9S_MB_2U_LIB.S9S_MB_2U(SCH_1):PAGE70
  DM20    GND @S9S_MB_2U_LIB.S9S_MB_2U(SCH_1):GND     I8 @S9S_MB_2U_LIB.S9S_MB_2U(SCH_1):PAGE70
  DM18    GND @S9S_MB_2U_LIB.S9S_MB_2U(SCH_1):GND     I8 @S9S_MB_2U_LIB.S9S_MB_2U(SCH_1):PAGE70
  DM16    GND @S9S_MB_2U_LIB.S9S_MB_2U(SCH_1):GND     I8 @S9S_MB_2U_LIB.S9S_MB_2U(SCH_1):PAGE70
  DM12    GND @S9S_MB_2U_LIB.S9S_MB_2U(SCH_1):GND     I8 @S9S_MB_2U_LIB.S9S_MB_2U(SCH_1):PAGE70
  DW60    GND @S9S_MB_2U_LIB.S9S_MB_2U(SCH_1):GND     I8 @S9S_MB_2U_LIB.S9S_MB_2U(SCH_1):PAGE70
  DW21    GND @S9S_MB_2U_LIB.S9S_MB_2U(SCH_1):GND     I8 @S9S_MB_2U_LIB.S9S_MB_2U(SCH_1):PAGE70
  DV42    GND @S9S_MB_2U_LIB.S9S_MB_2U(SCH_1):GND     I8 @S9S_MB_2U_LIB.S9S_MB_2U(SCH_1):PAGE70
   DV4    GND @S9S_MB_2U_LIB.S9S_MB_2U(SCH_1):GND     I8 @S9S_MB_2U_LIB.S9S_MB_2U(SCH_1):PAGE70
  DV16    GND @S9S_MB_2U_LIB.S9S_MB_2U(SCH_1):GND     I8 @S9S_MB_2U_LIB.S9S_MB_2U(SCH_1):PAGE70
  DV12    GND @S9S_MB_2U_LIB.S9S_MB_2U(SCH_1):GND     I8 @S9S_MB_2U_LIB.S9S_MB_2U(SCH_1):PAGE70
  DU70    GND @S9S_MB_2U_LIB.S9S_MB_2U(SCH_1):GND     I8 @S9S_MB_2U_LIB.S9S_MB_2U(SCH_1):PAGE70
  DU64    GND @S9S_MB_2U_LIB.S9S_MB_2U(SCH_1):GND     I8 @S9S_MB_2U_LIB.S9S_MB_2U(SCH_1):PAGE70
  DU58    GND @S9S_MB_2U_LIB.S9S_MB_2U(SCH_1):GND     I8 @S9S_MB_2U_LIB.S9S_MB_2U(SCH_1):PAGE70
  DU52    GND @S9S_MB_2U_LIB.S9S_MB_2U(SCH_1):GND     I8 @S9S_MB_2U_LIB.S9S_MB_2U(SCH_1):PAGE70
  DU45    GND @S9S_MB_2U_LIB.S9S_MB_2U(SCH_1):GND     I8 @S9S_MB_2U_LIB.S9S_MB_2U(SCH_1):PAGE70
  DU39    GND @S9S_MB_2U_LIB.S9S_MB_2U(SCH_1):GND     I8 @S9S_MB_2U_LIB.S9S_MB_2U(SCH_1):PAGE70
  DT83    GND @S9S_MB_2U_LIB.S9S_MB_2U(SCH_1):GND     I8 @S9S_MB_2U_LIB.S9S_MB_2U(SCH_1):PAGE70
  DT63    GND @S9S_MB_2U_LIB.S9S_MB_2U(SCH_1):GND     I8 @S9S_MB_2U_LIB.S9S_MB_2U(SCH_1):PAGE70
  DT59    GND @S9S_MB_2U_LIB.S9S_MB_2U(SCH_1):GND     I8 @S9S_MB_2U_LIB.S9S_MB_2U(SCH_1):PAGE70
  DT53    GND @S9S_MB_2U_LIB.S9S_MB_2U(SCH_1):GND     I8 @S9S_MB_2U_LIB.S9S_MB_2U(SCH_1):PAGE70
  DT51    GND @S9S_MB_2U_LIB.S9S_MB_2U(SCH_1):GND     I8 @S9S_MB_2U_LIB.S9S_MB_2U(SCH_1):PAGE70
  DT44    GND @S9S_MB_2U_LIB.S9S_MB_2U(SCH_1):GND     I8 @S9S_MB_2U_LIB.S9S_MB_2U(SCH_1):PAGE70
   DT4    GND @S9S_MB_2U_LIB.S9S_MB_2U(SCH_1):GND     I8 @S9S_MB_2U_LIB.S9S_MB_2U(SCH_1):PAGE70
  DT26    GND @S9S_MB_2U_LIB.S9S_MB_2U(SCH_1):GND     I8 @S9S_MB_2U_LIB.S9S_MB_2U(SCH_1):PAGE70
  DT20    GND @S9S_MB_2U_LIB.S9S_MB_2U(SCH_1):GND     I8 @S9S_MB_2U_LIB.S9S_MB_2U(SCH_1):PAGE70
  DT16    GND @S9S_MB_2U_LIB.S9S_MB_2U(SCH_1):GND     I8 @S9S_MB_2U_LIB.S9S_MB_2U(SCH_1):PAGE70
  DR72    GND @S9S_MB_2U_LIB.S9S_MB_2U(SCH_1):GND     I8 @S9S_MB_2U_LIB.S9S_MB_2U(SCH_1):PAGE70
  DR68    GND @S9S_MB_2U_LIB.S9S_MB_2U(SCH_1):GND     I8 @S9S_MB_2U_LIB.S9S_MB_2U(SCH_1):PAGE70
  DR62    GND @S9S_MB_2U_LIB.S9S_MB_2U(SCH_1):GND     I8 @S9S_MB_2U_LIB.S9S_MB_2U(SCH_1):PAGE70
  DR60    GND @S9S_MB_2U_LIB.S9S_MB_2U(SCH_1):GND     I8 @S9S_MB_2U_LIB.S9S_MB_2U(SCH_1):PAGE70
  DR54    GND @S9S_MB_2U_LIB.S9S_MB_2U(SCH_1):GND     I8 @S9S_MB_2U_LIB.S9S_MB_2U(SCH_1):PAGE70
   DR5    GND @S9S_MB_2U_LIB.S9S_MB_2U(SCH_1):GND     I8 @S9S_MB_2U_LIB.S9S_MB_2U(SCH_1):PAGE70
  DR35    GND @S9S_MB_2U_LIB.S9S_MB_2U(SCH_1):GND     I8 @S9S_MB_2U_LIB.S9S_MB_2U(SCH_1):PAGE70
  DR25    GND @S9S_MB_2U_LIB.S9S_MB_2U(SCH_1):GND     I8 @S9S_MB_2U_LIB.S9S_MB_2U(SCH_1):PAGE70
  DP91    GND @S9S_MB_2U_LIB.S9S_MB_2U(SCH_1):GND     I8 @S9S_MB_2U_LIB.S9S_MB_2U(SCH_1):PAGE70
  DP67    GND @S9S_MB_2U_LIB.S9S_MB_2U(SCH_1):GND     I8 @S9S_MB_2U_LIB.S9S_MB_2U(SCH_1):PAGE70
  DP61    GND @S9S_MB_2U_LIB.S9S_MB_2U(SCH_1):GND     I8 @S9S_MB_2U_LIB.S9S_MB_2U(SCH_1):PAGE70
  DP55    GND @S9S_MB_2U_LIB.S9S_MB_2U(SCH_1):GND     I8 @S9S_MB_2U_LIB.S9S_MB_2U(SCH_1):PAGE70
  DP42    GND @S9S_MB_2U_LIB.S9S_MB_2U(SCH_1):GND     I8 @S9S_MB_2U_LIB.S9S_MB_2U(SCH_1):PAGE70
  DP24    GND @S9S_MB_2U_LIB.S9S_MB_2U(SCH_1):GND     I8 @S9S_MB_2U_LIB.S9S_MB_2U(SCH_1):PAGE70
  DP18    GND @S9S_MB_2U_LIB.S9S_MB_2U(SCH_1):GND     I8 @S9S_MB_2U_LIB.S9S_MB_2U(SCH_1):PAGE70
  DP12    GND @S9S_MB_2U_LIB.S9S_MB_2U(SCH_1):GND     I8 @S9S_MB_2U_LIB.S9S_MB_2U(SCH_1):PAGE70
  DN52    GND @S9S_MB_2U_LIB.S9S_MB_2U(SCH_1):GND     I8 @S9S_MB_2U_LIB.S9S_MB_2U(SCH_1):PAGE70
  DN39    GND @S9S_MB_2U_LIB.S9S_MB_2U(SCH_1):GND     I8 @S9S_MB_2U_LIB.S9S_MB_2U(SCH_1):PAGE70
  DN17    GND @S9S_MB_2U_LIB.S9S_MB_2U(SCH_1):GND     I8 @S9S_MB_2U_LIB.S9S_MB_2U(SCH_1):PAGE70
  DM73    GND @S9S_MB_2U_LIB.S9S_MB_2U(SCH_1):GND     I8 @S9S_MB_2U_LIB.S9S_MB_2U(SCH_1):PAGE70
  DM51    GND @S9S_MB_2U_LIB.S9S_MB_2U(SCH_1):GND     I8 @S9S_MB_2U_LIB.S9S_MB_2U(SCH_1):PAGE70
   DL9    GND @S9S_MB_2U_LIB.S9S_MB_2U(SCH_1):GND     I2 @S9S_MB_2U_LIB.S9S_MB_2U(SCH_1):PAGE71
  DL88    GND @S9S_MB_2U_LIB.S9S_MB_2U(SCH_1):GND     I2 @S9S_MB_2U_LIB.S9S_MB_2U(SCH_1):PAGE71
  DL84    GND @S9S_MB_2U_LIB.S9S_MB_2U(SCH_1):GND     I2 @S9S_MB_2U_LIB.S9S_MB_2U(SCH_1):PAGE71
  DL39    GND @S9S_MB_2U_LIB.S9S_MB_2U(SCH_1):GND     I2 @S9S_MB_2U_LIB.S9S_MB_2U(SCH_1):PAGE71
  DK91    GND @S9S_MB_2U_LIB.S9S_MB_2U(SCH_1):GND     I2 @S9S_MB_2U_LIB.S9S_MB_2U(SCH_1):PAGE71
  DK87    GND @S9S_MB_2U_LIB.S9S_MB_2U(SCH_1):GND     I2 @S9S_MB_2U_LIB.S9S_MB_2U(SCH_1):PAGE71
  DK83    GND @S9S_MB_2U_LIB.S9S_MB_2U(SCH_1):GND     I2 @S9S_MB_2U_LIB.S9S_MB_2U(SCH_1):PAGE71
  DK81    GND @S9S_MB_2U_LIB.S9S_MB_2U(SCH_1):GND     I2 @S9S_MB_2U_LIB.S9S_MB_2U(SCH_1):PAGE71
   DK8    GND @S9S_MB_2U_LIB.S9S_MB_2U(SCH_1):GND     I2 @S9S_MB_2U_LIB.S9S_MB_2U(SCH_1):PAGE71
  DK79    GND @S9S_MB_2U_LIB.S9S_MB_2U(SCH_1):GND     I2 @S9S_MB_2U_LIB.S9S_MB_2U(SCH_1):PAGE71
  DK77    GND @S9S_MB_2U_LIB.S9S_MB_2U(SCH_1):GND     I2 @S9S_MB_2U_LIB.S9S_MB_2U(SCH_1):PAGE71
  DK73    GND @S9S_MB_2U_LIB.S9S_MB_2U(SCH_1):GND     I2 @S9S_MB_2U_LIB.S9S_MB_2U(SCH_1):PAGE71
  DK49    GND @S9S_MB_2U_LIB.S9S_MB_2U(SCH_1):GND     I2 @S9S_MB_2U_LIB.S9S_MB_2U(SCH_1):PAGE71
   DK4    GND @S9S_MB_2U_LIB.S9S_MB_2U(SCH_1):GND     I2 @S9S_MB_2U_LIB.S9S_MB_2U(SCH_1):PAGE71
  DK36    GND @S9S_MB_2U_LIB.S9S_MB_2U(SCH_1):GND     I2 @S9S_MB_2U_LIB.S9S_MB_2U(SCH_1):PAGE71
  DK30    GND @S9S_MB_2U_LIB.S9S_MB_2U(SCH_1):GND     I2 @S9S_MB_2U_LIB.S9S_MB_2U(SCH_1):PAGE71
  DK16    GND @S9S_MB_2U_LIB.S9S_MB_2U(SCH_1):GND     I2 @S9S_MB_2U_LIB.S9S_MB_2U(SCH_1):PAGE71
  DJ88    GND @S9S_MB_2U_LIB.S9S_MB_2U(SCH_1):GND     I2 @S9S_MB_2U_LIB.S9S_MB_2U(SCH_1):PAGE71
  DJ84    GND @S9S_MB_2U_LIB.S9S_MB_2U(SCH_1):GND     I2 @S9S_MB_2U_LIB.S9S_MB_2U(SCH_1):PAGE71
  DJ82    GND @S9S_MB_2U_LIB.S9S_MB_2U(SCH_1):GND     I2 @S9S_MB_2U_LIB.S9S_MB_2U(SCH_1):PAGE71
  DJ80    GND @S9S_MB_2U_LIB.S9S_MB_2U(SCH_1):GND     I2 @S9S_MB_2U_LIB.S9S_MB_2U(SCH_1):PAGE71
  DJ74    GND @S9S_MB_2U_LIB.S9S_MB_2U(SCH_1):GND     I2 @S9S_MB_2U_LIB.S9S_MB_2U(SCH_1):PAGE71
  DJ72    GND @S9S_MB_2U_LIB.S9S_MB_2U(SCH_1):GND     I2 @S9S_MB_2U_LIB.S9S_MB_2U(SCH_1):PAGE71
  DJ66    GND @S9S_MB_2U_LIB.S9S_MB_2U(SCH_1):GND     I2 @S9S_MB_2U_LIB.S9S_MB_2U(SCH_1):PAGE71
  DJ60    GND @S9S_MB_2U_LIB.S9S_MB_2U(SCH_1):GND     I2 @S9S_MB_2U_LIB.S9S_MB_2U(SCH_1):PAGE71
  DJ56    GND @S9S_MB_2U_LIB.S9S_MB_2U(SCH_1):GND     I2 @S9S_MB_2U_LIB.S9S_MB_2U(SCH_1):PAGE71
  DJ50    GND @S9S_MB_2U_LIB.S9S_MB_2U(SCH_1):GND     I2 @S9S_MB_2U_LIB.S9S_MB_2U(SCH_1):PAGE71
  DJ48    GND @S9S_MB_2U_LIB.S9S_MB_2U(SCH_1):GND     I2 @S9S_MB_2U_LIB.S9S_MB_2U(SCH_1):PAGE71
  DJ43    GND @S9S_MB_2U_LIB.S9S_MB_2U(SCH_1):GND     I2 @S9S_MB_2U_LIB.S9S_MB_2U(SCH_1):PAGE71
  DJ41    GND @S9S_MB_2U_LIB.S9S_MB_2U(SCH_1):GND     I2 @S9S_MB_2U_LIB.S9S_MB_2U(SCH_1):PAGE71
  DJ37    GND @S9S_MB_2U_LIB.S9S_MB_2U(SCH_1):GND     I2 @S9S_MB_2U_LIB.S9S_MB_2U(SCH_1):PAGE71
  DJ31    GND @S9S_MB_2U_LIB.S9S_MB_2U(SCH_1):GND     I2 @S9S_MB_2U_LIB.S9S_MB_2U(SCH_1):PAGE71
  DJ29    GND @S9S_MB_2U_LIB.S9S_MB_2U(SCH_1):GND     I2 @S9S_MB_2U_LIB.S9S_MB_2U(SCH_1):PAGE71
  DJ23    GND @S9S_MB_2U_LIB.S9S_MB_2U(SCH_1):GND     I2 @S9S_MB_2U_LIB.S9S_MB_2U(SCH_1):PAGE71
  DJ19    GND @S9S_MB_2U_LIB.S9S_MB_2U(SCH_1):GND     I2 @S9S_MB_2U_LIB.S9S_MB_2U(SCH_1):PAGE71
  DH85    GND @S9S_MB_2U_LIB.S9S_MB_2U(SCH_1):GND     I2 @S9S_MB_2U_LIB.S9S_MB_2U(SCH_1):PAGE71
   DH8    GND @S9S_MB_2U_LIB.S9S_MB_2U(SCH_1):GND     I2 @S9S_MB_2U_LIB.S9S_MB_2U(SCH_1):PAGE71
  DH77    GND @S9S_MB_2U_LIB.S9S_MB_2U(SCH_1):GND     I2 @S9S_MB_2U_LIB.S9S_MB_2U(SCH_1):PAGE71
  DH71    GND @S9S_MB_2U_LIB.S9S_MB_2U(SCH_1):GND     I2 @S9S_MB_2U_LIB.S9S_MB_2U(SCH_1):PAGE71
  DH65    GND @S9S_MB_2U_LIB.S9S_MB_2U(SCH_1):GND     I2 @S9S_MB_2U_LIB.S9S_MB_2U(SCH_1):PAGE71
  DH57    GND @S9S_MB_2U_LIB.S9S_MB_2U(SCH_1):GND     I2 @S9S_MB_2U_LIB.S9S_MB_2U(SCH_1):PAGE71
  DH47    GND @S9S_MB_2U_LIB.S9S_MB_2U(SCH_1):GND     I2 @S9S_MB_2U_LIB.S9S_MB_2U(SCH_1):PAGE71
  DH40    GND @S9S_MB_2U_LIB.S9S_MB_2U(SCH_1):GND     I2 @S9S_MB_2U_LIB.S9S_MB_2U(SCH_1):PAGE71
   DH4    GND @S9S_MB_2U_LIB.S9S_MB_2U(SCH_1):GND     I2 @S9S_MB_2U_LIB.S9S_MB_2U(SCH_1):PAGE71
  DH38    GND @S9S_MB_2U_LIB.S9S_MB_2U(SCH_1):GND     I2 @S9S_MB_2U_LIB.S9S_MB_2U(SCH_1):PAGE71
  DH32    GND @S9S_MB_2U_LIB.S9S_MB_2U(SCH_1):GND     I2 @S9S_MB_2U_LIB.S9S_MB_2U(SCH_1):PAGE71
  DH28    GND @S9S_MB_2U_LIB.S9S_MB_2U(SCH_1):GND     I2 @S9S_MB_2U_LIB.S9S_MB_2U(SCH_1):PAGE71
  DH22    GND @S9S_MB_2U_LIB.S9S_MB_2U(SCH_1):GND     I2 @S9S_MB_2U_LIB.S9S_MB_2U(SCH_1):PAGE71
  DH12    GND @S9S_MB_2U_LIB.S9S_MB_2U(SCH_1):GND     I2 @S9S_MB_2U_LIB.S9S_MB_2U(SCH_1):PAGE71
   DG9    GND @S9S_MB_2U_LIB.S9S_MB_2U(SCH_1):GND     I2 @S9S_MB_2U_LIB.S9S_MB_2U(SCH_1):PAGE71
  DG88    GND @S9S_MB_2U_LIB.S9S_MB_2U(SCH_1):GND     I2 @S9S_MB_2U_LIB.S9S_MB_2U(SCH_1):PAGE71
  DG84    GND @S9S_MB_2U_LIB.S9S_MB_2U(SCH_1):GND     I2 @S9S_MB_2U_LIB.S9S_MB_2U(SCH_1):PAGE71
  DG80    GND @S9S_MB_2U_LIB.S9S_MB_2U(SCH_1):GND     I2 @S9S_MB_2U_LIB.S9S_MB_2U(SCH_1):PAGE71
  DG76    GND @S9S_MB_2U_LIB.S9S_MB_2U(SCH_1):GND     I2 @S9S_MB_2U_LIB.S9S_MB_2U(SCH_1):PAGE71
  DG70    GND @S9S_MB_2U_LIB.S9S_MB_2U(SCH_1):GND     I2 @S9S_MB_2U_LIB.S9S_MB_2U(SCH_1):PAGE71
   DG5    GND @S9S_MB_2U_LIB.S9S_MB_2U(SCH_1):GND     I2 @S9S_MB_2U_LIB.S9S_MB_2U(SCH_1):PAGE71
  DG45    GND @S9S_MB_2U_LIB.S9S_MB_2U(SCH_1):GND     I2 @S9S_MB_2U_LIB.S9S_MB_2U(SCH_1):PAGE71
  DG39    GND @S9S_MB_2U_LIB.S9S_MB_2U(SCH_1):GND     I2 @S9S_MB_2U_LIB.S9S_MB_2U(SCH_1):PAGE71
  DG33    GND @S9S_MB_2U_LIB.S9S_MB_2U(SCH_1):GND     I2 @S9S_MB_2U_LIB.S9S_MB_2U(SCH_1):PAGE71
  DG27    GND @S9S_MB_2U_LIB.S9S_MB_2U(SCH_1):GND     I2 @S9S_MB_2U_LIB.S9S_MB_2U(SCH_1):PAGE71
  DF87    GND @S9S_MB_2U_LIB.S9S_MB_2U(SCH_1):GND     I2 @S9S_MB_2U_LIB.S9S_MB_2U(SCH_1):PAGE71
   DF8    GND @S9S_MB_2U_LIB.S9S_MB_2U(SCH_1):GND     I2 @S9S_MB_2U_LIB.S9S_MB_2U(SCH_1):PAGE71
  DF79    GND @S9S_MB_2U_LIB.S9S_MB_2U(SCH_1):GND     I2 @S9S_MB_2U_LIB.S9S_MB_2U(SCH_1):PAGE71
   DF4    GND @S9S_MB_2U_LIB.S9S_MB_2U(SCH_1):GND     I2 @S9S_MB_2U_LIB.S9S_MB_2U(SCH_1):PAGE71
  DE88    GND @S9S_MB_2U_LIB.S9S_MB_2U(SCH_1):GND     I2 @S9S_MB_2U_LIB.S9S_MB_2U(SCH_1):PAGE71
  DE84    GND @S9S_MB_2U_LIB.S9S_MB_2U(SCH_1):GND     I2 @S9S_MB_2U_LIB.S9S_MB_2U(SCH_1):PAGE71
  DE82    GND @S9S_MB_2U_LIB.S9S_MB_2U(SCH_1):GND     I2 @S9S_MB_2U_LIB.S9S_MB_2U(SCH_1):PAGE71
  DE76    GND @S9S_MB_2U_LIB.S9S_MB_2U(SCH_1):GND     I2 @S9S_MB_2U_LIB.S9S_MB_2U(SCH_1):PAGE71
  DE74    GND @S9S_MB_2U_LIB.S9S_MB_2U(SCH_1):GND     I2 @S9S_MB_2U_LIB.S9S_MB_2U(SCH_1):PAGE71
  DE72    GND @S9S_MB_2U_LIB.S9S_MB_2U(SCH_1):GND     I2 @S9S_MB_2U_LIB.S9S_MB_2U(SCH_1):PAGE71
  DE68    GND @S9S_MB_2U_LIB.S9S_MB_2U(SCH_1):GND     I2 @S9S_MB_2U_LIB.S9S_MB_2U(SCH_1):PAGE71
  DE66    GND @S9S_MB_2U_LIB.S9S_MB_2U(SCH_1):GND     I2 @S9S_MB_2U_LIB.S9S_MB_2U(SCH_1):PAGE71
  DE64    GND @S9S_MB_2U_LIB.S9S_MB_2U(SCH_1):GND     I2 @S9S_MB_2U_LIB.S9S_MB_2U(SCH_1):PAGE71
  DE62    GND @S9S_MB_2U_LIB.S9S_MB_2U(SCH_1):GND     I2 @S9S_MB_2U_LIB.S9S_MB_2U(SCH_1):PAGE71
  DE60    GND @S9S_MB_2U_LIB.S9S_MB_2U(SCH_1):GND     I2 @S9S_MB_2U_LIB.S9S_MB_2U(SCH_1):PAGE71
  DE58    GND @S9S_MB_2U_LIB.S9S_MB_2U(SCH_1):GND     I2 @S9S_MB_2U_LIB.S9S_MB_2U(SCH_1):PAGE71
  DE56    GND @S9S_MB_2U_LIB.S9S_MB_2U(SCH_1):GND     I2 @S9S_MB_2U_LIB.S9S_MB_2U(SCH_1):PAGE71
  DE54    GND @S9S_MB_2U_LIB.S9S_MB_2U(SCH_1):GND     I2 @S9S_MB_2U_LIB.S9S_MB_2U(SCH_1):PAGE71
  DE52    GND @S9S_MB_2U_LIB.S9S_MB_2U(SCH_1):GND     I2 @S9S_MB_2U_LIB.S9S_MB_2U(SCH_1):PAGE71
  DE50    GND @S9S_MB_2U_LIB.S9S_MB_2U(SCH_1):GND     I2 @S9S_MB_2U_LIB.S9S_MB_2U(SCH_1):PAGE71
  DE48    GND @S9S_MB_2U_LIB.S9S_MB_2U(SCH_1):GND     I2 @S9S_MB_2U_LIB.S9S_MB_2U(SCH_1):PAGE71
  DE45    GND @S9S_MB_2U_LIB.S9S_MB_2U(SCH_1):GND     I2 @S9S_MB_2U_LIB.S9S_MB_2U(SCH_1):PAGE71
  DE43    GND @S9S_MB_2U_LIB.S9S_MB_2U(SCH_1):GND     I2 @S9S_MB_2U_LIB.S9S_MB_2U(SCH_1):PAGE71
  DE41    GND @S9S_MB_2U_LIB.S9S_MB_2U(SCH_1):GND     I2 @S9S_MB_2U_LIB.S9S_MB_2U(SCH_1):PAGE71
  DE37    GND @S9S_MB_2U_LIB.S9S_MB_2U(SCH_1):GND     I2 @S9S_MB_2U_LIB.S9S_MB_2U(SCH_1):PAGE71
  DE35    GND @S9S_MB_2U_LIB.S9S_MB_2U(SCH_1):GND     I2 @S9S_MB_2U_LIB.S9S_MB_2U(SCH_1):PAGE71
  DE33    GND @S9S_MB_2U_LIB.S9S_MB_2U(SCH_1):GND     I2 @S9S_MB_2U_LIB.S9S_MB_2U(SCH_1):PAGE71
  DE31    GND @S9S_MB_2U_LIB.S9S_MB_2U(SCH_1):GND     I2 @S9S_MB_2U_LIB.S9S_MB_2U(SCH_1):PAGE71
  DE29    GND @S9S_MB_2U_LIB.S9S_MB_2U(SCH_1):GND     I2 @S9S_MB_2U_LIB.S9S_MB_2U(SCH_1):PAGE71
  DE27    GND @S9S_MB_2U_LIB.S9S_MB_2U(SCH_1):GND     I2 @S9S_MB_2U_LIB.S9S_MB_2U(SCH_1):PAGE71
  DE25    GND @S9S_MB_2U_LIB.S9S_MB_2U(SCH_1):GND     I2 @S9S_MB_2U_LIB.S9S_MB_2U(SCH_1):PAGE71
  DE23    GND @S9S_MB_2U_LIB.S9S_MB_2U(SCH_1):GND     I2 @S9S_MB_2U_LIB.S9S_MB_2U(SCH_1):PAGE71
  DE21    GND @S9S_MB_2U_LIB.S9S_MB_2U(SCH_1):GND     I2 @S9S_MB_2U_LIB.S9S_MB_2U(SCH_1):PAGE71
  DE19    GND @S9S_MB_2U_LIB.S9S_MB_2U(SCH_1):GND     I2 @S9S_MB_2U_LIB.S9S_MB_2U(SCH_1):PAGE71
  DE17    GND @S9S_MB_2U_LIB.S9S_MB_2U(SCH_1):GND     I2 @S9S_MB_2U_LIB.S9S_MB_2U(SCH_1):PAGE71
   DD8    GND @S9S_MB_2U_LIB.S9S_MB_2U(SCH_1):GND     I2 @S9S_MB_2U_LIB.S9S_MB_2U(SCH_1):PAGE71
  DD79    GND @S9S_MB_2U_LIB.S9S_MB_2U(SCH_1):GND     I2 @S9S_MB_2U_LIB.S9S_MB_2U(SCH_1):PAGE71
   DD4    GND @S9S_MB_2U_LIB.S9S_MB_2U(SCH_1):GND     I2 @S9S_MB_2U_LIB.S9S_MB_2U(SCH_1):PAGE71
   DC9    GND @S9S_MB_2U_LIB.S9S_MB_2U(SCH_1):GND     I2 @S9S_MB_2U_LIB.S9S_MB_2U(SCH_1):PAGE71
  DC88    GND @S9S_MB_2U_LIB.S9S_MB_2U(SCH_1):GND     I2 @S9S_MB_2U_LIB.S9S_MB_2U(SCH_1):PAGE71
  DC84    GND @S9S_MB_2U_LIB.S9S_MB_2U(SCH_1):GND     I2 @S9S_MB_2U_LIB.S9S_MB_2U(SCH_1):PAGE71
  DC80    GND @S9S_MB_2U_LIB.S9S_MB_2U(SCH_1):GND     I2 @S9S_MB_2U_LIB.S9S_MB_2U(SCH_1):PAGE71
  DC78    GND @S9S_MB_2U_LIB.S9S_MB_2U(SCH_1):GND     I2 @S9S_MB_2U_LIB.S9S_MB_2U(SCH_1):PAGE71
  DC76    GND @S9S_MB_2U_LIB.S9S_MB_2U(SCH_1):GND     I2 @S9S_MB_2U_LIB.S9S_MB_2U(SCH_1):PAGE71
  DC70    GND @S9S_MB_2U_LIB.S9S_MB_2U(SCH_1):GND     I2 @S9S_MB_2U_LIB.S9S_MB_2U(SCH_1):PAGE71
   DC5    GND @S9S_MB_2U_LIB.S9S_MB_2U(SCH_1):GND     I2 @S9S_MB_2U_LIB.S9S_MB_2U(SCH_1):PAGE71
  DC45    GND @S9S_MB_2U_LIB.S9S_MB_2U(SCH_1):GND     I2 @S9S_MB_2U_LIB.S9S_MB_2U(SCH_1):PAGE71
  DC39    GND @S9S_MB_2U_LIB.S9S_MB_2U(SCH_1):GND     I2 @S9S_MB_2U_LIB.S9S_MB_2U(SCH_1):PAGE71
  DC33    GND @S9S_MB_2U_LIB.S9S_MB_2U(SCH_1):GND     I2 @S9S_MB_2U_LIB.S9S_MB_2U(SCH_1):PAGE71
  DC27    GND @S9S_MB_2U_LIB.S9S_MB_2U(SCH_1):GND     I2 @S9S_MB_2U_LIB.S9S_MB_2U(SCH_1):PAGE71
  DL52    GND @S9S_MB_2U_LIB.S9S_MB_2U(SCH_1):GND     I2 @S9S_MB_2U_LIB.S9S_MB_2U(SCH_1):PAGE71
   DL5    GND @S9S_MB_2U_LIB.S9S_MB_2U(SCH_1):GND     I2 @S9S_MB_2U_LIB.S9S_MB_2U(SCH_1):PAGE71
  DL17    GND @S9S_MB_2U_LIB.S9S_MB_2U(SCH_1):GND     I2 @S9S_MB_2U_LIB.S9S_MB_2U(SCH_1):PAGE71
  DL13    GND @S9S_MB_2U_LIB.S9S_MB_2U(SCH_1):GND     I2 @S9S_MB_2U_LIB.S9S_MB_2U(SCH_1):PAGE71
   DL1    GND @S9S_MB_2U_LIB.S9S_MB_2U(SCH_1):GND     I2 @S9S_MB_2U_LIB.S9S_MB_2U(SCH_1):PAGE71
  DK67    GND @S9S_MB_2U_LIB.S9S_MB_2U(SCH_1):GND     I2 @S9S_MB_2U_LIB.S9S_MB_2U(SCH_1):PAGE71
  DK61    GND @S9S_MB_2U_LIB.S9S_MB_2U(SCH_1):GND     I2 @S9S_MB_2U_LIB.S9S_MB_2U(SCH_1):PAGE71
  DK55    GND @S9S_MB_2U_LIB.S9S_MB_2U(SCH_1):GND     I2 @S9S_MB_2U_LIB.S9S_MB_2U(SCH_1):PAGE71
  DK42    GND @S9S_MB_2U_LIB.S9S_MB_2U(SCH_1):GND     I2 @S9S_MB_2U_LIB.S9S_MB_2U(SCH_1):PAGE71
  DK24    GND @S9S_MB_2U_LIB.S9S_MB_2U(SCH_1):GND     I2 @S9S_MB_2U_LIB.S9S_MB_2U(SCH_1):PAGE71
  DK18    GND @S9S_MB_2U_LIB.S9S_MB_2U(SCH_1):GND     I2 @S9S_MB_2U_LIB.S9S_MB_2U(SCH_1):PAGE71
  DK12    GND @S9S_MB_2U_LIB.S9S_MB_2U(SCH_1):GND     I2 @S9S_MB_2U_LIB.S9S_MB_2U(SCH_1):PAGE71
  DJ68    GND @S9S_MB_2U_LIB.S9S_MB_2U(SCH_1):GND     I2 @S9S_MB_2U_LIB.S9S_MB_2U(SCH_1):PAGE71
  DJ62    GND @S9S_MB_2U_LIB.S9S_MB_2U(SCH_1):GND     I2 @S9S_MB_2U_LIB.S9S_MB_2U(SCH_1):PAGE71
  DJ54    GND @S9S_MB_2U_LIB.S9S_MB_2U(SCH_1):GND     I2 @S9S_MB_2U_LIB.S9S_MB_2U(SCH_1):PAGE71
  DJ35    GND @S9S_MB_2U_LIB.S9S_MB_2U(SCH_1):GND     I2 @S9S_MB_2U_LIB.S9S_MB_2U(SCH_1):PAGE71
  DJ25    GND @S9S_MB_2U_LIB.S9S_MB_2U(SCH_1):GND     I2 @S9S_MB_2U_LIB.S9S_MB_2U(SCH_1):PAGE71
  DH75    GND @S9S_MB_2U_LIB.S9S_MB_2U(SCH_1):GND     I2 @S9S_MB_2U_LIB.S9S_MB_2U(SCH_1):PAGE71
  DH69    GND @S9S_MB_2U_LIB.S9S_MB_2U(SCH_1):GND     I2 @S9S_MB_2U_LIB.S9S_MB_2U(SCH_1):PAGE71
  DH63    GND @S9S_MB_2U_LIB.S9S_MB_2U(SCH_1):GND     I2 @S9S_MB_2U_LIB.S9S_MB_2U(SCH_1):PAGE71
  DH59    GND @S9S_MB_2U_LIB.S9S_MB_2U(SCH_1):GND     I2 @S9S_MB_2U_LIB.S9S_MB_2U(SCH_1):PAGE71
  DH53    GND @S9S_MB_2U_LIB.S9S_MB_2U(SCH_1):GND     I2 @S9S_MB_2U_LIB.S9S_MB_2U(SCH_1):PAGE71
  DH51    GND @S9S_MB_2U_LIB.S9S_MB_2U(SCH_1):GND     I2 @S9S_MB_2U_LIB.S9S_MB_2U(SCH_1):PAGE71
  DH44    GND @S9S_MB_2U_LIB.S9S_MB_2U(SCH_1):GND     I2 @S9S_MB_2U_LIB.S9S_MB_2U(SCH_1):PAGE71
  DH34    GND @S9S_MB_2U_LIB.S9S_MB_2U(SCH_1):GND     I2 @S9S_MB_2U_LIB.S9S_MB_2U(SCH_1):PAGE71
  DH26    GND @S9S_MB_2U_LIB.S9S_MB_2U(SCH_1):GND     I2 @S9S_MB_2U_LIB.S9S_MB_2U(SCH_1):PAGE71
  DH20    GND @S9S_MB_2U_LIB.S9S_MB_2U(SCH_1):GND     I2 @S9S_MB_2U_LIB.S9S_MB_2U(SCH_1):PAGE71
  DH16    GND @S9S_MB_2U_LIB.S9S_MB_2U(SCH_1):GND     I2 @S9S_MB_2U_LIB.S9S_MB_2U(SCH_1):PAGE71
  DG64    GND @S9S_MB_2U_LIB.S9S_MB_2U(SCH_1):GND     I2 @S9S_MB_2U_LIB.S9S_MB_2U(SCH_1):PAGE71
  DG58    GND @S9S_MB_2U_LIB.S9S_MB_2U(SCH_1):GND     I2 @S9S_MB_2U_LIB.S9S_MB_2U(SCH_1):PAGE71
  DG52    GND @S9S_MB_2U_LIB.S9S_MB_2U(SCH_1):GND     I2 @S9S_MB_2U_LIB.S9S_MB_2U(SCH_1):PAGE71
  DG21    GND @S9S_MB_2U_LIB.S9S_MB_2U(SCH_1):GND     I2 @S9S_MB_2U_LIB.S9S_MB_2U(SCH_1):PAGE71
  DG13    GND @S9S_MB_2U_LIB.S9S_MB_2U(SCH_1):GND     I2 @S9S_MB_2U_LIB.S9S_MB_2U(SCH_1):PAGE71
   DG1    GND @S9S_MB_2U_LIB.S9S_MB_2U(SCH_1):GND     I2 @S9S_MB_2U_LIB.S9S_MB_2U(SCH_1):PAGE71
  DF91    GND @S9S_MB_2U_LIB.S9S_MB_2U(SCH_1):GND     I2 @S9S_MB_2U_LIB.S9S_MB_2U(SCH_1):PAGE71
  DF49    GND @S9S_MB_2U_LIB.S9S_MB_2U(SCH_1):GND     I2 @S9S_MB_2U_LIB.S9S_MB_2U(SCH_1):PAGE71
  DF16    GND @S9S_MB_2U_LIB.S9S_MB_2U(SCH_1):GND     I2 @S9S_MB_2U_LIB.S9S_MB_2U(SCH_1):PAGE71
  DF12    GND @S9S_MB_2U_LIB.S9S_MB_2U(SCH_1):GND     I2 @S9S_MB_2U_LIB.S9S_MB_2U(SCH_1):PAGE71
  DE70    GND @S9S_MB_2U_LIB.S9S_MB_2U(SCH_1):GND     I2 @S9S_MB_2U_LIB.S9S_MB_2U(SCH_1):PAGE71
  DE39    GND @S9S_MB_2U_LIB.S9S_MB_2U(SCH_1):GND     I2 @S9S_MB_2U_LIB.S9S_MB_2U(SCH_1):PAGE71
  DD49    GND @S9S_MB_2U_LIB.S9S_MB_2U(SCH_1):GND     I2 @S9S_MB_2U_LIB.S9S_MB_2U(SCH_1):PAGE71
  DD16    GND @S9S_MB_2U_LIB.S9S_MB_2U(SCH_1):GND     I2 @S9S_MB_2U_LIB.S9S_MB_2U(SCH_1):PAGE71
  DD12    GND @S9S_MB_2U_LIB.S9S_MB_2U(SCH_1):GND     I2 @S9S_MB_2U_LIB.S9S_MB_2U(SCH_1):PAGE71
  DC64    GND @S9S_MB_2U_LIB.S9S_MB_2U(SCH_1):GND     I2 @S9S_MB_2U_LIB.S9S_MB_2U(SCH_1):PAGE71
  DC58    GND @S9S_MB_2U_LIB.S9S_MB_2U(SCH_1):GND     I2 @S9S_MB_2U_LIB.S9S_MB_2U(SCH_1):PAGE71
  DC52    GND @S9S_MB_2U_LIB.S9S_MB_2U(SCH_1):GND     I2 @S9S_MB_2U_LIB.S9S_MB_2U(SCH_1):PAGE71
  DC21    GND @S9S_MB_2U_LIB.S9S_MB_2U(SCH_1):GND     I2 @S9S_MB_2U_LIB.S9S_MB_2U(SCH_1):PAGE71
  DC13    GND @S9S_MB_2U_LIB.S9S_MB_2U(SCH_1):GND     I2 @S9S_MB_2U_LIB.S9S_MB_2U(SCH_1):PAGE71
   DC1    GND @S9S_MB_2U_LIB.S9S_MB_2U(SCH_1):GND     I2 @S9S_MB_2U_LIB.S9S_MB_2U(SCH_1):PAGE71
  DB91    GND @S9S_MB_2U_LIB.S9S_MB_2U(SCH_1):GND     I2 @S9S_MB_2U_LIB.S9S_MB_2U(SCH_1):PAGE71
  DB87    GND @S9S_MB_2U_LIB.S9S_MB_2U(SCH_1):GND     I5 @S9S_MB_2U_LIB.S9S_MB_2U(SCH_1):PAGE71
   DB8    GND @S9S_MB_2U_LIB.S9S_MB_2U(SCH_1):GND     I5 @S9S_MB_2U_LIB.S9S_MB_2U(SCH_1):PAGE71
  DB77    GND @S9S_MB_2U_LIB.S9S_MB_2U(SCH_1):GND     I5 @S9S_MB_2U_LIB.S9S_MB_2U(SCH_1):PAGE71
  DB71    GND @S9S_MB_2U_LIB.S9S_MB_2U(SCH_1):GND     I5 @S9S_MB_2U_LIB.S9S_MB_2U(SCH_1):PAGE71
  DB65    GND @S9S_MB_2U_LIB.S9S_MB_2U(SCH_1):GND     I5 @S9S_MB_2U_LIB.S9S_MB_2U(SCH_1):PAGE71
  DB57    GND @S9S_MB_2U_LIB.S9S_MB_2U(SCH_1):GND     I5 @S9S_MB_2U_LIB.S9S_MB_2U(SCH_1):PAGE71
  DB47    GND @S9S_MB_2U_LIB.S9S_MB_2U(SCH_1):GND     I5 @S9S_MB_2U_LIB.S9S_MB_2U(SCH_1):PAGE71
  DB40    GND @S9S_MB_2U_LIB.S9S_MB_2U(SCH_1):GND     I5 @S9S_MB_2U_LIB.S9S_MB_2U(SCH_1):PAGE71
   DB4    GND @S9S_MB_2U_LIB.S9S_MB_2U(SCH_1):GND     I5 @S9S_MB_2U_LIB.S9S_MB_2U(SCH_1):PAGE71
  DB38    GND @S9S_MB_2U_LIB.S9S_MB_2U(SCH_1):GND     I5 @S9S_MB_2U_LIB.S9S_MB_2U(SCH_1):PAGE71
  DB32    GND @S9S_MB_2U_LIB.S9S_MB_2U(SCH_1):GND     I5 @S9S_MB_2U_LIB.S9S_MB_2U(SCH_1):PAGE71
  DB28    GND @S9S_MB_2U_LIB.S9S_MB_2U(SCH_1):GND     I5 @S9S_MB_2U_LIB.S9S_MB_2U(SCH_1):PAGE71
  DB22    GND @S9S_MB_2U_LIB.S9S_MB_2U(SCH_1):GND     I5 @S9S_MB_2U_LIB.S9S_MB_2U(SCH_1):PAGE71
  DB12    GND @S9S_MB_2U_LIB.S9S_MB_2U(SCH_1):GND     I5 @S9S_MB_2U_LIB.S9S_MB_2U(SCH_1):PAGE71
  DA88    GND @S9S_MB_2U_LIB.S9S_MB_2U(SCH_1):GND     I5 @S9S_MB_2U_LIB.S9S_MB_2U(SCH_1):PAGE71
  DA84    GND @S9S_MB_2U_LIB.S9S_MB_2U(SCH_1):GND     I5 @S9S_MB_2U_LIB.S9S_MB_2U(SCH_1):PAGE71
  DA82    GND @S9S_MB_2U_LIB.S9S_MB_2U(SCH_1):GND     I5 @S9S_MB_2U_LIB.S9S_MB_2U(SCH_1):PAGE71
  DA80    GND @S9S_MB_2U_LIB.S9S_MB_2U(SCH_1):GND     I5 @S9S_MB_2U_LIB.S9S_MB_2U(SCH_1):PAGE71
  DA74    GND @S9S_MB_2U_LIB.S9S_MB_2U(SCH_1):GND     I5 @S9S_MB_2U_LIB.S9S_MB_2U(SCH_1):PAGE71
  DA72    GND @S9S_MB_2U_LIB.S9S_MB_2U(SCH_1):GND     I5 @S9S_MB_2U_LIB.S9S_MB_2U(SCH_1):PAGE71
  DA66    GND @S9S_MB_2U_LIB.S9S_MB_2U(SCH_1):GND     I5 @S9S_MB_2U_LIB.S9S_MB_2U(SCH_1):PAGE71
  DA62    GND @S9S_MB_2U_LIB.S9S_MB_2U(SCH_1):GND     I5 @S9S_MB_2U_LIB.S9S_MB_2U(SCH_1):PAGE71
  DA60    GND @S9S_MB_2U_LIB.S9S_MB_2U(SCH_1):GND     I5 @S9S_MB_2U_LIB.S9S_MB_2U(SCH_1):PAGE71
  DA58    GND @S9S_MB_2U_LIB.S9S_MB_2U(SCH_1):GND     I5 @S9S_MB_2U_LIB.S9S_MB_2U(SCH_1):PAGE71
  DA56    GND @S9S_MB_2U_LIB.S9S_MB_2U(SCH_1):GND     I5 @S9S_MB_2U_LIB.S9S_MB_2U(SCH_1):PAGE71
  DA54    GND @S9S_MB_2U_LIB.S9S_MB_2U(SCH_1):GND     I5 @S9S_MB_2U_LIB.S9S_MB_2U(SCH_1):PAGE71
  DA50    GND @S9S_MB_2U_LIB.S9S_MB_2U(SCH_1):GND     I5 @S9S_MB_2U_LIB.S9S_MB_2U(SCH_1):PAGE71
  DA48    GND @S9S_MB_2U_LIB.S9S_MB_2U(SCH_1):GND     I5 @S9S_MB_2U_LIB.S9S_MB_2U(SCH_1):PAGE71
  DA41    GND @S9S_MB_2U_LIB.S9S_MB_2U(SCH_1):GND     I5 @S9S_MB_2U_LIB.S9S_MB_2U(SCH_1):PAGE71
  DA37    GND @S9S_MB_2U_LIB.S9S_MB_2U(SCH_1):GND     I5 @S9S_MB_2U_LIB.S9S_MB_2U(SCH_1):PAGE71
  DA35    GND @S9S_MB_2U_LIB.S9S_MB_2U(SCH_1):GND     I5 @S9S_MB_2U_LIB.S9S_MB_2U(SCH_1):PAGE71
  DA33    GND @S9S_MB_2U_LIB.S9S_MB_2U(SCH_1):GND     I5 @S9S_MB_2U_LIB.S9S_MB_2U(SCH_1):PAGE71
  DA31    GND @S9S_MB_2U_LIB.S9S_MB_2U(SCH_1):GND     I5 @S9S_MB_2U_LIB.S9S_MB_2U(SCH_1):PAGE71
  DA29    GND @S9S_MB_2U_LIB.S9S_MB_2U(SCH_1):GND     I5 @S9S_MB_2U_LIB.S9S_MB_2U(SCH_1):PAGE71
  DA25    GND @S9S_MB_2U_LIB.S9S_MB_2U(SCH_1):GND     I5 @S9S_MB_2U_LIB.S9S_MB_2U(SCH_1):PAGE71
  DA23    GND @S9S_MB_2U_LIB.S9S_MB_2U(SCH_1):GND     I5 @S9S_MB_2U_LIB.S9S_MB_2U(SCH_1):PAGE71
  DA19    GND @S9S_MB_2U_LIB.S9S_MB_2U(SCH_1):GND     I5 @S9S_MB_2U_LIB.S9S_MB_2U(SCH_1):PAGE71
  CY83    GND @S9S_MB_2U_LIB.S9S_MB_2U(SCH_1):GND     I5 @S9S_MB_2U_LIB.S9S_MB_2U(SCH_1):PAGE71
  CY81    GND @S9S_MB_2U_LIB.S9S_MB_2U(SCH_1):GND     I5 @S9S_MB_2U_LIB.S9S_MB_2U(SCH_1):PAGE71
   CY8    GND @S9S_MB_2U_LIB.S9S_MB_2U(SCH_1):GND     I5 @S9S_MB_2U_LIB.S9S_MB_2U(SCH_1):PAGE71
  CY77    GND @S9S_MB_2U_LIB.S9S_MB_2U(SCH_1):GND     I5 @S9S_MB_2U_LIB.S9S_MB_2U(SCH_1):PAGE71
  CY73    GND @S9S_MB_2U_LIB.S9S_MB_2U(SCH_1):GND     I5 @S9S_MB_2U_LIB.S9S_MB_2U(SCH_1):PAGE71
  CY63    GND @S9S_MB_2U_LIB.S9S_MB_2U(SCH_1):GND     I5 @S9S_MB_2U_LIB.S9S_MB_2U(SCH_1):PAGE71
  CY30    GND @S9S_MB_2U_LIB.S9S_MB_2U(SCH_1):GND     I5 @S9S_MB_2U_LIB.S9S_MB_2U(SCH_1):PAGE71
  CY26    GND @S9S_MB_2U_LIB.S9S_MB_2U(SCH_1):GND     I5 @S9S_MB_2U_LIB.S9S_MB_2U(SCH_1):PAGE71
  CY18    GND @S9S_MB_2U_LIB.S9S_MB_2U(SCH_1):GND     I5 @S9S_MB_2U_LIB.S9S_MB_2U(SCH_1):PAGE71
  CY16    GND @S9S_MB_2U_LIB.S9S_MB_2U(SCH_1):GND     I5 @S9S_MB_2U_LIB.S9S_MB_2U(SCH_1):PAGE71
  CY12    GND @S9S_MB_2U_LIB.S9S_MB_2U(SCH_1):GND     I5 @S9S_MB_2U_LIB.S9S_MB_2U(SCH_1):PAGE71
   CW9    GND @S9S_MB_2U_LIB.S9S_MB_2U(SCH_1):GND     I5 @S9S_MB_2U_LIB.S9S_MB_2U(SCH_1):PAGE71
  CW88    GND @S9S_MB_2U_LIB.S9S_MB_2U(SCH_1):GND     I5 @S9S_MB_2U_LIB.S9S_MB_2U(SCH_1):PAGE71
  CW84    GND @S9S_MB_2U_LIB.S9S_MB_2U(SCH_1):GND     I5 @S9S_MB_2U_LIB.S9S_MB_2U(SCH_1):PAGE71
  CW78    GND @S9S_MB_2U_LIB.S9S_MB_2U(SCH_1):GND     I5 @S9S_MB_2U_LIB.S9S_MB_2U(SCH_1):PAGE71
  CW72    GND @S9S_MB_2U_LIB.S9S_MB_2U(SCH_1):GND     I5 @S9S_MB_2U_LIB.S9S_MB_2U(SCH_1):PAGE71
   CW5    GND @S9S_MB_2U_LIB.S9S_MB_2U(SCH_1):GND     I5 @S9S_MB_2U_LIB.S9S_MB_2U(SCH_1):PAGE71
  CW17    GND @S9S_MB_2U_LIB.S9S_MB_2U(SCH_1):GND     I5 @S9S_MB_2U_LIB.S9S_MB_2U(SCH_1):PAGE71
  CW13    GND @S9S_MB_2U_LIB.S9S_MB_2U(SCH_1):GND     I5 @S9S_MB_2U_LIB.S9S_MB_2U(SCH_1):PAGE71
   CW1    GND @S9S_MB_2U_LIB.S9S_MB_2U(SCH_1):GND     I5 @S9S_MB_2U_LIB.S9S_MB_2U(SCH_1):PAGE71
  CV91    GND @S9S_MB_2U_LIB.S9S_MB_2U(SCH_1):GND     I5 @S9S_MB_2U_LIB.S9S_MB_2U(SCH_1):PAGE71
  CV87    GND @S9S_MB_2U_LIB.S9S_MB_2U(SCH_1):GND     I5 @S9S_MB_2U_LIB.S9S_MB_2U(SCH_1):PAGE71
  CV83    GND @S9S_MB_2U_LIB.S9S_MB_2U(SCH_1):GND     I5 @S9S_MB_2U_LIB.S9S_MB_2U(SCH_1):PAGE71
   CV8    GND @S9S_MB_2U_LIB.S9S_MB_2U(SCH_1):GND     I5 @S9S_MB_2U_LIB.S9S_MB_2U(SCH_1):PAGE71
  CV75    GND @S9S_MB_2U_LIB.S9S_MB_2U(SCH_1):GND     I5 @S9S_MB_2U_LIB.S9S_MB_2U(SCH_1):PAGE71
   CV4    GND @S9S_MB_2U_LIB.S9S_MB_2U(SCH_1):GND     I5 @S9S_MB_2U_LIB.S9S_MB_2U(SCH_1):PAGE71
  CV12    GND @S9S_MB_2U_LIB.S9S_MB_2U(SCH_1):GND     I5 @S9S_MB_2U_LIB.S9S_MB_2U(SCH_1):PAGE71
  CU88    GND @S9S_MB_2U_LIB.S9S_MB_2U(SCH_1):GND     I5 @S9S_MB_2U_LIB.S9S_MB_2U(SCH_1):PAGE71
  CU84    GND @S9S_MB_2U_LIB.S9S_MB_2U(SCH_1):GND     I5 @S9S_MB_2U_LIB.S9S_MB_2U(SCH_1):PAGE71
  CU68    GND @S9S_MB_2U_LIB.S9S_MB_2U(SCH_1):GND     I5 @S9S_MB_2U_LIB.S9S_MB_2U(SCH_1):PAGE71
  CU66    GND @S9S_MB_2U_LIB.S9S_MB_2U(SCH_1):GND     I5 @S9S_MB_2U_LIB.S9S_MB_2U(SCH_1):PAGE71
  CU60    GND @S9S_MB_2U_LIB.S9S_MB_2U(SCH_1):GND     I5 @S9S_MB_2U_LIB.S9S_MB_2U(SCH_1):PAGE71
  CU23    GND @S9S_MB_2U_LIB.S9S_MB_2U(SCH_1):GND     I5 @S9S_MB_2U_LIB.S9S_MB_2U(SCH_1):PAGE71
  CU21    GND @S9S_MB_2U_LIB.S9S_MB_2U(SCH_1):GND     I5 @S9S_MB_2U_LIB.S9S_MB_2U(SCH_1):PAGE71
  CU19    GND @S9S_MB_2U_LIB.S9S_MB_2U(SCH_1):GND     I5 @S9S_MB_2U_LIB.S9S_MB_2U(SCH_1):PAGE71
  CT81    GND @S9S_MB_2U_LIB.S9S_MB_2U(SCH_1):GND     I5 @S9S_MB_2U_LIB.S9S_MB_2U(SCH_1):PAGE71
  CT73    GND @S9S_MB_2U_LIB.S9S_MB_2U(SCH_1):GND     I5 @S9S_MB_2U_LIB.S9S_MB_2U(SCH_1):PAGE71
  CT69    GND @S9S_MB_2U_LIB.S9S_MB_2U(SCH_1):GND     I5 @S9S_MB_2U_LIB.S9S_MB_2U(SCH_1):PAGE71
  CT12    GND @S9S_MB_2U_LIB.S9S_MB_2U(SCH_1):GND     I5 @S9S_MB_2U_LIB.S9S_MB_2U(SCH_1):PAGE71
  CT10    GND @S9S_MB_2U_LIB.S9S_MB_2U(SCH_1):GND     I5 @S9S_MB_2U_LIB.S9S_MB_2U(SCH_1):PAGE71
  CR90    GND @S9S_MB_2U_LIB.S9S_MB_2U(SCH_1):GND     I5 @S9S_MB_2U_LIB.S9S_MB_2U(SCH_1):PAGE71
   CR9    GND @S9S_MB_2U_LIB.S9S_MB_2U(SCH_1):GND     I5 @S9S_MB_2U_LIB.S9S_MB_2U(SCH_1):PAGE71
  CR88    GND @S9S_MB_2U_LIB.S9S_MB_2U(SCH_1):GND     I5 @S9S_MB_2U_LIB.S9S_MB_2U(SCH_1):PAGE71
  CR84    GND @S9S_MB_2U_LIB.S9S_MB_2U(SCH_1):GND     I5 @S9S_MB_2U_LIB.S9S_MB_2U(SCH_1):PAGE71
  CR64    GND @S9S_MB_2U_LIB.S9S_MB_2U(SCH_1):GND     I5 @S9S_MB_2U_LIB.S9S_MB_2U(SCH_1):PAGE71
  CR62    GND @S9S_MB_2U_LIB.S9S_MB_2U(SCH_1):GND     I5 @S9S_MB_2U_LIB.S9S_MB_2U(SCH_1):PAGE71
   CR5    GND @S9S_MB_2U_LIB.S9S_MB_2U(SCH_1):GND     I5 @S9S_MB_2U_LIB.S9S_MB_2U(SCH_1):PAGE71
  CR17    GND @S9S_MB_2U_LIB.S9S_MB_2U(SCH_1):GND     I5 @S9S_MB_2U_LIB.S9S_MB_2U(SCH_1):PAGE71
  CR13    GND @S9S_MB_2U_LIB.S9S_MB_2U(SCH_1):GND     I5 @S9S_MB_2U_LIB.S9S_MB_2U(SCH_1):PAGE71
  CR11    GND @S9S_MB_2U_LIB.S9S_MB_2U(SCH_1):GND     I5 @S9S_MB_2U_LIB.S9S_MB_2U(SCH_1):PAGE71
   CR1    GND @S9S_MB_2U_LIB.S9S_MB_2U(SCH_1):GND     I5 @S9S_MB_2U_LIB.S9S_MB_2U(SCH_1):PAGE71
  CP91    GND @S9S_MB_2U_LIB.S9S_MB_2U(SCH_1):GND     I5 @S9S_MB_2U_LIB.S9S_MB_2U(SCH_1):PAGE71
  CP87    GND @S9S_MB_2U_LIB.S9S_MB_2U(SCH_1):GND     I5 @S9S_MB_2U_LIB.S9S_MB_2U(SCH_1):PAGE71
  CP83    GND @S9S_MB_2U_LIB.S9S_MB_2U(SCH_1):GND     I5 @S9S_MB_2U_LIB.S9S_MB_2U(SCH_1):PAGE71
   CP8    GND @S9S_MB_2U_LIB.S9S_MB_2U(SCH_1):GND     I5 @S9S_MB_2U_LIB.S9S_MB_2U(SCH_1):PAGE71
  CP77    GND @S9S_MB_2U_LIB.S9S_MB_2U(SCH_1):GND     I5 @S9S_MB_2U_LIB.S9S_MB_2U(SCH_1):PAGE71
  CP75    GND @S9S_MB_2U_LIB.S9S_MB_2U(SCH_1):GND     I5 @S9S_MB_2U_LIB.S9S_MB_2U(SCH_1):PAGE71
   CP4    GND @S9S_MB_2U_LIB.S9S_MB_2U(SCH_1):GND     I5 @S9S_MB_2U_LIB.S9S_MB_2U(SCH_1):PAGE71
  CP18    GND @S9S_MB_2U_LIB.S9S_MB_2U(SCH_1):GND     I5 @S9S_MB_2U_LIB.S9S_MB_2U(SCH_1):PAGE71
  CP12    GND @S9S_MB_2U_LIB.S9S_MB_2U(SCH_1):GND     I5 @S9S_MB_2U_LIB.S9S_MB_2U(SCH_1):PAGE71
  CN86    GND @S9S_MB_2U_LIB.S9S_MB_2U(SCH_1):GND     I5 @S9S_MB_2U_LIB.S9S_MB_2U(SCH_1):PAGE71
  CN84    GND @S9S_MB_2U_LIB.S9S_MB_2U(SCH_1):GND     I5 @S9S_MB_2U_LIB.S9S_MB_2U(SCH_1):PAGE71
  CN74    GND @S9S_MB_2U_LIB.S9S_MB_2U(SCH_1):GND     I5 @S9S_MB_2U_LIB.S9S_MB_2U(SCH_1):PAGE71
  CN72    GND @S9S_MB_2U_LIB.S9S_MB_2U(SCH_1):GND     I5 @S9S_MB_2U_LIB.S9S_MB_2U(SCH_1):PAGE71
  CN70    GND @S9S_MB_2U_LIB.S9S_MB_2U(SCH_1):GND     I5 @S9S_MB_2U_LIB.S9S_MB_2U(SCH_1):PAGE71
  CN68    GND @S9S_MB_2U_LIB.S9S_MB_2U(SCH_1):GND     I5 @S9S_MB_2U_LIB.S9S_MB_2U(SCH_1):PAGE71
  CM85    GND @S9S_MB_2U_LIB.S9S_MB_2U(SCH_1):GND     I5 @S9S_MB_2U_LIB.S9S_MB_2U(SCH_1):PAGE71
  CM83    GND @S9S_MB_2U_LIB.S9S_MB_2U(SCH_1):GND     I5 @S9S_MB_2U_LIB.S9S_MB_2U(SCH_1):PAGE71
  CM81    GND @S9S_MB_2U_LIB.S9S_MB_2U(SCH_1):GND     I5 @S9S_MB_2U_LIB.S9S_MB_2U(SCH_1):PAGE71
   CM8    GND @S9S_MB_2U_LIB.S9S_MB_2U(SCH_1):GND     I5 @S9S_MB_2U_LIB.S9S_MB_2U(SCH_1):PAGE71
  CM79    GND @S9S_MB_2U_LIB.S9S_MB_2U(SCH_1):GND     I5 @S9S_MB_2U_LIB.S9S_MB_2U(SCH_1):PAGE71
  CM67    GND @S9S_MB_2U_LIB.S9S_MB_2U(SCH_1):GND     I5 @S9S_MB_2U_LIB.S9S_MB_2U(SCH_1):PAGE71
  CM65    GND @S9S_MB_2U_LIB.S9S_MB_2U(SCH_1):GND     I5 @S9S_MB_2U_LIB.S9S_MB_2U(SCH_1):PAGE71
  CM61    GND @S9S_MB_2U_LIB.S9S_MB_2U(SCH_1):GND     I5 @S9S_MB_2U_LIB.S9S_MB_2U(SCH_1):PAGE71
   CM4    GND @S9S_MB_2U_LIB.S9S_MB_2U(SCH_1):GND     I5 @S9S_MB_2U_LIB.S9S_MB_2U(SCH_1):PAGE71
  CM24    GND @S9S_MB_2U_LIB.S9S_MB_2U(SCH_1):GND     I5 @S9S_MB_2U_LIB.S9S_MB_2U(SCH_1):PAGE71
  CM20    GND @S9S_MB_2U_LIB.S9S_MB_2U(SCH_1):GND     I5 @S9S_MB_2U_LIB.S9S_MB_2U(SCH_1):PAGE71
  CM12    GND @S9S_MB_2U_LIB.S9S_MB_2U(SCH_1):GND     I5 @S9S_MB_2U_LIB.S9S_MB_2U(SCH_1):PAGE71
   CL9    GND @S9S_MB_2U_LIB.S9S_MB_2U(SCH_1):GND     I5 @S9S_MB_2U_LIB.S9S_MB_2U(SCH_1):PAGE71
  CL82    GND @S9S_MB_2U_LIB.S9S_MB_2U(SCH_1):GND     I5 @S9S_MB_2U_LIB.S9S_MB_2U(SCH_1):PAGE71
  CL80    GND @S9S_MB_2U_LIB.S9S_MB_2U(SCH_1):GND     I5 @S9S_MB_2U_LIB.S9S_MB_2U(SCH_1):PAGE71
  CL78    GND @S9S_MB_2U_LIB.S9S_MB_2U(SCH_1):GND     I5 @S9S_MB_2U_LIB.S9S_MB_2U(SCH_1):PAGE71
  CL74    GND @S9S_MB_2U_LIB.S9S_MB_2U(SCH_1):GND     I5 @S9S_MB_2U_LIB.S9S_MB_2U(SCH_1):PAGE71
  CL62    GND @S9S_MB_2U_LIB.S9S_MB_2U(SCH_1):GND     I5 @S9S_MB_2U_LIB.S9S_MB_2U(SCH_1):PAGE71
   CL5    GND @S9S_MB_2U_LIB.S9S_MB_2U(SCH_1):GND     I5 @S9S_MB_2U_LIB.S9S_MB_2U(SCH_1):PAGE71
  CL17    GND @S9S_MB_2U_LIB.S9S_MB_2U(SCH_1):GND     I5 @S9S_MB_2U_LIB.S9S_MB_2U(SCH_1):PAGE71
  CL13    GND @S9S_MB_2U_LIB.S9S_MB_2U(SCH_1):GND     I5 @S9S_MB_2U_LIB.S9S_MB_2U(SCH_1):PAGE71
   CL1    GND @S9S_MB_2U_LIB.S9S_MB_2U(SCH_1):GND     I5 @S9S_MB_2U_LIB.S9S_MB_2U(SCH_1):PAGE71
  CK81    GND @S9S_MB_2U_LIB.S9S_MB_2U(SCH_1):GND     I5 @S9S_MB_2U_LIB.S9S_MB_2U(SCH_1):PAGE71
  CK69    GND @S9S_MB_2U_LIB.S9S_MB_2U(SCH_1):GND     I5 @S9S_MB_2U_LIB.S9S_MB_2U(SCH_1):PAGE71
  CK63    GND @S9S_MB_2U_LIB.S9S_MB_2U(SCH_1):GND     I5 @S9S_MB_2U_LIB.S9S_MB_2U(SCH_1):PAGE71
  DB75    GND @S9S_MB_2U_LIB.S9S_MB_2U(SCH_1):GND     I5 @S9S_MB_2U_LIB.S9S_MB_2U(SCH_1):PAGE71
  DB69    GND @S9S_MB_2U_LIB.S9S_MB_2U(SCH_1):GND     I5 @S9S_MB_2U_LIB.S9S_MB_2U(SCH_1):PAGE71
  DB63    GND @S9S_MB_2U_LIB.S9S_MB_2U(SCH_1):GND     I5 @S9S_MB_2U_LIB.S9S_MB_2U(SCH_1):PAGE71
  DB59    GND @S9S_MB_2U_LIB.S9S_MB_2U(SCH_1):GND     I5 @S9S_MB_2U_LIB.S9S_MB_2U(SCH_1):PAGE71
  DB53    GND @S9S_MB_2U_LIB.S9S_MB_2U(SCH_1):GND     I5 @S9S_MB_2U_LIB.S9S_MB_2U(SCH_1):PAGE71
  DB51    GND @S9S_MB_2U_LIB.S9S_MB_2U(SCH_1):GND     I5 @S9S_MB_2U_LIB.S9S_MB_2U(SCH_1):PAGE71
  DB44    GND @S9S_MB_2U_LIB.S9S_MB_2U(SCH_1):GND     I5 @S9S_MB_2U_LIB.S9S_MB_2U(SCH_1):PAGE71
  DB34    GND @S9S_MB_2U_LIB.S9S_MB_2U(SCH_1):GND     I5 @S9S_MB_2U_LIB.S9S_MB_2U(SCH_1):PAGE71
  DB26    GND @S9S_MB_2U_LIB.S9S_MB_2U(SCH_1):GND     I5 @S9S_MB_2U_LIB.S9S_MB_2U(SCH_1):PAGE71
  DB20    GND @S9S_MB_2U_LIB.S9S_MB_2U(SCH_1):GND     I5 @S9S_MB_2U_LIB.S9S_MB_2U(SCH_1):PAGE71
  DB16    GND @S9S_MB_2U_LIB.S9S_MB_2U(SCH_1):GND     I5 @S9S_MB_2U_LIB.S9S_MB_2U(SCH_1):PAGE71
  DA68    GND @S9S_MB_2U_LIB.S9S_MB_2U(SCH_1):GND     I5 @S9S_MB_2U_LIB.S9S_MB_2U(SCH_1):PAGE71
  DA43    GND @S9S_MB_2U_LIB.S9S_MB_2U(SCH_1):GND     I5 @S9S_MB_2U_LIB.S9S_MB_2U(SCH_1):PAGE71
   CY4    GND @S9S_MB_2U_LIB.S9S_MB_2U(SCH_1):GND     I5 @S9S_MB_2U_LIB.S9S_MB_2U(SCH_1):PAGE71
  CW70    GND @S9S_MB_2U_LIB.S9S_MB_2U(SCH_1):GND     I5 @S9S_MB_2U_LIB.S9S_MB_2U(SCH_1):PAGE71
  CW33    GND @S9S_MB_2U_LIB.S9S_MB_2U(SCH_1):GND     I5 @S9S_MB_2U_LIB.S9S_MB_2U(SCH_1):PAGE71
  CV79    GND @S9S_MB_2U_LIB.S9S_MB_2U(SCH_1):GND     I5 @S9S_MB_2U_LIB.S9S_MB_2U(SCH_1):PAGE71
  CV26    GND @S9S_MB_2U_LIB.S9S_MB_2U(SCH_1):GND     I5 @S9S_MB_2U_LIB.S9S_MB_2U(SCH_1):PAGE71
  CV16    GND @S9S_MB_2U_LIB.S9S_MB_2U(SCH_1):GND     I5 @S9S_MB_2U_LIB.S9S_MB_2U(SCH_1):PAGE71
  CU78    GND @S9S_MB_2U_LIB.S9S_MB_2U(SCH_1):GND     I5 @S9S_MB_2U_LIB.S9S_MB_2U(SCH_1):PAGE71
  CU72    GND @S9S_MB_2U_LIB.S9S_MB_2U(SCH_1):GND     I5 @S9S_MB_2U_LIB.S9S_MB_2U(SCH_1):PAGE71
  CU25    GND @S9S_MB_2U_LIB.S9S_MB_2U(SCH_1):GND     I5 @S9S_MB_2U_LIB.S9S_MB_2U(SCH_1):PAGE71
  CT89    GND @S9S_MB_2U_LIB.S9S_MB_2U(SCH_1):GND     I5 @S9S_MB_2U_LIB.S9S_MB_2U(SCH_1):PAGE71
   CT8    GND @S9S_MB_2U_LIB.S9S_MB_2U(SCH_1):GND     I5 @S9S_MB_2U_LIB.S9S_MB_2U(SCH_1):PAGE71
   CT4    GND @S9S_MB_2U_LIB.S9S_MB_2U(SCH_1):GND     I5 @S9S_MB_2U_LIB.S9S_MB_2U(SCH_1):PAGE71
  CT16    GND @S9S_MB_2U_LIB.S9S_MB_2U(SCH_1):GND     I5 @S9S_MB_2U_LIB.S9S_MB_2U(SCH_1):PAGE71
  CR78    GND @S9S_MB_2U_LIB.S9S_MB_2U(SCH_1):GND     I5 @S9S_MB_2U_LIB.S9S_MB_2U(SCH_1):PAGE71
  CP79    GND @S9S_MB_2U_LIB.S9S_MB_2U(SCH_1):GND     I5 @S9S_MB_2U_LIB.S9S_MB_2U(SCH_1):PAGE71
  CP16    GND @S9S_MB_2U_LIB.S9S_MB_2U(SCH_1):GND     I5 @S9S_MB_2U_LIB.S9S_MB_2U(SCH_1):PAGE71
  CN76    GND @S9S_MB_2U_LIB.S9S_MB_2U(SCH_1):GND     I5 @S9S_MB_2U_LIB.S9S_MB_2U(SCH_1):PAGE71
  CM22    GND @S9S_MB_2U_LIB.S9S_MB_2U(SCH_1):GND     I5 @S9S_MB_2U_LIB.S9S_MB_2U(SCH_1):PAGE71
  CM16    GND @S9S_MB_2U_LIB.S9S_MB_2U(SCH_1):GND     I5 @S9S_MB_2U_LIB.S9S_MB_2U(SCH_1):PAGE71
   CK8    GND @S9S_MB_2U_LIB.S9S_MB_2U(SCH_1):GND     I8 @S9S_MB_2U_LIB.S9S_MB_2U(SCH_1):PAGE71
  CK26    GND @S9S_MB_2U_LIB.S9S_MB_2U(SCH_1):GND     I8 @S9S_MB_2U_LIB.S9S_MB_2U(SCH_1):PAGE71
  CK20    GND @S9S_MB_2U_LIB.S9S_MB_2U(SCH_1):GND     I8 @S9S_MB_2U_LIB.S9S_MB_2U(SCH_1):PAGE71
  CK16    GND @S9S_MB_2U_LIB.S9S_MB_2U(SCH_1):GND     I8 @S9S_MB_2U_LIB.S9S_MB_2U(SCH_1):PAGE71
  CK12    GND @S9S_MB_2U_LIB.S9S_MB_2U(SCH_1):GND     I8 @S9S_MB_2U_LIB.S9S_MB_2U(SCH_1):PAGE71
  CJ80    GND @S9S_MB_2U_LIB.S9S_MB_2U(SCH_1):GND     I8 @S9S_MB_2U_LIB.S9S_MB_2U(SCH_1):PAGE71
  CJ60    GND @S9S_MB_2U_LIB.S9S_MB_2U(SCH_1):GND     I8 @S9S_MB_2U_LIB.S9S_MB_2U(SCH_1):PAGE71
  CH89    GND @S9S_MB_2U_LIB.S9S_MB_2U(SCH_1):GND     I8 @S9S_MB_2U_LIB.S9S_MB_2U(SCH_1):PAGE71
  CH87    GND @S9S_MB_2U_LIB.S9S_MB_2U(SCH_1):GND     I8 @S9S_MB_2U_LIB.S9S_MB_2U(SCH_1):PAGE71
  CH85    GND @S9S_MB_2U_LIB.S9S_MB_2U(SCH_1):GND     I8 @S9S_MB_2U_LIB.S9S_MB_2U(SCH_1):PAGE71
  CH83    GND @S9S_MB_2U_LIB.S9S_MB_2U(SCH_1):GND     I8 @S9S_MB_2U_LIB.S9S_MB_2U(SCH_1):PAGE71
   CH8    GND @S9S_MB_2U_LIB.S9S_MB_2U(SCH_1):GND     I8 @S9S_MB_2U_LIB.S9S_MB_2U(SCH_1):PAGE71
  CH79    GND @S9S_MB_2U_LIB.S9S_MB_2U(SCH_1):GND     I8 @S9S_MB_2U_LIB.S9S_MB_2U(SCH_1):PAGE71
  CH73    GND @S9S_MB_2U_LIB.S9S_MB_2U(SCH_1):GND     I8 @S9S_MB_2U_LIB.S9S_MB_2U(SCH_1):PAGE71
  CH67    GND @S9S_MB_2U_LIB.S9S_MB_2U(SCH_1):GND     I8 @S9S_MB_2U_LIB.S9S_MB_2U(SCH_1):PAGE71
   CH4    GND @S9S_MB_2U_LIB.S9S_MB_2U(SCH_1):GND     I8 @S9S_MB_2U_LIB.S9S_MB_2U(SCH_1):PAGE71
  CH20    GND @S9S_MB_2U_LIB.S9S_MB_2U(SCH_1):GND     I8 @S9S_MB_2U_LIB.S9S_MB_2U(SCH_1):PAGE71
  CH16    GND @S9S_MB_2U_LIB.S9S_MB_2U(SCH_1):GND     I8 @S9S_MB_2U_LIB.S9S_MB_2U(SCH_1):PAGE71
  CH12    GND @S9S_MB_2U_LIB.S9S_MB_2U(SCH_1):GND     I8 @S9S_MB_2U_LIB.S9S_MB_2U(SCH_1):PAGE71
   CG9    GND @S9S_MB_2U_LIB.S9S_MB_2U(SCH_1):GND     I8 @S9S_MB_2U_LIB.S9S_MB_2U(SCH_1):PAGE71
  CG78    GND @S9S_MB_2U_LIB.S9S_MB_2U(SCH_1):GND     I8 @S9S_MB_2U_LIB.S9S_MB_2U(SCH_1):PAGE71
  CG74    GND @S9S_MB_2U_LIB.S9S_MB_2U(SCH_1):GND     I8 @S9S_MB_2U_LIB.S9S_MB_2U(SCH_1):PAGE71
  CG72    GND @S9S_MB_2U_LIB.S9S_MB_2U(SCH_1):GND     I8 @S9S_MB_2U_LIB.S9S_MB_2U(SCH_1):PAGE71
  CG70    GND @S9S_MB_2U_LIB.S9S_MB_2U(SCH_1):GND     I8 @S9S_MB_2U_LIB.S9S_MB_2U(SCH_1):PAGE71
  CG64    GND @S9S_MB_2U_LIB.S9S_MB_2U(SCH_1):GND     I8 @S9S_MB_2U_LIB.S9S_MB_2U(SCH_1):PAGE71
  CG62    GND @S9S_MB_2U_LIB.S9S_MB_2U(SCH_1):GND     I8 @S9S_MB_2U_LIB.S9S_MB_2U(SCH_1):PAGE71
   CG5    GND @S9S_MB_2U_LIB.S9S_MB_2U(SCH_1):GND     I8 @S9S_MB_2U_LIB.S9S_MB_2U(SCH_1):PAGE71
  CG25    GND @S9S_MB_2U_LIB.S9S_MB_2U(SCH_1):GND     I8 @S9S_MB_2U_LIB.S9S_MB_2U(SCH_1):PAGE71
  CG23    GND @S9S_MB_2U_LIB.S9S_MB_2U(SCH_1):GND     I8 @S9S_MB_2U_LIB.S9S_MB_2U(SCH_1):PAGE71
  CG21    GND @S9S_MB_2U_LIB.S9S_MB_2U(SCH_1):GND     I8 @S9S_MB_2U_LIB.S9S_MB_2U(SCH_1):PAGE71
  CG17    GND @S9S_MB_2U_LIB.S9S_MB_2U(SCH_1):GND     I8 @S9S_MB_2U_LIB.S9S_MB_2U(SCH_1):PAGE71
  CG13    GND @S9S_MB_2U_LIB.S9S_MB_2U(SCH_1):GND     I8 @S9S_MB_2U_LIB.S9S_MB_2U(SCH_1):PAGE71
   CG1    GND @S9S_MB_2U_LIB.S9S_MB_2U(SCH_1):GND     I8 @S9S_MB_2U_LIB.S9S_MB_2U(SCH_1):PAGE71
   CF8    GND @S9S_MB_2U_LIB.S9S_MB_2U(SCH_1):GND     I8 @S9S_MB_2U_LIB.S9S_MB_2U(SCH_1):PAGE71
  CF71    GND @S9S_MB_2U_LIB.S9S_MB_2U(SCH_1):GND     I8 @S9S_MB_2U_LIB.S9S_MB_2U(SCH_1):PAGE71
  CF69    GND @S9S_MB_2U_LIB.S9S_MB_2U(SCH_1):GND     I8 @S9S_MB_2U_LIB.S9S_MB_2U(SCH_1):PAGE71
   CF4    GND @S9S_MB_2U_LIB.S9S_MB_2U(SCH_1):GND     I8 @S9S_MB_2U_LIB.S9S_MB_2U(SCH_1):PAGE71
  CF20    GND @S9S_MB_2U_LIB.S9S_MB_2U(SCH_1):GND     I8 @S9S_MB_2U_LIB.S9S_MB_2U(SCH_1):PAGE71
  CF16    GND @S9S_MB_2U_LIB.S9S_MB_2U(SCH_1):GND     I8 @S9S_MB_2U_LIB.S9S_MB_2U(SCH_1):PAGE71
  CF12    GND @S9S_MB_2U_LIB.S9S_MB_2U(SCH_1):GND     I8 @S9S_MB_2U_LIB.S9S_MB_2U(SCH_1):PAGE71
  CE78    GND @S9S_MB_2U_LIB.S9S_MB_2U(SCH_1):GND     I8 @S9S_MB_2U_LIB.S9S_MB_2U(SCH_1):PAGE71
  CE76    GND @S9S_MB_2U_LIB.S9S_MB_2U(SCH_1):GND     I8 @S9S_MB_2U_LIB.S9S_MB_2U(SCH_1):PAGE71
  CE72    GND @S9S_MB_2U_LIB.S9S_MB_2U(SCH_1):GND     I8 @S9S_MB_2U_LIB.S9S_MB_2U(SCH_1):PAGE71
  CE66    GND @S9S_MB_2U_LIB.S9S_MB_2U(SCH_1):GND     I8 @S9S_MB_2U_LIB.S9S_MB_2U(SCH_1):PAGE71
  CE60    GND @S9S_MB_2U_LIB.S9S_MB_2U(SCH_1):GND     I8 @S9S_MB_2U_LIB.S9S_MB_2U(SCH_1):PAGE71
   CE3    GND @S9S_MB_2U_LIB.S9S_MB_2U(SCH_1):GND     I8 @S9S_MB_2U_LIB.S9S_MB_2U(SCH_1):PAGE71
   CD8    GND @S9S_MB_2U_LIB.S9S_MB_2U(SCH_1):GND     I8 @S9S_MB_2U_LIB.S9S_MB_2U(SCH_1):PAGE71
  CD77    GND @S9S_MB_2U_LIB.S9S_MB_2U(SCH_1):GND     I8 @S9S_MB_2U_LIB.S9S_MB_2U(SCH_1):PAGE71
  CD75    GND @S9S_MB_2U_LIB.S9S_MB_2U(SCH_1):GND     I8 @S9S_MB_2U_LIB.S9S_MB_2U(SCH_1):PAGE71
  CD61    GND @S9S_MB_2U_LIB.S9S_MB_2U(SCH_1):GND     I8 @S9S_MB_2U_LIB.S9S_MB_2U(SCH_1):PAGE71
   CD4    GND @S9S_MB_2U_LIB.S9S_MB_2U(SCH_1):GND     I8 @S9S_MB_2U_LIB.S9S_MB_2U(SCH_1):PAGE71
  CD20    GND @S9S_MB_2U_LIB.S9S_MB_2U(SCH_1):GND     I8 @S9S_MB_2U_LIB.S9S_MB_2U(SCH_1):PAGE71
  CD16    GND @S9S_MB_2U_LIB.S9S_MB_2U(SCH_1):GND     I8 @S9S_MB_2U_LIB.S9S_MB_2U(SCH_1):PAGE71
  CD12    GND @S9S_MB_2U_LIB.S9S_MB_2U(SCH_1):GND     I8 @S9S_MB_2U_LIB.S9S_MB_2U(SCH_1):PAGE71
   CC9    GND @S9S_MB_2U_LIB.S9S_MB_2U(SCH_1):GND     I8 @S9S_MB_2U_LIB.S9S_MB_2U(SCH_1):PAGE71
  CC74    GND @S9S_MB_2U_LIB.S9S_MB_2U(SCH_1):GND     I8 @S9S_MB_2U_LIB.S9S_MB_2U(SCH_1):PAGE71
  CC72    GND @S9S_MB_2U_LIB.S9S_MB_2U(SCH_1):GND     I8 @S9S_MB_2U_LIB.S9S_MB_2U(SCH_1):PAGE71
  CC70    GND @S9S_MB_2U_LIB.S9S_MB_2U(SCH_1):GND     I8 @S9S_MB_2U_LIB.S9S_MB_2U(SCH_1):PAGE71
  CC62    GND @S9S_MB_2U_LIB.S9S_MB_2U(SCH_1):GND     I8 @S9S_MB_2U_LIB.S9S_MB_2U(SCH_1):PAGE71
   CC5    GND @S9S_MB_2U_LIB.S9S_MB_2U(SCH_1):GND     I8 @S9S_MB_2U_LIB.S9S_MB_2U(SCH_1):PAGE71
  CC31    GND @S9S_MB_2U_LIB.S9S_MB_2U(SCH_1):GND     I8 @S9S_MB_2U_LIB.S9S_MB_2U(SCH_1):PAGE71
  CC17    GND @S9S_MB_2U_LIB.S9S_MB_2U(SCH_1):GND     I8 @S9S_MB_2U_LIB.S9S_MB_2U(SCH_1):PAGE71
  CC13    GND @S9S_MB_2U_LIB.S9S_MB_2U(SCH_1):GND     I8 @S9S_MB_2U_LIB.S9S_MB_2U(SCH_1):PAGE71
  CB89    GND @S9S_MB_2U_LIB.S9S_MB_2U(SCH_1):GND     I8 @S9S_MB_2U_LIB.S9S_MB_2U(SCH_1):PAGE71
  CB87    GND @S9S_MB_2U_LIB.S9S_MB_2U(SCH_1):GND     I8 @S9S_MB_2U_LIB.S9S_MB_2U(SCH_1):PAGE71
  CB85    GND @S9S_MB_2U_LIB.S9S_MB_2U(SCH_1):GND     I8 @S9S_MB_2U_LIB.S9S_MB_2U(SCH_1):PAGE71
  CB83    GND @S9S_MB_2U_LIB.S9S_MB_2U(SCH_1):GND     I8 @S9S_MB_2U_LIB.S9S_MB_2U(SCH_1):PAGE71
  CB81    GND @S9S_MB_2U_LIB.S9S_MB_2U(SCH_1):GND     I8 @S9S_MB_2U_LIB.S9S_MB_2U(SCH_1):PAGE71
   CB8    GND @S9S_MB_2U_LIB.S9S_MB_2U(SCH_1):GND     I8 @S9S_MB_2U_LIB.S9S_MB_2U(SCH_1):PAGE71
  CB79    GND @S9S_MB_2U_LIB.S9S_MB_2U(SCH_1):GND     I8 @S9S_MB_2U_LIB.S9S_MB_2U(SCH_1):PAGE71
  CB73    GND @S9S_MB_2U_LIB.S9S_MB_2U(SCH_1):GND     I8 @S9S_MB_2U_LIB.S9S_MB_2U(SCH_1):PAGE71
  CB71    GND @S9S_MB_2U_LIB.S9S_MB_2U(SCH_1):GND     I8 @S9S_MB_2U_LIB.S9S_MB_2U(SCH_1):PAGE71
  CB69    GND @S9S_MB_2U_LIB.S9S_MB_2U(SCH_1):GND     I8 @S9S_MB_2U_LIB.S9S_MB_2U(SCH_1):PAGE71
  CB67    GND @S9S_MB_2U_LIB.S9S_MB_2U(SCH_1):GND     I8 @S9S_MB_2U_LIB.S9S_MB_2U(SCH_1):PAGE71
  CB65    GND @S9S_MB_2U_LIB.S9S_MB_2U(SCH_1):GND     I8 @S9S_MB_2U_LIB.S9S_MB_2U(SCH_1):PAGE71
  CB63    GND @S9S_MB_2U_LIB.S9S_MB_2U(SCH_1):GND     I8 @S9S_MB_2U_LIB.S9S_MB_2U(SCH_1):PAGE71
  CB59    GND @S9S_MB_2U_LIB.S9S_MB_2U(SCH_1):GND     I8 @S9S_MB_2U_LIB.S9S_MB_2U(SCH_1):PAGE71
  CB57    GND @S9S_MB_2U_LIB.S9S_MB_2U(SCH_1):GND     I8 @S9S_MB_2U_LIB.S9S_MB_2U(SCH_1):PAGE71
  CB55    GND @S9S_MB_2U_LIB.S9S_MB_2U(SCH_1):GND     I8 @S9S_MB_2U_LIB.S9S_MB_2U(SCH_1):PAGE71
  CB53    GND @S9S_MB_2U_LIB.S9S_MB_2U(SCH_1):GND     I8 @S9S_MB_2U_LIB.S9S_MB_2U(SCH_1):PAGE71
  CB51    GND @S9S_MB_2U_LIB.S9S_MB_2U(SCH_1):GND     I8 @S9S_MB_2U_LIB.S9S_MB_2U(SCH_1):PAGE71
  CB49    GND @S9S_MB_2U_LIB.S9S_MB_2U(SCH_1):GND     I8 @S9S_MB_2U_LIB.S9S_MB_2U(SCH_1):PAGE71
  CB47    GND @S9S_MB_2U_LIB.S9S_MB_2U(SCH_1):GND     I8 @S9S_MB_2U_LIB.S9S_MB_2U(SCH_1):PAGE71
  CB44    GND @S9S_MB_2U_LIB.S9S_MB_2U(SCH_1):GND     I8 @S9S_MB_2U_LIB.S9S_MB_2U(SCH_1):PAGE71
  CB42    GND @S9S_MB_2U_LIB.S9S_MB_2U(SCH_1):GND     I8 @S9S_MB_2U_LIB.S9S_MB_2U(SCH_1):PAGE71
  CB40    GND @S9S_MB_2U_LIB.S9S_MB_2U(SCH_1):GND     I8 @S9S_MB_2U_LIB.S9S_MB_2U(SCH_1):PAGE71
   CB4    GND @S9S_MB_2U_LIB.S9S_MB_2U(SCH_1):GND     I8 @S9S_MB_2U_LIB.S9S_MB_2U(SCH_1):PAGE71
  CB38    GND @S9S_MB_2U_LIB.S9S_MB_2U(SCH_1):GND     I8 @S9S_MB_2U_LIB.S9S_MB_2U(SCH_1):PAGE71
  CB36    GND @S9S_MB_2U_LIB.S9S_MB_2U(SCH_1):GND     I8 @S9S_MB_2U_LIB.S9S_MB_2U(SCH_1):PAGE71
  CB34    GND @S9S_MB_2U_LIB.S9S_MB_2U(SCH_1):GND     I8 @S9S_MB_2U_LIB.S9S_MB_2U(SCH_1):PAGE71
  CB32    GND @S9S_MB_2U_LIB.S9S_MB_2U(SCH_1):GND     I8 @S9S_MB_2U_LIB.S9S_MB_2U(SCH_1):PAGE71
  CB28    GND @S9S_MB_2U_LIB.S9S_MB_2U(SCH_1):GND     I8 @S9S_MB_2U_LIB.S9S_MB_2U(SCH_1):PAGE71
  CB26    GND @S9S_MB_2U_LIB.S9S_MB_2U(SCH_1):GND     I8 @S9S_MB_2U_LIB.S9S_MB_2U(SCH_1):PAGE71
  CB24    GND @S9S_MB_2U_LIB.S9S_MB_2U(SCH_1):GND     I8 @S9S_MB_2U_LIB.S9S_MB_2U(SCH_1):PAGE71
  CB22    GND @S9S_MB_2U_LIB.S9S_MB_2U(SCH_1):GND     I8 @S9S_MB_2U_LIB.S9S_MB_2U(SCH_1):PAGE71
  CB20    GND @S9S_MB_2U_LIB.S9S_MB_2U(SCH_1):GND     I8 @S9S_MB_2U_LIB.S9S_MB_2U(SCH_1):PAGE71
  CB16    GND @S9S_MB_2U_LIB.S9S_MB_2U(SCH_1):GND     I8 @S9S_MB_2U_LIB.S9S_MB_2U(SCH_1):PAGE71
  CB12    GND @S9S_MB_2U_LIB.S9S_MB_2U(SCH_1):GND     I8 @S9S_MB_2U_LIB.S9S_MB_2U(SCH_1):PAGE71
  CA31    GND @S9S_MB_2U_LIB.S9S_MB_2U(SCH_1):GND     I8 @S9S_MB_2U_LIB.S9S_MB_2U(SCH_1):PAGE71
   CA3    GND @S9S_MB_2U_LIB.S9S_MB_2U(SCH_1):GND     I8 @S9S_MB_2U_LIB.S9S_MB_2U(SCH_1):PAGE71
   BY8    GND @S9S_MB_2U_LIB.S9S_MB_2U(SCH_1):GND     I8 @S9S_MB_2U_LIB.S9S_MB_2U(SCH_1):PAGE71
   BY4    GND @S9S_MB_2U_LIB.S9S_MB_2U(SCH_1):GND     I8 @S9S_MB_2U_LIB.S9S_MB_2U(SCH_1):PAGE71
  BY20    GND @S9S_MB_2U_LIB.S9S_MB_2U(SCH_1):GND     I8 @S9S_MB_2U_LIB.S9S_MB_2U(SCH_1):PAGE71
  BY16    GND @S9S_MB_2U_LIB.S9S_MB_2U(SCH_1):GND     I8 @S9S_MB_2U_LIB.S9S_MB_2U(SCH_1):PAGE71
  BY12    GND @S9S_MB_2U_LIB.S9S_MB_2U(SCH_1):GND     I8 @S9S_MB_2U_LIB.S9S_MB_2U(SCH_1):PAGE71
   BW9    GND @S9S_MB_2U_LIB.S9S_MB_2U(SCH_1):GND     I8 @S9S_MB_2U_LIB.S9S_MB_2U(SCH_1):PAGE71
   BW5    GND @S9S_MB_2U_LIB.S9S_MB_2U(SCH_1):GND     I8 @S9S_MB_2U_LIB.S9S_MB_2U(SCH_1):PAGE71
  BW31    GND @S9S_MB_2U_LIB.S9S_MB_2U(SCH_1):GND     I8 @S9S_MB_2U_LIB.S9S_MB_2U(SCH_1):PAGE71
   BW3    GND @S9S_MB_2U_LIB.S9S_MB_2U(SCH_1):GND     I8 @S9S_MB_2U_LIB.S9S_MB_2U(SCH_1):PAGE71
  BW29    GND @S9S_MB_2U_LIB.S9S_MB_2U(SCH_1):GND     I8 @S9S_MB_2U_LIB.S9S_MB_2U(SCH_1):PAGE71
  BW27    GND @S9S_MB_2U_LIB.S9S_MB_2U(SCH_1):GND     I8 @S9S_MB_2U_LIB.S9S_MB_2U(SCH_1):PAGE71
  BW17    GND @S9S_MB_2U_LIB.S9S_MB_2U(SCH_1):GND     I8 @S9S_MB_2U_LIB.S9S_MB_2U(SCH_1):PAGE71
  BW13    GND @S9S_MB_2U_LIB.S9S_MB_2U(SCH_1):GND     I8 @S9S_MB_2U_LIB.S9S_MB_2U(SCH_1):PAGE71
   BV8    GND @S9S_MB_2U_LIB.S9S_MB_2U(SCH_1):GND     I8 @S9S_MB_2U_LIB.S9S_MB_2U(SCH_1):PAGE71
   BV6    GND @S9S_MB_2U_LIB.S9S_MB_2U(SCH_1):GND     I8 @S9S_MB_2U_LIB.S9S_MB_2U(SCH_1):PAGE71
   BV4    GND @S9S_MB_2U_LIB.S9S_MB_2U(SCH_1):GND     I8 @S9S_MB_2U_LIB.S9S_MB_2U(SCH_1):PAGE71
  BV20    GND @S9S_MB_2U_LIB.S9S_MB_2U(SCH_1):GND     I8 @S9S_MB_2U_LIB.S9S_MB_2U(SCH_1):PAGE71
   BV2    GND @S9S_MB_2U_LIB.S9S_MB_2U(SCH_1):GND     I8 @S9S_MB_2U_LIB.S9S_MB_2U(SCH_1):PAGE71
  BV18    GND @S9S_MB_2U_LIB.S9S_MB_2U(SCH_1):GND     I8 @S9S_MB_2U_LIB.S9S_MB_2U(SCH_1):PAGE71
  BV16    GND @S9S_MB_2U_LIB.S9S_MB_2U(SCH_1):GND     I8 @S9S_MB_2U_LIB.S9S_MB_2U(SCH_1):PAGE71
  BV12    GND @S9S_MB_2U_LIB.S9S_MB_2U(SCH_1):GND     I8 @S9S_MB_2U_LIB.S9S_MB_2U(SCH_1):PAGE71
   BU7    GND @S9S_MB_2U_LIB.S9S_MB_2U(SCH_1):GND     I8 @S9S_MB_2U_LIB.S9S_MB_2U(SCH_1):PAGE71
  BU31    GND @S9S_MB_2U_LIB.S9S_MB_2U(SCH_1):GND     I8 @S9S_MB_2U_LIB.S9S_MB_2U(SCH_1):PAGE71
  BU25    GND @S9S_MB_2U_LIB.S9S_MB_2U(SCH_1):GND     I8 @S9S_MB_2U_LIB.S9S_MB_2U(SCH_1):PAGE71
  BU23    GND @S9S_MB_2U_LIB.S9S_MB_2U(SCH_1):GND     I8 @S9S_MB_2U_LIB.S9S_MB_2U(SCH_1):PAGE71
  BU21    GND @S9S_MB_2U_LIB.S9S_MB_2U(SCH_1):GND     I8 @S9S_MB_2U_LIB.S9S_MB_2U(SCH_1):PAGE71
  BU19    GND @S9S_MB_2U_LIB.S9S_MB_2U(SCH_1):GND     I8 @S9S_MB_2U_LIB.S9S_MB_2U(SCH_1):PAGE71
  BU15    GND @S9S_MB_2U_LIB.S9S_MB_2U(SCH_1):GND     I8 @S9S_MB_2U_LIB.S9S_MB_2U(SCH_1):PAGE71
   BT8    GND @S9S_MB_2U_LIB.S9S_MB_2U(SCH_1):GND     I8 @S9S_MB_2U_LIB.S9S_MB_2U(SCH_1):PAGE71
   BT4    GND @S9S_MB_2U_LIB.S9S_MB_2U(SCH_1):GND     I8 @S9S_MB_2U_LIB.S9S_MB_2U(SCH_1):PAGE71
  BT20    GND @S9S_MB_2U_LIB.S9S_MB_2U(SCH_1):GND     I8 @S9S_MB_2U_LIB.S9S_MB_2U(SCH_1):PAGE71
  BT16    GND @S9S_MB_2U_LIB.S9S_MB_2U(SCH_1):GND     I8 @S9S_MB_2U_LIB.S9S_MB_2U(SCH_1):PAGE71
  BT12    GND @S9S_MB_2U_LIB.S9S_MB_2U(SCH_1):GND     I8 @S9S_MB_2U_LIB.S9S_MB_2U(SCH_1):PAGE71
  BR90    GND @S9S_MB_2U_LIB.S9S_MB_2U(SCH_1):GND     I8 @S9S_MB_2U_LIB.S9S_MB_2U(SCH_1):PAGE71
  BR88    GND @S9S_MB_2U_LIB.S9S_MB_2U(SCH_1):GND     I8 @S9S_MB_2U_LIB.S9S_MB_2U(SCH_1):PAGE71
  BR86    GND @S9S_MB_2U_LIB.S9S_MB_2U(SCH_1):GND     I8 @S9S_MB_2U_LIB.S9S_MB_2U(SCH_1):PAGE71
  BR84    GND @S9S_MB_2U_LIB.S9S_MB_2U(SCH_1):GND     I8 @S9S_MB_2U_LIB.S9S_MB_2U(SCH_1):PAGE71
  BR82    GND @S9S_MB_2U_LIB.S9S_MB_2U(SCH_1):GND     I8 @S9S_MB_2U_LIB.S9S_MB_2U(SCH_1):PAGE71
  BR80    GND @S9S_MB_2U_LIB.S9S_MB_2U(SCH_1):GND     I8 @S9S_MB_2U_LIB.S9S_MB_2U(SCH_1):PAGE71
  BR76    GND @S9S_MB_2U_LIB.S9S_MB_2U(SCH_1):GND     I8 @S9S_MB_2U_LIB.S9S_MB_2U(SCH_1):PAGE71
  BR74    GND @S9S_MB_2U_LIB.S9S_MB_2U(SCH_1):GND     I8 @S9S_MB_2U_LIB.S9S_MB_2U(SCH_1):PAGE71
  BR72    GND @S9S_MB_2U_LIB.S9S_MB_2U(SCH_1):GND     I8 @S9S_MB_2U_LIB.S9S_MB_2U(SCH_1):PAGE71
  BR70    GND @S9S_MB_2U_LIB.S9S_MB_2U(SCH_1):GND     I8 @S9S_MB_2U_LIB.S9S_MB_2U(SCH_1):PAGE71
  BR68    GND @S9S_MB_2U_LIB.S9S_MB_2U(SCH_1):GND     I8 @S9S_MB_2U_LIB.S9S_MB_2U(SCH_1):PAGE71
  BR66    GND @S9S_MB_2U_LIB.S9S_MB_2U(SCH_1):GND     I8 @S9S_MB_2U_LIB.S9S_MB_2U(SCH_1):PAGE71
  BR64    GND @S9S_MB_2U_LIB.S9S_MB_2U(SCH_1):GND     I8 @S9S_MB_2U_LIB.S9S_MB_2U(SCH_1):PAGE71
  BR58    GND @S9S_MB_2U_LIB.S9S_MB_2U(SCH_1):GND     I8 @S9S_MB_2U_LIB.S9S_MB_2U(SCH_1):PAGE71
  BR56    GND @S9S_MB_2U_LIB.S9S_MB_2U(SCH_1):GND     I8 @S9S_MB_2U_LIB.S9S_MB_2U(SCH_1):PAGE71
  BR54    GND @S9S_MB_2U_LIB.S9S_MB_2U(SCH_1):GND     I8 @S9S_MB_2U_LIB.S9S_MB_2U(SCH_1):PAGE71
  BR52    GND @S9S_MB_2U_LIB.S9S_MB_2U(SCH_1):GND     I8 @S9S_MB_2U_LIB.S9S_MB_2U(SCH_1):PAGE71
  BR50    GND @S9S_MB_2U_LIB.S9S_MB_2U(SCH_1):GND     I8 @S9S_MB_2U_LIB.S9S_MB_2U(SCH_1):PAGE71
  BR48    GND @S9S_MB_2U_LIB.S9S_MB_2U(SCH_1):GND     I8 @S9S_MB_2U_LIB.S9S_MB_2U(SCH_1):PAGE71
  BR45    GND @S9S_MB_2U_LIB.S9S_MB_2U(SCH_1):GND     I8 @S9S_MB_2U_LIB.S9S_MB_2U(SCH_1):PAGE71
  BR43    GND @S9S_MB_2U_LIB.S9S_MB_2U(SCH_1):GND     I8 @S9S_MB_2U_LIB.S9S_MB_2U(SCH_1):PAGE71
  BR41    GND @S9S_MB_2U_LIB.S9S_MB_2U(SCH_1):GND     I8 @S9S_MB_2U_LIB.S9S_MB_2U(SCH_1):PAGE71
  BR39    GND @S9S_MB_2U_LIB.S9S_MB_2U(SCH_1):GND     I8 @S9S_MB_2U_LIB.S9S_MB_2U(SCH_1):PAGE71
  BR37    GND @S9S_MB_2U_LIB.S9S_MB_2U(SCH_1):GND     I8 @S9S_MB_2U_LIB.S9S_MB_2U(SCH_1):PAGE71
  BR35    GND @S9S_MB_2U_LIB.S9S_MB_2U(SCH_1):GND     I8 @S9S_MB_2U_LIB.S9S_MB_2U(SCH_1):PAGE71
   CK4    GND @S9S_MB_2U_LIB.S9S_MB_2U(SCH_1):GND     I8 @S9S_MB_2U_LIB.S9S_MB_2U(SCH_1):PAGE71
  CJ76    GND @S9S_MB_2U_LIB.S9S_MB_2U(SCH_1):GND     I8 @S9S_MB_2U_LIB.S9S_MB_2U(SCH_1):PAGE71
   BR9    GND @S9S_MB_2U_LIB.S9S_MB_2U(SCH_1):GND     I2 @S9S_MB_2U_LIB.S9S_MB_2U(SCH_1):PAGE72
  BR33    GND @S9S_MB_2U_LIB.S9S_MB_2U(SCH_1):GND     I2 @S9S_MB_2U_LIB.S9S_MB_2U(SCH_1):PAGE72
  BR31    GND @S9S_MB_2U_LIB.S9S_MB_2U(SCH_1):GND     I2 @S9S_MB_2U_LIB.S9S_MB_2U(SCH_1):PAGE72
  BR29    GND @S9S_MB_2U_LIB.S9S_MB_2U(SCH_1):GND     I2 @S9S_MB_2U_LIB.S9S_MB_2U(SCH_1):PAGE72
  BR27    GND @S9S_MB_2U_LIB.S9S_MB_2U(SCH_1):GND     I2 @S9S_MB_2U_LIB.S9S_MB_2U(SCH_1):PAGE72
  BR17    GND @S9S_MB_2U_LIB.S9S_MB_2U(SCH_1):GND     I2 @S9S_MB_2U_LIB.S9S_MB_2U(SCH_1):PAGE72
  BR13    GND @S9S_MB_2U_LIB.S9S_MB_2U(SCH_1):GND     I2 @S9S_MB_2U_LIB.S9S_MB_2U(SCH_1):PAGE72
   BP8    GND @S9S_MB_2U_LIB.S9S_MB_2U(SCH_1):GND     I2 @S9S_MB_2U_LIB.S9S_MB_2U(SCH_1):PAGE72
  BP77    GND @S9S_MB_2U_LIB.S9S_MB_2U(SCH_1):GND     I2 @S9S_MB_2U_LIB.S9S_MB_2U(SCH_1):PAGE72
  BP75    GND @S9S_MB_2U_LIB.S9S_MB_2U(SCH_1):GND     I2 @S9S_MB_2U_LIB.S9S_MB_2U(SCH_1):PAGE72
  BP73    GND @S9S_MB_2U_LIB.S9S_MB_2U(SCH_1):GND     I2 @S9S_MB_2U_LIB.S9S_MB_2U(SCH_1):PAGE72
  BP71    GND @S9S_MB_2U_LIB.S9S_MB_2U(SCH_1):GND     I2 @S9S_MB_2U_LIB.S9S_MB_2U(SCH_1):PAGE72
  BP63    GND @S9S_MB_2U_LIB.S9S_MB_2U(SCH_1):GND     I2 @S9S_MB_2U_LIB.S9S_MB_2U(SCH_1):PAGE72
   BP4    GND @S9S_MB_2U_LIB.S9S_MB_2U(SCH_1):GND     I2 @S9S_MB_2U_LIB.S9S_MB_2U(SCH_1):PAGE72
  BP20    GND @S9S_MB_2U_LIB.S9S_MB_2U(SCH_1):GND     I2 @S9S_MB_2U_LIB.S9S_MB_2U(SCH_1):PAGE72
   BP2    GND @S9S_MB_2U_LIB.S9S_MB_2U(SCH_1):GND     I2 @S9S_MB_2U_LIB.S9S_MB_2U(SCH_1):PAGE72
  BP16    GND @S9S_MB_2U_LIB.S9S_MB_2U(SCH_1):GND     I2 @S9S_MB_2U_LIB.S9S_MB_2U(SCH_1):PAGE72
  BP12    GND @S9S_MB_2U_LIB.S9S_MB_2U(SCH_1):GND     I2 @S9S_MB_2U_LIB.S9S_MB_2U(SCH_1):PAGE72
  BN70    GND @S9S_MB_2U_LIB.S9S_MB_2U(SCH_1):GND     I2 @S9S_MB_2U_LIB.S9S_MB_2U(SCH_1):PAGE72
  BN62    GND @S9S_MB_2U_LIB.S9S_MB_2U(SCH_1):GND     I2 @S9S_MB_2U_LIB.S9S_MB_2U(SCH_1):PAGE72
  BN31    GND @S9S_MB_2U_LIB.S9S_MB_2U(SCH_1):GND     I2 @S9S_MB_2U_LIB.S9S_MB_2U(SCH_1):PAGE72
   BM8    GND @S9S_MB_2U_LIB.S9S_MB_2U(SCH_1):GND     I2 @S9S_MB_2U_LIB.S9S_MB_2U(SCH_1):PAGE72
  BM77    GND @S9S_MB_2U_LIB.S9S_MB_2U(SCH_1):GND     I2 @S9S_MB_2U_LIB.S9S_MB_2U(SCH_1):PAGE72
  BM73    GND @S9S_MB_2U_LIB.S9S_MB_2U(SCH_1):GND     I2 @S9S_MB_2U_LIB.S9S_MB_2U(SCH_1):PAGE72
  BM61    GND @S9S_MB_2U_LIB.S9S_MB_2U(SCH_1):GND     I2 @S9S_MB_2U_LIB.S9S_MB_2U(SCH_1):PAGE72
   BM4    GND @S9S_MB_2U_LIB.S9S_MB_2U(SCH_1):GND     I2 @S9S_MB_2U_LIB.S9S_MB_2U(SCH_1):PAGE72
  BM26    GND @S9S_MB_2U_LIB.S9S_MB_2U(SCH_1):GND     I2 @S9S_MB_2U_LIB.S9S_MB_2U(SCH_1):PAGE72
  BM24    GND @S9S_MB_2U_LIB.S9S_MB_2U(SCH_1):GND     I2 @S9S_MB_2U_LIB.S9S_MB_2U(SCH_1):PAGE72
  BM22    GND @S9S_MB_2U_LIB.S9S_MB_2U(SCH_1):GND     I2 @S9S_MB_2U_LIB.S9S_MB_2U(SCH_1):PAGE72
  BM20    GND @S9S_MB_2U_LIB.S9S_MB_2U(SCH_1):GND     I2 @S9S_MB_2U_LIB.S9S_MB_2U(SCH_1):PAGE72
  BM16    GND @S9S_MB_2U_LIB.S9S_MB_2U(SCH_1):GND     I2 @S9S_MB_2U_LIB.S9S_MB_2U(SCH_1):PAGE72
  BM12    GND @S9S_MB_2U_LIB.S9S_MB_2U(SCH_1):GND     I2 @S9S_MB_2U_LIB.S9S_MB_2U(SCH_1):PAGE72
   BL9    GND @S9S_MB_2U_LIB.S9S_MB_2U(SCH_1):GND     I2 @S9S_MB_2U_LIB.S9S_MB_2U(SCH_1):PAGE72
  BL78    GND @S9S_MB_2U_LIB.S9S_MB_2U(SCH_1):GND     I2 @S9S_MB_2U_LIB.S9S_MB_2U(SCH_1):PAGE72
  BL72    GND @S9S_MB_2U_LIB.S9S_MB_2U(SCH_1):GND     I2 @S9S_MB_2U_LIB.S9S_MB_2U(SCH_1):PAGE72
  BL70    GND @S9S_MB_2U_LIB.S9S_MB_2U(SCH_1):GND     I2 @S9S_MB_2U_LIB.S9S_MB_2U(SCH_1):PAGE72
  BL68    GND @S9S_MB_2U_LIB.S9S_MB_2U(SCH_1):GND     I2 @S9S_MB_2U_LIB.S9S_MB_2U(SCH_1):PAGE72
   BL5    GND @S9S_MB_2U_LIB.S9S_MB_2U(SCH_1):GND     I2 @S9S_MB_2U_LIB.S9S_MB_2U(SCH_1):PAGE72
  BL17    GND @S9S_MB_2U_LIB.S9S_MB_2U(SCH_1):GND     I2 @S9S_MB_2U_LIB.S9S_MB_2U(SCH_1):PAGE72
  BL13    GND @S9S_MB_2U_LIB.S9S_MB_2U(SCH_1):GND     I2 @S9S_MB_2U_LIB.S9S_MB_2U(SCH_1):PAGE72
   BL1    GND @S9S_MB_2U_LIB.S9S_MB_2U(SCH_1):GND     I2 @S9S_MB_2U_LIB.S9S_MB_2U(SCH_1):PAGE72
   BK8    GND @S9S_MB_2U_LIB.S9S_MB_2U(SCH_1):GND     I2 @S9S_MB_2U_LIB.S9S_MB_2U(SCH_1):PAGE72
  BK79    GND @S9S_MB_2U_LIB.S9S_MB_2U(SCH_1):GND     I2 @S9S_MB_2U_LIB.S9S_MB_2U(SCH_1):PAGE72
  BK75    GND @S9S_MB_2U_LIB.S9S_MB_2U(SCH_1):GND     I2 @S9S_MB_2U_LIB.S9S_MB_2U(SCH_1):PAGE72
  BK71    GND @S9S_MB_2U_LIB.S9S_MB_2U(SCH_1):GND     I2 @S9S_MB_2U_LIB.S9S_MB_2U(SCH_1):PAGE72
  BK65    GND @S9S_MB_2U_LIB.S9S_MB_2U(SCH_1):GND     I2 @S9S_MB_2U_LIB.S9S_MB_2U(SCH_1):PAGE72
   BK4    GND @S9S_MB_2U_LIB.S9S_MB_2U(SCH_1):GND     I2 @S9S_MB_2U_LIB.S9S_MB_2U(SCH_1):PAGE72
  BK20    GND @S9S_MB_2U_LIB.S9S_MB_2U(SCH_1):GND     I2 @S9S_MB_2U_LIB.S9S_MB_2U(SCH_1):PAGE72
  BK16    GND @S9S_MB_2U_LIB.S9S_MB_2U(SCH_1):GND     I2 @S9S_MB_2U_LIB.S9S_MB_2U(SCH_1):PAGE72
  BK12    GND @S9S_MB_2U_LIB.S9S_MB_2U(SCH_1):GND     I2 @S9S_MB_2U_LIB.S9S_MB_2U(SCH_1):PAGE72
  BJ90    GND @S9S_MB_2U_LIB.S9S_MB_2U(SCH_1):GND     I2 @S9S_MB_2U_LIB.S9S_MB_2U(SCH_1):PAGE72
  BJ88    GND @S9S_MB_2U_LIB.S9S_MB_2U(SCH_1):GND     I2 @S9S_MB_2U_LIB.S9S_MB_2U(SCH_1):PAGE72
  BJ86    GND @S9S_MB_2U_LIB.S9S_MB_2U(SCH_1):GND     I2 @S9S_MB_2U_LIB.S9S_MB_2U(SCH_1):PAGE72
  BJ84    GND @S9S_MB_2U_LIB.S9S_MB_2U(SCH_1):GND     I2 @S9S_MB_2U_LIB.S9S_MB_2U(SCH_1):PAGE72
  BJ82    GND @S9S_MB_2U_LIB.S9S_MB_2U(SCH_1):GND     I2 @S9S_MB_2U_LIB.S9S_MB_2U(SCH_1):PAGE72
  BJ80    GND @S9S_MB_2U_LIB.S9S_MB_2U(SCH_1):GND     I2 @S9S_MB_2U_LIB.S9S_MB_2U(SCH_1):PAGE72
  BJ68    GND @S9S_MB_2U_LIB.S9S_MB_2U(SCH_1):GND     I2 @S9S_MB_2U_LIB.S9S_MB_2U(SCH_1):PAGE72
  BJ62    GND @S9S_MB_2U_LIB.S9S_MB_2U(SCH_1):GND     I2 @S9S_MB_2U_LIB.S9S_MB_2U(SCH_1):PAGE72
  BH83    GND @S9S_MB_2U_LIB.S9S_MB_2U(SCH_1):GND     I2 @S9S_MB_2U_LIB.S9S_MB_2U(SCH_1):PAGE72
  BH81    GND @S9S_MB_2U_LIB.S9S_MB_2U(SCH_1):GND     I2 @S9S_MB_2U_LIB.S9S_MB_2U(SCH_1):PAGE72
   BH8    GND @S9S_MB_2U_LIB.S9S_MB_2U(SCH_1):GND     I2 @S9S_MB_2U_LIB.S9S_MB_2U(SCH_1):PAGE72
  BH77    GND @S9S_MB_2U_LIB.S9S_MB_2U(SCH_1):GND     I2 @S9S_MB_2U_LIB.S9S_MB_2U(SCH_1):PAGE72
  BH73    GND @S9S_MB_2U_LIB.S9S_MB_2U(SCH_1):GND     I2 @S9S_MB_2U_LIB.S9S_MB_2U(SCH_1):PAGE72
  BH67    GND @S9S_MB_2U_LIB.S9S_MB_2U(SCH_1):GND     I2 @S9S_MB_2U_LIB.S9S_MB_2U(SCH_1):PAGE72
   BH4    GND @S9S_MB_2U_LIB.S9S_MB_2U(SCH_1):GND     I2 @S9S_MB_2U_LIB.S9S_MB_2U(SCH_1):PAGE72
  BH20    GND @S9S_MB_2U_LIB.S9S_MB_2U(SCH_1):GND     I2 @S9S_MB_2U_LIB.S9S_MB_2U(SCH_1):PAGE72
  BH16    GND @S9S_MB_2U_LIB.S9S_MB_2U(SCH_1):GND     I2 @S9S_MB_2U_LIB.S9S_MB_2U(SCH_1):PAGE72
  BH12    GND @S9S_MB_2U_LIB.S9S_MB_2U(SCH_1):GND     I2 @S9S_MB_2U_LIB.S9S_MB_2U(SCH_1):PAGE72
   BG9    GND @S9S_MB_2U_LIB.S9S_MB_2U(SCH_1):GND     I2 @S9S_MB_2U_LIB.S9S_MB_2U(SCH_1):PAGE72
  BG70    GND @S9S_MB_2U_LIB.S9S_MB_2U(SCH_1):GND     I2 @S9S_MB_2U_LIB.S9S_MB_2U(SCH_1):PAGE72
   BG5    GND @S9S_MB_2U_LIB.S9S_MB_2U(SCH_1):GND     I2 @S9S_MB_2U_LIB.S9S_MB_2U(SCH_1):PAGE72
  BG25    GND @S9S_MB_2U_LIB.S9S_MB_2U(SCH_1):GND     I2 @S9S_MB_2U_LIB.S9S_MB_2U(SCH_1):PAGE72
  BG23    GND @S9S_MB_2U_LIB.S9S_MB_2U(SCH_1):GND     I2 @S9S_MB_2U_LIB.S9S_MB_2U(SCH_1):PAGE72
  BG21    GND @S9S_MB_2U_LIB.S9S_MB_2U(SCH_1):GND     I2 @S9S_MB_2U_LIB.S9S_MB_2U(SCH_1):PAGE72
  BG17    GND @S9S_MB_2U_LIB.S9S_MB_2U(SCH_1):GND     I2 @S9S_MB_2U_LIB.S9S_MB_2U(SCH_1):PAGE72
  BG13    GND @S9S_MB_2U_LIB.S9S_MB_2U(SCH_1):GND     I2 @S9S_MB_2U_LIB.S9S_MB_2U(SCH_1):PAGE72
   BG1    GND @S9S_MB_2U_LIB.S9S_MB_2U(SCH_1):GND     I2 @S9S_MB_2U_LIB.S9S_MB_2U(SCH_1):PAGE72
  BF83    GND @S9S_MB_2U_LIB.S9S_MB_2U(SCH_1):GND     I2 @S9S_MB_2U_LIB.S9S_MB_2U(SCH_1):PAGE72
   BF8    GND @S9S_MB_2U_LIB.S9S_MB_2U(SCH_1):GND     I2 @S9S_MB_2U_LIB.S9S_MB_2U(SCH_1):PAGE72
  BF79    GND @S9S_MB_2U_LIB.S9S_MB_2U(SCH_1):GND     I2 @S9S_MB_2U_LIB.S9S_MB_2U(SCH_1):PAGE72
  BF75    GND @S9S_MB_2U_LIB.S9S_MB_2U(SCH_1):GND     I2 @S9S_MB_2U_LIB.S9S_MB_2U(SCH_1):PAGE72
  BF73    GND @S9S_MB_2U_LIB.S9S_MB_2U(SCH_1):GND     I2 @S9S_MB_2U_LIB.S9S_MB_2U(SCH_1):PAGE72
  BF63    GND @S9S_MB_2U_LIB.S9S_MB_2U(SCH_1):GND     I2 @S9S_MB_2U_LIB.S9S_MB_2U(SCH_1):PAGE72
  BF61    GND @S9S_MB_2U_LIB.S9S_MB_2U(SCH_1):GND     I2 @S9S_MB_2U_LIB.S9S_MB_2U(SCH_1):PAGE72
   BF4    GND @S9S_MB_2U_LIB.S9S_MB_2U(SCH_1):GND     I2 @S9S_MB_2U_LIB.S9S_MB_2U(SCH_1):PAGE72
  BF20    GND @S9S_MB_2U_LIB.S9S_MB_2U(SCH_1):GND     I2 @S9S_MB_2U_LIB.S9S_MB_2U(SCH_1):PAGE72
  BF16    GND @S9S_MB_2U_LIB.S9S_MB_2U(SCH_1):GND     I2 @S9S_MB_2U_LIB.S9S_MB_2U(SCH_1):PAGE72
  BF12    GND @S9S_MB_2U_LIB.S9S_MB_2U(SCH_1):GND     I2 @S9S_MB_2U_LIB.S9S_MB_2U(SCH_1):PAGE72
  BE84    GND @S9S_MB_2U_LIB.S9S_MB_2U(SCH_1):GND     I2 @S9S_MB_2U_LIB.S9S_MB_2U(SCH_1):PAGE72
  BE78    GND @S9S_MB_2U_LIB.S9S_MB_2U(SCH_1):GND     I2 @S9S_MB_2U_LIB.S9S_MB_2U(SCH_1):PAGE72
  BE76    GND @S9S_MB_2U_LIB.S9S_MB_2U(SCH_1):GND     I2 @S9S_MB_2U_LIB.S9S_MB_2U(SCH_1):PAGE72
  BE74    GND @S9S_MB_2U_LIB.S9S_MB_2U(SCH_1):GND     I2 @S9S_MB_2U_LIB.S9S_MB_2U(SCH_1):PAGE72
  BE68    GND @S9S_MB_2U_LIB.S9S_MB_2U(SCH_1):GND     I2 @S9S_MB_2U_LIB.S9S_MB_2U(SCH_1):PAGE72
  BE66    GND @S9S_MB_2U_LIB.S9S_MB_2U(SCH_1):GND     I2 @S9S_MB_2U_LIB.S9S_MB_2U(SCH_1):PAGE72
  BE64    GND @S9S_MB_2U_LIB.S9S_MB_2U(SCH_1):GND     I2 @S9S_MB_2U_LIB.S9S_MB_2U(SCH_1):PAGE72
  BD89    GND @S9S_MB_2U_LIB.S9S_MB_2U(SCH_1):GND     I2 @S9S_MB_2U_LIB.S9S_MB_2U(SCH_1):PAGE72
  BD85    GND @S9S_MB_2U_LIB.S9S_MB_2U(SCH_1):GND     I2 @S9S_MB_2U_LIB.S9S_MB_2U(SCH_1):PAGE72
  BD81    GND @S9S_MB_2U_LIB.S9S_MB_2U(SCH_1):GND     I2 @S9S_MB_2U_LIB.S9S_MB_2U(SCH_1):PAGE72
   BD8    GND @S9S_MB_2U_LIB.S9S_MB_2U(SCH_1):GND     I2 @S9S_MB_2U_LIB.S9S_MB_2U(SCH_1):PAGE72
   BD4    GND @S9S_MB_2U_LIB.S9S_MB_2U(SCH_1):GND     I2 @S9S_MB_2U_LIB.S9S_MB_2U(SCH_1):PAGE72
  BD20    GND @S9S_MB_2U_LIB.S9S_MB_2U(SCH_1):GND     I2 @S9S_MB_2U_LIB.S9S_MB_2U(SCH_1):PAGE72
  BD16    GND @S9S_MB_2U_LIB.S9S_MB_2U(SCH_1):GND     I2 @S9S_MB_2U_LIB.S9S_MB_2U(SCH_1):PAGE72
  BD12    GND @S9S_MB_2U_LIB.S9S_MB_2U(SCH_1):GND     I2 @S9S_MB_2U_LIB.S9S_MB_2U(SCH_1):PAGE72
   BC9    GND @S9S_MB_2U_LIB.S9S_MB_2U(SCH_1):GND     I2 @S9S_MB_2U_LIB.S9S_MB_2U(SCH_1):PAGE72
  BC88    GND @S9S_MB_2U_LIB.S9S_MB_2U(SCH_1):GND     I2 @S9S_MB_2U_LIB.S9S_MB_2U(SCH_1):PAGE72
  BC86    GND @S9S_MB_2U_LIB.S9S_MB_2U(SCH_1):GND     I2 @S9S_MB_2U_LIB.S9S_MB_2U(SCH_1):PAGE72
  BC84    GND @S9S_MB_2U_LIB.S9S_MB_2U(SCH_1):GND     I2 @S9S_MB_2U_LIB.S9S_MB_2U(SCH_1):PAGE72
  BC78    GND @S9S_MB_2U_LIB.S9S_MB_2U(SCH_1):GND     I2 @S9S_MB_2U_LIB.S9S_MB_2U(SCH_1):PAGE72
  BC76    GND @S9S_MB_2U_LIB.S9S_MB_2U(SCH_1):GND     I2 @S9S_MB_2U_LIB.S9S_MB_2U(SCH_1):PAGE72
  BC72    GND @S9S_MB_2U_LIB.S9S_MB_2U(SCH_1):GND     I2 @S9S_MB_2U_LIB.S9S_MB_2U(SCH_1):PAGE72
  BC66    GND @S9S_MB_2U_LIB.S9S_MB_2U(SCH_1):GND     I2 @S9S_MB_2U_LIB.S9S_MB_2U(SCH_1):PAGE72
  BC62    GND @S9S_MB_2U_LIB.S9S_MB_2U(SCH_1):GND     I2 @S9S_MB_2U_LIB.S9S_MB_2U(SCH_1):PAGE72
   BC5    GND @S9S_MB_2U_LIB.S9S_MB_2U(SCH_1):GND     I2 @S9S_MB_2U_LIB.S9S_MB_2U(SCH_1):PAGE72
  BC17    GND @S9S_MB_2U_LIB.S9S_MB_2U(SCH_1):GND     I2 @S9S_MB_2U_LIB.S9S_MB_2U(SCH_1):PAGE72
  BC13    GND @S9S_MB_2U_LIB.S9S_MB_2U(SCH_1):GND     I2 @S9S_MB_2U_LIB.S9S_MB_2U(SCH_1):PAGE72
   BC1    GND @S9S_MB_2U_LIB.S9S_MB_2U(SCH_1):GND     I2 @S9S_MB_2U_LIB.S9S_MB_2U(SCH_1):PAGE72
  BB91    GND @S9S_MB_2U_LIB.S9S_MB_2U(SCH_1):GND     I2 @S9S_MB_2U_LIB.S9S_MB_2U(SCH_1):PAGE72
  BB87    GND @S9S_MB_2U_LIB.S9S_MB_2U(SCH_1):GND     I2 @S9S_MB_2U_LIB.S9S_MB_2U(SCH_1):PAGE72
  BB83    GND @S9S_MB_2U_LIB.S9S_MB_2U(SCH_1):GND     I2 @S9S_MB_2U_LIB.S9S_MB_2U(SCH_1):PAGE72
   BB8    GND @S9S_MB_2U_LIB.S9S_MB_2U(SCH_1):GND     I2 @S9S_MB_2U_LIB.S9S_MB_2U(SCH_1):PAGE72
  BB79    GND @S9S_MB_2U_LIB.S9S_MB_2U(SCH_1):GND     I2 @S9S_MB_2U_LIB.S9S_MB_2U(SCH_1):PAGE72
  BB77    GND @S9S_MB_2U_LIB.S9S_MB_2U(SCH_1):GND     I2 @S9S_MB_2U_LIB.S9S_MB_2U(SCH_1):PAGE72
  BB71    GND @S9S_MB_2U_LIB.S9S_MB_2U(SCH_1):GND     I2 @S9S_MB_2U_LIB.S9S_MB_2U(SCH_1):PAGE72
  BB69    GND @S9S_MB_2U_LIB.S9S_MB_2U(SCH_1):GND     I2 @S9S_MB_2U_LIB.S9S_MB_2U(SCH_1):PAGE72
  BB63    GND @S9S_MB_2U_LIB.S9S_MB_2U(SCH_1):GND     I2 @S9S_MB_2U_LIB.S9S_MB_2U(SCH_1):PAGE72
   BB4    GND @S9S_MB_2U_LIB.S9S_MB_2U(SCH_1):GND     I2 @S9S_MB_2U_LIB.S9S_MB_2U(SCH_1):PAGE72
  BB26    GND @S9S_MB_2U_LIB.S9S_MB_2U(SCH_1):GND     I2 @S9S_MB_2U_LIB.S9S_MB_2U(SCH_1):PAGE72
  BB24    GND @S9S_MB_2U_LIB.S9S_MB_2U(SCH_1):GND     I2 @S9S_MB_2U_LIB.S9S_MB_2U(SCH_1):PAGE72
  BB22    GND @S9S_MB_2U_LIB.S9S_MB_2U(SCH_1):GND     I2 @S9S_MB_2U_LIB.S9S_MB_2U(SCH_1):PAGE72
  BB20    GND @S9S_MB_2U_LIB.S9S_MB_2U(SCH_1):GND     I2 @S9S_MB_2U_LIB.S9S_MB_2U(SCH_1):PAGE72
  BB16    GND @S9S_MB_2U_LIB.S9S_MB_2U(SCH_1):GND     I2 @S9S_MB_2U_LIB.S9S_MB_2U(SCH_1):PAGE72
  BB12    GND @S9S_MB_2U_LIB.S9S_MB_2U(SCH_1):GND     I2 @S9S_MB_2U_LIB.S9S_MB_2U(SCH_1):PAGE72
  BB10    GND @S9S_MB_2U_LIB.S9S_MB_2U(SCH_1):GND     I2 @S9S_MB_2U_LIB.S9S_MB_2U(SCH_1):PAGE72
  BA88    GND @S9S_MB_2U_LIB.S9S_MB_2U(SCH_1):GND     I2 @S9S_MB_2U_LIB.S9S_MB_2U(SCH_1):PAGE72
  BA84    GND @S9S_MB_2U_LIB.S9S_MB_2U(SCH_1):GND     I2 @S9S_MB_2U_LIB.S9S_MB_2U(SCH_1):PAGE72
  BA74    GND @S9S_MB_2U_LIB.S9S_MB_2U(SCH_1):GND     I2 @S9S_MB_2U_LIB.S9S_MB_2U(SCH_1):PAGE72
  BA64    GND @S9S_MB_2U_LIB.S9S_MB_2U(SCH_1):GND     I2 @S9S_MB_2U_LIB.S9S_MB_2U(SCH_1):PAGE72
  BA60    GND @S9S_MB_2U_LIB.S9S_MB_2U(SCH_1):GND     I2 @S9S_MB_2U_LIB.S9S_MB_2U(SCH_1):PAGE72
  BA17    GND @S9S_MB_2U_LIB.S9S_MB_2U(SCH_1):GND     I2 @S9S_MB_2U_LIB.S9S_MB_2U(SCH_1):PAGE72
  AY83    GND @S9S_MB_2U_LIB.S9S_MB_2U(SCH_1):GND     I2 @S9S_MB_2U_LIB.S9S_MB_2U(SCH_1):PAGE72
  AY81    GND @S9S_MB_2U_LIB.S9S_MB_2U(SCH_1):GND     I2 @S9S_MB_2U_LIB.S9S_MB_2U(SCH_1):PAGE72
   AY8    GND @S9S_MB_2U_LIB.S9S_MB_2U(SCH_1):GND     I2 @S9S_MB_2U_LIB.S9S_MB_2U(SCH_1):PAGE72
  AY79    GND @S9S_MB_2U_LIB.S9S_MB_2U(SCH_1):GND     I2 @S9S_MB_2U_LIB.S9S_MB_2U(SCH_1):PAGE72
  AY77    GND @S9S_MB_2U_LIB.S9S_MB_2U(SCH_1):GND     I2 @S9S_MB_2U_LIB.S9S_MB_2U(SCH_1):PAGE72
  AY71    GND @S9S_MB_2U_LIB.S9S_MB_2U(SCH_1):GND     I2 @S9S_MB_2U_LIB.S9S_MB_2U(SCH_1):PAGE72
   AY4    GND @S9S_MB_2U_LIB.S9S_MB_2U(SCH_1):GND     I2 @S9S_MB_2U_LIB.S9S_MB_2U(SCH_1):PAGE72
  AY16    GND @S9S_MB_2U_LIB.S9S_MB_2U(SCH_1):GND     I2 @S9S_MB_2U_LIB.S9S_MB_2U(SCH_1):PAGE72
  AY12    GND @S9S_MB_2U_LIB.S9S_MB_2U(SCH_1):GND     I2 @S9S_MB_2U_LIB.S9S_MB_2U(SCH_1):PAGE72
  AW88    GND @S9S_MB_2U_LIB.S9S_MB_2U(SCH_1):GND     I2 @S9S_MB_2U_LIB.S9S_MB_2U(SCH_1):PAGE72
  AW84    GND @S9S_MB_2U_LIB.S9S_MB_2U(SCH_1):GND     I2 @S9S_MB_2U_LIB.S9S_MB_2U(SCH_1):PAGE72
  AW82    GND @S9S_MB_2U_LIB.S9S_MB_2U(SCH_1):GND     I2 @S9S_MB_2U_LIB.S9S_MB_2U(SCH_1):PAGE72
  AW80    GND @S9S_MB_2U_LIB.S9S_MB_2U(SCH_1):GND     I2 @S9S_MB_2U_LIB.S9S_MB_2U(SCH_1):PAGE72
  AW72    GND @S9S_MB_2U_LIB.S9S_MB_2U(SCH_1):GND     I2 @S9S_MB_2U_LIB.S9S_MB_2U(SCH_1):PAGE72
  AW68    GND @S9S_MB_2U_LIB.S9S_MB_2U(SCH_1):GND     I2 @S9S_MB_2U_LIB.S9S_MB_2U(SCH_1):PAGE72
  AW66    GND @S9S_MB_2U_LIB.S9S_MB_2U(SCH_1):GND     I2 @S9S_MB_2U_LIB.S9S_MB_2U(SCH_1):PAGE72
  AW62    GND @S9S_MB_2U_LIB.S9S_MB_2U(SCH_1):GND     I2 @S9S_MB_2U_LIB.S9S_MB_2U(SCH_1):PAGE72
  AW25    GND @S9S_MB_2U_LIB.S9S_MB_2U(SCH_1):GND     I2 @S9S_MB_2U_LIB.S9S_MB_2U(SCH_1):PAGE72
  AW23    GND @S9S_MB_2U_LIB.S9S_MB_2U(SCH_1):GND     I2 @S9S_MB_2U_LIB.S9S_MB_2U(SCH_1):PAGE72
  AW21    GND @S9S_MB_2U_LIB.S9S_MB_2U(SCH_1):GND     I2 @S9S_MB_2U_LIB.S9S_MB_2U(SCH_1):PAGE72
   BR5    GND @S9S_MB_2U_LIB.S9S_MB_2U(SCH_1):GND     I2 @S9S_MB_2U_LIB.S9S_MB_2U(SCH_1):PAGE72
   AW9    GND @S9S_MB_2U_LIB.S9S_MB_2U(SCH_1):GND     I5 @S9S_MB_2U_LIB.S9S_MB_2U(SCH_1):PAGE72
   AW5    GND @S9S_MB_2U_LIB.S9S_MB_2U(SCH_1):GND     I5 @S9S_MB_2U_LIB.S9S_MB_2U(SCH_1):PAGE72
  AW13    GND @S9S_MB_2U_LIB.S9S_MB_2U(SCH_1):GND     I5 @S9S_MB_2U_LIB.S9S_MB_2U(SCH_1):PAGE72
   AW1    GND @S9S_MB_2U_LIB.S9S_MB_2U(SCH_1):GND     I5 @S9S_MB_2U_LIB.S9S_MB_2U(SCH_1):PAGE72
  AV91    GND @S9S_MB_2U_LIB.S9S_MB_2U(SCH_1):GND     I5 @S9S_MB_2U_LIB.S9S_MB_2U(SCH_1):PAGE72
  AV87    GND @S9S_MB_2U_LIB.S9S_MB_2U(SCH_1):GND     I5 @S9S_MB_2U_LIB.S9S_MB_2U(SCH_1):PAGE72
   AV8    GND @S9S_MB_2U_LIB.S9S_MB_2U(SCH_1):GND     I5 @S9S_MB_2U_LIB.S9S_MB_2U(SCH_1):PAGE72
  AV77    GND @S9S_MB_2U_LIB.S9S_MB_2U(SCH_1):GND     I5 @S9S_MB_2U_LIB.S9S_MB_2U(SCH_1):PAGE72
   AV4    GND @S9S_MB_2U_LIB.S9S_MB_2U(SCH_1):GND     I5 @S9S_MB_2U_LIB.S9S_MB_2U(SCH_1):PAGE72
  AV16    GND @S9S_MB_2U_LIB.S9S_MB_2U(SCH_1):GND     I5 @S9S_MB_2U_LIB.S9S_MB_2U(SCH_1):PAGE72
  AV12    GND @S9S_MB_2U_LIB.S9S_MB_2U(SCH_1):GND     I5 @S9S_MB_2U_LIB.S9S_MB_2U(SCH_1):PAGE72
  AU88    GND @S9S_MB_2U_LIB.S9S_MB_2U(SCH_1):GND     I5 @S9S_MB_2U_LIB.S9S_MB_2U(SCH_1):PAGE72
  AU84    GND @S9S_MB_2U_LIB.S9S_MB_2U(SCH_1):GND     I5 @S9S_MB_2U_LIB.S9S_MB_2U(SCH_1):PAGE72
  AU80    GND @S9S_MB_2U_LIB.S9S_MB_2U(SCH_1):GND     I5 @S9S_MB_2U_LIB.S9S_MB_2U(SCH_1):PAGE72
  AU76    GND @S9S_MB_2U_LIB.S9S_MB_2U(SCH_1):GND     I5 @S9S_MB_2U_LIB.S9S_MB_2U(SCH_1):PAGE72
  AU74    GND @S9S_MB_2U_LIB.S9S_MB_2U(SCH_1):GND     I5 @S9S_MB_2U_LIB.S9S_MB_2U(SCH_1):PAGE72
  AU72    GND @S9S_MB_2U_LIB.S9S_MB_2U(SCH_1):GND     I5 @S9S_MB_2U_LIB.S9S_MB_2U(SCH_1):PAGE72
  AU70    GND @S9S_MB_2U_LIB.S9S_MB_2U(SCH_1):GND     I5 @S9S_MB_2U_LIB.S9S_MB_2U(SCH_1):PAGE72
  AU48    GND @S9S_MB_2U_LIB.S9S_MB_2U(SCH_1):GND     I5 @S9S_MB_2U_LIB.S9S_MB_2U(SCH_1):PAGE72
  AU45    GND @S9S_MB_2U_LIB.S9S_MB_2U(SCH_1):GND     I5 @S9S_MB_2U_LIB.S9S_MB_2U(SCH_1):PAGE72
  AU41    GND @S9S_MB_2U_LIB.S9S_MB_2U(SCH_1):GND     I5 @S9S_MB_2U_LIB.S9S_MB_2U(SCH_1):PAGE72
  AU39    GND @S9S_MB_2U_LIB.S9S_MB_2U(SCH_1):GND     I5 @S9S_MB_2U_LIB.S9S_MB_2U(SCH_1):PAGE72
  AU37    GND @S9S_MB_2U_LIB.S9S_MB_2U(SCH_1):GND     I5 @S9S_MB_2U_LIB.S9S_MB_2U(SCH_1):PAGE72
  AU31    GND @S9S_MB_2U_LIB.S9S_MB_2U(SCH_1):GND     I5 @S9S_MB_2U_LIB.S9S_MB_2U(SCH_1):PAGE72
  AU27    GND @S9S_MB_2U_LIB.S9S_MB_2U(SCH_1):GND     I5 @S9S_MB_2U_LIB.S9S_MB_2U(SCH_1):PAGE72
   AT8    GND @S9S_MB_2U_LIB.S9S_MB_2U(SCH_1):GND     I5 @S9S_MB_2U_LIB.S9S_MB_2U(SCH_1):PAGE72
  AT79    GND @S9S_MB_2U_LIB.S9S_MB_2U(SCH_1):GND     I5 @S9S_MB_2U_LIB.S9S_MB_2U(SCH_1):PAGE72
  AT77    GND @S9S_MB_2U_LIB.S9S_MB_2U(SCH_1):GND     I5 @S9S_MB_2U_LIB.S9S_MB_2U(SCH_1):PAGE72
  AT75    GND @S9S_MB_2U_LIB.S9S_MB_2U(SCH_1):GND     I5 @S9S_MB_2U_LIB.S9S_MB_2U(SCH_1):PAGE72
  AT71    GND @S9S_MB_2U_LIB.S9S_MB_2U(SCH_1):GND     I5 @S9S_MB_2U_LIB.S9S_MB_2U(SCH_1):PAGE72
  AT69    GND @S9S_MB_2U_LIB.S9S_MB_2U(SCH_1):GND     I5 @S9S_MB_2U_LIB.S9S_MB_2U(SCH_1):PAGE72
  AT65    GND @S9S_MB_2U_LIB.S9S_MB_2U(SCH_1):GND     I5 @S9S_MB_2U_LIB.S9S_MB_2U(SCH_1):PAGE72
  AT63    GND @S9S_MB_2U_LIB.S9S_MB_2U(SCH_1):GND     I5 @S9S_MB_2U_LIB.S9S_MB_2U(SCH_1):PAGE72
  AT59    GND @S9S_MB_2U_LIB.S9S_MB_2U(SCH_1):GND     I5 @S9S_MB_2U_LIB.S9S_MB_2U(SCH_1):PAGE72
  AT57    GND @S9S_MB_2U_LIB.S9S_MB_2U(SCH_1):GND     I5 @S9S_MB_2U_LIB.S9S_MB_2U(SCH_1):PAGE72
  AT53    GND @S9S_MB_2U_LIB.S9S_MB_2U(SCH_1):GND     I5 @S9S_MB_2U_LIB.S9S_MB_2U(SCH_1):PAGE72
  AT51    GND @S9S_MB_2U_LIB.S9S_MB_2U(SCH_1):GND     I5 @S9S_MB_2U_LIB.S9S_MB_2U(SCH_1):PAGE72
  AT44    GND @S9S_MB_2U_LIB.S9S_MB_2U(SCH_1):GND     I5 @S9S_MB_2U_LIB.S9S_MB_2U(SCH_1):PAGE72
  AT40    GND @S9S_MB_2U_LIB.S9S_MB_2U(SCH_1):GND     I5 @S9S_MB_2U_LIB.S9S_MB_2U(SCH_1):PAGE72
   AT4    GND @S9S_MB_2U_LIB.S9S_MB_2U(SCH_1):GND     I5 @S9S_MB_2U_LIB.S9S_MB_2U(SCH_1):PAGE72
  AT38    GND @S9S_MB_2U_LIB.S9S_MB_2U(SCH_1):GND     I5 @S9S_MB_2U_LIB.S9S_MB_2U(SCH_1):PAGE72
  AT34    GND @S9S_MB_2U_LIB.S9S_MB_2U(SCH_1):GND     I5 @S9S_MB_2U_LIB.S9S_MB_2U(SCH_1):PAGE72
  AT32    GND @S9S_MB_2U_LIB.S9S_MB_2U(SCH_1):GND     I5 @S9S_MB_2U_LIB.S9S_MB_2U(SCH_1):PAGE72
  AT28    GND @S9S_MB_2U_LIB.S9S_MB_2U(SCH_1):GND     I5 @S9S_MB_2U_LIB.S9S_MB_2U(SCH_1):PAGE72
  AT26    GND @S9S_MB_2U_LIB.S9S_MB_2U(SCH_1):GND     I5 @S9S_MB_2U_LIB.S9S_MB_2U(SCH_1):PAGE72
  AT22    GND @S9S_MB_2U_LIB.S9S_MB_2U(SCH_1):GND     I5 @S9S_MB_2U_LIB.S9S_MB_2U(SCH_1):PAGE72
  AT20    GND @S9S_MB_2U_LIB.S9S_MB_2U(SCH_1):GND     I5 @S9S_MB_2U_LIB.S9S_MB_2U(SCH_1):PAGE72
  AT16    GND @S9S_MB_2U_LIB.S9S_MB_2U(SCH_1):GND     I5 @S9S_MB_2U_LIB.S9S_MB_2U(SCH_1):PAGE72
  AT12    GND @S9S_MB_2U_LIB.S9S_MB_2U(SCH_1):GND     I5 @S9S_MB_2U_LIB.S9S_MB_2U(SCH_1):PAGE72
   AR9    GND @S9S_MB_2U_LIB.S9S_MB_2U(SCH_1):GND     I5 @S9S_MB_2U_LIB.S9S_MB_2U(SCH_1):PAGE72
  AR88    GND @S9S_MB_2U_LIB.S9S_MB_2U(SCH_1):GND     I5 @S9S_MB_2U_LIB.S9S_MB_2U(SCH_1):PAGE72
  AR84    GND @S9S_MB_2U_LIB.S9S_MB_2U(SCH_1):GND     I5 @S9S_MB_2U_LIB.S9S_MB_2U(SCH_1):PAGE72
  AR82    GND @S9S_MB_2U_LIB.S9S_MB_2U(SCH_1):GND     I5 @S9S_MB_2U_LIB.S9S_MB_2U(SCH_1):PAGE72
  AR78    GND @S9S_MB_2U_LIB.S9S_MB_2U(SCH_1):GND     I5 @S9S_MB_2U_LIB.S9S_MB_2U(SCH_1):PAGE72
  AR74    GND @S9S_MB_2U_LIB.S9S_MB_2U(SCH_1):GND     I5 @S9S_MB_2U_LIB.S9S_MB_2U(SCH_1):PAGE72
  AR72    GND @S9S_MB_2U_LIB.S9S_MB_2U(SCH_1):GND     I5 @S9S_MB_2U_LIB.S9S_MB_2U(SCH_1):PAGE72
  AR68    GND @S9S_MB_2U_LIB.S9S_MB_2U(SCH_1):GND     I5 @S9S_MB_2U_LIB.S9S_MB_2U(SCH_1):PAGE72
  AR66    GND @S9S_MB_2U_LIB.S9S_MB_2U(SCH_1):GND     I5 @S9S_MB_2U_LIB.S9S_MB_2U(SCH_1):PAGE72
  AR62    GND @S9S_MB_2U_LIB.S9S_MB_2U(SCH_1):GND     I5 @S9S_MB_2U_LIB.S9S_MB_2U(SCH_1):PAGE72
  AR60    GND @S9S_MB_2U_LIB.S9S_MB_2U(SCH_1):GND     I5 @S9S_MB_2U_LIB.S9S_MB_2U(SCH_1):PAGE72
  AR56    GND @S9S_MB_2U_LIB.S9S_MB_2U(SCH_1):GND     I5 @S9S_MB_2U_LIB.S9S_MB_2U(SCH_1):PAGE72
  AR54    GND @S9S_MB_2U_LIB.S9S_MB_2U(SCH_1):GND     I5 @S9S_MB_2U_LIB.S9S_MB_2U(SCH_1):PAGE72
  AR50    GND @S9S_MB_2U_LIB.S9S_MB_2U(SCH_1):GND     I5 @S9S_MB_2U_LIB.S9S_MB_2U(SCH_1):PAGE72
   AR5    GND @S9S_MB_2U_LIB.S9S_MB_2U(SCH_1):GND     I5 @S9S_MB_2U_LIB.S9S_MB_2U(SCH_1):PAGE72
  AR48    GND @S9S_MB_2U_LIB.S9S_MB_2U(SCH_1):GND     I5 @S9S_MB_2U_LIB.S9S_MB_2U(SCH_1):PAGE72
  AR43    GND @S9S_MB_2U_LIB.S9S_MB_2U(SCH_1):GND     I5 @S9S_MB_2U_LIB.S9S_MB_2U(SCH_1):PAGE72
  AR41    GND @S9S_MB_2U_LIB.S9S_MB_2U(SCH_1):GND     I5 @S9S_MB_2U_LIB.S9S_MB_2U(SCH_1):PAGE72
  AR37    GND @S9S_MB_2U_LIB.S9S_MB_2U(SCH_1):GND     I5 @S9S_MB_2U_LIB.S9S_MB_2U(SCH_1):PAGE72
  AR35    GND @S9S_MB_2U_LIB.S9S_MB_2U(SCH_1):GND     I5 @S9S_MB_2U_LIB.S9S_MB_2U(SCH_1):PAGE72
  AR31    GND @S9S_MB_2U_LIB.S9S_MB_2U(SCH_1):GND     I5 @S9S_MB_2U_LIB.S9S_MB_2U(SCH_1):PAGE72
  AR29    GND @S9S_MB_2U_LIB.S9S_MB_2U(SCH_1):GND     I5 @S9S_MB_2U_LIB.S9S_MB_2U(SCH_1):PAGE72
  AR25    GND @S9S_MB_2U_LIB.S9S_MB_2U(SCH_1):GND     I5 @S9S_MB_2U_LIB.S9S_MB_2U(SCH_1):PAGE72
  AR23    GND @S9S_MB_2U_LIB.S9S_MB_2U(SCH_1):GND     I5 @S9S_MB_2U_LIB.S9S_MB_2U(SCH_1):PAGE72
  AR19    GND @S9S_MB_2U_LIB.S9S_MB_2U(SCH_1):GND     I5 @S9S_MB_2U_LIB.S9S_MB_2U(SCH_1):PAGE72
  AR13    GND @S9S_MB_2U_LIB.S9S_MB_2U(SCH_1):GND     I5 @S9S_MB_2U_LIB.S9S_MB_2U(SCH_1):PAGE72
   AR1    GND @S9S_MB_2U_LIB.S9S_MB_2U(SCH_1):GND     I5 @S9S_MB_2U_LIB.S9S_MB_2U(SCH_1):PAGE72
  AP91    GND @S9S_MB_2U_LIB.S9S_MB_2U(SCH_1):GND     I5 @S9S_MB_2U_LIB.S9S_MB_2U(SCH_1):PAGE72
  AP87    GND @S9S_MB_2U_LIB.S9S_MB_2U(SCH_1):GND     I5 @S9S_MB_2U_LIB.S9S_MB_2U(SCH_1):PAGE72
  AP83    GND @S9S_MB_2U_LIB.S9S_MB_2U(SCH_1):GND     I5 @S9S_MB_2U_LIB.S9S_MB_2U(SCH_1):PAGE72
   AP8    GND @S9S_MB_2U_LIB.S9S_MB_2U(SCH_1):GND     I5 @S9S_MB_2U_LIB.S9S_MB_2U(SCH_1):PAGE72
  AP79    GND @S9S_MB_2U_LIB.S9S_MB_2U(SCH_1):GND     I5 @S9S_MB_2U_LIB.S9S_MB_2U(SCH_1):PAGE72
  AP73    GND @S9S_MB_2U_LIB.S9S_MB_2U(SCH_1):GND     I5 @S9S_MB_2U_LIB.S9S_MB_2U(SCH_1):PAGE72
  AP67    GND @S9S_MB_2U_LIB.S9S_MB_2U(SCH_1):GND     I5 @S9S_MB_2U_LIB.S9S_MB_2U(SCH_1):PAGE72
  AP61    GND @S9S_MB_2U_LIB.S9S_MB_2U(SCH_1):GND     I5 @S9S_MB_2U_LIB.S9S_MB_2U(SCH_1):PAGE72
  AP55    GND @S9S_MB_2U_LIB.S9S_MB_2U(SCH_1):GND     I5 @S9S_MB_2U_LIB.S9S_MB_2U(SCH_1):PAGE72
  AP49    GND @S9S_MB_2U_LIB.S9S_MB_2U(SCH_1):GND     I5 @S9S_MB_2U_LIB.S9S_MB_2U(SCH_1):PAGE72
  AP42    GND @S9S_MB_2U_LIB.S9S_MB_2U(SCH_1):GND     I5 @S9S_MB_2U_LIB.S9S_MB_2U(SCH_1):PAGE72
   AP4    GND @S9S_MB_2U_LIB.S9S_MB_2U(SCH_1):GND     I5 @S9S_MB_2U_LIB.S9S_MB_2U(SCH_1):PAGE72
  AP36    GND @S9S_MB_2U_LIB.S9S_MB_2U(SCH_1):GND     I5 @S9S_MB_2U_LIB.S9S_MB_2U(SCH_1):PAGE72
  AP30    GND @S9S_MB_2U_LIB.S9S_MB_2U(SCH_1):GND     I5 @S9S_MB_2U_LIB.S9S_MB_2U(SCH_1):PAGE72
  AP24    GND @S9S_MB_2U_LIB.S9S_MB_2U(SCH_1):GND     I5 @S9S_MB_2U_LIB.S9S_MB_2U(SCH_1):PAGE72
  AP18    GND @S9S_MB_2U_LIB.S9S_MB_2U(SCH_1):GND     I5 @S9S_MB_2U_LIB.S9S_MB_2U(SCH_1):PAGE72
  AP16    GND @S9S_MB_2U_LIB.S9S_MB_2U(SCH_1):GND     I5 @S9S_MB_2U_LIB.S9S_MB_2U(SCH_1):PAGE72
  AP12    GND @S9S_MB_2U_LIB.S9S_MB_2U(SCH_1):GND     I5 @S9S_MB_2U_LIB.S9S_MB_2U(SCH_1):PAGE72
  AN88    GND @S9S_MB_2U_LIB.S9S_MB_2U(SCH_1):GND     I5 @S9S_MB_2U_LIB.S9S_MB_2U(SCH_1):PAGE72
  AN84    GND @S9S_MB_2U_LIB.S9S_MB_2U(SCH_1):GND     I5 @S9S_MB_2U_LIB.S9S_MB_2U(SCH_1):PAGE72
  AN52    GND @S9S_MB_2U_LIB.S9S_MB_2U(SCH_1):GND     I5 @S9S_MB_2U_LIB.S9S_MB_2U(SCH_1):PAGE72
   AM8    GND @S9S_MB_2U_LIB.S9S_MB_2U(SCH_1):GND     I5 @S9S_MB_2U_LIB.S9S_MB_2U(SCH_1):PAGE72
  AM77    GND @S9S_MB_2U_LIB.S9S_MB_2U(SCH_1):GND     I5 @S9S_MB_2U_LIB.S9S_MB_2U(SCH_1):PAGE72
  AM75    GND @S9S_MB_2U_LIB.S9S_MB_2U(SCH_1):GND     I5 @S9S_MB_2U_LIB.S9S_MB_2U(SCH_1):PAGE72
  AM73    GND @S9S_MB_2U_LIB.S9S_MB_2U(SCH_1):GND     I5 @S9S_MB_2U_LIB.S9S_MB_2U(SCH_1):PAGE72
  AM71    GND @S9S_MB_2U_LIB.S9S_MB_2U(SCH_1):GND     I5 @S9S_MB_2U_LIB.S9S_MB_2U(SCH_1):PAGE72
  AM69    GND @S9S_MB_2U_LIB.S9S_MB_2U(SCH_1):GND     I5 @S9S_MB_2U_LIB.S9S_MB_2U(SCH_1):PAGE72
  AM67    GND @S9S_MB_2U_LIB.S9S_MB_2U(SCH_1):GND     I5 @S9S_MB_2U_LIB.S9S_MB_2U(SCH_1):PAGE72
  AM65    GND @S9S_MB_2U_LIB.S9S_MB_2U(SCH_1):GND     I5 @S9S_MB_2U_LIB.S9S_MB_2U(SCH_1):PAGE72
  AM63    GND @S9S_MB_2U_LIB.S9S_MB_2U(SCH_1):GND     I5 @S9S_MB_2U_LIB.S9S_MB_2U(SCH_1):PAGE72
  AM61    GND @S9S_MB_2U_LIB.S9S_MB_2U(SCH_1):GND     I5 @S9S_MB_2U_LIB.S9S_MB_2U(SCH_1):PAGE72
  AM59    GND @S9S_MB_2U_LIB.S9S_MB_2U(SCH_1):GND     I5 @S9S_MB_2U_LIB.S9S_MB_2U(SCH_1):PAGE72
  AM57    GND @S9S_MB_2U_LIB.S9S_MB_2U(SCH_1):GND     I5 @S9S_MB_2U_LIB.S9S_MB_2U(SCH_1):PAGE72
  AM55    GND @S9S_MB_2U_LIB.S9S_MB_2U(SCH_1):GND     I5 @S9S_MB_2U_LIB.S9S_MB_2U(SCH_1):PAGE72
  AM53    GND @S9S_MB_2U_LIB.S9S_MB_2U(SCH_1):GND     I5 @S9S_MB_2U_LIB.S9S_MB_2U(SCH_1):PAGE72
  AM51    GND @S9S_MB_2U_LIB.S9S_MB_2U(SCH_1):GND     I5 @S9S_MB_2U_LIB.S9S_MB_2U(SCH_1):PAGE72
  AM49    GND @S9S_MB_2U_LIB.S9S_MB_2U(SCH_1):GND     I5 @S9S_MB_2U_LIB.S9S_MB_2U(SCH_1):PAGE72
  AM47    GND @S9S_MB_2U_LIB.S9S_MB_2U(SCH_1):GND     I5 @S9S_MB_2U_LIB.S9S_MB_2U(SCH_1):PAGE72
  AM44    GND @S9S_MB_2U_LIB.S9S_MB_2U(SCH_1):GND     I5 @S9S_MB_2U_LIB.S9S_MB_2U(SCH_1):PAGE72
  AM42    GND @S9S_MB_2U_LIB.S9S_MB_2U(SCH_1):GND     I5 @S9S_MB_2U_LIB.S9S_MB_2U(SCH_1):PAGE72
  AM40    GND @S9S_MB_2U_LIB.S9S_MB_2U(SCH_1):GND     I5 @S9S_MB_2U_LIB.S9S_MB_2U(SCH_1):PAGE72
   AM4    GND @S9S_MB_2U_LIB.S9S_MB_2U(SCH_1):GND     I5 @S9S_MB_2U_LIB.S9S_MB_2U(SCH_1):PAGE72
  AM38    GND @S9S_MB_2U_LIB.S9S_MB_2U(SCH_1):GND     I5 @S9S_MB_2U_LIB.S9S_MB_2U(SCH_1):PAGE72
  AM36    GND @S9S_MB_2U_LIB.S9S_MB_2U(SCH_1):GND     I5 @S9S_MB_2U_LIB.S9S_MB_2U(SCH_1):PAGE72
  AM34    GND @S9S_MB_2U_LIB.S9S_MB_2U(SCH_1):GND     I5 @S9S_MB_2U_LIB.S9S_MB_2U(SCH_1):PAGE72
  AM32    GND @S9S_MB_2U_LIB.S9S_MB_2U(SCH_1):GND     I5 @S9S_MB_2U_LIB.S9S_MB_2U(SCH_1):PAGE72
  AM30    GND @S9S_MB_2U_LIB.S9S_MB_2U(SCH_1):GND     I5 @S9S_MB_2U_LIB.S9S_MB_2U(SCH_1):PAGE72
  AM28    GND @S9S_MB_2U_LIB.S9S_MB_2U(SCH_1):GND     I5 @S9S_MB_2U_LIB.S9S_MB_2U(SCH_1):PAGE72
  AM26    GND @S9S_MB_2U_LIB.S9S_MB_2U(SCH_1):GND     I5 @S9S_MB_2U_LIB.S9S_MB_2U(SCH_1):PAGE72
  AM24    GND @S9S_MB_2U_LIB.S9S_MB_2U(SCH_1):GND     I5 @S9S_MB_2U_LIB.S9S_MB_2U(SCH_1):PAGE72
  AM22    GND @S9S_MB_2U_LIB.S9S_MB_2U(SCH_1):GND     I5 @S9S_MB_2U_LIB.S9S_MB_2U(SCH_1):PAGE72
  AM20    GND @S9S_MB_2U_LIB.S9S_MB_2U(SCH_1):GND     I5 @S9S_MB_2U_LIB.S9S_MB_2U(SCH_1):PAGE72
  AM18    GND @S9S_MB_2U_LIB.S9S_MB_2U(SCH_1):GND     I5 @S9S_MB_2U_LIB.S9S_MB_2U(SCH_1):PAGE72
  AM16    GND @S9S_MB_2U_LIB.S9S_MB_2U(SCH_1):GND     I5 @S9S_MB_2U_LIB.S9S_MB_2U(SCH_1):PAGE72
  AM12    GND @S9S_MB_2U_LIB.S9S_MB_2U(SCH_1):GND     I5 @S9S_MB_2U_LIB.S9S_MB_2U(SCH_1):PAGE72
   AL9    GND @S9S_MB_2U_LIB.S9S_MB_2U(SCH_1):GND     I5 @S9S_MB_2U_LIB.S9S_MB_2U(SCH_1):PAGE72
  AL88    GND @S9S_MB_2U_LIB.S9S_MB_2U(SCH_1):GND     I5 @S9S_MB_2U_LIB.S9S_MB_2U(SCH_1):PAGE72
  AL84    GND @S9S_MB_2U_LIB.S9S_MB_2U(SCH_1):GND     I5 @S9S_MB_2U_LIB.S9S_MB_2U(SCH_1):PAGE72
  AL82    GND @S9S_MB_2U_LIB.S9S_MB_2U(SCH_1):GND     I5 @S9S_MB_2U_LIB.S9S_MB_2U(SCH_1):PAGE72
  AL80    GND @S9S_MB_2U_LIB.S9S_MB_2U(SCH_1):GND     I5 @S9S_MB_2U_LIB.S9S_MB_2U(SCH_1):PAGE72
  AL52    GND @S9S_MB_2U_LIB.S9S_MB_2U(SCH_1):GND     I5 @S9S_MB_2U_LIB.S9S_MB_2U(SCH_1):PAGE72
   AL5    GND @S9S_MB_2U_LIB.S9S_MB_2U(SCH_1):GND     I5 @S9S_MB_2U_LIB.S9S_MB_2U(SCH_1):PAGE72
  AL17    GND @S9S_MB_2U_LIB.S9S_MB_2U(SCH_1):GND     I5 @S9S_MB_2U_LIB.S9S_MB_2U(SCH_1):PAGE72
  AL13    GND @S9S_MB_2U_LIB.S9S_MB_2U(SCH_1):GND     I5 @S9S_MB_2U_LIB.S9S_MB_2U(SCH_1):PAGE72
   AL1    GND @S9S_MB_2U_LIB.S9S_MB_2U(SCH_1):GND     I5 @S9S_MB_2U_LIB.S9S_MB_2U(SCH_1):PAGE72
  AK91    GND @S9S_MB_2U_LIB.S9S_MB_2U(SCH_1):GND     I5 @S9S_MB_2U_LIB.S9S_MB_2U(SCH_1):PAGE72
  AK87    GND @S9S_MB_2U_LIB.S9S_MB_2U(SCH_1):GND     I5 @S9S_MB_2U_LIB.S9S_MB_2U(SCH_1):PAGE72
  AK83    GND @S9S_MB_2U_LIB.S9S_MB_2U(SCH_1):GND     I5 @S9S_MB_2U_LIB.S9S_MB_2U(SCH_1):PAGE72
  AK81    GND @S9S_MB_2U_LIB.S9S_MB_2U(SCH_1):GND     I5 @S9S_MB_2U_LIB.S9S_MB_2U(SCH_1):PAGE72
   AK8    GND @S9S_MB_2U_LIB.S9S_MB_2U(SCH_1):GND     I5 @S9S_MB_2U_LIB.S9S_MB_2U(SCH_1):PAGE72
  AK79    GND @S9S_MB_2U_LIB.S9S_MB_2U(SCH_1):GND     I5 @S9S_MB_2U_LIB.S9S_MB_2U(SCH_1):PAGE72
  AK73    GND @S9S_MB_2U_LIB.S9S_MB_2U(SCH_1):GND     I5 @S9S_MB_2U_LIB.S9S_MB_2U(SCH_1):PAGE72
  AK67    GND @S9S_MB_2U_LIB.S9S_MB_2U(SCH_1):GND     I5 @S9S_MB_2U_LIB.S9S_MB_2U(SCH_1):PAGE72
  AK61    GND @S9S_MB_2U_LIB.S9S_MB_2U(SCH_1):GND     I5 @S9S_MB_2U_LIB.S9S_MB_2U(SCH_1):PAGE72
  AK55    GND @S9S_MB_2U_LIB.S9S_MB_2U(SCH_1):GND     I5 @S9S_MB_2U_LIB.S9S_MB_2U(SCH_1):PAGE72
  AK49    GND @S9S_MB_2U_LIB.S9S_MB_2U(SCH_1):GND     I5 @S9S_MB_2U_LIB.S9S_MB_2U(SCH_1):PAGE72
  AK42    GND @S9S_MB_2U_LIB.S9S_MB_2U(SCH_1):GND     I5 @S9S_MB_2U_LIB.S9S_MB_2U(SCH_1):PAGE72
   AK4    GND @S9S_MB_2U_LIB.S9S_MB_2U(SCH_1):GND     I5 @S9S_MB_2U_LIB.S9S_MB_2U(SCH_1):PAGE72
  AK36    GND @S9S_MB_2U_LIB.S9S_MB_2U(SCH_1):GND     I5 @S9S_MB_2U_LIB.S9S_MB_2U(SCH_1):PAGE72
  AK30    GND @S9S_MB_2U_LIB.S9S_MB_2U(SCH_1):GND     I5 @S9S_MB_2U_LIB.S9S_MB_2U(SCH_1):PAGE72
  AK24    GND @S9S_MB_2U_LIB.S9S_MB_2U(SCH_1):GND     I5 @S9S_MB_2U_LIB.S9S_MB_2U(SCH_1):PAGE72
  AK18    GND @S9S_MB_2U_LIB.S9S_MB_2U(SCH_1):GND     I5 @S9S_MB_2U_LIB.S9S_MB_2U(SCH_1):PAGE72
  AK16    GND @S9S_MB_2U_LIB.S9S_MB_2U(SCH_1):GND     I5 @S9S_MB_2U_LIB.S9S_MB_2U(SCH_1):PAGE72
  AK12    GND @S9S_MB_2U_LIB.S9S_MB_2U(SCH_1):GND     I5 @S9S_MB_2U_LIB.S9S_MB_2U(SCH_1):PAGE72
  AJ88    GND @S9S_MB_2U_LIB.S9S_MB_2U(SCH_1):GND     I8 @S9S_MB_2U_LIB.S9S_MB_2U(SCH_1):PAGE72
  AJ84    GND @S9S_MB_2U_LIB.S9S_MB_2U(SCH_1):GND     I8 @S9S_MB_2U_LIB.S9S_MB_2U(SCH_1):PAGE72
  AJ78    GND @S9S_MB_2U_LIB.S9S_MB_2U(SCH_1):GND     I8 @S9S_MB_2U_LIB.S9S_MB_2U(SCH_1):PAGE72
  AJ74    GND @S9S_MB_2U_LIB.S9S_MB_2U(SCH_1):GND     I8 @S9S_MB_2U_LIB.S9S_MB_2U(SCH_1):PAGE72
  AJ72    GND @S9S_MB_2U_LIB.S9S_MB_2U(SCH_1):GND     I8 @S9S_MB_2U_LIB.S9S_MB_2U(SCH_1):PAGE72
  AJ68    GND @S9S_MB_2U_LIB.S9S_MB_2U(SCH_1):GND     I8 @S9S_MB_2U_LIB.S9S_MB_2U(SCH_1):PAGE72
  AJ66    GND @S9S_MB_2U_LIB.S9S_MB_2U(SCH_1):GND     I8 @S9S_MB_2U_LIB.S9S_MB_2U(SCH_1):PAGE72
  AJ62    GND @S9S_MB_2U_LIB.S9S_MB_2U(SCH_1):GND     I8 @S9S_MB_2U_LIB.S9S_MB_2U(SCH_1):PAGE72
  AJ60    GND @S9S_MB_2U_LIB.S9S_MB_2U(SCH_1):GND     I8 @S9S_MB_2U_LIB.S9S_MB_2U(SCH_1):PAGE72
  AJ56    GND @S9S_MB_2U_LIB.S9S_MB_2U(SCH_1):GND     I8 @S9S_MB_2U_LIB.S9S_MB_2U(SCH_1):PAGE72
  AJ54    GND @S9S_MB_2U_LIB.S9S_MB_2U(SCH_1):GND     I8 @S9S_MB_2U_LIB.S9S_MB_2U(SCH_1):PAGE72
  AJ50    GND @S9S_MB_2U_LIB.S9S_MB_2U(SCH_1):GND     I8 @S9S_MB_2U_LIB.S9S_MB_2U(SCH_1):PAGE72
  AJ48    GND @S9S_MB_2U_LIB.S9S_MB_2U(SCH_1):GND     I8 @S9S_MB_2U_LIB.S9S_MB_2U(SCH_1):PAGE72
  AJ43    GND @S9S_MB_2U_LIB.S9S_MB_2U(SCH_1):GND     I8 @S9S_MB_2U_LIB.S9S_MB_2U(SCH_1):PAGE72
  AJ41    GND @S9S_MB_2U_LIB.S9S_MB_2U(SCH_1):GND     I8 @S9S_MB_2U_LIB.S9S_MB_2U(SCH_1):PAGE72
  AJ37    GND @S9S_MB_2U_LIB.S9S_MB_2U(SCH_1):GND     I8 @S9S_MB_2U_LIB.S9S_MB_2U(SCH_1):PAGE72
  AJ35    GND @S9S_MB_2U_LIB.S9S_MB_2U(SCH_1):GND     I8 @S9S_MB_2U_LIB.S9S_MB_2U(SCH_1):PAGE72
  AJ31    GND @S9S_MB_2U_LIB.S9S_MB_2U(SCH_1):GND     I8 @S9S_MB_2U_LIB.S9S_MB_2U(SCH_1):PAGE72
  AJ29    GND @S9S_MB_2U_LIB.S9S_MB_2U(SCH_1):GND     I8 @S9S_MB_2U_LIB.S9S_MB_2U(SCH_1):PAGE72
  AJ25    GND @S9S_MB_2U_LIB.S9S_MB_2U(SCH_1):GND     I8 @S9S_MB_2U_LIB.S9S_MB_2U(SCH_1):PAGE72
  AJ23    GND @S9S_MB_2U_LIB.S9S_MB_2U(SCH_1):GND     I8 @S9S_MB_2U_LIB.S9S_MB_2U(SCH_1):PAGE72
  AJ19    GND @S9S_MB_2U_LIB.S9S_MB_2U(SCH_1):GND     I8 @S9S_MB_2U_LIB.S9S_MB_2U(SCH_1):PAGE72
  AH83    GND @S9S_MB_2U_LIB.S9S_MB_2U(SCH_1):GND     I8 @S9S_MB_2U_LIB.S9S_MB_2U(SCH_1):PAGE72
   AH8    GND @S9S_MB_2U_LIB.S9S_MB_2U(SCH_1):GND     I8 @S9S_MB_2U_LIB.S9S_MB_2U(SCH_1):PAGE72
  AH79    GND @S9S_MB_2U_LIB.S9S_MB_2U(SCH_1):GND     I8 @S9S_MB_2U_LIB.S9S_MB_2U(SCH_1):PAGE72
  AH77    GND @S9S_MB_2U_LIB.S9S_MB_2U(SCH_1):GND     I8 @S9S_MB_2U_LIB.S9S_MB_2U(SCH_1):PAGE72
  AH75    GND @S9S_MB_2U_LIB.S9S_MB_2U(SCH_1):GND     I8 @S9S_MB_2U_LIB.S9S_MB_2U(SCH_1):PAGE72
  AH71    GND @S9S_MB_2U_LIB.S9S_MB_2U(SCH_1):GND     I8 @S9S_MB_2U_LIB.S9S_MB_2U(SCH_1):PAGE72
  AH69    GND @S9S_MB_2U_LIB.S9S_MB_2U(SCH_1):GND     I8 @S9S_MB_2U_LIB.S9S_MB_2U(SCH_1):PAGE72
  AH65    GND @S9S_MB_2U_LIB.S9S_MB_2U(SCH_1):GND     I8 @S9S_MB_2U_LIB.S9S_MB_2U(SCH_1):PAGE72
  AH63    GND @S9S_MB_2U_LIB.S9S_MB_2U(SCH_1):GND     I8 @S9S_MB_2U_LIB.S9S_MB_2U(SCH_1):PAGE72
  AH59    GND @S9S_MB_2U_LIB.S9S_MB_2U(SCH_1):GND     I8 @S9S_MB_2U_LIB.S9S_MB_2U(SCH_1):PAGE72
  AH57    GND @S9S_MB_2U_LIB.S9S_MB_2U(SCH_1):GND     I8 @S9S_MB_2U_LIB.S9S_MB_2U(SCH_1):PAGE72
  AH53    GND @S9S_MB_2U_LIB.S9S_MB_2U(SCH_1):GND     I8 @S9S_MB_2U_LIB.S9S_MB_2U(SCH_1):PAGE72
  AH51    GND @S9S_MB_2U_LIB.S9S_MB_2U(SCH_1):GND     I8 @S9S_MB_2U_LIB.S9S_MB_2U(SCH_1):PAGE72
  AH47    GND @S9S_MB_2U_LIB.S9S_MB_2U(SCH_1):GND     I8 @S9S_MB_2U_LIB.S9S_MB_2U(SCH_1):PAGE72
  AH44    GND @S9S_MB_2U_LIB.S9S_MB_2U(SCH_1):GND     I8 @S9S_MB_2U_LIB.S9S_MB_2U(SCH_1):PAGE72
  AH40    GND @S9S_MB_2U_LIB.S9S_MB_2U(SCH_1):GND     I8 @S9S_MB_2U_LIB.S9S_MB_2U(SCH_1):PAGE72
   AH4    GND @S9S_MB_2U_LIB.S9S_MB_2U(SCH_1):GND     I8 @S9S_MB_2U_LIB.S9S_MB_2U(SCH_1):PAGE72
  AH38    GND @S9S_MB_2U_LIB.S9S_MB_2U(SCH_1):GND     I8 @S9S_MB_2U_LIB.S9S_MB_2U(SCH_1):PAGE72
  AH34    GND @S9S_MB_2U_LIB.S9S_MB_2U(SCH_1):GND     I8 @S9S_MB_2U_LIB.S9S_MB_2U(SCH_1):PAGE72
  AH32    GND @S9S_MB_2U_LIB.S9S_MB_2U(SCH_1):GND     I8 @S9S_MB_2U_LIB.S9S_MB_2U(SCH_1):PAGE72
  AH28    GND @S9S_MB_2U_LIB.S9S_MB_2U(SCH_1):GND     I8 @S9S_MB_2U_LIB.S9S_MB_2U(SCH_1):PAGE72
  AH26    GND @S9S_MB_2U_LIB.S9S_MB_2U(SCH_1):GND     I8 @S9S_MB_2U_LIB.S9S_MB_2U(SCH_1):PAGE72
  AH22    GND @S9S_MB_2U_LIB.S9S_MB_2U(SCH_1):GND     I8 @S9S_MB_2U_LIB.S9S_MB_2U(SCH_1):PAGE72
  AH20    GND @S9S_MB_2U_LIB.S9S_MB_2U(SCH_1):GND     I8 @S9S_MB_2U_LIB.S9S_MB_2U(SCH_1):PAGE72
  AH16    GND @S9S_MB_2U_LIB.S9S_MB_2U(SCH_1):GND     I8 @S9S_MB_2U_LIB.S9S_MB_2U(SCH_1):PAGE72
  AH12    GND @S9S_MB_2U_LIB.S9S_MB_2U(SCH_1):GND     I8 @S9S_MB_2U_LIB.S9S_MB_2U(SCH_1):PAGE72
   AG9    GND @S9S_MB_2U_LIB.S9S_MB_2U(SCH_1):GND     I8 @S9S_MB_2U_LIB.S9S_MB_2U(SCH_1):PAGE72
  AG88    GND @S9S_MB_2U_LIB.S9S_MB_2U(SCH_1):GND     I8 @S9S_MB_2U_LIB.S9S_MB_2U(SCH_1):PAGE72
  AG84    GND @S9S_MB_2U_LIB.S9S_MB_2U(SCH_1):GND     I8 @S9S_MB_2U_LIB.S9S_MB_2U(SCH_1):PAGE72
  AG76    GND @S9S_MB_2U_LIB.S9S_MB_2U(SCH_1):GND     I8 @S9S_MB_2U_LIB.S9S_MB_2U(SCH_1):PAGE72
  AG70    GND @S9S_MB_2U_LIB.S9S_MB_2U(SCH_1):GND     I8 @S9S_MB_2U_LIB.S9S_MB_2U(SCH_1):PAGE72
  AG64    GND @S9S_MB_2U_LIB.S9S_MB_2U(SCH_1):GND     I8 @S9S_MB_2U_LIB.S9S_MB_2U(SCH_1):PAGE72
  AG58    GND @S9S_MB_2U_LIB.S9S_MB_2U(SCH_1):GND     I8 @S9S_MB_2U_LIB.S9S_MB_2U(SCH_1):PAGE72
  AG52    GND @S9S_MB_2U_LIB.S9S_MB_2U(SCH_1):GND     I8 @S9S_MB_2U_LIB.S9S_MB_2U(SCH_1):PAGE72
   AG5    GND @S9S_MB_2U_LIB.S9S_MB_2U(SCH_1):GND     I8 @S9S_MB_2U_LIB.S9S_MB_2U(SCH_1):PAGE72
  AG45    GND @S9S_MB_2U_LIB.S9S_MB_2U(SCH_1):GND     I8 @S9S_MB_2U_LIB.S9S_MB_2U(SCH_1):PAGE72
  AG39    GND @S9S_MB_2U_LIB.S9S_MB_2U(SCH_1):GND     I8 @S9S_MB_2U_LIB.S9S_MB_2U(SCH_1):PAGE72
  AG33    GND @S9S_MB_2U_LIB.S9S_MB_2U(SCH_1):GND     I8 @S9S_MB_2U_LIB.S9S_MB_2U(SCH_1):PAGE72
  AG27    GND @S9S_MB_2U_LIB.S9S_MB_2U(SCH_1):GND     I8 @S9S_MB_2U_LIB.S9S_MB_2U(SCH_1):PAGE72
  AG21    GND @S9S_MB_2U_LIB.S9S_MB_2U(SCH_1):GND     I8 @S9S_MB_2U_LIB.S9S_MB_2U(SCH_1):PAGE72
  AG13    GND @S9S_MB_2U_LIB.S9S_MB_2U(SCH_1):GND     I8 @S9S_MB_2U_LIB.S9S_MB_2U(SCH_1):PAGE72
   AG1    GND @S9S_MB_2U_LIB.S9S_MB_2U(SCH_1):GND     I8 @S9S_MB_2U_LIB.S9S_MB_2U(SCH_1):PAGE72
  AF91    GND @S9S_MB_2U_LIB.S9S_MB_2U(SCH_1):GND     I8 @S9S_MB_2U_LIB.S9S_MB_2U(SCH_1):PAGE72
  AF87    GND @S9S_MB_2U_LIB.S9S_MB_2U(SCH_1):GND     I8 @S9S_MB_2U_LIB.S9S_MB_2U(SCH_1):PAGE72
  AF81    GND @S9S_MB_2U_LIB.S9S_MB_2U(SCH_1):GND     I8 @S9S_MB_2U_LIB.S9S_MB_2U(SCH_1):PAGE72
   AF8    GND @S9S_MB_2U_LIB.S9S_MB_2U(SCH_1):GND     I8 @S9S_MB_2U_LIB.S9S_MB_2U(SCH_1):PAGE72
  AF42    GND @S9S_MB_2U_LIB.S9S_MB_2U(SCH_1):GND     I8 @S9S_MB_2U_LIB.S9S_MB_2U(SCH_1):PAGE72
   AF4    GND @S9S_MB_2U_LIB.S9S_MB_2U(SCH_1):GND     I8 @S9S_MB_2U_LIB.S9S_MB_2U(SCH_1):PAGE72
  AF16    GND @S9S_MB_2U_LIB.S9S_MB_2U(SCH_1):GND     I8 @S9S_MB_2U_LIB.S9S_MB_2U(SCH_1):PAGE72
  AF12    GND @S9S_MB_2U_LIB.S9S_MB_2U(SCH_1):GND     I8 @S9S_MB_2U_LIB.S9S_MB_2U(SCH_1):PAGE72
  AE88    GND @S9S_MB_2U_LIB.S9S_MB_2U(SCH_1):GND     I8 @S9S_MB_2U_LIB.S9S_MB_2U(SCH_1):PAGE72
  AE84    GND @S9S_MB_2U_LIB.S9S_MB_2U(SCH_1):GND     I8 @S9S_MB_2U_LIB.S9S_MB_2U(SCH_1):PAGE72
  AE78    GND @S9S_MB_2U_LIB.S9S_MB_2U(SCH_1):GND     I8 @S9S_MB_2U_LIB.S9S_MB_2U(SCH_1):PAGE72
  AE76    GND @S9S_MB_2U_LIB.S9S_MB_2U(SCH_1):GND     I8 @S9S_MB_2U_LIB.S9S_MB_2U(SCH_1):PAGE72
  AE74    GND @S9S_MB_2U_LIB.S9S_MB_2U(SCH_1):GND     I8 @S9S_MB_2U_LIB.S9S_MB_2U(SCH_1):PAGE72
  AE72    GND @S9S_MB_2U_LIB.S9S_MB_2U(SCH_1):GND     I8 @S9S_MB_2U_LIB.S9S_MB_2U(SCH_1):PAGE72
  AE70    GND @S9S_MB_2U_LIB.S9S_MB_2U(SCH_1):GND     I8 @S9S_MB_2U_LIB.S9S_MB_2U(SCH_1):PAGE72
  AE68    GND @S9S_MB_2U_LIB.S9S_MB_2U(SCH_1):GND     I8 @S9S_MB_2U_LIB.S9S_MB_2U(SCH_1):PAGE72
  AE66    GND @S9S_MB_2U_LIB.S9S_MB_2U(SCH_1):GND     I8 @S9S_MB_2U_LIB.S9S_MB_2U(SCH_1):PAGE72
  AE64    GND @S9S_MB_2U_LIB.S9S_MB_2U(SCH_1):GND     I8 @S9S_MB_2U_LIB.S9S_MB_2U(SCH_1):PAGE72
  AE62    GND @S9S_MB_2U_LIB.S9S_MB_2U(SCH_1):GND     I8 @S9S_MB_2U_LIB.S9S_MB_2U(SCH_1):PAGE72
  AE60    GND @S9S_MB_2U_LIB.S9S_MB_2U(SCH_1):GND     I8 @S9S_MB_2U_LIB.S9S_MB_2U(SCH_1):PAGE72
  AE58    GND @S9S_MB_2U_LIB.S9S_MB_2U(SCH_1):GND     I8 @S9S_MB_2U_LIB.S9S_MB_2U(SCH_1):PAGE72
  AE56    GND @S9S_MB_2U_LIB.S9S_MB_2U(SCH_1):GND     I8 @S9S_MB_2U_LIB.S9S_MB_2U(SCH_1):PAGE72
  AE54    GND @S9S_MB_2U_LIB.S9S_MB_2U(SCH_1):GND     I8 @S9S_MB_2U_LIB.S9S_MB_2U(SCH_1):PAGE72
  AE52    GND @S9S_MB_2U_LIB.S9S_MB_2U(SCH_1):GND     I8 @S9S_MB_2U_LIB.S9S_MB_2U(SCH_1):PAGE72
  AE50    GND @S9S_MB_2U_LIB.S9S_MB_2U(SCH_1):GND     I8 @S9S_MB_2U_LIB.S9S_MB_2U(SCH_1):PAGE72
  AE48    GND @S9S_MB_2U_LIB.S9S_MB_2U(SCH_1):GND     I8 @S9S_MB_2U_LIB.S9S_MB_2U(SCH_1):PAGE72
  AE45    GND @S9S_MB_2U_LIB.S9S_MB_2U(SCH_1):GND     I8 @S9S_MB_2U_LIB.S9S_MB_2U(SCH_1):PAGE72
  AE43    GND @S9S_MB_2U_LIB.S9S_MB_2U(SCH_1):GND     I8 @S9S_MB_2U_LIB.S9S_MB_2U(SCH_1):PAGE72
  AE41    GND @S9S_MB_2U_LIB.S9S_MB_2U(SCH_1):GND     I8 @S9S_MB_2U_LIB.S9S_MB_2U(SCH_1):PAGE72
  AE39    GND @S9S_MB_2U_LIB.S9S_MB_2U(SCH_1):GND     I8 @S9S_MB_2U_LIB.S9S_MB_2U(SCH_1):PAGE72
  AE37    GND @S9S_MB_2U_LIB.S9S_MB_2U(SCH_1):GND     I8 @S9S_MB_2U_LIB.S9S_MB_2U(SCH_1):PAGE72
  AE35    GND @S9S_MB_2U_LIB.S9S_MB_2U(SCH_1):GND     I8 @S9S_MB_2U_LIB.S9S_MB_2U(SCH_1):PAGE72
  AE33    GND @S9S_MB_2U_LIB.S9S_MB_2U(SCH_1):GND     I8 @S9S_MB_2U_LIB.S9S_MB_2U(SCH_1):PAGE72
  AE31    GND @S9S_MB_2U_LIB.S9S_MB_2U(SCH_1):GND     I8 @S9S_MB_2U_LIB.S9S_MB_2U(SCH_1):PAGE72
  AE29    GND @S9S_MB_2U_LIB.S9S_MB_2U(SCH_1):GND     I8 @S9S_MB_2U_LIB.S9S_MB_2U(SCH_1):PAGE72
  AE27    GND @S9S_MB_2U_LIB.S9S_MB_2U(SCH_1):GND     I8 @S9S_MB_2U_LIB.S9S_MB_2U(SCH_1):PAGE72
  AE25    GND @S9S_MB_2U_LIB.S9S_MB_2U(SCH_1):GND     I8 @S9S_MB_2U_LIB.S9S_MB_2U(SCH_1):PAGE72
  AE23    GND @S9S_MB_2U_LIB.S9S_MB_2U(SCH_1):GND     I8 @S9S_MB_2U_LIB.S9S_MB_2U(SCH_1):PAGE72
  AE21    GND @S9S_MB_2U_LIB.S9S_MB_2U(SCH_1):GND     I8 @S9S_MB_2U_LIB.S9S_MB_2U(SCH_1):PAGE72
  AE19    GND @S9S_MB_2U_LIB.S9S_MB_2U(SCH_1):GND     I8 @S9S_MB_2U_LIB.S9S_MB_2U(SCH_1):PAGE72
  AE17    GND @S9S_MB_2U_LIB.S9S_MB_2U(SCH_1):GND     I8 @S9S_MB_2U_LIB.S9S_MB_2U(SCH_1):PAGE72
  AD83    GND @S9S_MB_2U_LIB.S9S_MB_2U(SCH_1):GND     I8 @S9S_MB_2U_LIB.S9S_MB_2U(SCH_1):PAGE72
   AD8    GND @S9S_MB_2U_LIB.S9S_MB_2U(SCH_1):GND     I8 @S9S_MB_2U_LIB.S9S_MB_2U(SCH_1):PAGE72
  AD79    GND @S9S_MB_2U_LIB.S9S_MB_2U(SCH_1):GND     I8 @S9S_MB_2U_LIB.S9S_MB_2U(SCH_1):PAGE72
  AD42    GND @S9S_MB_2U_LIB.S9S_MB_2U(SCH_1):GND     I8 @S9S_MB_2U_LIB.S9S_MB_2U(SCH_1):PAGE72
   AD4    GND @S9S_MB_2U_LIB.S9S_MB_2U(SCH_1):GND     I8 @S9S_MB_2U_LIB.S9S_MB_2U(SCH_1):PAGE72
  AD16    GND @S9S_MB_2U_LIB.S9S_MB_2U(SCH_1):GND     I8 @S9S_MB_2U_LIB.S9S_MB_2U(SCH_1):PAGE72
  AD12    GND @S9S_MB_2U_LIB.S9S_MB_2U(SCH_1):GND     I8 @S9S_MB_2U_LIB.S9S_MB_2U(SCH_1):PAGE72
   AC9    GND @S9S_MB_2U_LIB.S9S_MB_2U(SCH_1):GND     I8 @S9S_MB_2U_LIB.S9S_MB_2U(SCH_1):PAGE72
  AC88    GND @S9S_MB_2U_LIB.S9S_MB_2U(SCH_1):GND     I8 @S9S_MB_2U_LIB.S9S_MB_2U(SCH_1):PAGE72
  AC84    GND @S9S_MB_2U_LIB.S9S_MB_2U(SCH_1):GND     I8 @S9S_MB_2U_LIB.S9S_MB_2U(SCH_1):PAGE72
  AC76    GND @S9S_MB_2U_LIB.S9S_MB_2U(SCH_1):GND     I8 @S9S_MB_2U_LIB.S9S_MB_2U(SCH_1):PAGE72
  AC70    GND @S9S_MB_2U_LIB.S9S_MB_2U(SCH_1):GND     I8 @S9S_MB_2U_LIB.S9S_MB_2U(SCH_1):PAGE72
  AC64    GND @S9S_MB_2U_LIB.S9S_MB_2U(SCH_1):GND     I8 @S9S_MB_2U_LIB.S9S_MB_2U(SCH_1):PAGE72
  AC58    GND @S9S_MB_2U_LIB.S9S_MB_2U(SCH_1):GND     I8 @S9S_MB_2U_LIB.S9S_MB_2U(SCH_1):PAGE72
  AC52    GND @S9S_MB_2U_LIB.S9S_MB_2U(SCH_1):GND     I8 @S9S_MB_2U_LIB.S9S_MB_2U(SCH_1):PAGE72
   AC5    GND @S9S_MB_2U_LIB.S9S_MB_2U(SCH_1):GND     I8 @S9S_MB_2U_LIB.S9S_MB_2U(SCH_1):PAGE72
  AC45    GND @S9S_MB_2U_LIB.S9S_MB_2U(SCH_1):GND     I8 @S9S_MB_2U_LIB.S9S_MB_2U(SCH_1):PAGE72
  AC39    GND @S9S_MB_2U_LIB.S9S_MB_2U(SCH_1):GND     I8 @S9S_MB_2U_LIB.S9S_MB_2U(SCH_1):PAGE72
  AC33    GND @S9S_MB_2U_LIB.S9S_MB_2U(SCH_1):GND     I8 @S9S_MB_2U_LIB.S9S_MB_2U(SCH_1):PAGE72
  AC27    GND @S9S_MB_2U_LIB.S9S_MB_2U(SCH_1):GND     I8 @S9S_MB_2U_LIB.S9S_MB_2U(SCH_1):PAGE72
  AC21    GND @S9S_MB_2U_LIB.S9S_MB_2U(SCH_1):GND     I8 @S9S_MB_2U_LIB.S9S_MB_2U(SCH_1):PAGE72
  AC13    GND @S9S_MB_2U_LIB.S9S_MB_2U(SCH_1):GND     I8 @S9S_MB_2U_LIB.S9S_MB_2U(SCH_1):PAGE72
   AC1    GND @S9S_MB_2U_LIB.S9S_MB_2U(SCH_1):GND     I8 @S9S_MB_2U_LIB.S9S_MB_2U(SCH_1):PAGE72
  AB91    GND @S9S_MB_2U_LIB.S9S_MB_2U(SCH_1):GND     I8 @S9S_MB_2U_LIB.S9S_MB_2U(SCH_1):PAGE72
  AB87    GND @S9S_MB_2U_LIB.S9S_MB_2U(SCH_1):GND     I8 @S9S_MB_2U_LIB.S9S_MB_2U(SCH_1):PAGE72
  AB83    GND @S9S_MB_2U_LIB.S9S_MB_2U(SCH_1):GND     I8 @S9S_MB_2U_LIB.S9S_MB_2U(SCH_1):PAGE72
  AB81    GND @S9S_MB_2U_LIB.S9S_MB_2U(SCH_1):GND     I8 @S9S_MB_2U_LIB.S9S_MB_2U(SCH_1):PAGE72
   AB8    GND @S9S_MB_2U_LIB.S9S_MB_2U(SCH_1):GND     I8 @S9S_MB_2U_LIB.S9S_MB_2U(SCH_1):PAGE72
  AB79    GND @S9S_MB_2U_LIB.S9S_MB_2U(SCH_1):GND     I8 @S9S_MB_2U_LIB.S9S_MB_2U(SCH_1):PAGE72
  AB77    GND @S9S_MB_2U_LIB.S9S_MB_2U(SCH_1):GND     I8 @S9S_MB_2U_LIB.S9S_MB_2U(SCH_1):PAGE72
  AB75    GND @S9S_MB_2U_LIB.S9S_MB_2U(SCH_1):GND     I8 @S9S_MB_2U_LIB.S9S_MB_2U(SCH_1):PAGE72
  AB71    GND @S9S_MB_2U_LIB.S9S_MB_2U(SCH_1):GND     I8 @S9S_MB_2U_LIB.S9S_MB_2U(SCH_1):PAGE72
  AB69    GND @S9S_MB_2U_LIB.S9S_MB_2U(SCH_1):GND     I8 @S9S_MB_2U_LIB.S9S_MB_2U(SCH_1):PAGE72
  AB65    GND @S9S_MB_2U_LIB.S9S_MB_2U(SCH_1):GND     I8 @S9S_MB_2U_LIB.S9S_MB_2U(SCH_1):PAGE72
  AB63    GND @S9S_MB_2U_LIB.S9S_MB_2U(SCH_1):GND     I8 @S9S_MB_2U_LIB.S9S_MB_2U(SCH_1):PAGE72
  AB59    GND @S9S_MB_2U_LIB.S9S_MB_2U(SCH_1):GND     I8 @S9S_MB_2U_LIB.S9S_MB_2U(SCH_1):PAGE72
  AB57    GND @S9S_MB_2U_LIB.S9S_MB_2U(SCH_1):GND     I8 @S9S_MB_2U_LIB.S9S_MB_2U(SCH_1):PAGE72
  AB53    GND @S9S_MB_2U_LIB.S9S_MB_2U(SCH_1):GND     I8 @S9S_MB_2U_LIB.S9S_MB_2U(SCH_1):PAGE72
  AB51    GND @S9S_MB_2U_LIB.S9S_MB_2U(SCH_1):GND     I8 @S9S_MB_2U_LIB.S9S_MB_2U(SCH_1):PAGE72
  AB47    GND @S9S_MB_2U_LIB.S9S_MB_2U(SCH_1):GND     I8 @S9S_MB_2U_LIB.S9S_MB_2U(SCH_1):PAGE72
  AB44    GND @S9S_MB_2U_LIB.S9S_MB_2U(SCH_1):GND     I8 @S9S_MB_2U_LIB.S9S_MB_2U(SCH_1):PAGE72
  AB40    GND @S9S_MB_2U_LIB.S9S_MB_2U(SCH_1):GND     I8 @S9S_MB_2U_LIB.S9S_MB_2U(SCH_1):PAGE72
   AB4    GND @S9S_MB_2U_LIB.S9S_MB_2U(SCH_1):GND     I8 @S9S_MB_2U_LIB.S9S_MB_2U(SCH_1):PAGE72
  AB38    GND @S9S_MB_2U_LIB.S9S_MB_2U(SCH_1):GND     I8 @S9S_MB_2U_LIB.S9S_MB_2U(SCH_1):PAGE72
  AB34    GND @S9S_MB_2U_LIB.S9S_MB_2U(SCH_1):GND     I8 @S9S_MB_2U_LIB.S9S_MB_2U(SCH_1):PAGE72
  AB32    GND @S9S_MB_2U_LIB.S9S_MB_2U(SCH_1):GND     I8 @S9S_MB_2U_LIB.S9S_MB_2U(SCH_1):PAGE72
  AB28    GND @S9S_MB_2U_LIB.S9S_MB_2U(SCH_1):GND     I8 @S9S_MB_2U_LIB.S9S_MB_2U(SCH_1):PAGE72
  AB26    GND @S9S_MB_2U_LIB.S9S_MB_2U(SCH_1):GND     I8 @S9S_MB_2U_LIB.S9S_MB_2U(SCH_1):PAGE72
  AB22    GND @S9S_MB_2U_LIB.S9S_MB_2U(SCH_1):GND     I8 @S9S_MB_2U_LIB.S9S_MB_2U(SCH_1):PAGE72
  AB20    GND @S9S_MB_2U_LIB.S9S_MB_2U(SCH_1):GND     I8 @S9S_MB_2U_LIB.S9S_MB_2U(SCH_1):PAGE72
  AB16    GND @S9S_MB_2U_LIB.S9S_MB_2U(SCH_1):GND     I8 @S9S_MB_2U_LIB.S9S_MB_2U(SCH_1):PAGE72
  AB12    GND @S9S_MB_2U_LIB.S9S_MB_2U(SCH_1):GND     I8 @S9S_MB_2U_LIB.S9S_MB_2U(SCH_1):PAGE72
  AA88    GND @S9S_MB_2U_LIB.S9S_MB_2U(SCH_1):GND     I8 @S9S_MB_2U_LIB.S9S_MB_2U(SCH_1):PAGE72
  AA84    GND @S9S_MB_2U_LIB.S9S_MB_2U(SCH_1):GND     I8 @S9S_MB_2U_LIB.S9S_MB_2U(SCH_1):PAGE72
  AA82    GND @S9S_MB_2U_LIB.S9S_MB_2U(SCH_1):GND     I8 @S9S_MB_2U_LIB.S9S_MB_2U(SCH_1):PAGE72
   Y73    GND @S9S_MB_2U_LIB.S9S_MB_2U(SCH_1):GND     I2 @S9S_MB_2U_LIB.S9S_MB_2U(SCH_1):PAGE73
    Y8    GND @S9S_MB_2U_LIB.S9S_MB_2U(SCH_1):GND     I2 @S9S_MB_2U_LIB.S9S_MB_2U(SCH_1):PAGE73
   Y55    GND @S9S_MB_2U_LIB.S9S_MB_2U(SCH_1):GND     I2 @S9S_MB_2U_LIB.S9S_MB_2U(SCH_1):PAGE73
   Y49    GND @S9S_MB_2U_LIB.S9S_MB_2U(SCH_1):GND     I2 @S9S_MB_2U_LIB.S9S_MB_2U(SCH_1):PAGE73
   Y67    GND @S9S_MB_2U_LIB.S9S_MB_2U(SCH_1):GND     I2 @S9S_MB_2U_LIB.S9S_MB_2U(SCH_1):PAGE73
   Y61    GND @S9S_MB_2U_LIB.S9S_MB_2U(SCH_1):GND     I2 @S9S_MB_2U_LIB.S9S_MB_2U(SCH_1):PAGE73
   Y42    GND @S9S_MB_2U_LIB.S9S_MB_2U(SCH_1):GND     I2 @S9S_MB_2U_LIB.S9S_MB_2U(SCH_1):PAGE73
    Y4    GND @S9S_MB_2U_LIB.S9S_MB_2U(SCH_1):GND     I2 @S9S_MB_2U_LIB.S9S_MB_2U(SCH_1):PAGE73
   Y36    GND @S9S_MB_2U_LIB.S9S_MB_2U(SCH_1):GND     I2 @S9S_MB_2U_LIB.S9S_MB_2U(SCH_1):PAGE73
   Y30    GND @S9S_MB_2U_LIB.S9S_MB_2U(SCH_1):GND     I2 @S9S_MB_2U_LIB.S9S_MB_2U(SCH_1):PAGE73
   Y24    GND @S9S_MB_2U_LIB.S9S_MB_2U(SCH_1):GND     I2 @S9S_MB_2U_LIB.S9S_MB_2U(SCH_1):PAGE73
   Y18    GND @S9S_MB_2U_LIB.S9S_MB_2U(SCH_1):GND     I2 @S9S_MB_2U_LIB.S9S_MB_2U(SCH_1):PAGE73
   Y16    GND @S9S_MB_2U_LIB.S9S_MB_2U(SCH_1):GND     I2 @S9S_MB_2U_LIB.S9S_MB_2U(SCH_1):PAGE73
   Y12    GND @S9S_MB_2U_LIB.S9S_MB_2U(SCH_1):GND     I2 @S9S_MB_2U_LIB.S9S_MB_2U(SCH_1):PAGE73
    W9    GND @S9S_MB_2U_LIB.S9S_MB_2U(SCH_1):GND     I2 @S9S_MB_2U_LIB.S9S_MB_2U(SCH_1):PAGE73
   W88    GND @S9S_MB_2U_LIB.S9S_MB_2U(SCH_1):GND     I2 @S9S_MB_2U_LIB.S9S_MB_2U(SCH_1):PAGE73
   W84    GND @S9S_MB_2U_LIB.S9S_MB_2U(SCH_1):GND     I2 @S9S_MB_2U_LIB.S9S_MB_2U(SCH_1):PAGE73
   W39    GND @S9S_MB_2U_LIB.S9S_MB_2U(SCH_1):GND     I2 @S9S_MB_2U_LIB.S9S_MB_2U(SCH_1):PAGE73
   W52    GND @S9S_MB_2U_LIB.S9S_MB_2U(SCH_1):GND     I2 @S9S_MB_2U_LIB.S9S_MB_2U(SCH_1):PAGE73
    W5    GND @S9S_MB_2U_LIB.S9S_MB_2U(SCH_1):GND     I2 @S9S_MB_2U_LIB.S9S_MB_2U(SCH_1):PAGE73
   V87    GND @S9S_MB_2U_LIB.S9S_MB_2U(SCH_1):GND     I2 @S9S_MB_2U_LIB.S9S_MB_2U(SCH_1):PAGE73
    V8    GND @S9S_MB_2U_LIB.S9S_MB_2U(SCH_1):GND     I2 @S9S_MB_2U_LIB.S9S_MB_2U(SCH_1):PAGE73
   V79    GND @S9S_MB_2U_LIB.S9S_MB_2U(SCH_1):GND     I2 @S9S_MB_2U_LIB.S9S_MB_2U(SCH_1):PAGE73
   V77    GND @S9S_MB_2U_LIB.S9S_MB_2U(SCH_1):GND     I2 @S9S_MB_2U_LIB.S9S_MB_2U(SCH_1):PAGE73
   W13    GND @S9S_MB_2U_LIB.S9S_MB_2U(SCH_1):GND     I2 @S9S_MB_2U_LIB.S9S_MB_2U(SCH_1):PAGE73
    W1    GND @S9S_MB_2U_LIB.S9S_MB_2U(SCH_1):GND     I2 @S9S_MB_2U_LIB.S9S_MB_2U(SCH_1):PAGE73
   V91    GND @S9S_MB_2U_LIB.S9S_MB_2U(SCH_1):GND     I2 @S9S_MB_2U_LIB.S9S_MB_2U(SCH_1):PAGE73
   V75    GND @S9S_MB_2U_LIB.S9S_MB_2U(SCH_1):GND     I2 @S9S_MB_2U_LIB.S9S_MB_2U(SCH_1):PAGE73
   V69    GND @S9S_MB_2U_LIB.S9S_MB_2U(SCH_1):GND     I2 @S9S_MB_2U_LIB.S9S_MB_2U(SCH_1):PAGE73
   V67    GND @S9S_MB_2U_LIB.S9S_MB_2U(SCH_1):GND     I2 @S9S_MB_2U_LIB.S9S_MB_2U(SCH_1):PAGE73
   V65    GND @S9S_MB_2U_LIB.S9S_MB_2U(SCH_1):GND     I2 @S9S_MB_2U_LIB.S9S_MB_2U(SCH_1):PAGE73
   V63    GND @S9S_MB_2U_LIB.S9S_MB_2U(SCH_1):GND     I2 @S9S_MB_2U_LIB.S9S_MB_2U(SCH_1):PAGE73
   V73    GND @S9S_MB_2U_LIB.S9S_MB_2U(SCH_1):GND     I2 @S9S_MB_2U_LIB.S9S_MB_2U(SCH_1):PAGE73
   V71    GND @S9S_MB_2U_LIB.S9S_MB_2U(SCH_1):GND     I2 @S9S_MB_2U_LIB.S9S_MB_2U(SCH_1):PAGE73
   V61    GND @S9S_MB_2U_LIB.S9S_MB_2U(SCH_1):GND     I2 @S9S_MB_2U_LIB.S9S_MB_2U(SCH_1):PAGE73
   V59    GND @S9S_MB_2U_LIB.S9S_MB_2U(SCH_1):GND     I2 @S9S_MB_2U_LIB.S9S_MB_2U(SCH_1):PAGE73
   V57    GND @S9S_MB_2U_LIB.S9S_MB_2U(SCH_1):GND     I2 @S9S_MB_2U_LIB.S9S_MB_2U(SCH_1):PAGE73
   V55    GND @S9S_MB_2U_LIB.S9S_MB_2U(SCH_1):GND     I2 @S9S_MB_2U_LIB.S9S_MB_2U(SCH_1):PAGE73
   V53    GND @S9S_MB_2U_LIB.S9S_MB_2U(SCH_1):GND     I2 @S9S_MB_2U_LIB.S9S_MB_2U(SCH_1):PAGE73
   V51    GND @S9S_MB_2U_LIB.S9S_MB_2U(SCH_1):GND     I2 @S9S_MB_2U_LIB.S9S_MB_2U(SCH_1):PAGE73
   V47    GND @S9S_MB_2U_LIB.S9S_MB_2U(SCH_1):GND     I2 @S9S_MB_2U_LIB.S9S_MB_2U(SCH_1):PAGE73
   V44    GND @S9S_MB_2U_LIB.S9S_MB_2U(SCH_1):GND     I2 @S9S_MB_2U_LIB.S9S_MB_2U(SCH_1):PAGE73
   V42    GND @S9S_MB_2U_LIB.S9S_MB_2U(SCH_1):GND     I2 @S9S_MB_2U_LIB.S9S_MB_2U(SCH_1):PAGE73
   V40    GND @S9S_MB_2U_LIB.S9S_MB_2U(SCH_1):GND     I2 @S9S_MB_2U_LIB.S9S_MB_2U(SCH_1):PAGE73
   V49    GND @S9S_MB_2U_LIB.S9S_MB_2U(SCH_1):GND     I2 @S9S_MB_2U_LIB.S9S_MB_2U(SCH_1):PAGE73
    V4    GND @S9S_MB_2U_LIB.S9S_MB_2U(SCH_1):GND     I2 @S9S_MB_2U_LIB.S9S_MB_2U(SCH_1):PAGE73
   V38    GND @S9S_MB_2U_LIB.S9S_MB_2U(SCH_1):GND     I2 @S9S_MB_2U_LIB.S9S_MB_2U(SCH_1):PAGE73
   V36    GND @S9S_MB_2U_LIB.S9S_MB_2U(SCH_1):GND     I2 @S9S_MB_2U_LIB.S9S_MB_2U(SCH_1):PAGE73
   V34    GND @S9S_MB_2U_LIB.S9S_MB_2U(SCH_1):GND     I2 @S9S_MB_2U_LIB.S9S_MB_2U(SCH_1):PAGE73
   V32    GND @S9S_MB_2U_LIB.S9S_MB_2U(SCH_1):GND     I2 @S9S_MB_2U_LIB.S9S_MB_2U(SCH_1):PAGE73
   V30    GND @S9S_MB_2U_LIB.S9S_MB_2U(SCH_1):GND     I2 @S9S_MB_2U_LIB.S9S_MB_2U(SCH_1):PAGE73
   V28    GND @S9S_MB_2U_LIB.S9S_MB_2U(SCH_1):GND     I2 @S9S_MB_2U_LIB.S9S_MB_2U(SCH_1):PAGE73
   V26    GND @S9S_MB_2U_LIB.S9S_MB_2U(SCH_1):GND     I2 @S9S_MB_2U_LIB.S9S_MB_2U(SCH_1):PAGE73
   V24    GND @S9S_MB_2U_LIB.S9S_MB_2U(SCH_1):GND     I2 @S9S_MB_2U_LIB.S9S_MB_2U(SCH_1):PAGE73
   V22    GND @S9S_MB_2U_LIB.S9S_MB_2U(SCH_1):GND     I2 @S9S_MB_2U_LIB.S9S_MB_2U(SCH_1):PAGE73
   V20    GND @S9S_MB_2U_LIB.S9S_MB_2U(SCH_1):GND     I2 @S9S_MB_2U_LIB.S9S_MB_2U(SCH_1):PAGE73
   V18    GND @S9S_MB_2U_LIB.S9S_MB_2U(SCH_1):GND     I2 @S9S_MB_2U_LIB.S9S_MB_2U(SCH_1):PAGE73
   V16    GND @S9S_MB_2U_LIB.S9S_MB_2U(SCH_1):GND     I2 @S9S_MB_2U_LIB.S9S_MB_2U(SCH_1):PAGE73
   V12    GND @S9S_MB_2U_LIB.S9S_MB_2U(SCH_1):GND     I2 @S9S_MB_2U_LIB.S9S_MB_2U(SCH_1):PAGE73
   U88    GND @S9S_MB_2U_LIB.S9S_MB_2U(SCH_1):GND     I2 @S9S_MB_2U_LIB.S9S_MB_2U(SCH_1):PAGE73
   U84    GND @S9S_MB_2U_LIB.S9S_MB_2U(SCH_1):GND     I2 @S9S_MB_2U_LIB.S9S_MB_2U(SCH_1):PAGE73
   U82    GND @S9S_MB_2U_LIB.S9S_MB_2U(SCH_1):GND     I2 @S9S_MB_2U_LIB.S9S_MB_2U(SCH_1):PAGE73
   U39    GND @S9S_MB_2U_LIB.S9S_MB_2U(SCH_1):GND     I2 @S9S_MB_2U_LIB.S9S_MB_2U(SCH_1):PAGE73
   T83    GND @S9S_MB_2U_LIB.S9S_MB_2U(SCH_1):GND     I2 @S9S_MB_2U_LIB.S9S_MB_2U(SCH_1):PAGE73
    T8    GND @S9S_MB_2U_LIB.S9S_MB_2U(SCH_1):GND     I2 @S9S_MB_2U_LIB.S9S_MB_2U(SCH_1):PAGE73
   T79    GND @S9S_MB_2U_LIB.S9S_MB_2U(SCH_1):GND     I2 @S9S_MB_2U_LIB.S9S_MB_2U(SCH_1):PAGE73
   T73    GND @S9S_MB_2U_LIB.S9S_MB_2U(SCH_1):GND     I2 @S9S_MB_2U_LIB.S9S_MB_2U(SCH_1):PAGE73
   U52    GND @S9S_MB_2U_LIB.S9S_MB_2U(SCH_1):GND     I2 @S9S_MB_2U_LIB.S9S_MB_2U(SCH_1):PAGE73
   T67    GND @S9S_MB_2U_LIB.S9S_MB_2U(SCH_1):GND     I2 @S9S_MB_2U_LIB.S9S_MB_2U(SCH_1):PAGE73
   T61    GND @S9S_MB_2U_LIB.S9S_MB_2U(SCH_1):GND     I2 @S9S_MB_2U_LIB.S9S_MB_2U(SCH_1):PAGE73
   T42    GND @S9S_MB_2U_LIB.S9S_MB_2U(SCH_1):GND     I2 @S9S_MB_2U_LIB.S9S_MB_2U(SCH_1):PAGE73
    T4    GND @S9S_MB_2U_LIB.S9S_MB_2U(SCH_1):GND     I2 @S9S_MB_2U_LIB.S9S_MB_2U(SCH_1):PAGE73
   T30    GND @S9S_MB_2U_LIB.S9S_MB_2U(SCH_1):GND     I2 @S9S_MB_2U_LIB.S9S_MB_2U(SCH_1):PAGE73
   T24    GND @S9S_MB_2U_LIB.S9S_MB_2U(SCH_1):GND     I2 @S9S_MB_2U_LIB.S9S_MB_2U(SCH_1):PAGE73
    R9    GND @S9S_MB_2U_LIB.S9S_MB_2U(SCH_1):GND     I2 @S9S_MB_2U_LIB.S9S_MB_2U(SCH_1):PAGE73
   R88    GND @S9S_MB_2U_LIB.S9S_MB_2U(SCH_1):GND     I2 @S9S_MB_2U_LIB.S9S_MB_2U(SCH_1):PAGE73
   R84    GND @S9S_MB_2U_LIB.S9S_MB_2U(SCH_1):GND     I2 @S9S_MB_2U_LIB.S9S_MB_2U(SCH_1):PAGE73
   R78    GND @S9S_MB_2U_LIB.S9S_MB_2U(SCH_1):GND     I2 @S9S_MB_2U_LIB.S9S_MB_2U(SCH_1):PAGE73
   R74    GND @S9S_MB_2U_LIB.S9S_MB_2U(SCH_1):GND     I2 @S9S_MB_2U_LIB.S9S_MB_2U(SCH_1):PAGE73
   R72    GND @S9S_MB_2U_LIB.S9S_MB_2U(SCH_1):GND     I2 @S9S_MB_2U_LIB.S9S_MB_2U(SCH_1):PAGE73
   R68    GND @S9S_MB_2U_LIB.S9S_MB_2U(SCH_1):GND     I2 @S9S_MB_2U_LIB.S9S_MB_2U(SCH_1):PAGE73
   R62    GND @S9S_MB_2U_LIB.S9S_MB_2U(SCH_1):GND     I2 @S9S_MB_2U_LIB.S9S_MB_2U(SCH_1):PAGE73
   R56    GND @S9S_MB_2U_LIB.S9S_MB_2U(SCH_1):GND     I2 @S9S_MB_2U_LIB.S9S_MB_2U(SCH_1):PAGE73
   T55    GND @S9S_MB_2U_LIB.S9S_MB_2U(SCH_1):GND     I2 @S9S_MB_2U_LIB.S9S_MB_2U(SCH_1):PAGE73
   T49    GND @S9S_MB_2U_LIB.S9S_MB_2U(SCH_1):GND     I2 @S9S_MB_2U_LIB.S9S_MB_2U(SCH_1):PAGE73
   R54    GND @S9S_MB_2U_LIB.S9S_MB_2U(SCH_1):GND     I2 @S9S_MB_2U_LIB.S9S_MB_2U(SCH_1):PAGE73
   R50    GND @S9S_MB_2U_LIB.S9S_MB_2U(SCH_1):GND     I2 @S9S_MB_2U_LIB.S9S_MB_2U(SCH_1):PAGE73
   T36    GND @S9S_MB_2U_LIB.S9S_MB_2U(SCH_1):GND     I2 @S9S_MB_2U_LIB.S9S_MB_2U(SCH_1):PAGE73
    R5    GND @S9S_MB_2U_LIB.S9S_MB_2U(SCH_1):GND     I2 @S9S_MB_2U_LIB.S9S_MB_2U(SCH_1):PAGE73
   R43    GND @S9S_MB_2U_LIB.S9S_MB_2U(SCH_1):GND     I2 @S9S_MB_2U_LIB.S9S_MB_2U(SCH_1):PAGE73
   R41    GND @S9S_MB_2U_LIB.S9S_MB_2U(SCH_1):GND     I2 @S9S_MB_2U_LIB.S9S_MB_2U(SCH_1):PAGE73
   R37    GND @S9S_MB_2U_LIB.S9S_MB_2U(SCH_1):GND     I2 @S9S_MB_2U_LIB.S9S_MB_2U(SCH_1):PAGE73
   T18    GND @S9S_MB_2U_LIB.S9S_MB_2U(SCH_1):GND     I2 @S9S_MB_2U_LIB.S9S_MB_2U(SCH_1):PAGE73
   T16    GND @S9S_MB_2U_LIB.S9S_MB_2U(SCH_1):GND     I2 @S9S_MB_2U_LIB.S9S_MB_2U(SCH_1):PAGE73
   T12    GND @S9S_MB_2U_LIB.S9S_MB_2U(SCH_1):GND     I2 @S9S_MB_2U_LIB.S9S_MB_2U(SCH_1):PAGE73
   R35    GND @S9S_MB_2U_LIB.S9S_MB_2U(SCH_1):GND     I2 @S9S_MB_2U_LIB.S9S_MB_2U(SCH_1):PAGE73
   R31    GND @S9S_MB_2U_LIB.S9S_MB_2U(SCH_1):GND     I2 @S9S_MB_2U_LIB.S9S_MB_2U(SCH_1):PAGE73
   R29    GND @S9S_MB_2U_LIB.S9S_MB_2U(SCH_1):GND     I2 @S9S_MB_2U_LIB.S9S_MB_2U(SCH_1):PAGE73
   R25    GND @S9S_MB_2U_LIB.S9S_MB_2U(SCH_1):GND     I2 @S9S_MB_2U_LIB.S9S_MB_2U(SCH_1):PAGE73
   R17    GND @S9S_MB_2U_LIB.S9S_MB_2U(SCH_1):GND     I2 @S9S_MB_2U_LIB.S9S_MB_2U(SCH_1):PAGE73
   R13    GND @S9S_MB_2U_LIB.S9S_MB_2U(SCH_1):GND     I2 @S9S_MB_2U_LIB.S9S_MB_2U(SCH_1):PAGE73
   P91    GND @S9S_MB_2U_LIB.S9S_MB_2U(SCH_1):GND     I2 @S9S_MB_2U_LIB.S9S_MB_2U(SCH_1):PAGE73
   P87    GND @S9S_MB_2U_LIB.S9S_MB_2U(SCH_1):GND     I2 @S9S_MB_2U_LIB.S9S_MB_2U(SCH_1):PAGE73
   R66    GND @S9S_MB_2U_LIB.S9S_MB_2U(SCH_1):GND     I2 @S9S_MB_2U_LIB.S9S_MB_2U(SCH_1):PAGE73
    P8    GND @S9S_MB_2U_LIB.S9S_MB_2U(SCH_1):GND     I2 @S9S_MB_2U_LIB.S9S_MB_2U(SCH_1):PAGE73
   R60    GND @S9S_MB_2U_LIB.S9S_MB_2U(SCH_1):GND     I2 @S9S_MB_2U_LIB.S9S_MB_2U(SCH_1):PAGE73
   P77    GND @S9S_MB_2U_LIB.S9S_MB_2U(SCH_1):GND     I2 @S9S_MB_2U_LIB.S9S_MB_2U(SCH_1):PAGE73
   P75    GND @S9S_MB_2U_LIB.S9S_MB_2U(SCH_1):GND     I2 @S9S_MB_2U_LIB.S9S_MB_2U(SCH_1):PAGE73
   P69    GND @S9S_MB_2U_LIB.S9S_MB_2U(SCH_1):GND     I2 @S9S_MB_2U_LIB.S9S_MB_2U(SCH_1):PAGE73
   P65    GND @S9S_MB_2U_LIB.S9S_MB_2U(SCH_1):GND     I2 @S9S_MB_2U_LIB.S9S_MB_2U(SCH_1):PAGE73
   R48    GND @S9S_MB_2U_LIB.S9S_MB_2U(SCH_1):GND     I2 @S9S_MB_2U_LIB.S9S_MB_2U(SCH_1):PAGE73
   P63    GND @S9S_MB_2U_LIB.S9S_MB_2U(SCH_1):GND     I2 @S9S_MB_2U_LIB.S9S_MB_2U(SCH_1):PAGE73
   P59    GND @S9S_MB_2U_LIB.S9S_MB_2U(SCH_1):GND     I2 @S9S_MB_2U_LIB.S9S_MB_2U(SCH_1):PAGE73
   P53    GND @S9S_MB_2U_LIB.S9S_MB_2U(SCH_1):GND     I2 @S9S_MB_2U_LIB.S9S_MB_2U(SCH_1):PAGE73
   P47    GND @S9S_MB_2U_LIB.S9S_MB_2U(SCH_1):GND     I2 @S9S_MB_2U_LIB.S9S_MB_2U(SCH_1):PAGE73
   P44    GND @S9S_MB_2U_LIB.S9S_MB_2U(SCH_1):GND     I2 @S9S_MB_2U_LIB.S9S_MB_2U(SCH_1):PAGE73
   P40    GND @S9S_MB_2U_LIB.S9S_MB_2U(SCH_1):GND     I2 @S9S_MB_2U_LIB.S9S_MB_2U(SCH_1):PAGE73
    P4    GND @S9S_MB_2U_LIB.S9S_MB_2U(SCH_1):GND     I2 @S9S_MB_2U_LIB.S9S_MB_2U(SCH_1):PAGE73
   R23    GND @S9S_MB_2U_LIB.S9S_MB_2U(SCH_1):GND     I2 @S9S_MB_2U_LIB.S9S_MB_2U(SCH_1):PAGE73
   R19    GND @S9S_MB_2U_LIB.S9S_MB_2U(SCH_1):GND     I2 @S9S_MB_2U_LIB.S9S_MB_2U(SCH_1):PAGE73
   P38    GND @S9S_MB_2U_LIB.S9S_MB_2U(SCH_1):GND     I2 @S9S_MB_2U_LIB.S9S_MB_2U(SCH_1):PAGE73
   P34    GND @S9S_MB_2U_LIB.S9S_MB_2U(SCH_1):GND     I2 @S9S_MB_2U_LIB.S9S_MB_2U(SCH_1):PAGE73
    R1    GND @S9S_MB_2U_LIB.S9S_MB_2U(SCH_1):GND     I2 @S9S_MB_2U_LIB.S9S_MB_2U(SCH_1):PAGE73
   P28    GND @S9S_MB_2U_LIB.S9S_MB_2U(SCH_1):GND     I2 @S9S_MB_2U_LIB.S9S_MB_2U(SCH_1):PAGE73
   P26    GND @S9S_MB_2U_LIB.S9S_MB_2U(SCH_1):GND     I2 @S9S_MB_2U_LIB.S9S_MB_2U(SCH_1):PAGE73
   P22    GND @S9S_MB_2U_LIB.S9S_MB_2U(SCH_1):GND     I2 @S9S_MB_2U_LIB.S9S_MB_2U(SCH_1):PAGE73
   P20    GND @S9S_MB_2U_LIB.S9S_MB_2U(SCH_1):GND     I2 @S9S_MB_2U_LIB.S9S_MB_2U(SCH_1):PAGE73
   P16    GND @S9S_MB_2U_LIB.S9S_MB_2U(SCH_1):GND     I2 @S9S_MB_2U_LIB.S9S_MB_2U(SCH_1):PAGE73
   P12    GND @S9S_MB_2U_LIB.S9S_MB_2U(SCH_1):GND     I2 @S9S_MB_2U_LIB.S9S_MB_2U(SCH_1):PAGE73
   P71    GND @S9S_MB_2U_LIB.S9S_MB_2U(SCH_1):GND     I2 @S9S_MB_2U_LIB.S9S_MB_2U(SCH_1):PAGE73
   N88    GND @S9S_MB_2U_LIB.S9S_MB_2U(SCH_1):GND     I2 @S9S_MB_2U_LIB.S9S_MB_2U(SCH_1):PAGE73
   N84    GND @S9S_MB_2U_LIB.S9S_MB_2U(SCH_1):GND     I2 @S9S_MB_2U_LIB.S9S_MB_2U(SCH_1):PAGE73
   N82    GND @S9S_MB_2U_LIB.S9S_MB_2U(SCH_1):GND     I2 @S9S_MB_2U_LIB.S9S_MB_2U(SCH_1):PAGE73
   N80    GND @S9S_MB_2U_LIB.S9S_MB_2U(SCH_1):GND     I2 @S9S_MB_2U_LIB.S9S_MB_2U(SCH_1):PAGE73
   P57    GND @S9S_MB_2U_LIB.S9S_MB_2U(SCH_1):GND     I2 @S9S_MB_2U_LIB.S9S_MB_2U(SCH_1):PAGE73
   N78    GND @S9S_MB_2U_LIB.S9S_MB_2U(SCH_1):GND     I2 @S9S_MB_2U_LIB.S9S_MB_2U(SCH_1):PAGE73
   P51    GND @S9S_MB_2U_LIB.S9S_MB_2U(SCH_1):GND     I2 @S9S_MB_2U_LIB.S9S_MB_2U(SCH_1):PAGE73
   N76    GND @S9S_MB_2U_LIB.S9S_MB_2U(SCH_1):GND     I2 @S9S_MB_2U_LIB.S9S_MB_2U(SCH_1):PAGE73
   P32    GND @S9S_MB_2U_LIB.S9S_MB_2U(SCH_1):GND     I2 @S9S_MB_2U_LIB.S9S_MB_2U(SCH_1):PAGE73
  AA80    GND @S9S_MB_2U_LIB.S9S_MB_2U(SCH_1):GND     I2 @S9S_MB_2U_LIB.S9S_MB_2U(SCH_1):PAGE73
  AA78    GND @S9S_MB_2U_LIB.S9S_MB_2U(SCH_1):GND     I2 @S9S_MB_2U_LIB.S9S_MB_2U(SCH_1):PAGE73
  AA74    GND @S9S_MB_2U_LIB.S9S_MB_2U(SCH_1):GND     I2 @S9S_MB_2U_LIB.S9S_MB_2U(SCH_1):PAGE73
  AA72    GND @S9S_MB_2U_LIB.S9S_MB_2U(SCH_1):GND     I2 @S9S_MB_2U_LIB.S9S_MB_2U(SCH_1):PAGE73
  AA68    GND @S9S_MB_2U_LIB.S9S_MB_2U(SCH_1):GND     I2 @S9S_MB_2U_LIB.S9S_MB_2U(SCH_1):PAGE73
  AA66    GND @S9S_MB_2U_LIB.S9S_MB_2U(SCH_1):GND     I2 @S9S_MB_2U_LIB.S9S_MB_2U(SCH_1):PAGE73
  AA62    GND @S9S_MB_2U_LIB.S9S_MB_2U(SCH_1):GND     I2 @S9S_MB_2U_LIB.S9S_MB_2U(SCH_1):PAGE73
  AA60    GND @S9S_MB_2U_LIB.S9S_MB_2U(SCH_1):GND     I2 @S9S_MB_2U_LIB.S9S_MB_2U(SCH_1):PAGE73
  AA56    GND @S9S_MB_2U_LIB.S9S_MB_2U(SCH_1):GND     I2 @S9S_MB_2U_LIB.S9S_MB_2U(SCH_1):PAGE73
  AA54    GND @S9S_MB_2U_LIB.S9S_MB_2U(SCH_1):GND     I2 @S9S_MB_2U_LIB.S9S_MB_2U(SCH_1):PAGE73
  AA50    GND @S9S_MB_2U_LIB.S9S_MB_2U(SCH_1):GND     I2 @S9S_MB_2U_LIB.S9S_MB_2U(SCH_1):PAGE73
  AA48    GND @S9S_MB_2U_LIB.S9S_MB_2U(SCH_1):GND     I2 @S9S_MB_2U_LIB.S9S_MB_2U(SCH_1):PAGE73
  AA43    GND @S9S_MB_2U_LIB.S9S_MB_2U(SCH_1):GND     I2 @S9S_MB_2U_LIB.S9S_MB_2U(SCH_1):PAGE73
  AA41    GND @S9S_MB_2U_LIB.S9S_MB_2U(SCH_1):GND     I2 @S9S_MB_2U_LIB.S9S_MB_2U(SCH_1):PAGE73
  AA37    GND @S9S_MB_2U_LIB.S9S_MB_2U(SCH_1):GND     I2 @S9S_MB_2U_LIB.S9S_MB_2U(SCH_1):PAGE73
  AA35    GND @S9S_MB_2U_LIB.S9S_MB_2U(SCH_1):GND     I2 @S9S_MB_2U_LIB.S9S_MB_2U(SCH_1):PAGE73
  AA31    GND @S9S_MB_2U_LIB.S9S_MB_2U(SCH_1):GND     I2 @S9S_MB_2U_LIB.S9S_MB_2U(SCH_1):PAGE73
  AA29    GND @S9S_MB_2U_LIB.S9S_MB_2U(SCH_1):GND     I2 @S9S_MB_2U_LIB.S9S_MB_2U(SCH_1):PAGE73
  AA25    GND @S9S_MB_2U_LIB.S9S_MB_2U(SCH_1):GND     I2 @S9S_MB_2U_LIB.S9S_MB_2U(SCH_1):PAGE73
  AA23    GND @S9S_MB_2U_LIB.S9S_MB_2U(SCH_1):GND     I2 @S9S_MB_2U_LIB.S9S_MB_2U(SCH_1):PAGE73
  AA19    GND @S9S_MB_2U_LIB.S9S_MB_2U(SCH_1):GND     I2 @S9S_MB_2U_LIB.S9S_MB_2U(SCH_1):PAGE73
   N70    GND @S9S_MB_2U_LIB.S9S_MB_2U(SCH_1):GND     I5 @S9S_MB_2U_LIB.S9S_MB_2U(SCH_1):PAGE73
   N58    GND @S9S_MB_2U_LIB.S9S_MB_2U(SCH_1):GND     I5 @S9S_MB_2U_LIB.S9S_MB_2U(SCH_1):PAGE73
   N52    GND @S9S_MB_2U_LIB.S9S_MB_2U(SCH_1):GND     I5 @S9S_MB_2U_LIB.S9S_MB_2U(SCH_1):PAGE73
   N45    GND @S9S_MB_2U_LIB.S9S_MB_2U(SCH_1):GND     I5 @S9S_MB_2U_LIB.S9S_MB_2U(SCH_1):PAGE73
   N33    GND @S9S_MB_2U_LIB.S9S_MB_2U(SCH_1):GND     I5 @S9S_MB_2U_LIB.S9S_MB_2U(SCH_1):PAGE73
   N27    GND @S9S_MB_2U_LIB.S9S_MB_2U(SCH_1):GND     I5 @S9S_MB_2U_LIB.S9S_MB_2U(SCH_1):PAGE73
   N15    GND @S9S_MB_2U_LIB.S9S_MB_2U(SCH_1):GND     I5 @S9S_MB_2U_LIB.S9S_MB_2U(SCH_1):PAGE73
   M83    GND @S9S_MB_2U_LIB.S9S_MB_2U(SCH_1):GND     I5 @S9S_MB_2U_LIB.S9S_MB_2U(SCH_1):PAGE73
   M81    GND @S9S_MB_2U_LIB.S9S_MB_2U(SCH_1):GND     I5 @S9S_MB_2U_LIB.S9S_MB_2U(SCH_1):PAGE73
   L78    GND @S9S_MB_2U_LIB.S9S_MB_2U(SCH_1):GND     I5 @S9S_MB_2U_LIB.S9S_MB_2U(SCH_1):PAGE73
   L76    GND @S9S_MB_2U_LIB.S9S_MB_2U(SCH_1):GND     I5 @S9S_MB_2U_LIB.S9S_MB_2U(SCH_1):PAGE73
   L74    GND @S9S_MB_2U_LIB.S9S_MB_2U(SCH_1):GND     I5 @S9S_MB_2U_LIB.S9S_MB_2U(SCH_1):PAGE73
   L72    GND @S9S_MB_2U_LIB.S9S_MB_2U(SCH_1):GND     I5 @S9S_MB_2U_LIB.S9S_MB_2U(SCH_1):PAGE73
   L68    GND @S9S_MB_2U_LIB.S9S_MB_2U(SCH_1):GND     I5 @S9S_MB_2U_LIB.S9S_MB_2U(SCH_1):PAGE73
   L66    GND @S9S_MB_2U_LIB.S9S_MB_2U(SCH_1):GND     I5 @S9S_MB_2U_LIB.S9S_MB_2U(SCH_1):PAGE73
   L64    GND @S9S_MB_2U_LIB.S9S_MB_2U(SCH_1):GND     I5 @S9S_MB_2U_LIB.S9S_MB_2U(SCH_1):PAGE73
   L62    GND @S9S_MB_2U_LIB.S9S_MB_2U(SCH_1):GND     I5 @S9S_MB_2U_LIB.S9S_MB_2U(SCH_1):PAGE73
   L60    GND @S9S_MB_2U_LIB.S9S_MB_2U(SCH_1):GND     I5 @S9S_MB_2U_LIB.S9S_MB_2U(SCH_1):PAGE73
   L56    GND @S9S_MB_2U_LIB.S9S_MB_2U(SCH_1):GND     I5 @S9S_MB_2U_LIB.S9S_MB_2U(SCH_1):PAGE73
   N64    GND @S9S_MB_2U_LIB.S9S_MB_2U(SCH_1):GND     I5 @S9S_MB_2U_LIB.S9S_MB_2U(SCH_1):PAGE73
   L54    GND @S9S_MB_2U_LIB.S9S_MB_2U(SCH_1):GND     I5 @S9S_MB_2U_LIB.S9S_MB_2U(SCH_1):PAGE73
   L52    GND @S9S_MB_2U_LIB.S9S_MB_2U(SCH_1):GND     I5 @S9S_MB_2U_LIB.S9S_MB_2U(SCH_1):PAGE73
   L50    GND @S9S_MB_2U_LIB.S9S_MB_2U(SCH_1):GND     I5 @S9S_MB_2U_LIB.S9S_MB_2U(SCH_1):PAGE73
    L5    GND @S9S_MB_2U_LIB.S9S_MB_2U(SCH_1):GND     I5 @S9S_MB_2U_LIB.S9S_MB_2U(SCH_1):PAGE73
   L48    GND @S9S_MB_2U_LIB.S9S_MB_2U(SCH_1):GND     I5 @S9S_MB_2U_LIB.S9S_MB_2U(SCH_1):PAGE73
   N39    GND @S9S_MB_2U_LIB.S9S_MB_2U(SCH_1):GND     I5 @S9S_MB_2U_LIB.S9S_MB_2U(SCH_1):PAGE73
   L45    GND @S9S_MB_2U_LIB.S9S_MB_2U(SCH_1):GND     I5 @S9S_MB_2U_LIB.S9S_MB_2U(SCH_1):PAGE73
   L43    GND @S9S_MB_2U_LIB.S9S_MB_2U(SCH_1):GND     I5 @S9S_MB_2U_LIB.S9S_MB_2U(SCH_1):PAGE73
   L41    GND @S9S_MB_2U_LIB.S9S_MB_2U(SCH_1):GND     I5 @S9S_MB_2U_LIB.S9S_MB_2U(SCH_1):PAGE73
   L39    GND @S9S_MB_2U_LIB.S9S_MB_2U(SCH_1):GND     I5 @S9S_MB_2U_LIB.S9S_MB_2U(SCH_1):PAGE73
   N21    GND @S9S_MB_2U_LIB.S9S_MB_2U(SCH_1):GND     I5 @S9S_MB_2U_LIB.S9S_MB_2U(SCH_1):PAGE73
   L37    GND @S9S_MB_2U_LIB.S9S_MB_2U(SCH_1):GND     I5 @S9S_MB_2U_LIB.S9S_MB_2U(SCH_1):PAGE73
   L35    GND @S9S_MB_2U_LIB.S9S_MB_2U(SCH_1):GND     I5 @S9S_MB_2U_LIB.S9S_MB_2U(SCH_1):PAGE73
   L33    GND @S9S_MB_2U_LIB.S9S_MB_2U(SCH_1):GND     I5 @S9S_MB_2U_LIB.S9S_MB_2U(SCH_1):PAGE73
   L31    GND @S9S_MB_2U_LIB.S9S_MB_2U(SCH_1):GND     I5 @S9S_MB_2U_LIB.S9S_MB_2U(SCH_1):PAGE73
   L29    GND @S9S_MB_2U_LIB.S9S_MB_2U(SCH_1):GND     I5 @S9S_MB_2U_LIB.S9S_MB_2U(SCH_1):PAGE73
   L27    GND @S9S_MB_2U_LIB.S9S_MB_2U(SCH_1):GND     I5 @S9S_MB_2U_LIB.S9S_MB_2U(SCH_1):PAGE73
    M8    GND @S9S_MB_2U_LIB.S9S_MB_2U(SCH_1):GND     I5 @S9S_MB_2U_LIB.S9S_MB_2U(SCH_1):PAGE73
   L25    GND @S9S_MB_2U_LIB.S9S_MB_2U(SCH_1):GND     I5 @S9S_MB_2U_LIB.S9S_MB_2U(SCH_1):PAGE73
   L23    GND @S9S_MB_2U_LIB.S9S_MB_2U(SCH_1):GND     I5 @S9S_MB_2U_LIB.S9S_MB_2U(SCH_1):PAGE73
   M49    GND @S9S_MB_2U_LIB.S9S_MB_2U(SCH_1):GND     I5 @S9S_MB_2U_LIB.S9S_MB_2U(SCH_1):PAGE73
   M42    GND @S9S_MB_2U_LIB.S9S_MB_2U(SCH_1):GND     I5 @S9S_MB_2U_LIB.S9S_MB_2U(SCH_1):PAGE73
    M4    GND @S9S_MB_2U_LIB.S9S_MB_2U(SCH_1):GND     I5 @S9S_MB_2U_LIB.S9S_MB_2U(SCH_1):PAGE73
   L21    GND @S9S_MB_2U_LIB.S9S_MB_2U(SCH_1):GND     I5 @S9S_MB_2U_LIB.S9S_MB_2U(SCH_1):PAGE73
   L17    GND @S9S_MB_2U_LIB.S9S_MB_2U(SCH_1):GND     I5 @S9S_MB_2U_LIB.S9S_MB_2U(SCH_1):PAGE73
   M12    GND @S9S_MB_2U_LIB.S9S_MB_2U(SCH_1):GND     I5 @S9S_MB_2U_LIB.S9S_MB_2U(SCH_1):PAGE73
   L90    GND @S9S_MB_2U_LIB.S9S_MB_2U(SCH_1):GND     I5 @S9S_MB_2U_LIB.S9S_MB_2U(SCH_1):PAGE73
    L9    GND @S9S_MB_2U_LIB.S9S_MB_2U(SCH_1):GND     I5 @S9S_MB_2U_LIB.S9S_MB_2U(SCH_1):PAGE73
   L88    GND @S9S_MB_2U_LIB.S9S_MB_2U(SCH_1):GND     I5 @S9S_MB_2U_LIB.S9S_MB_2U(SCH_1):PAGE73
   L15    GND @S9S_MB_2U_LIB.S9S_MB_2U(SCH_1):GND     I5 @S9S_MB_2U_LIB.S9S_MB_2U(SCH_1):PAGE73
   L13    GND @S9S_MB_2U_LIB.S9S_MB_2U(SCH_1):GND     I5 @S9S_MB_2U_LIB.S9S_MB_2U(SCH_1):PAGE73
   K85    GND @S9S_MB_2U_LIB.S9S_MB_2U(SCH_1):GND     I5 @S9S_MB_2U_LIB.S9S_MB_2U(SCH_1):PAGE73
   K83    GND @S9S_MB_2U_LIB.S9S_MB_2U(SCH_1):GND     I5 @S9S_MB_2U_LIB.S9S_MB_2U(SCH_1):PAGE73
    K8    GND @S9S_MB_2U_LIB.S9S_MB_2U(SCH_1):GND     I5 @S9S_MB_2U_LIB.S9S_MB_2U(SCH_1):PAGE73
   L70    GND @S9S_MB_2U_LIB.S9S_MB_2U(SCH_1):GND     I5 @S9S_MB_2U_LIB.S9S_MB_2U(SCH_1):PAGE73
   K77    GND @S9S_MB_2U_LIB.S9S_MB_2U(SCH_1):GND     I5 @S9S_MB_2U_LIB.S9S_MB_2U(SCH_1):PAGE73
   J86    GND @S9S_MB_2U_LIB.S9S_MB_2U(SCH_1):GND     I5 @S9S_MB_2U_LIB.S9S_MB_2U(SCH_1):PAGE73
   J84    GND @S9S_MB_2U_LIB.S9S_MB_2U(SCH_1):GND     I5 @S9S_MB_2U_LIB.S9S_MB_2U(SCH_1):PAGE73
   J78    GND @S9S_MB_2U_LIB.S9S_MB_2U(SCH_1):GND     I5 @S9S_MB_2U_LIB.S9S_MB_2U(SCH_1):PAGE73
   J76    GND @S9S_MB_2U_LIB.S9S_MB_2U(SCH_1):GND     I5 @S9S_MB_2U_LIB.S9S_MB_2U(SCH_1):PAGE73
   L58    GND @S9S_MB_2U_LIB.S9S_MB_2U(SCH_1):GND     I5 @S9S_MB_2U_LIB.S9S_MB_2U(SCH_1):PAGE73
   J58    GND @S9S_MB_2U_LIB.S9S_MB_2U(SCH_1):GND     I5 @S9S_MB_2U_LIB.S9S_MB_2U(SCH_1):PAGE73
   J52    GND @S9S_MB_2U_LIB.S9S_MB_2U(SCH_1):GND     I5 @S9S_MB_2U_LIB.S9S_MB_2U(SCH_1):PAGE73
   J45    GND @S9S_MB_2U_LIB.S9S_MB_2U(SCH_1):GND     I5 @S9S_MB_2U_LIB.S9S_MB_2U(SCH_1):PAGE73
   J33    GND @S9S_MB_2U_LIB.S9S_MB_2U(SCH_1):GND     I5 @S9S_MB_2U_LIB.S9S_MB_2U(SCH_1):PAGE73
   J27    GND @S9S_MB_2U_LIB.S9S_MB_2U(SCH_1):GND     I5 @S9S_MB_2U_LIB.S9S_MB_2U(SCH_1):PAGE73
   J15    GND @S9S_MB_2U_LIB.S9S_MB_2U(SCH_1):GND     I5 @S9S_MB_2U_LIB.S9S_MB_2U(SCH_1):PAGE73
   H81    GND @S9S_MB_2U_LIB.S9S_MB_2U(SCH_1):GND     I5 @S9S_MB_2U_LIB.S9S_MB_2U(SCH_1):PAGE73
    H8    GND @S9S_MB_2U_LIB.S9S_MB_2U(SCH_1):GND     I5 @S9S_MB_2U_LIB.S9S_MB_2U(SCH_1):PAGE73
   H79    GND @S9S_MB_2U_LIB.S9S_MB_2U(SCH_1):GND     I5 @S9S_MB_2U_LIB.S9S_MB_2U(SCH_1):PAGE73
   H71    GND @S9S_MB_2U_LIB.S9S_MB_2U(SCH_1):GND     I5 @S9S_MB_2U_LIB.S9S_MB_2U(SCH_1):PAGE73
   H69    GND @S9S_MB_2U_LIB.S9S_MB_2U(SCH_1):GND     I5 @S9S_MB_2U_LIB.S9S_MB_2U(SCH_1):PAGE73
   H63    GND @S9S_MB_2U_LIB.S9S_MB_2U(SCH_1):GND     I5 @S9S_MB_2U_LIB.S9S_MB_2U(SCH_1):PAGE73
    H6    GND @S9S_MB_2U_LIB.S9S_MB_2U(SCH_1):GND     I5 @S9S_MB_2U_LIB.S9S_MB_2U(SCH_1):PAGE73
   H59    GND @S9S_MB_2U_LIB.S9S_MB_2U(SCH_1):GND     I5 @S9S_MB_2U_LIB.S9S_MB_2U(SCH_1):PAGE73
   H53    GND @S9S_MB_2U_LIB.S9S_MB_2U(SCH_1):GND     I5 @S9S_MB_2U_LIB.S9S_MB_2U(SCH_1):PAGE73
   H47    GND @S9S_MB_2U_LIB.S9S_MB_2U(SCH_1):GND     I5 @S9S_MB_2U_LIB.S9S_MB_2U(SCH_1):PAGE73
   H44    GND @S9S_MB_2U_LIB.S9S_MB_2U(SCH_1):GND     I5 @S9S_MB_2U_LIB.S9S_MB_2U(SCH_1):PAGE73
   H40    GND @S9S_MB_2U_LIB.S9S_MB_2U(SCH_1):GND     I5 @S9S_MB_2U_LIB.S9S_MB_2U(SCH_1):PAGE73
    H4    GND @S9S_MB_2U_LIB.S9S_MB_2U(SCH_1):GND     I5 @S9S_MB_2U_LIB.S9S_MB_2U(SCH_1):PAGE73
   L19    GND @S9S_MB_2U_LIB.S9S_MB_2U(SCH_1):GND     I5 @S9S_MB_2U_LIB.S9S_MB_2U(SCH_1):PAGE73
   H38    GND @S9S_MB_2U_LIB.S9S_MB_2U(SCH_1):GND     I5 @S9S_MB_2U_LIB.S9S_MB_2U(SCH_1):PAGE73
   H34    GND @S9S_MB_2U_LIB.S9S_MB_2U(SCH_1):GND     I5 @S9S_MB_2U_LIB.S9S_MB_2U(SCH_1):PAGE73
   H32    GND @S9S_MB_2U_LIB.S9S_MB_2U(SCH_1):GND     I5 @S9S_MB_2U_LIB.S9S_MB_2U(SCH_1):PAGE73
   H28    GND @S9S_MB_2U_LIB.S9S_MB_2U(SCH_1):GND     I5 @S9S_MB_2U_LIB.S9S_MB_2U(SCH_1):PAGE73
   H26    GND @S9S_MB_2U_LIB.S9S_MB_2U(SCH_1):GND     I5 @S9S_MB_2U_LIB.S9S_MB_2U(SCH_1):PAGE73
   H22    GND @S9S_MB_2U_LIB.S9S_MB_2U(SCH_1):GND     I5 @S9S_MB_2U_LIB.S9S_MB_2U(SCH_1):PAGE73
   H20    GND @S9S_MB_2U_LIB.S9S_MB_2U(SCH_1):GND     I5 @S9S_MB_2U_LIB.S9S_MB_2U(SCH_1):PAGE73
   H16    GND @S9S_MB_2U_LIB.S9S_MB_2U(SCH_1):GND     I5 @S9S_MB_2U_LIB.S9S_MB_2U(SCH_1):PAGE73
   H10    GND @S9S_MB_2U_LIB.S9S_MB_2U(SCH_1):GND     I5 @S9S_MB_2U_LIB.S9S_MB_2U(SCH_1):PAGE73
   G90    GND @S9S_MB_2U_LIB.S9S_MB_2U(SCH_1):GND     I5 @S9S_MB_2U_LIB.S9S_MB_2U(SCH_1):PAGE73
   K49    GND @S9S_MB_2U_LIB.S9S_MB_2U(SCH_1):GND     I5 @S9S_MB_2U_LIB.S9S_MB_2U(SCH_1):PAGE73
   K42    GND @S9S_MB_2U_LIB.S9S_MB_2U(SCH_1):GND     I5 @S9S_MB_2U_LIB.S9S_MB_2U(SCH_1):PAGE73
   G88    GND @S9S_MB_2U_LIB.S9S_MB_2U(SCH_1):GND     I5 @S9S_MB_2U_LIB.S9S_MB_2U(SCH_1):PAGE73
   G84    GND @S9S_MB_2U_LIB.S9S_MB_2U(SCH_1):GND     I5 @S9S_MB_2U_LIB.S9S_MB_2U(SCH_1):PAGE73
    K2    GND @S9S_MB_2U_LIB.S9S_MB_2U(SCH_1):GND     I5 @S9S_MB_2U_LIB.S9S_MB_2U(SCH_1):PAGE73
   K14    GND @S9S_MB_2U_LIB.S9S_MB_2U(SCH_1):GND     I5 @S9S_MB_2U_LIB.S9S_MB_2U(SCH_1):PAGE73
   K12    GND @S9S_MB_2U_LIB.S9S_MB_2U(SCH_1):GND     I5 @S9S_MB_2U_LIB.S9S_MB_2U(SCH_1):PAGE73
    J9    GND @S9S_MB_2U_LIB.S9S_MB_2U(SCH_1):GND     I5 @S9S_MB_2U_LIB.S9S_MB_2U(SCH_1):PAGE73
   J88    GND @S9S_MB_2U_LIB.S9S_MB_2U(SCH_1):GND     I5 @S9S_MB_2U_LIB.S9S_MB_2U(SCH_1):PAGE73
   G72    GND @S9S_MB_2U_LIB.S9S_MB_2U(SCH_1):GND     I5 @S9S_MB_2U_LIB.S9S_MB_2U(SCH_1):PAGE73
   G62    GND @S9S_MB_2U_LIB.S9S_MB_2U(SCH_1):GND     I5 @S9S_MB_2U_LIB.S9S_MB_2U(SCH_1):PAGE73
   G56    GND @S9S_MB_2U_LIB.S9S_MB_2U(SCH_1):GND     I5 @S9S_MB_2U_LIB.S9S_MB_2U(SCH_1):PAGE73
   G54    GND @S9S_MB_2U_LIB.S9S_MB_2U(SCH_1):GND     I5 @S9S_MB_2U_LIB.S9S_MB_2U(SCH_1):PAGE73
   G50    GND @S9S_MB_2U_LIB.S9S_MB_2U(SCH_1):GND     I5 @S9S_MB_2U_LIB.S9S_MB_2U(SCH_1):PAGE73
   J70    GND @S9S_MB_2U_LIB.S9S_MB_2U(SCH_1):GND     I5 @S9S_MB_2U_LIB.S9S_MB_2U(SCH_1):PAGE73
   G43    GND @S9S_MB_2U_LIB.S9S_MB_2U(SCH_1):GND     I5 @S9S_MB_2U_LIB.S9S_MB_2U(SCH_1):PAGE73
   J64    GND @S9S_MB_2U_LIB.S9S_MB_2U(SCH_1):GND     I5 @S9S_MB_2U_LIB.S9S_MB_2U(SCH_1):PAGE73
   G41    GND @S9S_MB_2U_LIB.S9S_MB_2U(SCH_1):GND     I5 @S9S_MB_2U_LIB.S9S_MB_2U(SCH_1):PAGE73
   G37    GND @S9S_MB_2U_LIB.S9S_MB_2U(SCH_1):GND     I5 @S9S_MB_2U_LIB.S9S_MB_2U(SCH_1):PAGE73
   G31    GND @S9S_MB_2U_LIB.S9S_MB_2U(SCH_1):GND     I5 @S9S_MB_2U_LIB.S9S_MB_2U(SCH_1):PAGE73
   G29    GND @S9S_MB_2U_LIB.S9S_MB_2U(SCH_1):GND     I5 @S9S_MB_2U_LIB.S9S_MB_2U(SCH_1):PAGE73
    J5    GND @S9S_MB_2U_LIB.S9S_MB_2U(SCH_1):GND     I5 @S9S_MB_2U_LIB.S9S_MB_2U(SCH_1):PAGE73
   G23    GND @S9S_MB_2U_LIB.S9S_MB_2U(SCH_1):GND     I5 @S9S_MB_2U_LIB.S9S_MB_2U(SCH_1):PAGE73
   J39    GND @S9S_MB_2U_LIB.S9S_MB_2U(SCH_1):GND     I5 @S9S_MB_2U_LIB.S9S_MB_2U(SCH_1):PAGE73
   G19    GND @S9S_MB_2U_LIB.S9S_MB_2U(SCH_1):GND     I5 @S9S_MB_2U_LIB.S9S_MB_2U(SCH_1):PAGE73
   G13    GND @S9S_MB_2U_LIB.S9S_MB_2U(SCH_1):GND     I5 @S9S_MB_2U_LIB.S9S_MB_2U(SCH_1):PAGE73
   F89    GND @S9S_MB_2U_LIB.S9S_MB_2U(SCH_1):GND     I5 @S9S_MB_2U_LIB.S9S_MB_2U(SCH_1):PAGE73
   F83    GND @S9S_MB_2U_LIB.S9S_MB_2U(SCH_1):GND     I5 @S9S_MB_2U_LIB.S9S_MB_2U(SCH_1):PAGE73
   J21    GND @S9S_MB_2U_LIB.S9S_MB_2U(SCH_1):GND     I5 @S9S_MB_2U_LIB.S9S_MB_2U(SCH_1):PAGE73
   F49    GND @S9S_MB_2U_LIB.S9S_MB_2U(SCH_1):GND     I5 @S9S_MB_2U_LIB.S9S_MB_2U(SCH_1):PAGE73
    F4    GND @S9S_MB_2U_LIB.S9S_MB_2U(SCH_1):GND     I5 @S9S_MB_2U_LIB.S9S_MB_2U(SCH_1):PAGE73
   F36    GND @S9S_MB_2U_LIB.S9S_MB_2U(SCH_1):GND     I5 @S9S_MB_2U_LIB.S9S_MB_2U(SCH_1):PAGE73
   F30    GND @S9S_MB_2U_LIB.S9S_MB_2U(SCH_1):GND     I5 @S9S_MB_2U_LIB.S9S_MB_2U(SCH_1):PAGE73
   F24    GND @S9S_MB_2U_LIB.S9S_MB_2U(SCH_1):GND     I5 @S9S_MB_2U_LIB.S9S_MB_2U(SCH_1):PAGE73
   H75    GND @S9S_MB_2U_LIB.S9S_MB_2U(SCH_1):GND     I5 @S9S_MB_2U_LIB.S9S_MB_2U(SCH_1):PAGE73
   H65    GND @S9S_MB_2U_LIB.S9S_MB_2U(SCH_1):GND     I5 @S9S_MB_2U_LIB.S9S_MB_2U(SCH_1):PAGE73
   H57    GND @S9S_MB_2U_LIB.S9S_MB_2U(SCH_1):GND     I5 @S9S_MB_2U_LIB.S9S_MB_2U(SCH_1):PAGE73
   H51    GND @S9S_MB_2U_LIB.S9S_MB_2U(SCH_1):GND     I5 @S9S_MB_2U_LIB.S9S_MB_2U(SCH_1):PAGE73
    H2    GND @S9S_MB_2U_LIB.S9S_MB_2U(SCH_1):GND     I5 @S9S_MB_2U_LIB.S9S_MB_2U(SCH_1):PAGE73
   H14    GND @S9S_MB_2U_LIB.S9S_MB_2U(SCH_1):GND     I5 @S9S_MB_2U_LIB.S9S_MB_2U(SCH_1):PAGE73
   G74    GND @S9S_MB_2U_LIB.S9S_MB_2U(SCH_1):GND     I5 @S9S_MB_2U_LIB.S9S_MB_2U(SCH_1):PAGE73
    G7    GND @S9S_MB_2U_LIB.S9S_MB_2U(SCH_1):GND     I5 @S9S_MB_2U_LIB.S9S_MB_2U(SCH_1):PAGE73
   G68    GND @S9S_MB_2U_LIB.S9S_MB_2U(SCH_1):GND     I5 @S9S_MB_2U_LIB.S9S_MB_2U(SCH_1):PAGE73
   G66    GND @S9S_MB_2U_LIB.S9S_MB_2U(SCH_1):GND     I5 @S9S_MB_2U_LIB.S9S_MB_2U(SCH_1):PAGE73
   G60    GND @S9S_MB_2U_LIB.S9S_MB_2U(SCH_1):GND     I5 @S9S_MB_2U_LIB.S9S_MB_2U(SCH_1):PAGE73
   G48    GND @S9S_MB_2U_LIB.S9S_MB_2U(SCH_1):GND     I5 @S9S_MB_2U_LIB.S9S_MB_2U(SCH_1):PAGE73
   G35    GND @S9S_MB_2U_LIB.S9S_MB_2U(SCH_1):GND     I5 @S9S_MB_2U_LIB.S9S_MB_2U(SCH_1):PAGE73
    G3    GND @S9S_MB_2U_LIB.S9S_MB_2U(SCH_1):GND     I5 @S9S_MB_2U_LIB.S9S_MB_2U(SCH_1):PAGE73
   G25    GND @S9S_MB_2U_LIB.S9S_MB_2U(SCH_1):GND     I5 @S9S_MB_2U_LIB.S9S_MB_2U(SCH_1):PAGE73
   G17    GND @S9S_MB_2U_LIB.S9S_MB_2U(SCH_1):GND     I5 @S9S_MB_2U_LIB.S9S_MB_2U(SCH_1):PAGE73
   G11    GND @S9S_MB_2U_LIB.S9S_MB_2U(SCH_1):GND     I5 @S9S_MB_2U_LIB.S9S_MB_2U(SCH_1):PAGE73
   F79    GND @S9S_MB_2U_LIB.S9S_MB_2U(SCH_1):GND     I5 @S9S_MB_2U_LIB.S9S_MB_2U(SCH_1):PAGE73
   F73    GND @S9S_MB_2U_LIB.S9S_MB_2U(SCH_1):GND     I5 @S9S_MB_2U_LIB.S9S_MB_2U(SCH_1):PAGE73
   F67    GND @S9S_MB_2U_LIB.S9S_MB_2U(SCH_1):GND     I5 @S9S_MB_2U_LIB.S9S_MB_2U(SCH_1):PAGE73
   F61    GND @S9S_MB_2U_LIB.S9S_MB_2U(SCH_1):GND     I5 @S9S_MB_2U_LIB.S9S_MB_2U(SCH_1):PAGE73
    F6    GND @S9S_MB_2U_LIB.S9S_MB_2U(SCH_1):GND     I5 @S9S_MB_2U_LIB.S9S_MB_2U(SCH_1):PAGE73
   F55    GND @S9S_MB_2U_LIB.S9S_MB_2U(SCH_1):GND     I5 @S9S_MB_2U_LIB.S9S_MB_2U(SCH_1):PAGE73
   F42    GND @S9S_MB_2U_LIB.S9S_MB_2U(SCH_1):GND     I5 @S9S_MB_2U_LIB.S9S_MB_2U(SCH_1):PAGE73
   F18    GND @S9S_MB_2U_LIB.S9S_MB_2U(SCH_1):GND     I5 @S9S_MB_2U_LIB.S9S_MB_2U(SCH_1):PAGE73
   F12    GND @S9S_MB_2U_LIB.S9S_MB_2U(SCH_1):GND     I5 @S9S_MB_2U_LIB.S9S_MB_2U(SCH_1):PAGE73
   E86    GND @S9S_MB_2U_LIB.S9S_MB_2U(SCH_1):GND     I5 @S9S_MB_2U_LIB.S9S_MB_2U(SCH_1):PAGE73
   E76    GND @S9S_MB_2U_LIB.S9S_MB_2U(SCH_1):GND     I5 @S9S_MB_2U_LIB.S9S_MB_2U(SCH_1):PAGE73
   E78    GND @S9S_MB_2U_LIB.S9S_MB_2U(SCH_1):GND     I5 @S9S_MB_2U_LIB.S9S_MB_2U(SCH_1):PAGE73
   E74    GND @S9S_MB_2U_LIB.S9S_MB_2U(SCH_1):GND     I5 @S9S_MB_2U_LIB.S9S_MB_2U(SCH_1):PAGE73
   E52    GND @S9S_MB_2U_LIB.S9S_MB_2U(SCH_1):GND     I5 @S9S_MB_2U_LIB.S9S_MB_2U(SCH_1):PAGE73
   E39    GND @S9S_MB_2U_LIB.S9S_MB_2U(SCH_1):GND     I8 @S9S_MB_2U_LIB.S9S_MB_2U(SCH_1):PAGE73
    E5    GND @S9S_MB_2U_LIB.S9S_MB_2U(SCH_1):GND     I8 @S9S_MB_2U_LIB.S9S_MB_2U(SCH_1):PAGE73
   D83    GND @S9S_MB_2U_LIB.S9S_MB_2U(SCH_1):GND     I8 @S9S_MB_2U_LIB.S9S_MB_2U(SCH_1):PAGE73
   D81    GND @S9S_MB_2U_LIB.S9S_MB_2U(SCH_1):GND     I8 @S9S_MB_2U_LIB.S9S_MB_2U(SCH_1):PAGE73
   D71    GND @S9S_MB_2U_LIB.S9S_MB_2U(SCH_1):GND     I8 @S9S_MB_2U_LIB.S9S_MB_2U(SCH_1):PAGE73
   D69    GND @S9S_MB_2U_LIB.S9S_MB_2U(SCH_1):GND     I8 @S9S_MB_2U_LIB.S9S_MB_2U(SCH_1):PAGE73
   D61    GND @S9S_MB_2U_LIB.S9S_MB_2U(SCH_1):GND     I8 @S9S_MB_2U_LIB.S9S_MB_2U(SCH_1):PAGE73
    D6    GND @S9S_MB_2U_LIB.S9S_MB_2U(SCH_1):GND     I8 @S9S_MB_2U_LIB.S9S_MB_2U(SCH_1):PAGE73
   D59    GND @S9S_MB_2U_LIB.S9S_MB_2U(SCH_1):GND     I8 @S9S_MB_2U_LIB.S9S_MB_2U(SCH_1):PAGE73
   D57    GND @S9S_MB_2U_LIB.S9S_MB_2U(SCH_1):GND     I8 @S9S_MB_2U_LIB.S9S_MB_2U(SCH_1):PAGE73
   D55    GND @S9S_MB_2U_LIB.S9S_MB_2U(SCH_1):GND     I8 @S9S_MB_2U_LIB.S9S_MB_2U(SCH_1):PAGE73
   D53    GND @S9S_MB_2U_LIB.S9S_MB_2U(SCH_1):GND     I8 @S9S_MB_2U_LIB.S9S_MB_2U(SCH_1):PAGE73
   D51    GND @S9S_MB_2U_LIB.S9S_MB_2U(SCH_1):GND     I8 @S9S_MB_2U_LIB.S9S_MB_2U(SCH_1):PAGE73
   D49    GND @S9S_MB_2U_LIB.S9S_MB_2U(SCH_1):GND     I8 @S9S_MB_2U_LIB.S9S_MB_2U(SCH_1):PAGE73
   D47    GND @S9S_MB_2U_LIB.S9S_MB_2U(SCH_1):GND     I8 @S9S_MB_2U_LIB.S9S_MB_2U(SCH_1):PAGE73
   D44    GND @S9S_MB_2U_LIB.S9S_MB_2U(SCH_1):GND     I8 @S9S_MB_2U_LIB.S9S_MB_2U(SCH_1):PAGE73
   D42    GND @S9S_MB_2U_LIB.S9S_MB_2U(SCH_1):GND     I8 @S9S_MB_2U_LIB.S9S_MB_2U(SCH_1):PAGE73
   D40    GND @S9S_MB_2U_LIB.S9S_MB_2U(SCH_1):GND     I8 @S9S_MB_2U_LIB.S9S_MB_2U(SCH_1):PAGE73
   D38    GND @S9S_MB_2U_LIB.S9S_MB_2U(SCH_1):GND     I8 @S9S_MB_2U_LIB.S9S_MB_2U(SCH_1):PAGE73
   D36    GND @S9S_MB_2U_LIB.S9S_MB_2U(SCH_1):GND     I8 @S9S_MB_2U_LIB.S9S_MB_2U(SCH_1):PAGE73
   D34    GND @S9S_MB_2U_LIB.S9S_MB_2U(SCH_1):GND     I8 @S9S_MB_2U_LIB.S9S_MB_2U(SCH_1):PAGE73
   D32    GND @S9S_MB_2U_LIB.S9S_MB_2U(SCH_1):GND     I8 @S9S_MB_2U_LIB.S9S_MB_2U(SCH_1):PAGE73
   D30    GND @S9S_MB_2U_LIB.S9S_MB_2U(SCH_1):GND     I8 @S9S_MB_2U_LIB.S9S_MB_2U(SCH_1):PAGE73
   D28    GND @S9S_MB_2U_LIB.S9S_MB_2U(SCH_1):GND     I8 @S9S_MB_2U_LIB.S9S_MB_2U(SCH_1):PAGE73
   D26    GND @S9S_MB_2U_LIB.S9S_MB_2U(SCH_1):GND     I8 @S9S_MB_2U_LIB.S9S_MB_2U(SCH_1):PAGE73
   D24    GND @S9S_MB_2U_LIB.S9S_MB_2U(SCH_1):GND     I8 @S9S_MB_2U_LIB.S9S_MB_2U(SCH_1):PAGE73
   D22    GND @S9S_MB_2U_LIB.S9S_MB_2U(SCH_1):GND     I8 @S9S_MB_2U_LIB.S9S_MB_2U(SCH_1):PAGE73
   D20    GND @S9S_MB_2U_LIB.S9S_MB_2U(SCH_1):GND     I8 @S9S_MB_2U_LIB.S9S_MB_2U(SCH_1):PAGE73
   D18    GND @S9S_MB_2U_LIB.S9S_MB_2U(SCH_1):GND     I8 @S9S_MB_2U_LIB.S9S_MB_2U(SCH_1):PAGE73
   D16    GND @S9S_MB_2U_LIB.S9S_MB_2U(SCH_1):GND     I8 @S9S_MB_2U_LIB.S9S_MB_2U(SCH_1):PAGE73
   D14    GND @S9S_MB_2U_LIB.S9S_MB_2U(SCH_1):GND     I8 @S9S_MB_2U_LIB.S9S_MB_2U(SCH_1):PAGE73
   D12    GND @S9S_MB_2U_LIB.S9S_MB_2U(SCH_1):GND     I8 @S9S_MB_2U_LIB.S9S_MB_2U(SCH_1):PAGE73
   D10    GND @S9S_MB_2U_LIB.S9S_MB_2U(SCH_1):GND     I8 @S9S_MB_2U_LIB.S9S_MB_2U(SCH_1):PAGE73
    D8    GND @S9S_MB_2U_LIB.S9S_MB_2U(SCH_1):GND     I8 @S9S_MB_2U_LIB.S9S_MB_2U(SCH_1):PAGE73
   D79    GND @S9S_MB_2U_LIB.S9S_MB_2U(SCH_1):GND     I8 @S9S_MB_2U_LIB.S9S_MB_2U(SCH_1):PAGE73
   D67    GND @S9S_MB_2U_LIB.S9S_MB_2U(SCH_1):GND     I8 @S9S_MB_2U_LIB.S9S_MB_2U(SCH_1):PAGE73
   D65    GND @S9S_MB_2U_LIB.S9S_MB_2U(SCH_1):GND     I8 @S9S_MB_2U_LIB.S9S_MB_2U(SCH_1):PAGE73
   D63    GND @S9S_MB_2U_LIB.S9S_MB_2U(SCH_1):GND     I8 @S9S_MB_2U_LIB.S9S_MB_2U(SCH_1):PAGE73
   C86    GND @S9S_MB_2U_LIB.S9S_MB_2U(SCH_1):GND     I8 @S9S_MB_2U_LIB.S9S_MB_2U(SCH_1):PAGE73
   C82    GND @S9S_MB_2U_LIB.S9S_MB_2U(SCH_1):GND     I8 @S9S_MB_2U_LIB.S9S_MB_2U(SCH_1):PAGE73
   C80    GND @S9S_MB_2U_LIB.S9S_MB_2U(SCH_1):GND     I8 @S9S_MB_2U_LIB.S9S_MB_2U(SCH_1):PAGE73
   C78    GND @S9S_MB_2U_LIB.S9S_MB_2U(SCH_1):GND     I8 @S9S_MB_2U_LIB.S9S_MB_2U(SCH_1):PAGE73
   C74    GND @S9S_MB_2U_LIB.S9S_MB_2U(SCH_1):GND     I8 @S9S_MB_2U_LIB.S9S_MB_2U(SCH_1):PAGE73
   C72    GND @S9S_MB_2U_LIB.S9S_MB_2U(SCH_1):GND     I8 @S9S_MB_2U_LIB.S9S_MB_2U(SCH_1):PAGE73
   C52    GND @S9S_MB_2U_LIB.S9S_MB_2U(SCH_1):GND     I8 @S9S_MB_2U_LIB.S9S_MB_2U(SCH_1):PAGE73
    C5    GND @S9S_MB_2U_LIB.S9S_MB_2U(SCH_1):GND     I8 @S9S_MB_2U_LIB.S9S_MB_2U(SCH_1):PAGE73
   C45    GND @S9S_MB_2U_LIB.S9S_MB_2U(SCH_1):GND     I8 @S9S_MB_2U_LIB.S9S_MB_2U(SCH_1):PAGE73
   C39    GND @S9S_MB_2U_LIB.S9S_MB_2U(SCH_1):GND     I8 @S9S_MB_2U_LIB.S9S_MB_2U(SCH_1):PAGE73
   B87    GND @S9S_MB_2U_LIB.S9S_MB_2U(SCH_1):GND     I8 @S9S_MB_2U_LIB.S9S_MB_2U(SCH_1):PAGE73
   B83    GND @S9S_MB_2U_LIB.S9S_MB_2U(SCH_1):GND     I8 @S9S_MB_2U_LIB.S9S_MB_2U(SCH_1):PAGE73
   B75    GND @S9S_MB_2U_LIB.S9S_MB_2U(SCH_1):GND     I8 @S9S_MB_2U_LIB.S9S_MB_2U(SCH_1):PAGE73
   B67    GND @S9S_MB_2U_LIB.S9S_MB_2U(SCH_1):GND     I8 @S9S_MB_2U_LIB.S9S_MB_2U(SCH_1):PAGE73
   B61    GND @S9S_MB_2U_LIB.S9S_MB_2U(SCH_1):GND     I8 @S9S_MB_2U_LIB.S9S_MB_2U(SCH_1):PAGE73
    B6    GND @S9S_MB_2U_LIB.S9S_MB_2U(SCH_1):GND     I8 @S9S_MB_2U_LIB.S9S_MB_2U(SCH_1):PAGE73
   B55    GND @S9S_MB_2U_LIB.S9S_MB_2U(SCH_1):GND     I8 @S9S_MB_2U_LIB.S9S_MB_2U(SCH_1):PAGE73
   B49    GND @S9S_MB_2U_LIB.S9S_MB_2U(SCH_1):GND     I8 @S9S_MB_2U_LIB.S9S_MB_2U(SCH_1):PAGE73
   B42    GND @S9S_MB_2U_LIB.S9S_MB_2U(SCH_1):GND     I8 @S9S_MB_2U_LIB.S9S_MB_2U(SCH_1):PAGE73
   B36    GND @S9S_MB_2U_LIB.S9S_MB_2U(SCH_1):GND     I8 @S9S_MB_2U_LIB.S9S_MB_2U(SCH_1):PAGE73
   B30    GND @S9S_MB_2U_LIB.S9S_MB_2U(SCH_1):GND     I8 @S9S_MB_2U_LIB.S9S_MB_2U(SCH_1):PAGE73
   B24    GND @S9S_MB_2U_LIB.S9S_MB_2U(SCH_1):GND     I8 @S9S_MB_2U_LIB.S9S_MB_2U(SCH_1):PAGE73
   B18    GND @S9S_MB_2U_LIB.S9S_MB_2U(SCH_1):GND     I8 @S9S_MB_2U_LIB.S9S_MB_2U(SCH_1):PAGE73
   B12    GND @S9S_MB_2U_LIB.S9S_MB_2U(SCH_1):GND     I8 @S9S_MB_2U_LIB.S9S_MB_2U(SCH_1):PAGE73
   A62    GND @S9S_MB_2U_LIB.S9S_MB_2U(SCH_1):GND     I8 @S9S_MB_2U_LIB.S9S_MB_2U(SCH_1):PAGE73
   A60    GND @S9S_MB_2U_LIB.S9S_MB_2U(SCH_1):GND     I8 @S9S_MB_2U_LIB.S9S_MB_2U(SCH_1):PAGE73
   A56    GND @S9S_MB_2U_LIB.S9S_MB_2U(SCH_1):GND     I8 @S9S_MB_2U_LIB.S9S_MB_2U(SCH_1):PAGE73
   A54    GND @S9S_MB_2U_LIB.S9S_MB_2U(SCH_1):GND     I8 @S9S_MB_2U_LIB.S9S_MB_2U(SCH_1):PAGE73
   A50    GND @S9S_MB_2U_LIB.S9S_MB_2U(SCH_1):GND     I8 @S9S_MB_2U_LIB.S9S_MB_2U(SCH_1):PAGE73
   A41    GND @S9S_MB_2U_LIB.S9S_MB_2U(SCH_1):GND     I8 @S9S_MB_2U_LIB.S9S_MB_2U(SCH_1):PAGE73
   A37    GND @S9S_MB_2U_LIB.S9S_MB_2U(SCH_1):GND     I8 @S9S_MB_2U_LIB.S9S_MB_2U(SCH_1):PAGE73
   A35    GND @S9S_MB_2U_LIB.S9S_MB_2U(SCH_1):GND     I8 @S9S_MB_2U_LIB.S9S_MB_2U(SCH_1):PAGE73
   A31    GND @S9S_MB_2U_LIB.S9S_MB_2U(SCH_1):GND     I8 @S9S_MB_2U_LIB.S9S_MB_2U(SCH_1):PAGE73
   A29    GND @S9S_MB_2U_LIB.S9S_MB_2U(SCH_1):GND     I8 @S9S_MB_2U_LIB.S9S_MB_2U(SCH_1):PAGE73
   A25    GND @S9S_MB_2U_LIB.S9S_MB_2U(SCH_1):GND     I8 @S9S_MB_2U_LIB.S9S_MB_2U(SCH_1):PAGE73
   A23    GND @S9S_MB_2U_LIB.S9S_MB_2U(SCH_1):GND     I8 @S9S_MB_2U_LIB.S9S_MB_2U(SCH_1):PAGE73
   A19    GND @S9S_MB_2U_LIB.S9S_MB_2U(SCH_1):GND     I8 @S9S_MB_2U_LIB.S9S_MB_2U(SCH_1):PAGE73
   A17    GND @S9S_MB_2U_LIB.S9S_MB_2U(SCH_1):GND     I8 @S9S_MB_2U_LIB.S9S_MB_2U(SCH_1):PAGE73
   A13    GND @S9S_MB_2U_LIB.S9S_MB_2U(SCH_1):GND     I8 @S9S_MB_2U_LIB.S9S_MB_2U(SCH_1):PAGE73
   A11    GND @S9S_MB_2U_LIB.S9S_MB_2U(SCH_1):GND     I8 @S9S_MB_2U_LIB.S9S_MB_2U(SCH_1):PAGE73

U1_BL TP_TP_BOM ONLY-NA,TP12_BOM
     1     NC     NC    I40 @S9S_MB_2U_LIB.S9S_MB_2U(SCH_1):PAGE290

U1_BP TP_TP_BOM ONLY-NA,TP12_BOM
     1     NC     NC    I43 @S9S_MB_2U_LIB.S9S_MB_2U(SCH_1):PAGE290

U1_DC TP_TP_BOM ONLY-NA,TP12_BOM
     1     NC     NC    I47 @S9S_MB_2U_LIB.S9S_MB_2U(SCH_1):PAGE290

  U2 SOCKET4677_AZIF0045P001C01CS-SA
  CY32 CLK_25M_NSSC_CPU0_DP @S9S_MB_2U_LIB.S9S_MB_2U(SCH_1):CLK_25M_NSSC_CPU0_DP    I57 @S9S_MB_2U_LIB.S9S_MB_2U(SCH_1):PAGE13
  CT20 PD_CPU0_TXT_PLTEN @S9S_MB_2U_LIB.S9S_MB_2U(SCH_1):PD_CPU0_TXT_PLTEN    I57 @S9S_MB_2U_LIB.S9S_MB_2U(SCH_1):PAGE13
  BT26 PU_CPU0_TXT_AGENT @S9S_MB_2U_LIB.S9S_MB_2U(SCH_1):PU_CPU0_TXT_AGENT    I57 @S9S_MB_2U_LIB.S9S_MB_2U(SCH_1):PAGE13
  BR25 JTAG_DBP_CPU0_QS_GTL_R_TMS @S9S_MB_2U_LIB.S9S_MB_2U(SCH_1):JTAG_DBP_CPU0_QS_GTL_R_TMS    I57 @S9S_MB_2U_LIB.S9S_MB_2U(SCH_1):PAGE13
  BW25 JTAG_CPU0_MUX_GTL_TDO @S9S_MB_2U_LIB.S9S_MB_2U(SCH_1):JTAG_CPU0_MUX_GTL_TDO    I57 @S9S_MB_2U_LIB.S9S_MB_2U(SCH_1):PAGE13
  BV24 JTAG_DBP_CPU0_GTL_R_TDI @S9S_MB_2U_LIB.S9S_MB_2U(SCH_1):JTAG_DBP_CPU0_GTL_R_TDI    I57 @S9S_MB_2U_LIB.S9S_MB_2U(SCH_1):PAGE13
  BT24 JTAG_DBP_CPU0_GTL_R_TCK @S9S_MB_2U_LIB.S9S_MB_2U(SCH_1):JTAG_DBP_CPU0_GTL_R_TCK    I57 @S9S_MB_2U_LIB.S9S_MB_2U(SCH_1):PAGE13
  CW60 PU_CPU0_SOCKET_ID0 @S9S_MB_2U_LIB.S9S_MB_2U(SCH_1):PU_CPU0_SOCKET_ID0    I57 @S9S_MB_2U_LIB.S9S_MB_2U(SCH_1):PAGE13
  CY61 PU_CPU0_SOCKET_ID1 @S9S_MB_2U_LIB.S9S_MB_2U(SCH_1):PU_CPU0_SOCKET_ID1    I57 @S9S_MB_2U_LIB.S9S_MB_2U(SCH_1):PAGE13
  CT61 PU_CPU0_SOCKET_ID2 @S9S_MB_2U_LIB.S9S_MB_2U(SCH_1):PU_CPU0_SOCKET_ID2    I57 @S9S_MB_2U_LIB.S9S_MB_2U(SCH_1):PAGE13
  AU23 PU_CPU0_SAFE_MODE_BOOT @S9S_MB_2U_LIB.S9S_MB_2U(SCH_1):PU_CPU0_SAFE_MODE_BOOT    I57 @S9S_MB_2U_LIB.S9S_MB_2U(SCH_1):PAGE13
  CE70 NC_CLK_PFT_OUT_CPU0_DN @S9S_MB_2U_LIB.S9S_MB_2U(SCH_1):NC_CLK_PFT_OUT_CPU0_DN    I57 @S9S_MB_2U_LIB.S9S_MB_2U(SCH_1):PAGE13
  CD71 NC_CLK_PFT_OUT_CPU0_DP @S9S_MB_2U_LIB.S9S_MB_2U(SCH_1):NC_CLK_PFT_OUT_CPU0_DP    I57 @S9S_MB_2U_LIB.S9S_MB_2U(SCH_1):PAGE13
  BY24 PD_EXT_CLK_SEL_CPU0 @S9S_MB_2U_LIB.S9S_MB_2U(SCH_1):PD_EXT_CLK_SEL_CPU0    I57 @S9S_MB_2U_LIB.S9S_MB_2U(SCH_1):PAGE13
    G5 NC_XTAL_CPU0_25M_IN @S9S_MB_2U_LIB.S9S_MB_2U(SCH_1):NC_XTAL_CPU0_25M_IN    I57 @S9S_MB_2U_LIB.S9S_MB_2U(SCH_1):PAGE13
  CJ72 PUD_XTAL_CPU0_MODE1 @S9S_MB_2U_LIB.S9S_MB_2U(SCH_1):PUD_XTAL_CPU0_MODE1    I57 @S9S_MB_2U_LIB.S9S_MB_2U(SCH_1):PAGE13
  BG72 FM_CPU0_PROC_ID0 @S9S_MB_2U_LIB.S9S_MB_2U(SCH_1):FM_CPU0_PROC_ID0    I57 @S9S_MB_2U_LIB.S9S_MB_2U(SCH_1):PAGE13
  BH71 FM_CPU0_PROC_ID1 @S9S_MB_2U_LIB.S9S_MB_2U(SCH_1):FM_CPU0_PROC_ID1    I57 @S9S_MB_2U_LIB.S9S_MB_2U(SCH_1):PAGE13
  DA52 TP_CPU0_PROCDIS_COD_GTL_N @S9S_MB_2U_LIB.S9S_MB_2U(SCH_1):TP_CPU0_PROCDIS_COD_GTL_N    I57 @S9S_MB_2U_LIB.S9S_MB_2U(SCH_1):PAGE13
  AV22 H_CPU0_PREQ_QS_GTL_R_N @S9S_MB_2U_LIB.S9S_MB_2U(SCH_1):H_CPU0_PREQ_QS_GTL_R_N    I57 @S9S_MB_2U_LIB.S9S_MB_2U(SCH_1):PAGE13
  BP26 H_CPU0_PRDY_QS_GTL_R_N @S9S_MB_2U_LIB.S9S_MB_2U(SCH_1):H_CPU0_PRDY_QS_GTL_R_N    I57 @S9S_MB_2U_LIB.S9S_MB_2U(SCH_1):PAGE13
  BL64 FM_CPU0_PKGID0 @S9S_MB_2U_LIB.S9S_MB_2U(SCH_1):FM_CPU0_PKGID0    I57 @S9S_MB_2U_LIB.S9S_MB_2U(SCH_1):PAGE13
  AY63 FM_CPU0_PKGID1 @S9S_MB_2U_LIB.S9S_MB_2U(SCH_1):FM_CPU0_PKGID1    I57 @S9S_MB_2U_LIB.S9S_MB_2U(SCH_1):PAGE13
  BN64 FM_CPU0_PKGID2 @S9S_MB_2U_LIB.S9S_MB_2U(SCH_1):FM_CPU0_PKGID2    I57 @S9S_MB_2U_LIB.S9S_MB_2U(SCH_1):PAGE13
  BH24 PECI_CPU0_GTL_R @S9S_MB_2U_LIB.S9S_MB_2U(SCH_1):PECI_CPU0_GTL_R    I57 @S9S_MB_2U_LIB.S9S_MB_2U(SCH_1):PAGE13
  BR23 TP_CPU0_BR23 @S9S_MB_2U_LIB.S9S_MB_2U(SCH_1):TP_CPU0_BR23    I57 @S9S_MB_2U_LIB.S9S_MB_2U(SCH_1):PAGE13
  CY59 PU_CPU0_LEGACY_SKT @S9S_MB_2U_LIB.S9S_MB_2U(SCH_1):PU_CPU0_LEGACY_SKT    I57 @S9S_MB_2U_LIB.S9S_MB_2U(SCH_1):PAGE13
  AU17 PU_CPU0_FRMAGENT @S9S_MB_2U_LIB.S9S_MB_2U(SCH_1):PU_CPU0_FRMAGENT    I57 @S9S_MB_2U_LIB.S9S_MB_2U(SCH_1):PAGE13
  AW17 PD_CPU0_DMIMODE_OVERRIDE @S9S_MB_2U_LIB.S9S_MB_2U(SCH_1):PD_CPU0_DMIMODE_OVERRIDE    I57 @S9S_MB_2U_LIB.S9S_MB_2U(SCH_1):PAGE13
  CY55 RST_CPU0_DRAM_GH_N @S9S_MB_2U_LIB.S9S_MB_2U(SCH_1):RST_CPU0_DRAM_GH_N    I57 @S9S_MB_2U_LIB.S9S_MB_2U(SCH_1):PAGE13
  CY42 RST_CPU0_DRAM_EF_N @S9S_MB_2U_LIB.S9S_MB_2U(SCH_1):RST_CPU0_DRAM_EF_N    I57 @S9S_MB_2U_LIB.S9S_MB_2U(SCH_1):PAGE13
  CT18 I3C_SPD_DDREFGH_CPU0_SDA @S9S_MB_2U_LIB.S9S_MB_2U(SCH_1):I3C_SPD_DDREFGH_CPU0_SDA    I57 @S9S_MB_2U_LIB.S9S_MB_2U(SCH_1):PAGE13
  CU17 I3C_SPD_DDREFGH_CPU0_SCL @S9S_MB_2U_LIB.S9S_MB_2U(SCH_1):I3C_SPD_DDREFGH_CPU0_SCL    I57 @S9S_MB_2U_LIB.S9S_MB_2U(SCH_1):PAGE13
  AV51 RST_CPU0_DRAM_CD_N @S9S_MB_2U_LIB.S9S_MB_2U(SCH_1):RST_CPU0_DRAM_CD_N    I57 @S9S_MB_2U_LIB.S9S_MB_2U(SCH_1):PAGE13
  AU50 RST_CPU0_DRAM_AB_N @S9S_MB_2U_LIB.S9S_MB_2U(SCH_1):RST_CPU0_DRAM_AB_N    I57 @S9S_MB_2U_LIB.S9S_MB_2U(SCH_1):PAGE13
  BY22 I3C_SPD_DDRABCD_CPU0_SDA @S9S_MB_2U_LIB.S9S_MB_2U(SCH_1):I3C_SPD_DDRABCD_CPU0_SDA    I57 @S9S_MB_2U_LIB.S9S_MB_2U(SCH_1):PAGE13
  BT22 I3C_SPD_DDRABCD_CPU0_SCL @S9S_MB_2U_LIB.S9S_MB_2U(SCH_1):I3C_SPD_DDRABCD_CPU0_SCL    I57 @S9S_MB_2U_LIB.S9S_MB_2U(SCH_1):PAGE13
  BN23 H_CPU0_BMCINIT_LVC1 @S9S_MB_2U_LIB.S9S_MB_2U(SCH_1):H_CPU0_BMCINIT_LVC1    I57 @S9S_MB_2U_LIB.S9S_MB_2U(SCH_1):PAGE13
  AT18 PD_CPU0_BIST_ENABLE @S9S_MB_2U_LIB.S9S_MB_2U(SCH_1):PD_CPU0_BIST_ENABLE    I57 @S9S_MB_2U_LIB.S9S_MB_2U(SCH_1):PAGE13
  DA27 CLK_100M_DB2000_CPU0_BCLK3_DP @S9S_MB_2U_LIB.S9S_MB_2U(SCH_1):CLK_100M_DB2000_CPU0_BCLK3_DP    I57 @S9S_MB_2U_LIB.S9S_MB_2U(SCH_1):PAGE13
  CW27 CLK_100M_DB2000_CPU0_BCLK3_DN @S9S_MB_2U_LIB.S9S_MB_2U(SCH_1):CLK_100M_DB2000_CPU0_BCLK3_DN    I57 @S9S_MB_2U_LIB.S9S_MB_2U(SCH_1):PAGE13
  AV28 CLK_100M_DB2000_CPU0_BCLK2_DP @S9S_MB_2U_LIB.S9S_MB_2U(SCH_1):CLK_100M_DB2000_CPU0_BCLK2_DP    I57 @S9S_MB_2U_LIB.S9S_MB_2U(SCH_1):PAGE13
  AU29 CLK_100M_DB2000_CPU0_BCLK2_DN @S9S_MB_2U_LIB.S9S_MB_2U(SCH_1):CLK_100M_DB2000_CPU0_BCLK2_DN    I57 @S9S_MB_2U_LIB.S9S_MB_2U(SCH_1):PAGE13
  AV30 CLK_100M_DB2000_CPU0_BCLK0_DP @S9S_MB_2U_LIB.S9S_MB_2U(SCH_1):CLK_100M_DB2000_CPU0_BCLK0_DP    I57 @S9S_MB_2U_LIB.S9S_MB_2U(SCH_1):PAGE13
  CY28 CLK_100M_DB2000_CPU0_BCLK1_DN @S9S_MB_2U_LIB.S9S_MB_2U(SCH_1):CLK_100M_DB2000_CPU0_BCLK1_DN    I57 @S9S_MB_2U_LIB.S9S_MB_2U(SCH_1):PAGE13
  CW29 CLK_100M_DB2000_CPU0_BCLK1_DP @S9S_MB_2U_LIB.S9S_MB_2U(SCH_1):CLK_100M_DB2000_CPU0_BCLK1_DP    I57 @S9S_MB_2U_LIB.S9S_MB_2U(SCH_1):PAGE13
  AT30 CLK_100M_DB2000_CPU0_BCLK0_DN @S9S_MB_2U_LIB.S9S_MB_2U(SCH_1):CLK_100M_DB2000_CPU0_BCLK0_DN    I57 @S9S_MB_2U_LIB.S9S_MB_2U(SCH_1):PAGE13
  CL72 PUD_XTAL_CPU0_MODE0 @S9S_MB_2U_LIB.S9S_MB_2U(SCH_1):PUD_XTAL_CPU0_MODE0    I57 @S9S_MB_2U_LIB.S9S_MB_2U(SCH_1):PAGE13
    D4 NC_XTAL_CPU0_25M_OUT @S9S_MB_2U_LIB.S9S_MB_2U(SCH_1):NC_XTAL_CPU0_25M_OUT    I57 @S9S_MB_2U_LIB.S9S_MB_2U(SCH_1):PAGE13
  CW31 CLK_25M_NSSC_CPU0_DN @S9S_MB_2U_LIB.S9S_MB_2U(SCH_1):CLK_25M_NSSC_CPU0_DN    I57 @S9S_MB_2U_LIB.S9S_MB_2U(SCH_1):PAGE13
  BP24 H_CPU0_CATERR_LVC1_R_N @S9S_MB_2U_LIB.S9S_MB_2U(SCH_1):H_CPU0_CATERR_LVC1_R_N     I1 @S9S_MB_2U_LIB.S9S_MB_2U(SCH_1):PAGE14
  CA25 SMB_PEHPCPU0_GTL_SCL @S9S_MB_2U_LIB.S9S_MB_2U(SCH_1):SMB_PEHPCPU0_GTL_SCL     I1 @S9S_MB_2U_LIB.S9S_MB_2U(SCH_1):PAGE14
  BY26 SMB_PEHPCPU0_GTL_SDA @S9S_MB_2U_LIB.S9S_MB_2U(SCH_1):SMB_PEHPCPU0_GTL_SDA     I1 @S9S_MB_2U_LIB.S9S_MB_2U(SCH_1):PAGE14
  BV26 FM_PEHPCPU0_ALERT_N @S9S_MB_2U_LIB.S9S_MB_2U(SCH_1):FM_PEHPCPU0_ALERT_N     I1 @S9S_MB_2U_LIB.S9S_MB_2U(SCH_1):PAGE14
   A43 PWRGD_DRAMPWRGD_CPU0_AB_LVC1_R @S9S_MB_2U_LIB.S9S_MB_2U(SCH_1):PWRGD_DRAMPWRGD_CPU0_AB_LVC1_R     I1 @S9S_MB_2U_LIB.S9S_MB_2U(SCH_1):PAGE14
   F47 PWRGD_DRAMPWRGD_CPU0_CD_LVC1_R @S9S_MB_2U_LIB.S9S_MB_2U(SCH_1):PWRGD_DRAMPWRGD_CPU0_CD_LVC1_R     I1 @S9S_MB_2U_LIB.S9S_MB_2U(SCH_1):PAGE14
  CY44 PWRGD_DRAMPWRGD_CPU0_EF_LVC1_R @S9S_MB_2U_LIB.S9S_MB_2U(SCH_1):PWRGD_DRAMPWRGD_CPU0_EF_LVC1_R     I1 @S9S_MB_2U_LIB.S9S_MB_2U(SCH_1):PAGE14
  CW45 PWRGD_DRAMPWRGD_CPU0_GH_LVC1_R @S9S_MB_2U_LIB.S9S_MB_2U(SCH_1):PWRGD_DRAMPWRGD_CPU0_GH_LVC1_R     I1 @S9S_MB_2U_LIB.S9S_MB_2U(SCH_1):PAGE14
  CH22 PD_CPU0_ENH_MCECC_DIS @S9S_MB_2U_LIB.S9S_MB_2U(SCH_1):PD_CPU0_ENH_MCECC_DIS     I1 @S9S_MB_2U_LIB.S9S_MB_2U(SCH_1):PAGE14
  BD22 H_CPU0_ERR2_LVC1_R_N @S9S_MB_2U_LIB.S9S_MB_2U(SCH_1):H_CPU0_ERR2_LVC1_R_N     I1 @S9S_MB_2U_LIB.S9S_MB_2U(SCH_1):PAGE14
  AY22 H_CPU0_ERR1_LVC1_R_N @S9S_MB_2U_LIB.S9S_MB_2U(SCH_1):H_CPU0_ERR1_LVC1_R_N     I1 @S9S_MB_2U_LIB.S9S_MB_2U(SCH_1):PAGE14
  BF22 H_CPU0_ERR0_LVC1_R_N @S9S_MB_2U_LIB.S9S_MB_2U(SCH_1):H_CPU0_ERR0_LVC1_R_N     I1 @S9S_MB_2U_LIB.S9S_MB_2U(SCH_1):PAGE14
  AV57 FM_CPU_FBRK_DEBUG_R_N @S9S_MB_2U_LIB.S9S_MB_2U(SCH_1):FM_CPU_FBRK_DEBUG_R_N     I1 @S9S_MB_2U_LIB.S9S_MB_2U(SCH_1):PAGE14
  AU21 H_CPU0_MEMHOT_IN_LVC1_N @S9S_MB_2U_LIB.S9S_MB_2U(SCH_1):H_CPU0_MEMHOT_IN_LVC1_N     I1 @S9S_MB_2U_LIB.S9S_MB_2U(SCH_1):PAGE14
  CF26 H_CPU0_MEMHOT_OUT_LVC1_R_N @S9S_MB_2U_LIB.S9S_MB_2U(SCH_1):H_CPU0_MEMHOT_OUT_LVC1_R_N     I1 @S9S_MB_2U_LIB.S9S_MB_2U(SCH_1):PAGE14
  AV24 H_CPU0_MEMTRIP_LVC1_R_N @S9S_MB_2U_LIB.S9S_MB_2U(SCH_1):H_CPU0_MEMTRIP_LVC1_R_N     I1 @S9S_MB_2U_LIB.S9S_MB_2U(SCH_1):PAGE14
  AV18 H_CPU0_NMI_LVC1_N @S9S_MB_2U_LIB.S9S_MB_2U(SCH_1):H_CPU0_NMI_LVC1_N     I1 @S9S_MB_2U_LIB.S9S_MB_2U(SCH_1):PAGE14
  CP71 PD_PIROM_CPU0_ADDR2 @S9S_MB_2U_LIB.S9S_MB_2U(SCH_1):PD_PIROM_CPU0_ADDR2     I1 @S9S_MB_2U_LIB.S9S_MB_2U(SCH_1):PAGE14
  CT71 PD_PIROM_CPU0_ADDR1 @S9S_MB_2U_LIB.S9S_MB_2U(SCH_1):PD_PIROM_CPU0_ADDR1     I1 @S9S_MB_2U_LIB.S9S_MB_2U(SCH_1):PAGE14
  CR70 PD_PIROM_CPU0_ADDR0 @S9S_MB_2U_LIB.S9S_MB_2U(SCH_1):PD_PIROM_CPU0_ADDR0     I1 @S9S_MB_2U_LIB.S9S_MB_2U(SCH_1):PAGE14
  CU70 SMB_S3M_CPU0_PIROM_3V3AUX_SCL_1 @S9S_MB_2U_LIB.S9S_MB_2U(SCH_1):SMB_S3M_CPU0_PIROM_3V3AUX_SCL_R1     I1 @S9S_MB_2U_LIB.S9S_MB_2U(SCH_1):PAGE14
  CM71 SMB_S3M_CPU0_PIROM_3V3AUX_SDA_1 @S9S_MB_2U_LIB.S9S_MB_2U(SCH_1):SMB_S3M_CPU0_PIROM_3V3AUX_SDA_R1     I1 @S9S_MB_2U_LIB.S9S_MB_2U(SCH_1):PAGE14
  CR72 PU_PIROM_CPU0_SM_WP @S9S_MB_2U_LIB.S9S_MB_2U(SCH_1):PU_PIROM_CPU0_SM_WP     I1 @S9S_MB_2U_LIB.S9S_MB_2U(SCH_1):PAGE14
  CC25 TP_H_SBLINK7_CPU0_PMDOWN @S9S_MB_2U_LIB.S9S_MB_2U(SCH_1):TP_H_SBLINK7_CPU0_PMDOWN     I1 @S9S_MB_2U_LIB.S9S_MB_2U(SCH_1):PAGE14
  CE23 TP_H_SBLINK6_CPU0_PMDOWN @S9S_MB_2U_LIB.S9S_MB_2U(SCH_1):TP_H_SBLINK6_CPU0_PMDOWN     I1 @S9S_MB_2U_LIB.S9S_MB_2U(SCH_1):PAGE14
  CV18 TP_H_SBLINK5_CPU0_PMDOWN @S9S_MB_2U_LIB.S9S_MB_2U(SCH_1):TP_H_SBLINK5_CPU0_PMDOWN     I1 @S9S_MB_2U_LIB.S9S_MB_2U(SCH_1):PAGE14
  CD24 TP_H_SBLINK4_CPU0_PMDOWN @S9S_MB_2U_LIB.S9S_MB_2U(SCH_1):TP_H_SBLINK4_CPU0_PMDOWN     I1 @S9S_MB_2U_LIB.S9S_MB_2U(SCH_1):PAGE14
  CM26 TP_H_SBLINK3_CPU0_PMDOWN @S9S_MB_2U_LIB.S9S_MB_2U(SCH_1):TP_H_SBLINK3_CPU0_PMDOWN     I1 @S9S_MB_2U_LIB.S9S_MB_2U(SCH_1):PAGE14
  CP26 TP_H_SBLINK2_CPU0_PMDOWN @S9S_MB_2U_LIB.S9S_MB_2U(SCH_1):TP_H_SBLINK2_CPU0_PMDOWN     I1 @S9S_MB_2U_LIB.S9S_MB_2U(SCH_1):PAGE14
  CW39 H_CPU0_PMDOWN_CPU1_R @S9S_MB_2U_LIB.S9S_MB_2U(SCH_1):H_CPU0_PMDOWN_CPU1_R     I1 @S9S_MB_2U_LIB.S9S_MB_2U(SCH_1):PAGE14
  CY40 H_CPU0_PMDOWN_PCH_R2 @S9S_MB_2U_LIB.S9S_MB_2U(SCH_1):H_CPU0_PMDOWN_PCH_R2     I1 @S9S_MB_2U_LIB.S9S_MB_2U(SCH_1):PAGE14
  CP20 H_CPU0_PM_FAST_WAKE_N @S9S_MB_2U_LIB.S9S_MB_2U(SCH_1):H_CPU0_PM_FAST_WAKE_N     I1 @S9S_MB_2U_LIB.S9S_MB_2U(SCH_1):PAGE14
  CF24 TP_H_SBLINK7_CPU0_PMSYNC @S9S_MB_2U_LIB.S9S_MB_2U(SCH_1):TP_H_SBLINK7_CPU0_PMSYNC     I1 @S9S_MB_2U_LIB.S9S_MB_2U(SCH_1):PAGE14
  CH24 TP_H_SBLINK6_CPU0_PMSYNC @S9S_MB_2U_LIB.S9S_MB_2U(SCH_1):TP_H_SBLINK6_CPU0_PMSYNC     I1 @S9S_MB_2U_LIB.S9S_MB_2U(SCH_1):PAGE14
  CR19 TP_H_SBLINK5_CPU0_PMSYNC @S9S_MB_2U_LIB.S9S_MB_2U(SCH_1):TP_H_SBLINK5_CPU0_PMSYNC     I1 @S9S_MB_2U_LIB.S9S_MB_2U(SCH_1):PAGE14
  CE25 TP_H_SBLINK4_CPU0_PMSYNC @S9S_MB_2U_LIB.S9S_MB_2U(SCH_1):TP_H_SBLINK4_CPU0_PMSYNC     I1 @S9S_MB_2U_LIB.S9S_MB_2U(SCH_1):PAGE14
  CH26 TP_H_SBLINK3_CPU0_PMSYNC @S9S_MB_2U_LIB.S9S_MB_2U(SCH_1):TP_H_SBLINK3_CPU0_PMSYNC     I1 @S9S_MB_2U_LIB.S9S_MB_2U(SCH_1):PAGE14
  CL25 TP_H_SBLINK2_CPU0_PMSYNC @S9S_MB_2U_LIB.S9S_MB_2U(SCH_1):TP_H_SBLINK2_CPU0_PMSYNC     I1 @S9S_MB_2U_LIB.S9S_MB_2U(SCH_1):PAGE14
  CN25 H_CPU0_PMSYNC_CPU1_R @S9S_MB_2U_LIB.S9S_MB_2U(SCH_1):H_CPU0_PMSYNC_CPU1_R     I1 @S9S_MB_2U_LIB.S9S_MB_2U(SCH_1):PAGE14
  DA39 H_CPU0_PMSYNC_PCH @S9S_MB_2U_LIB.S9S_MB_2U(SCH_1):H_CPU0_PMSYNC_PCH     I1 @S9S_MB_2U_LIB.S9S_MB_2U(SCH_1):PAGE14
  AU19 H_CPU0_PROCHOT_LVC1_N @S9S_MB_2U_LIB.S9S_MB_2U(SCH_1):H_CPU0_PROCHOT_LVC1_N     I1 @S9S_MB_2U_LIB.S9S_MB_2U(SCH_1):PAGE14
  AV20 PWRGD_CPU0_LVC1 @S9S_MB_2U_LIB.S9S_MB_2U(SCH_1):PWRGD_CPU0_LVC1     I1 @S9S_MB_2U_LIB.S9S_MB_2U(SCH_1):PAGE14
  BH61 RST_CPU0_LVC1_N @S9S_MB_2U_LIB.S9S_MB_2U(SCH_1):RST_CPU0_LVC1_N     I1 @S9S_MB_2U_LIB.S9S_MB_2U(SCH_1):PAGE14
  CL21 TP_IBL_PLT_RST_SYNC_N @S9S_MB_2U_LIB.S9S_MB_2U(SCH_1):TP_IBL_PLT_RST_SYNC_N     I1 @S9S_MB_2U_LIB.S9S_MB_2U(SCH_1):PAGE14
  CL64 NC_CPU0_VIEWPIN_DIE11<3> @S9S_MB_2U_LIB.S9S_MB_2U(SCH_1):NC_CPU0_VIEWPIN_DIE11(3)     I1 @S9S_MB_2U_LIB.S9S_MB_2U(SCH_1):PAGE14
  CM63 NC_CPU0_VIEWPIN_DIE11<2> @S9S_MB_2U_LIB.S9S_MB_2U(SCH_1):NC_CPU0_VIEWPIN_DIE11(2)     I1 @S9S_MB_2U_LIB.S9S_MB_2U(SCH_1):PAGE14
  CN62 NC_CPU0_VIEWPIN_DIE11<1> @S9S_MB_2U_LIB.S9S_MB_2U(SCH_1):NC_CPU0_VIEWPIN_DIE11(1)     I1 @S9S_MB_2U_LIB.S9S_MB_2U(SCH_1):PAGE14
  CR23 NC_CPU0_VIEWPIN_DIE10<0> @S9S_MB_2U_LIB.S9S_MB_2U(SCH_1):NC_CPU0_VIEWPIN_DIE10(0)     I1 @S9S_MB_2U_LIB.S9S_MB_2U(SCH_1):PAGE14
  CV24 NC_CPU0_VIEWPIN_DIE10<2> @S9S_MB_2U_LIB.S9S_MB_2U(SCH_1):NC_CPU0_VIEWPIN_DIE10(2)     I1 @S9S_MB_2U_LIB.S9S_MB_2U(SCH_1):PAGE14
  CW23 NC_CPU0_VIEWPIN_DIE10<3> @S9S_MB_2U_LIB.S9S_MB_2U(SCH_1):NC_CPU0_VIEWPIN_DIE10(3)     I1 @S9S_MB_2U_LIB.S9S_MB_2U(SCH_1):PAGE14
  CW25 NC_CPU0_VIEWPIN_DIE10<1> @S9S_MB_2U_LIB.S9S_MB_2U(SCH_1):NC_CPU0_VIEWPIN_DIE10(1)     I1 @S9S_MB_2U_LIB.S9S_MB_2U(SCH_1):PAGE14
  CW68 NC_CPU0_RSVD<144> @S9S_MB_2U_LIB.S9S_MB_2U(SCH_1):NC_CPU0_RSVD(144)     I1 @S9S_MB_2U_LIB.S9S_MB_2U(SCH_1):PAGE14
  AV26 NC_CPU0_VIEWPIN_DIE00<3> @S9S_MB_2U_LIB.S9S_MB_2U(SCH_1):NC_CPU0_VIEWPIN_DIE00(3)     I1 @S9S_MB_2U_LIB.S9S_MB_2U(SCH_1):PAGE14
  AY26 NC_CPU0_VIEWPIN_DIE00<0> @S9S_MB_2U_LIB.S9S_MB_2U(SCH_1):NC_CPU0_VIEWPIN_DIE00(0)     I1 @S9S_MB_2U_LIB.S9S_MB_2U(SCH_1):PAGE14
  AY65 NC_CPU0_VIEWPIN_DIE01<2> @S9S_MB_2U_LIB.S9S_MB_2U(SCH_1):NC_CPU0_VIEWPIN_DIE01(2)     I1 @S9S_MB_2U_LIB.S9S_MB_2U(SCH_1):PAGE14
  AT24 NC_CPU0_VIEWPIN_DIE00<1> @S9S_MB_2U_LIB.S9S_MB_2U(SCH_1):NC_CPU0_VIEWPIN_DIE00(1)     I1 @S9S_MB_2U_LIB.S9S_MB_2U(SCH_1):PAGE14
  BJ70 NC_CPU0_VIEWPIN_DIE01<3> @S9S_MB_2U_LIB.S9S_MB_2U(SCH_1):NC_CPU0_VIEWPIN_DIE01(3)     I1 @S9S_MB_2U_LIB.S9S_MB_2U(SCH_1):PAGE14
  AU25 NC_CPU0_VIEWPIN_DIE00<2> @S9S_MB_2U_LIB.S9S_MB_2U(SCH_1):NC_CPU0_VIEWPIN_DIE00(2)     I1 @S9S_MB_2U_LIB.S9S_MB_2U(SCH_1):PAGE14
  BP67 NC_CPU0_VIEWPIN_DIE01<1> @S9S_MB_2U_LIB.S9S_MB_2U(SCH_1):NC_CPU0_VIEWPIN_DIE01(1)     I1 @S9S_MB_2U_LIB.S9S_MB_2U(SCH_1):PAGE14
  BP69 NC_CPU0_VIEWPIN_DIE01<0> @S9S_MB_2U_LIB.S9S_MB_2U(SCH_1):NC_CPU0_VIEWPIN_DIE01(0)     I1 @S9S_MB_2U_LIB.S9S_MB_2U(SCH_1):PAGE14
  CJ62 NC_CPU0_VIEWPIN_DIE11<0> @S9S_MB_2U_LIB.S9S_MB_2U(SCH_1):NC_CPU0_VIEWPIN_DIE11(0)     I1 @S9S_MB_2U_LIB.S9S_MB_2U(SCH_1):PAGE14
  CG66 FM_CPU0_SKTOCC_LVT3_N @S9S_MB_2U_LIB.S9S_MB_2U(SCH_1):FM_CPU0_SKTOCC_LVT3_N     I1 @S9S_MB_2U_LIB.S9S_MB_2U(SCH_1):PAGE14
  BK26 SVID_ALERT0_CPU0_N @S9S_MB_2U_LIB.S9S_MB_2U(SCH_1):SVID_ALERT0_CPU0_N     I1 @S9S_MB_2U_LIB.S9S_MB_2U(SCH_1):PAGE14
  BJ25 SVID_ALERT1_CPU0_N @S9S_MB_2U_LIB.S9S_MB_2U(SCH_1):SVID_ALERT1_CPU0_N     I1 @S9S_MB_2U_LIB.S9S_MB_2U(SCH_1):PAGE14
  BH26 SVID_CLK0_CPU0 @S9S_MB_2U_LIB.S9S_MB_2U(SCH_1):SVID_CLK0_CPU0     I1 @S9S_MB_2U_LIB.S9S_MB_2U(SCH_1):PAGE14
  BF26 SVID_CLK1_CPU0 @S9S_MB_2U_LIB.S9S_MB_2U(SCH_1):SVID_CLK1_CPU0     I1 @S9S_MB_2U_LIB.S9S_MB_2U(SCH_1):PAGE14
  BD26 SVID_DIO0_CPU0 @S9S_MB_2U_LIB.S9S_MB_2U(SCH_1):SVID_DIO0_CPU0     I1 @S9S_MB_2U_LIB.S9S_MB_2U(SCH_1):PAGE14
  BL25 SVID_DIO1_CPU0 @S9S_MB_2U_LIB.S9S_MB_2U(SCH_1):SVID_DIO1_CPU0     I1 @S9S_MB_2U_LIB.S9S_MB_2U(SCH_1):PAGE14
  AY20 PU_TAP_ODT_CPU0_EN @S9S_MB_2U_LIB.S9S_MB_2U(SCH_1):PU_TAP_ODT_CPU0_EN     I1 @S9S_MB_2U_LIB.S9S_MB_2U(SCH_1):PAGE14
  AV59 TP_EV_CPU0_EXT_BGREF @S9S_MB_2U_LIB.S9S_MB_2U(SCH_1):TP_EV_CPU0_EXT_BGREF     I1 @S9S_MB_2U_LIB.S9S_MB_2U(SCH_1):PAGE14
  BL62 H_CPU0_THERMTRIP_LVC1_R_N @S9S_MB_2U_LIB.S9S_MB_2U(SCH_1):H_CPU0_THERMTRIP_LVC1_R_N     I1 @S9S_MB_2U_LIB.S9S_MB_2U(SCH_1):PAGE14
  CV20 PWRGD_PLT_AUX_CPU0_LVT3 @S9S_MB_2U_LIB.S9S_MB_2U(SCH_1):PWRGD_PLT_AUX_CPU0_LVT3     I1 @S9S_MB_2U_LIB.S9S_MB_2U(SCH_1):PAGE15
  CK22 TP_FM_IBL_SYS_RST_CPU0_N @S9S_MB_2U_LIB.S9S_MB_2U(SCH_1):TP_FM_IBL_SYS_RST_CPU0_N     I1 @S9S_MB_2U_LIB.S9S_MB_2U(SCH_1):PAGE15
  CK24 TP_CPU0_PWRBTN_N @S9S_MB_2U_LIB.S9S_MB_2U(SCH_1):TP_CPU0_PWRBTN_N     I1 @S9S_MB_2U_LIB.S9S_MB_2U(SCH_1):PAGE15
  CL23 TP_I2C_S3M_RTC_CPU0_SCL @S9S_MB_2U_LIB.S9S_MB_2U(SCH_1):TP_I2C_S3M_RTC_CPU0_SCL     I1 @S9S_MB_2U_LIB.S9S_MB_2U(SCH_1):PAGE15
  AU62 TP_SPI_IBL_CPU0_TPM_CLK @S9S_MB_2U_LIB.S9S_MB_2U(SCH_1):TP_SPI_IBL_CPU0_TPM_CLK     I1 @S9S_MB_2U_LIB.S9S_MB_2U(SCH_1):PAGE15
  CL66 TP_CPU0_SSC_SYNC @S9S_MB_2U_LIB.S9S_MB_2U(SCH_1):TP_CPU0_SSC_SYNC     I1 @S9S_MB_2U_LIB.S9S_MB_2U(SCH_1):PAGE15
  CN21 TP_IBL_SLPS4_CPU0_R_N @S9S_MB_2U_LIB.S9S_MB_2U(SCH_1):TP_IBL_SLPS4_CPU0_R_N     I1 @S9S_MB_2U_LIB.S9S_MB_2U(SCH_1):PAGE15
  CN23 TP_FM_IBL_ADR_ACK_CPU0 @S9S_MB_2U_LIB.S9S_MB_2U(SCH_1):TP_FM_IBL_ADR_ACK_CPU0     I1 @S9S_MB_2U_LIB.S9S_MB_2U(SCH_1):PAGE15
  AU64 TP_ESPI_IBL_CPU0_IO2_LVC1 @S9S_MB_2U_LIB.S9S_MB_2U(SCH_1):TP_ESPI_IBL_CPU0_IO2_LVC1     I1 @S9S_MB_2U_LIB.S9S_MB_2U(SCH_1):PAGE15
  CP22 TP_JTAG_CPU0_PLD_TDO @S9S_MB_2U_LIB.S9S_MB_2U(SCH_1):TP_JTAG_CPU0_PLD_TDO     I1 @S9S_MB_2U_LIB.S9S_MB_2U(SCH_1):PAGE15
  CP24 TP_FM_IBL_ADR_COMPLETE_CPU0_R @S9S_MB_2U_LIB.S9S_MB_2U(SCH_1):TP_FM_IBL_ADR_COMPLETE_CPU0_R     I1 @S9S_MB_2U_LIB.S9S_MB_2U(SCH_1):PAGE15
  CR21 TP_IBL_SLPS3_CPU0_R_N @S9S_MB_2U_LIB.S9S_MB_2U(SCH_1):TP_IBL_SLPS3_CPU0_R_N     I1 @S9S_MB_2U_LIB.S9S_MB_2U(SCH_1):PAGE15
  CT22 TP_JTAG_CPU0_PLD_TDI @S9S_MB_2U_LIB.S9S_MB_2U(SCH_1):TP_JTAG_CPU0_PLD_TDI     I1 @S9S_MB_2U_LIB.S9S_MB_2U(SCH_1):PAGE15
  CT24 TP_FM_IBL_ADR_TRIGGER_CPU0_R @S9S_MB_2U_LIB.S9S_MB_2U(SCH_1):TP_FM_IBL_ADR_TRIGGER_CPU0_R     I1 @S9S_MB_2U_LIB.S9S_MB_2U(SCH_1):PAGE15
  CV22 TP_JTAG_CPU0_PLD_TMS @S9S_MB_2U_LIB.S9S_MB_2U(SCH_1):TP_JTAG_CPU0_PLD_TMS     I1 @S9S_MB_2U_LIB.S9S_MB_2U(SCH_1):PAGE15
  CV69 NC_UART_IBL_CPU0_TXD @S9S_MB_2U_LIB.S9S_MB_2U(SCH_1):NC_UART_IBL_CPU0_TXD     I1 @S9S_MB_2U_LIB.S9S_MB_2U(SCH_1):PAGE15
  CV71 NC_UART_IBL_CPU0_CTS @S9S_MB_2U_LIB.S9S_MB_2U(SCH_1):NC_UART_IBL_CPU0_CTS     I1 @S9S_MB_2U_LIB.S9S_MB_2U(SCH_1):PAGE15
  CW21 TP_IBL_SLPS5_CPU0_R_N @S9S_MB_2U_LIB.S9S_MB_2U(SCH_1):TP_IBL_SLPS5_CPU0_R_N     I1 @S9S_MB_2U_LIB.S9S_MB_2U(SCH_1):PAGE15
  CY20 FM_S3M_CPU0_CPLD_CRC_ERROR @S9S_MB_2U_LIB.S9S_MB_2U(SCH_1):FM_S3M_CPU0_CPLD_CRC_ERROR     I1 @S9S_MB_2U_LIB.S9S_MB_2U(SCH_1):PAGE15
  CY22 PD_JTAG_CPU0_PLD_TCK @S9S_MB_2U_LIB.S9S_MB_2U(SCH_1):PD_JTAG_CPU0_PLD_TCK     I1 @S9S_MB_2U_LIB.S9S_MB_2U(SCH_1):PAGE15
  CY69 NC_UART_IBL_CPU0_RXD @S9S_MB_2U_LIB.S9S_MB_2U(SCH_1):NC_UART_IBL_CPU0_RXD     I1 @S9S_MB_2U_LIB.S9S_MB_2U(SCH_1):PAGE15
  CY71 NC_UART_IBL_CPU0_RTS @S9S_MB_2U_LIB.S9S_MB_2U(SCH_1):NC_UART_IBL_CPU0_RTS     I1 @S9S_MB_2U_LIB.S9S_MB_2U(SCH_1):PAGE15
  AV63 TP_SPI_S3M_CPU0_CS1_LVC1_R_N @S9S_MB_2U_LIB.S9S_MB_2U(SCH_1):TP_SPI_S3M_CPU0_CS1_LVC1_R_N     I1 @S9S_MB_2U_LIB.S9S_MB_2U(SCH_1):PAGE15
  AW19 TP_FM_IBL_WAKE_CPU0_N @S9S_MB_2U_LIB.S9S_MB_2U(SCH_1):TP_FM_IBL_WAKE_CPU0_N     I1 @S9S_MB_2U_LIB.S9S_MB_2U(SCH_1):PAGE15
  AW64 TP_SPI_S3M_CPU0_IO1_LVC1_R @S9S_MB_2U_LIB.S9S_MB_2U(SCH_1):TP_SPI_S3M_CPU0_IO1_LVC1_R     I1 @S9S_MB_2U_LIB.S9S_MB_2U(SCH_1):PAGE15
  AY61 TP_SPI_IBL_CPU0_TPM_IO1 @S9S_MB_2U_LIB.S9S_MB_2U(SCH_1):TP_SPI_IBL_CPU0_TPM_IO1     I1 @S9S_MB_2U_LIB.S9S_MB_2U(SCH_1):PAGE15
  AY67 TP_SPI_IBL_CPU0_TPM_CS0_N @S9S_MB_2U_LIB.S9S_MB_2U(SCH_1):TP_SPI_IBL_CPU0_TPM_CS0_N     I1 @S9S_MB_2U_LIB.S9S_MB_2U(SCH_1):PAGE15
  BA62 TP_SPI_S3M_CPU0_IO0_LVC1_R @S9S_MB_2U_LIB.S9S_MB_2U(SCH_1):TP_SPI_S3M_CPU0_IO0_LVC1_R     I1 @S9S_MB_2U_LIB.S9S_MB_2U(SCH_1):PAGE15
  BA66 TP_SPI_IBL_CPU0_TPM_IO0 @S9S_MB_2U_LIB.S9S_MB_2U(SCH_1):TP_SPI_IBL_CPU0_TPM_IO0     I1 @S9S_MB_2U_LIB.S9S_MB_2U(SCH_1):PAGE15
  BA68 TP_SPI_S3M_CPU0_OE_LVC1_R_N @S9S_MB_2U_LIB.S9S_MB_2U(SCH_1):TP_SPI_S3M_CPU0_OE_LVC1_R_N     I1 @S9S_MB_2U_LIB.S9S_MB_2U(SCH_1):PAGE15
  BB61 TP_SPI_S3M_CPU0_CS0_LVC1_R_N @S9S_MB_2U_LIB.S9S_MB_2U(SCH_1):TP_SPI_S3M_CPU0_CS0_LVC1_R_N     I1 @S9S_MB_2U_LIB.S9S_MB_2U(SCH_1):PAGE15
  BB67 TP_SPI_IBL_CPU0_TPM_OE_N @S9S_MB_2U_LIB.S9S_MB_2U(SCH_1):TP_SPI_IBL_CPU0_TPM_OE_N     I1 @S9S_MB_2U_LIB.S9S_MB_2U(SCH_1):PAGE15
  BC25 TP_I3C_MNG2_BMC_SW_SDA @S9S_MB_2U_LIB.S9S_MB_2U(SCH_1):TP_I3C_MNG2_BMC_SW_SDA     I1 @S9S_MB_2U_LIB.S9S_MB_2U(SCH_1):PAGE15
  BC64 TP_SPI_S3M_CPU0_CLK_LVC1_R @S9S_MB_2U_LIB.S9S_MB_2U(SCH_1):TP_SPI_S3M_CPU0_CLK_LVC1_R     I1 @S9S_MB_2U_LIB.S9S_MB_2U(SCH_1):PAGE15
  BD61 TP_SPI_S3M_CPU0_IO3_LVC1_R @S9S_MB_2U_LIB.S9S_MB_2U(SCH_1):TP_SPI_S3M_CPU0_IO3_LVC1_R     I1 @S9S_MB_2U_LIB.S9S_MB_2U(SCH_1):PAGE15
  BD63 TP_ESPI_IBL_CPU0_ALERT1_N @S9S_MB_2U_LIB.S9S_MB_2U(SCH_1):TP_ESPI_IBL_CPU0_ALERT1_N     I1 @S9S_MB_2U_LIB.S9S_MB_2U(SCH_1):PAGE15
  BD65 TP_SPI_S3M_CPU0_IO2_LVC1_R @S9S_MB_2U_LIB.S9S_MB_2U(SCH_1):TP_SPI_S3M_CPU0_IO2_LVC1_R     I1 @S9S_MB_2U_LIB.S9S_MB_2U(SCH_1):PAGE15
  BE25 TP_I3C_MNG2_BMC_SW_SCL @S9S_MB_2U_LIB.S9S_MB_2U(SCH_1):TP_I3C_MNG2_BMC_SW_SCL     I1 @S9S_MB_2U_LIB.S9S_MB_2U(SCH_1):PAGE15
  BE62 TP_ESPI_IBL_CPU0_ALERT0_LVC1_N @S9S_MB_2U_LIB.S9S_MB_2U(SCH_1):TP_ESPI_IBL_CPU0_ALERT0_LVC1_N     I1 @S9S_MB_2U_LIB.S9S_MB_2U(SCH_1):PAGE15
  BF65 TP_ESPI_IBL_CPU0_CS0_LVC1_N @S9S_MB_2U_LIB.S9S_MB_2U(SCH_1):TP_ESPI_IBL_CPU0_CS0_LVC1_N     I1 @S9S_MB_2U_LIB.S9S_MB_2U(SCH_1):PAGE15
  BG62 TP_CLK_66M_ESPI_IBL_CPU0_LVC1 @S9S_MB_2U_LIB.S9S_MB_2U(SCH_1):TP_CLK_66M_ESPI_IBL_CPU0_LVC1     I1 @S9S_MB_2U_LIB.S9S_MB_2U(SCH_1):PAGE15
  BG64 TP_RST_ESPI_IBL_CPU0_LVC1_N @S9S_MB_2U_LIB.S9S_MB_2U(SCH_1):TP_RST_ESPI_IBL_CPU0_LVC1_N     I1 @S9S_MB_2U_LIB.S9S_MB_2U(SCH_1):PAGE15
  BH63 TP_ESPI_IBL_CPU0_OE_LVC1_N @S9S_MB_2U_LIB.S9S_MB_2U(SCH_1):TP_ESPI_IBL_CPU0_OE_LVC1_N     I1 @S9S_MB_2U_LIB.S9S_MB_2U(SCH_1):PAGE15
  BH65 TP_ESPI_IBL_CPU0_CS1_N @S9S_MB_2U_LIB.S9S_MB_2U(SCH_1):TP_ESPI_IBL_CPU0_CS1_N     I1 @S9S_MB_2U_LIB.S9S_MB_2U(SCH_1):PAGE15
  BJ64 TP_ESPI_IBL_CPU0_IO1_LVC1 @S9S_MB_2U_LIB.S9S_MB_2U(SCH_1):TP_ESPI_IBL_CPU0_IO1_LVC1     I1 @S9S_MB_2U_LIB.S9S_MB_2U(SCH_1):PAGE15
  BK63 TP_ESPI_IBL_CPU0_IO0_LVC1 @S9S_MB_2U_LIB.S9S_MB_2U(SCH_1):TP_ESPI_IBL_CPU0_IO0_LVC1     I1 @S9S_MB_2U_LIB.S9S_MB_2U(SCH_1):PAGE15
  BM63 TP_ESPI_IBL_CPU0_IO3_LVC1 @S9S_MB_2U_LIB.S9S_MB_2U(SCH_1):TP_ESPI_IBL_CPU0_IO3_LVC1     I1 @S9S_MB_2U_LIB.S9S_MB_2U(SCH_1):PAGE15
  CD65 TP_SGPIO_S3M_CPU0_RST_R_N @S9S_MB_2U_LIB.S9S_MB_2U(SCH_1):TP_SGPIO_S3M_CPU0_RST_R_N     I1 @S9S_MB_2U_LIB.S9S_MB_2U(SCH_1):PAGE15
  CF61 PUD_PCH_BOOT_MODE_CPU0 @S9S_MB_2U_LIB.S9S_MB_2U(SCH_1):PUD_PCH_BOOT_MODE_CPU0     I1 @S9S_MB_2U_LIB.S9S_MB_2U(SCH_1):PAGE15
  CF63 TP_SGPIO_S3M_CPU0_GSXCLK_R @S9S_MB_2U_LIB.S9S_MB_2U(SCH_1):TP_SGPIO_S3M_CPU0_GSXCLK_R     I1 @S9S_MB_2U_LIB.S9S_MB_2U(SCH_1):PAGE15
  CF65 TP_SGPIO_S3M_CPU0_GSXDOUT_R @S9S_MB_2U_LIB.S9S_MB_2U(SCH_1):TP_SGPIO_S3M_CPU0_GSXDOUT_R     I1 @S9S_MB_2U_LIB.S9S_MB_2U(SCH_1):PAGE15
  CH63 TP_SGPIO_S3M_CPU0_GSXDIN @S9S_MB_2U_LIB.S9S_MB_2U(SCH_1):TP_SGPIO_S3M_CPU0_GSXDIN     I1 @S9S_MB_2U_LIB.S9S_MB_2U(SCH_1):PAGE15
  CH71 TP_PWRGD_S0_PWROK_CPU0_LVC1 @S9S_MB_2U_LIB.S9S_MB_2U(SCH_1):TP_PWRGD_S0_PWROK_CPU0_LVC1     I1 @S9S_MB_2U_LIB.S9S_MB_2U(SCH_1):PAGE15
  CJ21 TP_IBL_GRST_WARN_PLD_R_N @S9S_MB_2U_LIB.S9S_MB_2U(SCH_1):TP_IBL_GRST_WARN_PLD_R_N     I1 @S9S_MB_2U_LIB.S9S_MB_2U(SCH_1):PAGE15
  CJ23 TP_I2C_S3M_RTC_CPU0_SDA @S9S_MB_2U_LIB.S9S_MB_2U(SCH_1):TP_I2C_S3M_RTC_CPU0_SDA     I1 @S9S_MB_2U_LIB.S9S_MB_2U(SCH_1):PAGE15
  CJ25 TP_I2C_S3M_RTC_CPU0_ALERT_N @S9S_MB_2U_LIB.S9S_MB_2U(SCH_1):TP_I2C_S3M_RTC_CPU0_ALERT_N     I1 @S9S_MB_2U_LIB.S9S_MB_2U(SCH_1):PAGE15
  CJ66 TP_SGPIO_S3M_CPU0_GSXDLOAD_R @S9S_MB_2U_LIB.S9S_MB_2U(SCH_1):TP_SGPIO_S3M_CPU0_GSXDLOAD_R     I1 @S9S_MB_2U_LIB.S9S_MB_2U(SCH_1):PAGE15
  AW70 FM_S3M_CPU0_LVC1_GPIO_4 @S9S_MB_2U_LIB.S9S_MB_2U(SCH_1):FM_S3M_CPU0_LVC1_GPIO_4     I1 @S9S_MB_2U_LIB.S9S_MB_2U(SCH_1):PAGE15
  AY69 FM_S3M_CPU0_LVC1_GPIO_3 @S9S_MB_2U_LIB.S9S_MB_2U(SCH_1):FM_S3M_CPU0_LVC1_GPIO_3     I1 @S9S_MB_2U_LIB.S9S_MB_2U(SCH_1):PAGE15
  AV69 FM_S3M_CPU0_LVC1_GPIO_2 @S9S_MB_2U_LIB.S9S_MB_2U(SCH_1):FM_S3M_CPU0_LVC1_GPIO_2     I1 @S9S_MB_2U_LIB.S9S_MB_2U(SCH_1):PAGE15
  AV71 FM_S3M_CPU0_LVC1_GPIO_1 @S9S_MB_2U_LIB.S9S_MB_2U(SCH_1):FM_S3M_CPU0_LVC1_GPIO_1     I1 @S9S_MB_2U_LIB.S9S_MB_2U(SCH_1):PAGE15
  BA70 FM_S3M_CPU0_LVC1_GPIO_0 @S9S_MB_2U_LIB.S9S_MB_2U(SCH_1):FM_S3M_CPU0_LVC1_GPIO_0     I1 @S9S_MB_2U_LIB.S9S_MB_2U(SCH_1):PAGE15
  CE64 SMB_S3M_CPU0_SCL @S9S_MB_2U_LIB.S9S_MB_2U(SCH_1):SMB_S3M_CPU0_SCL     I1 @S9S_MB_2U_LIB.S9S_MB_2U(SCH_1):PAGE15
  CD63 SMB_S3M_CPU0_SDA @S9S_MB_2U_LIB.S9S_MB_2U(SCH_1):SMB_S3M_CPU0_SDA     I1 @S9S_MB_2U_LIB.S9S_MB_2U(SCH_1):PAGE15
  CJ64 PU_S3M_CPU0_CPLD_CONFD @S9S_MB_2U_LIB.S9S_MB_2U(SCH_1):PU_S3M_CPU0_CPLD_CONFD     I1 @S9S_MB_2U_LIB.S9S_MB_2U(SCH_1):PAGE15
  CK65 FM_S3M_CPU0_CPLD_CONFIG_N @S9S_MB_2U_LIB.S9S_MB_2U(SCH_1):FM_S3M_CPU0_CPLD_CONFIG_N     I1 @S9S_MB_2U_LIB.S9S_MB_2U(SCH_1):PAGE15
  CH65 PU_S3M_CPU0_CPLD_STATUS @S9S_MB_2U_LIB.S9S_MB_2U(SCH_1):PU_S3M_CPU0_CPLD_STATUS     I1 @S9S_MB_2U_LIB.S9S_MB_2U(SCH_1):PAGE15
  BC23 TP_CPU0_IFST_DONE_LVC1_R @S9S_MB_2U_LIB.S9S_MB_2U(SCH_1):TP_CPU0_IFST_DONE_LVC1_R     I1 @S9S_MB_2U_LIB.S9S_MB_2U(SCH_1):PAGE16
  BE23 TP_CPU0_IFST_KOT_LVC1_R @S9S_MB_2U_LIB.S9S_MB_2U(SCH_1):TP_CPU0_IFST_KOT_LVC1_R     I1 @S9S_MB_2U_LIB.S9S_MB_2U(SCH_1):PAGE16
  BF24 TP_CPU0_IFST_TRIG_LVC1_R @S9S_MB_2U_LIB.S9S_MB_2U(SCH_1):TP_CPU0_IFST_TRIG_LVC1_R     I1 @S9S_MB_2U_LIB.S9S_MB_2U(SCH_1):PAGE16
  BL23 DBP_CPU0_MBP0_GTL_R_N @S9S_MB_2U_LIB.S9S_MB_2U(SCH_1):DBP_CPU0_MBP0_GTL_R_N     I1 @S9S_MB_2U_LIB.S9S_MB_2U(SCH_1):PAGE16
  BN25 DBP_CPU0_MBP1_GTL_R_N @S9S_MB_2U_LIB.S9S_MB_2U(SCH_1):DBP_CPU0_MBP1_GTL_R_N     I1 @S9S_MB_2U_LIB.S9S_MB_2U(SCH_1):PAGE16
  BJ23 DBP_CPU0_HOOK8_MBP2_GTL_QS_R_N @S9S_MB_2U_LIB.S9S_MB_2U(SCH_1):DBP_CPU0_HOOK8_MBP2_GTL_QS_R_N     I1 @S9S_MB_2U_LIB.S9S_MB_2U(SCH_1):PAGE16
  BK24 DBP_CPU0_HOOK9_MBP3_GTL_QS_R_N @S9S_MB_2U_LIB.S9S_MB_2U(SCH_1):DBP_CPU0_HOOK9_MBP3_GTL_QS_R_N     I1 @S9S_MB_2U_LIB.S9S_MB_2U(SCH_1):PAGE16
  BD24 H_PMAX_TRIGGER_IO_CPU0 @S9S_MB_2U_LIB.S9S_MB_2U(SCH_1):H_PMAX_TRIGGER_IO_CPU0     I1 @S9S_MB_2U_LIB.S9S_MB_2U(SCH_1):PAGE16
  BH22 H_CPU0_RMCA_LVC1_R_N @S9S_MB_2U_LIB.S9S_MB_2U(SCH_1):H_CPU0_RMCA_LVC1_R_N     I1 @S9S_MB_2U_LIB.S9S_MB_2U(SCH_1):PAGE16
  AU58 NC_CPU0_DDR01_VIEWDIG0 @S9S_MB_2U_LIB.S9S_MB_2U(SCH_1):NC_CPU0_DDR01_VIEWDIG0     I1 @S9S_MB_2U_LIB.S9S_MB_2U(SCH_1):PAGE16
  CE62 NC_CPU0_LGSSPARE3 @S9S_MB_2U_LIB.S9S_MB_2U(SCH_1):NC_CPU0_LGSSPARE3     I1 @S9S_MB_2U_LIB.S9S_MB_2U(SCH_1):PAGE16
  CU62 NC_CPU0_LGSSPARE2 @S9S_MB_2U_LIB.S9S_MB_2U(SCH_1):NC_CPU0_LGSSPARE2     I1 @S9S_MB_2U_LIB.S9S_MB_2U(SCH_1):PAGE16
  CN60 NC_CPU0_LGSSPARE1 @S9S_MB_2U_LIB.S9S_MB_2U(SCH_1):NC_CPU0_LGSSPARE1     I1 @S9S_MB_2U_LIB.S9S_MB_2U(SCH_1):PAGE16
  CP61 NC_CPU0_LGSSPARE5 @S9S_MB_2U_LIB.S9S_MB_2U(SCH_1):NC_CPU0_LGSSPARE5     I1 @S9S_MB_2U_LIB.S9S_MB_2U(SCH_1):PAGE16
  CR60 NC_CPU0_LGSSPARE0 @S9S_MB_2U_LIB.S9S_MB_2U(SCH_1):NC_CPU0_LGSSPARE0     I1 @S9S_MB_2U_LIB.S9S_MB_2U(SCH_1):PAGE16
  CY24 NC_CPU0_DDR45_VIEWDIG0 @S9S_MB_2U_LIB.S9S_MB_2U(SCH_1):NC_CPU0_DDR45_VIEWDIG0     I1 @S9S_MB_2U_LIB.S9S_MB_2U(SCH_1):PAGE16
  CY38 NC_CPU0_DDR45_VIEWDIG1 @S9S_MB_2U_LIB.S9S_MB_2U(SCH_1):NC_CPU0_DDR45_VIEWDIG1     I1 @S9S_MB_2U_LIB.S9S_MB_2U(SCH_1):PAGE16
  CY49 NC_CPU0_DDR67_VIEWDIG1 @S9S_MB_2U_LIB.S9S_MB_2U(SCH_1):NC_CPU0_DDR67_VIEWDIG1     I1 @S9S_MB_2U_LIB.S9S_MB_2U(SCH_1):PAGE16
  DA45 NC_CPU0_DDR67_VIEWDIG0 @S9S_MB_2U_LIB.S9S_MB_2U(SCH_1):NC_CPU0_DDR67_VIEWDIG0     I1 @S9S_MB_2U_LIB.S9S_MB_2U(SCH_1):PAGE16
   H12 TP_CPU0_A0_DEBUG_EN @S9S_MB_2U_LIB.S9S_MB_2U(SCH_1):TP_CPU0_A0_DEBUG_EN     I1 @S9S_MB_2U_LIB.S9S_MB_2U(SCH_1):PAGE16
  AV32 NC_CPU0_DDR23_VIEWDIG0 @S9S_MB_2U_LIB.S9S_MB_2U(SCH_1):NC_CPU0_DDR23_VIEWDIG0     I1 @S9S_MB_2U_LIB.S9S_MB_2U(SCH_1):PAGE16
  AV38 NC_CPU0_THERMADC @S9S_MB_2U_LIB.S9S_MB_2U(SCH_1):NC_CPU0_THERMADC     I1 @S9S_MB_2U_LIB.S9S_MB_2U(SCH_1):PAGE16
  AV40 NC_CPU0_THERMADA @S9S_MB_2U_LIB.S9S_MB_2U(SCH_1):NC_CPU0_THERMADA     I1 @S9S_MB_2U_LIB.S9S_MB_2U(SCH_1):PAGE16
  AU33 NC_CPU0_DDR23_VIEWDIG1 @S9S_MB_2U_LIB.S9S_MB_2U(SCH_1):NC_CPU0_DDR23_VIEWDIG1     I1 @S9S_MB_2U_LIB.S9S_MB_2U(SCH_1):PAGE16
  AU56 NC_CPU0_DDR01_VIEWDIG1 @S9S_MB_2U_LIB.S9S_MB_2U(SCH_1):NC_CPU0_DDR01_VIEWDIG1     I1 @S9S_MB_2U_LIB.S9S_MB_2U(SCH_1):PAGE16
  CC64 NC_CPU0_LGSSPARE4 @S9S_MB_2U_LIB.S9S_MB_2U(SCH_1):NC_CPU0_LGSSPARE4     I1 @S9S_MB_2U_LIB.S9S_MB_2U(SCH_1):PAGE16
  BU11 VSENSE_PVCCD_HV_CPU0_DP @S9S_MB_2U_LIB.S9S_MB_2U(SCH_1):VSENSE_PVCCD_HV_CPU0_DP     I1 @S9S_MB_2U_LIB.S9S_MB_2U(SCH_1):PAGE16
  AY85 VSENSE_PVCCFA_EHV_FIVRA_CPU0_DP @S9S_MB_2U_LIB.S9S_MB_2U(SCH_1):VSENSE_PVCCFA_EHV_FIVRA_CPU0_DP     I1 @S9S_MB_2U_LIB.S9S_MB_2U(SCH_1):PAGE16
  AU11 VSENSE_PVCCFA_EHV_CPU0_DP @S9S_MB_2U_LIB.S9S_MB_2U(SCH_1):VSENSE_PVCCFA_EHV_CPU0_DP     I1 @S9S_MB_2U_LIB.S9S_MB_2U(SCH_1):PAGE16
  CA11 VSENSE_PVCCINFAON_CPU0_DP @S9S_MB_2U_LIB.S9S_MB_2U(SCH_1):VSENSE_PVCCINFAON_CPU0_DP     I1 @S9S_MB_2U_LIB.S9S_MB_2U(SCH_1):PAGE16
  BD87 VSENSE_PVCCIN_CPU0_DP @S9S_MB_2U_LIB.S9S_MB_2U(SCH_1):VSENSE_PVCCIN_CPU0_DP     I1 @S9S_MB_2U_LIB.S9S_MB_2U(SCH_1):PAGE16
  BN11 VSENSE_PVCCD_HV_CPU0_DN @S9S_MB_2U_LIB.S9S_MB_2U(SCH_1):VSENSE_PVCCD_HV_CPU0_DN     I1 @S9S_MB_2U_LIB.S9S_MB_2U(SCH_1):PAGE16
  AT85 VSENSE_PVCCFA_EHV_FIVRA_CPU0_DN @S9S_MB_2U_LIB.S9S_MB_2U(SCH_1):VSENSE_PVCCFA_EHV_FIVRA_CPU0_DN     I1 @S9S_MB_2U_LIB.S9S_MB_2U(SCH_1):PAGE16
  BA11 VSENSE_PVCCFA_EHV_CPU0_DN @S9S_MB_2U_LIB.S9S_MB_2U(SCH_1):VSENSE_PVCCFA_EHV_CPU0_DN     I1 @S9S_MB_2U_LIB.S9S_MB_2U(SCH_1):PAGE16
  CE11 VSENSE_PVCCINFAON_CPU0_DN @S9S_MB_2U_LIB.S9S_MB_2U(SCH_1):VSENSE_PVCCINFAON_CPU0_DN     I1 @S9S_MB_2U_LIB.S9S_MB_2U(SCH_1):PAGE16
  BC90 VSENSE_PVCCIN_CPU0_DN @S9S_MB_2U_LIB.S9S_MB_2U(SCH_1):VSENSE_PVCCIN_CPU0_DN     I1 @S9S_MB_2U_LIB.S9S_MB_2U(SCH_1):PAGE16
  AC78 NC_CPU0_HBM2_VIEWDIG0 @S9S_MB_2U_LIB.S9S_MB_2U(SCH_1):NC_CPU0_HBM2_VIEWDIG0     I1 @S9S_MB_2U_LIB.S9S_MB_2U(SCH_1):PAGE17
  AD77 NC_CPU0_HBM2_VIEWDIG1 @S9S_MB_2U_LIB.S9S_MB_2U(SCH_1):NC_CPU0_HBM2_VIEWDIG1     I1 @S9S_MB_2U_LIB.S9S_MB_2U(SCH_1):PAGE17
  CJ68 NC_CPU0_MDFI_DIE11_NS0 @S9S_MB_2U_LIB.S9S_MB_2U(SCH_1):NC_CPU0_MDFI_DIE11_NS0     I1 @S9S_MB_2U_LIB.S9S_MB_2U(SCH_1):PAGE17
  CJ70 NC_CPU0_MDFI_DIE11_EW0 @S9S_MB_2U_LIB.S9S_MB_2U(SCH_1):NC_CPU0_MDFI_DIE11_EW0     I1 @S9S_MB_2U_LIB.S9S_MB_2U(SCH_1):PAGE17
  CK67 NC_CPU0_MDFI_DIE11_NS1 @S9S_MB_2U_LIB.S9S_MB_2U(SCH_1):NC_CPU0_MDFI_DIE11_NS1     I1 @S9S_MB_2U_LIB.S9S_MB_2U(SCH_1):PAGE17
  CR25 NC_CPU0_VIEWPIN_GNR2 @S9S_MB_2U_LIB.S9S_MB_2U(SCH_1):NC_CPU0_VIEWPIN_GNR2     I1 @S9S_MB_2U_LIB.S9S_MB_2U(SCH_1):PAGE17
  CT26 NC_CPU0_VIEWPIN_GNR0 @S9S_MB_2U_LIB.S9S_MB_2U(SCH_1):NC_CPU0_VIEWPIN_GNR0     I1 @S9S_MB_2U_LIB.S9S_MB_2U(SCH_1):PAGE17
  CW41 NC_CPU0_HBM1_VIEWDIG1 @S9S_MB_2U_LIB.S9S_MB_2U(SCH_1):NC_CPU0_HBM1_VIEWDIG1     I1 @S9S_MB_2U_LIB.S9S_MB_2U(SCH_1):PAGE17
  CW58 NC_CPU0_VIEWPIN_GNR1 @S9S_MB_2U_LIB.S9S_MB_2U(SCH_1):NC_CPU0_VIEWPIN_GNR1     I1 @S9S_MB_2U_LIB.S9S_MB_2U(SCH_1):PAGE17
  CY57 NC_CPU0_VIEWPIN_GNR3 @S9S_MB_2U_LIB.S9S_MB_2U(SCH_1):NC_CPU0_VIEWPIN_GNR3     I1 @S9S_MB_2U_LIB.S9S_MB_2U(SCH_1):PAGE17
  EG17 NC_CPU0_HBM0_VIEWDIG1 @S9S_MB_2U_LIB.S9S_MB_2U(SCH_1):NC_CPU0_HBM0_VIEWDIG1     I1 @S9S_MB_2U_LIB.S9S_MB_2U(SCH_1):PAGE17
   U17 NC_CPU0_HBM0_VIEWDIG0 @S9S_MB_2U_LIB.S9S_MB_2U(SCH_1):NC_CPU0_HBM0_VIEWDIG0     I1 @S9S_MB_2U_LIB.S9S_MB_2U(SCH_1):PAGE17
   W17 NC_CPU0_HBM1_VIEWDIG0 @S9S_MB_2U_LIB.S9S_MB_2U(SCH_1):NC_CPU0_HBM1_VIEWDIG0     I1 @S9S_MB_2U_LIB.S9S_MB_2U(SCH_1):PAGE17
  AV65 NC_CPU0_MDFI_DIE01_EW0 @S9S_MB_2U_LIB.S9S_MB_2U(SCH_1):NC_CPU0_MDFI_DIE01_EW0     I1 @S9S_MB_2U_LIB.S9S_MB_2U(SCH_1):PAGE17
  AY24 NC_CPU0_SOC_SPARE0 @S9S_MB_2U_LIB.S9S_MB_2U(SCH_1):NC_CPU0_SOC_SPARE0     I1 @S9S_MB_2U_LIB.S9S_MB_2U(SCH_1):PAGE17
  BA25 NC_CPU0_SOC_SPARE4 @S9S_MB_2U_LIB.S9S_MB_2U(SCH_1):NC_CPU0_SOC_SPARE4     I1 @S9S_MB_2U_LIB.S9S_MB_2U(SCH_1):PAGE17
  BD71 NC_CPU0_MDFI_DIE01_NS1 @S9S_MB_2U_LIB.S9S_MB_2U(SCH_1):NC_CPU0_MDFI_DIE01_NS1     I1 @S9S_MB_2U_LIB.S9S_MB_2U(SCH_1):PAGE17
  BE21 TP_CPU0_DIE_HVM_EN_LVC1 @S9S_MB_2U_LIB.S9S_MB_2U(SCH_1):TP_CPU0_DIE_HVM_EN_LVC1     I1 @S9S_MB_2U_LIB.S9S_MB_2U(SCH_1):PAGE17
  BF71 NC_CPU0_MDFI_DIE01_NS0 @S9S_MB_2U_LIB.S9S_MB_2U(SCH_1):NC_CPU0_MDFI_DIE01_NS0     I1 @S9S_MB_2U_LIB.S9S_MB_2U(SCH_1):PAGE17
  BG78 NC_CPU0_HBM3_VIEWDIG0 @S9S_MB_2U_LIB.S9S_MB_2U(SCH_1):NC_CPU0_HBM3_VIEWDIG0     I1 @S9S_MB_2U_LIB.S9S_MB_2U(SCH_1):PAGE17
  BJ21 NC_CPU0_MDFI_DIE00_NS1 @S9S_MB_2U_LIB.S9S_MB_2U(SCH_1):NC_CPU0_MDFI_DIE00_NS1     I1 @S9S_MB_2U_LIB.S9S_MB_2U(SCH_1):PAGE17
  BK22 NC_CPU0_MDFI_DIE00_NS0 @S9S_MB_2U_LIB.S9S_MB_2U(SCH_1):NC_CPU0_MDFI_DIE00_NS0     I1 @S9S_MB_2U_LIB.S9S_MB_2U(SCH_1):PAGE17
  BL60 NC_CPU0_HBM3_VIEWDIG1 @S9S_MB_2U_LIB.S9S_MB_2U(SCH_1):NC_CPU0_HBM3_VIEWDIG1     I1 @S9S_MB_2U_LIB.S9S_MB_2U(SCH_1):PAGE17
  BM65 NC_CPU0_SOC_SPARE1 @S9S_MB_2U_LIB.S9S_MB_2U(SCH_1):NC_CPU0_SOC_SPARE1     I1 @S9S_MB_2U_LIB.S9S_MB_2U(SCH_1):PAGE17
  BP22 NC_CPU0_MDFI_DIE00_EW0 @S9S_MB_2U_LIB.S9S_MB_2U(SCH_1):NC_CPU0_MDFI_DIE00_EW0     I1 @S9S_MB_2U_LIB.S9S_MB_2U(SCH_1):PAGE17
  BP65 NC_CPU0_SOC_SPARE5 @S9S_MB_2U_LIB.S9S_MB_2U(SCH_1):NC_CPU0_SOC_SPARE5     I1 @S9S_MB_2U_LIB.S9S_MB_2U(SCH_1):PAGE17
  BR21 NC_CPU0_MDFI_DIE00_EW1 @S9S_MB_2U_LIB.S9S_MB_2U(SCH_1):NC_CPU0_MDFI_DIE00_EW1     I1 @S9S_MB_2U_LIB.S9S_MB_2U(SCH_1):PAGE17
  CC66 NC_CPU0_MDFI_DIE01_EW1 @S9S_MB_2U_LIB.S9S_MB_2U(SCH_1):NC_CPU0_MDFI_DIE01_EW1     I1 @S9S_MB_2U_LIB.S9S_MB_2U(SCH_1):PAGE17
  CD22 NC_CPU0_MDFI_DIE10_NS1 @S9S_MB_2U_LIB.S9S_MB_2U(SCH_1):NC_CPU0_MDFI_DIE10_NS1     I1 @S9S_MB_2U_LIB.S9S_MB_2U(SCH_1):PAGE17
  CD26 NC_CPU0_MDFI_DIE10_EW0 @S9S_MB_2U_LIB.S9S_MB_2U(SCH_1):NC_CPU0_MDFI_DIE10_EW0     I1 @S9S_MB_2U_LIB.S9S_MB_2U(SCH_1):PAGE17
  CD30 NC_CPU0_MDFI_DIE10_EW1 @S9S_MB_2U_LIB.S9S_MB_2U(SCH_1):NC_CPU0_MDFI_DIE10_EW1     I1 @S9S_MB_2U_LIB.S9S_MB_2U(SCH_1):PAGE17
  CF22 NC_CPU0_MDFI_DIE10_NS0 @S9S_MB_2U_LIB.S9S_MB_2U(SCH_1):NC_CPU0_MDFI_DIE10_NS0     I1 @S9S_MB_2U_LIB.S9S_MB_2U(SCH_1):PAGE17
  CH69 NC_CPU0_MDFI_DIE11_EW1 @S9S_MB_2U_LIB.S9S_MB_2U(SCH_1):NC_CPU0_MDFI_DIE11_EW1     I1 @S9S_MB_2U_LIB.S9S_MB_2U(SCH_1):PAGE17
  CL70 TP_CPU0_SPARE12 @S9S_MB_2U_LIB.S9S_MB_2U(SCH_1):TP_CPU0_SPARE12     I1 @S9S_MB_2U_LIB.S9S_MB_2U(SCH_1):PAGE18
  CL60 TP_CPU0_SPARE7 @S9S_MB_2U_LIB.S9S_MB_2U(SCH_1):TP_CPU0_SPARE7     I1 @S9S_MB_2U_LIB.S9S_MB_2U(SCH_1):PAGE18
  CW43 TP_CPU0_SPARE6 @S9S_MB_2U_LIB.S9S_MB_2U(SCH_1):TP_CPU0_SPARE6     I1 @S9S_MB_2U_LIB.S9S_MB_2U(SCH_1):PAGE18
  DA70 TP_CPU0_SPARE4 @S9S_MB_2U_LIB.S9S_MB_2U(SCH_1):TP_CPU0_SPARE4     I1 @S9S_MB_2U_LIB.S9S_MB_2U(SCH_1):PAGE18
  BD77 TP_CPU0_SPARE13 @S9S_MB_2U_LIB.S9S_MB_2U(SCH_1):TP_CPU0_SPARE13     I1 @S9S_MB_2U_LIB.S9S_MB_2U(SCH_1):PAGE18
  CH61 TP_CPU0_SPARE9 @S9S_MB_2U_LIB.S9S_MB_2U(SCH_1):TP_CPU0_SPARE9     I1 @S9S_MB_2U_LIB.S9S_MB_2U(SCH_1):PAGE18
  AU52 TP_CPU0_SPARE5 @S9S_MB_2U_LIB.S9S_MB_2U(SCH_1):TP_CPU0_SPARE5     I1 @S9S_MB_2U_LIB.S9S_MB_2U(SCH_1):PAGE18
  CD69 TP_CPU0_SPARE11 @S9S_MB_2U_LIB.S9S_MB_2U(SCH_1):TP_CPU0_SPARE11     I1 @S9S_MB_2U_LIB.S9S_MB_2U(SCH_1):PAGE18
  CK61 TP_CPU0_SPARE8 @S9S_MB_2U_LIB.S9S_MB_2U(SCH_1):TP_CPU0_SPARE8     I1 @S9S_MB_2U_LIB.S9S_MB_2U(SCH_1):PAGE18
  CG60 TP_CPU0_SPARE10 @S9S_MB_2U_LIB.S9S_MB_2U(SCH_1):TP_CPU0_SPARE10     I1 @S9S_MB_2U_LIB.S9S_MB_2U(SCH_1):PAGE18
   J13 TP_CPU0_PPD @S9S_MB_2U_LIB.S9S_MB_2U(SCH_1):TP_CPU0_PPD     I1 @S9S_MB_2U_LIB.S9S_MB_2U(SCH_1):PAGE18
  BP30 TP_TRC_CPU0_PTI<15> @S9S_MB_2U_LIB.S9S_MB_2U(SCH_1):TP_TRC_CPU0_PTI(15)     I1 @S9S_MB_2U_LIB.S9S_MB_2U(SCH_1):PAGE19
  BN29 TP_TRC_CPU0_PTI<14> @S9S_MB_2U_LIB.S9S_MB_2U(SCH_1):TP_TRC_CPU0_PTI(14)     I1 @S9S_MB_2U_LIB.S9S_MB_2U(SCH_1):PAGE19
  BP28 TP_TRC_CPU0_PTI<13> @S9S_MB_2U_LIB.S9S_MB_2U(SCH_1):TP_TRC_CPU0_PTI(13)     I1 @S9S_MB_2U_LIB.S9S_MB_2U(SCH_1):PAGE19
  BN27 TP_TRC_CPU0_PTI<12> @S9S_MB_2U_LIB.S9S_MB_2U(SCH_1):TP_TRC_CPU0_PTI(12)     I1 @S9S_MB_2U_LIB.S9S_MB_2U(SCH_1):PAGE19
  BT30 TP_TRC_CPU0_PTI<11> @S9S_MB_2U_LIB.S9S_MB_2U(SCH_1):TP_TRC_CPU0_PTI(11)     I1 @S9S_MB_2U_LIB.S9S_MB_2U(SCH_1):PAGE19
  BU29 TP_TRC_CPU0_PTI<10> @S9S_MB_2U_LIB.S9S_MB_2U(SCH_1):TP_TRC_CPU0_PTI(10)     I1 @S9S_MB_2U_LIB.S9S_MB_2U(SCH_1):PAGE19
  BT28 TP_TRC_CPU0_PTI<9> @S9S_MB_2U_LIB.S9S_MB_2U(SCH_1):TP_TRC_CPU0_PTI(9)     I1 @S9S_MB_2U_LIB.S9S_MB_2U(SCH_1):PAGE19
  BU27 TP_TRC_CPU0_PTI<8> @S9S_MB_2U_LIB.S9S_MB_2U(SCH_1):TP_TRC_CPU0_PTI(8)     I1 @S9S_MB_2U_LIB.S9S_MB_2U(SCH_1):PAGE19
  BV28 TP_TRC_CPU0_PTI<7> @S9S_MB_2U_LIB.S9S_MB_2U(SCH_1):TP_TRC_CPU0_PTI(7)     I1 @S9S_MB_2U_LIB.S9S_MB_2U(SCH_1):PAGE19
  CA27 TP_TRC_CPU0_PTI<6> @S9S_MB_2U_LIB.S9S_MB_2U(SCH_1):TP_TRC_CPU0_PTI(6)     I1 @S9S_MB_2U_LIB.S9S_MB_2U(SCH_1):PAGE19
  BV30 TP_TRC_CPU0_PTI<5> @S9S_MB_2U_LIB.S9S_MB_2U(SCH_1):TP_TRC_CPU0_PTI(5)     I1 @S9S_MB_2U_LIB.S9S_MB_2U(SCH_1):PAGE19
  CA29 TP_TRC_CPU0_PTI<4> @S9S_MB_2U_LIB.S9S_MB_2U(SCH_1):TP_TRC_CPU0_PTI(4)     I1 @S9S_MB_2U_LIB.S9S_MB_2U(SCH_1):PAGE19
  BY30 TP_TRC_CPU0_PTI<3> @S9S_MB_2U_LIB.S9S_MB_2U(SCH_1):TP_TRC_CPU0_PTI(3)     I1 @S9S_MB_2U_LIB.S9S_MB_2U(SCH_1):PAGE19
  CC27 TP_TRC_CPU0_PTI<2> @S9S_MB_2U_LIB.S9S_MB_2U(SCH_1):TP_TRC_CPU0_PTI(2)     I1 @S9S_MB_2U_LIB.S9S_MB_2U(SCH_1):PAGE19
  CD28 TP_TRC_CPU0_PTI_MON<1> @S9S_MB_2U_LIB.S9S_MB_2U(SCH_1):TP_TRC_CPU0_PTI_MON(1)     I1 @S9S_MB_2U_LIB.S9S_MB_2U(SCH_1):PAGE19
  CC29 TP_TP_TRC_CPU0_PTI_MON<0> @S9S_MB_2U_LIB.S9S_MB_2U(SCH_1):TP_TP_TRC_CPU0_PTI_MON(0)     I1 @S9S_MB_2U_LIB.S9S_MB_2U(SCH_1):PAGE19
  CB30 TP_TRC_CPU0_PTI0_CLK @S9S_MB_2U_LIB.S9S_MB_2U(SCH_1):TP_TRC_CPU0_PTI0_CLK     I1 @S9S_MB_2U_LIB.S9S_MB_2U(SCH_1):PAGE19
  BY28 TP_TRC_CPU0_PTI1_CLK @S9S_MB_2U_LIB.S9S_MB_2U(SCH_1):TP_TRC_CPU0_PTI1_CLK     I1 @S9S_MB_2U_LIB.S9S_MB_2U(SCH_1):PAGE19
  BN66 TP_TRC_CPU0_PTI<31> @S9S_MB_2U_LIB.S9S_MB_2U(SCH_1):TP_TRC_CPU0_PTI(31)     I1 @S9S_MB_2U_LIB.S9S_MB_2U(SCH_1):PAGE19
  BM67 TP_TRC_CPU0_PTI<30> @S9S_MB_2U_LIB.S9S_MB_2U(SCH_1):TP_TRC_CPU0_PTI(30)     I1 @S9S_MB_2U_LIB.S9S_MB_2U(SCH_1):PAGE19
  BL66 TP_TRC_CPU0_PTI<29> @S9S_MB_2U_LIB.S9S_MB_2U(SCH_1):TP_TRC_CPU0_PTI(29)     I1 @S9S_MB_2U_LIB.S9S_MB_2U(SCH_1):PAGE19
  BJ66 TP_TRC_CPU0_PTI<28> @S9S_MB_2U_LIB.S9S_MB_2U(SCH_1):TP_TRC_CPU0_PTI(28)     I1 @S9S_MB_2U_LIB.S9S_MB_2U(SCH_1):PAGE19
  BG66 TP_TRC_CPU0_PTI<27> @S9S_MB_2U_LIB.S9S_MB_2U(SCH_1):TP_TRC_CPU0_PTI(27)     I1 @S9S_MB_2U_LIB.S9S_MB_2U(SCH_1):PAGE19
  BN68 TP_TRC_CPU0_PTI<26> @S9S_MB_2U_LIB.S9S_MB_2U(SCH_1):TP_TRC_CPU0_PTI(26)     I1 @S9S_MB_2U_LIB.S9S_MB_2U(SCH_1):PAGE19
  BM69 TP_TRC_CPU0_PTI<25> @S9S_MB_2U_LIB.S9S_MB_2U(SCH_1):TP_TRC_CPU0_PTI(25)     I1 @S9S_MB_2U_LIB.S9S_MB_2U(SCH_1):PAGE19
  BK69 TP_TRC_CPU0_PTI<24> @S9S_MB_2U_LIB.S9S_MB_2U(SCH_1):TP_TRC_CPU0_PTI(24)     I1 @S9S_MB_2U_LIB.S9S_MB_2U(SCH_1):PAGE19
  BD67 TP_TRC_CPU0_PTI<23> @S9S_MB_2U_LIB.S9S_MB_2U(SCH_1):TP_TRC_CPU0_PTI(23)     I1 @S9S_MB_2U_LIB.S9S_MB_2U(SCH_1):PAGE19
  BG68 TP_TRC_CPU0_PTI<22> @S9S_MB_2U_LIB.S9S_MB_2U(SCH_1):TP_TRC_CPU0_PTI(22)     I1 @S9S_MB_2U_LIB.S9S_MB_2U(SCH_1):PAGE19
  BC68 TP_TRC_CPU0_PTI<21> @S9S_MB_2U_LIB.S9S_MB_2U(SCH_1):TP_TRC_CPU0_PTI(21)     I1 @S9S_MB_2U_LIB.S9S_MB_2U(SCH_1):PAGE19
  BH69 TP_TRC_CPU0_PTI<20> @S9S_MB_2U_LIB.S9S_MB_2U(SCH_1):TP_TRC_CPU0_PTI(20)     I1 @S9S_MB_2U_LIB.S9S_MB_2U(SCH_1):PAGE19
  BF69 TP_TRC_CPU0_PTI<19> @S9S_MB_2U_LIB.S9S_MB_2U(SCH_1):TP_TRC_CPU0_PTI(19)     I1 @S9S_MB_2U_LIB.S9S_MB_2U(SCH_1):PAGE19
  BD69 TP_TRC_CPU0_PTI<18> @S9S_MB_2U_LIB.S9S_MB_2U(SCH_1):TP_TRC_CPU0_PTI(18)     I1 @S9S_MB_2U_LIB.S9S_MB_2U(SCH_1):PAGE19
  BE70 TP_TRC_CPU0_PTI<17> @S9S_MB_2U_LIB.S9S_MB_2U(SCH_1):TP_TRC_CPU0_PTI(17)     I1 @S9S_MB_2U_LIB.S9S_MB_2U(SCH_1):PAGE19
  BC70 TP_TRC_CPU0_PTI<16> @S9S_MB_2U_LIB.S9S_MB_2U(SCH_1):TP_TRC_CPU0_PTI(16)     I1 @S9S_MB_2U_LIB.S9S_MB_2U(SCH_1):PAGE19
  BF67 TP_TRC_CPU0_PTI2_CLK @S9S_MB_2U_LIB.S9S_MB_2U(SCH_1):TP_TRC_CPU0_PTI2_CLK     I1 @S9S_MB_2U_LIB.S9S_MB_2U(SCH_1):PAGE19
  BK67 TP_TRC_CPU0_PTI3_CLK @S9S_MB_2U_LIB.S9S_MB_2U(SCH_1):TP_TRC_CPU0_PTI3_CLK     I1 @S9S_MB_2U_LIB.S9S_MB_2U(SCH_1):PAGE19
  CL68 NC_CPU0_PE3_APROBE<0> @S9S_MB_2U_LIB.S9S_MB_2U(SCH_1):NC_CPU0_PE3_APROBE(0)     I1 @S9S_MB_2U_LIB.S9S_MB_2U(SCH_1):PAGE19
  CM69 NC_CPU0_PE3_APROBE<1> @S9S_MB_2U_LIB.S9S_MB_2U(SCH_1):NC_CPU0_PE3_APROBE(1)     I1 @S9S_MB_2U_LIB.S9S_MB_2U(SCH_1):PAGE19
  CP69 NC_CPU0_UPI3_APROBE<0> @S9S_MB_2U_LIB.S9S_MB_2U(SCH_1):NC_CPU0_UPI3_APROBE(0)     I1 @S9S_MB_2U_LIB.S9S_MB_2U(SCH_1):PAGE19
  CR68 NC_CPU0_UPI3_APROBE<1> @S9S_MB_2U_LIB.S9S_MB_2U(SCH_1):NC_CPU0_UPI3_APROBE(1)     I1 @S9S_MB_2U_LIB.S9S_MB_2U(SCH_1):PAGE19
  AU66 NC_CPU0_PE4_APROBE<1> @S9S_MB_2U_LIB.S9S_MB_2U(SCH_1):NC_CPU0_PE4_APROBE(1)     I1 @S9S_MB_2U_LIB.S9S_MB_2U(SCH_1):PAGE19
  AU68 NC_CPU0_UPI2_APROBE<0> @S9S_MB_2U_LIB.S9S_MB_2U(SCH_1):NC_CPU0_UPI2_APROBE(0)     I1 @S9S_MB_2U_LIB.S9S_MB_2U(SCH_1):PAGE19
  AN17 NC_CPU0_UPI0_APROBE<0> @S9S_MB_2U_LIB.S9S_MB_2U(SCH_1):NC_CPU0_UPI0_APROBE(0)     I1 @S9S_MB_2U_LIB.S9S_MB_2U(SCH_1):PAGE19
  AV67 NC_CPU0_PE4_APROBE<0> @S9S_MB_2U_LIB.S9S_MB_2U(SCH_1):NC_CPU0_PE4_APROBE(0)     I1 @S9S_MB_2U_LIB.S9S_MB_2U(SCH_1):PAGE19
  AR17 NC_CPU0_UPI0_APROBE<1> @S9S_MB_2U_LIB.S9S_MB_2U(SCH_1):NC_CPU0_UPI0_APROBE(1)     I1 @S9S_MB_2U_LIB.S9S_MB_2U(SCH_1):PAGE19
  AT67 NC_CPU0_UPI2_APROBE<1> @S9S_MB_2U_LIB.S9S_MB_2U(SCH_1):NC_CPU0_UPI2_APROBE(1)     I1 @S9S_MB_2U_LIB.S9S_MB_2U(SCH_1):PAGE19
  BL21 NC_CPU0_PE0_APROBE<1> @S9S_MB_2U_LIB.S9S_MB_2U(SCH_1):NC_CPU0_PE0_APROBE(1)     I1 @S9S_MB_2U_LIB.S9S_MB_2U(SCH_1):PAGE19
  BN21 NC_CPU0_PE0_APROBE<0> @S9S_MB_2U_LIB.S9S_MB_2U(SCH_1):NC_CPU0_PE0_APROBE(0)     I1 @S9S_MB_2U_LIB.S9S_MB_2U(SCH_1):PAGE19
  BV22 NC_CPU0_UPI1_APROBE<0> @S9S_MB_2U_LIB.S9S_MB_2U(SCH_1):NC_CPU0_UPI1_APROBE(0)     I1 @S9S_MB_2U_LIB.S9S_MB_2U(SCH_1):PAGE19
  BW21 NC_CPU0_DMI_APROBE<1> @S9S_MB_2U_LIB.S9S_MB_2U(SCH_1):NC_CPU0_DMI_APROBE(1)     I1 @S9S_MB_2U_LIB.S9S_MB_2U(SCH_1):PAGE19
  BW23 NC_CPU0_PE2_APROBE<1> @S9S_MB_2U_LIB.S9S_MB_2U(SCH_1):NC_CPU0_PE2_APROBE(1)     I1 @S9S_MB_2U_LIB.S9S_MB_2U(SCH_1):PAGE19
  CA21 NC_CPU0_DMI_APROBE<0> @S9S_MB_2U_LIB.S9S_MB_2U(SCH_1):NC_CPU0_DMI_APROBE(0)     I1 @S9S_MB_2U_LIB.S9S_MB_2U(SCH_1):PAGE19
  CA23 NC_CPU0_UPI1_APROBE<1> @S9S_MB_2U_LIB.S9S_MB_2U(SCH_1):NC_CPU0_UPI1_APROBE(1)     I1 @S9S_MB_2U_LIB.S9S_MB_2U(SCH_1):PAGE19
  CC21 NC_CPU0_PE1_APROBE<1> @S9S_MB_2U_LIB.S9S_MB_2U(SCH_1):NC_CPU0_PE1_APROBE(1)     I1 @S9S_MB_2U_LIB.S9S_MB_2U(SCH_1):PAGE19
  CC23 NC_CPU0_PE2_APROBE<0> @S9S_MB_2U_LIB.S9S_MB_2U(SCH_1):NC_CPU0_PE2_APROBE(0)     I1 @S9S_MB_2U_LIB.S9S_MB_2U(SCH_1):PAGE19
  CE21 NC_CPU0_PE1_APROBE<0> @S9S_MB_2U_LIB.S9S_MB_2U(SCH_1):NC_CPU0_PE1_APROBE(0)     I1 @S9S_MB_2U_LIB.S9S_MB_2U(SCH_1):PAGE19
  BA23 PU_CPU0_UPI0_AC_COUPLING @S9S_MB_2U_LIB.S9S_MB_2U(SCH_1):PU_CPU0_UPI0_AC_COUPLING     I1 @S9S_MB_2U_LIB.S9S_MB_2U(SCH_1):PAGE19
  CW19 PU_CPU0_UPI1_AC_COUPLING @S9S_MB_2U_LIB.S9S_MB_2U(SCH_1):PU_CPU0_UPI1_AC_COUPLING     I1 @S9S_MB_2U_LIB.S9S_MB_2U(SCH_1):PAGE19
  BB65 PU_CPU0_UPI2_AC_COUPLING @S9S_MB_2U_LIB.S9S_MB_2U(SCH_1):PU_CPU0_UPI2_AC_COUPLING     I1 @S9S_MB_2U_LIB.S9S_MB_2U(SCH_1):PAGE19
  CK71 PU_CPU0_UPI3_AC_COUPLING @S9S_MB_2U_LIB.S9S_MB_2U(SCH_1):PU_CPU0_UPI3_AC_COUPLING     I1 @S9S_MB_2U_LIB.S9S_MB_2U(SCH_1):PAGE19
  AT49 M_A_CPU0_ALERT_N @S9S_MB_2U_LIB.S9S_MB_2U(SCH_1):M_A_CPU0_ALERT_N     I1 @S9S_MB_2U_LIB.S9S_MB_2U(SCH_1):PAGE20
  AU43 M_A_CPU0_SA_RSP<1> @S9S_MB_2U_LIB.S9S_MB_2U(SCH_1):M_A_CPU0_SA_RSP(1)     I1 @S9S_MB_2U_LIB.S9S_MB_2U(SCH_1):PAGE20
  AT42 M_A_CPU0_SA_RSP<0> @S9S_MB_2U_LIB.S9S_MB_2U(SCH_1):M_A_CPU0_SA_RSP(0)     I1 @S9S_MB_2U_LIB.S9S_MB_2U(SCH_1):PAGE20
  AV42 M_A_CPU0_SB_RSP<1> @S9S_MB_2U_LIB.S9S_MB_2U(SCH_1):M_A_CPU0_SB_RSP(1)     I1 @S9S_MB_2U_LIB.S9S_MB_2U(SCH_1):PAGE20
  AV44 M_A_CPU0_SB_RSP<0> @S9S_MB_2U_LIB.S9S_MB_2U(SCH_1):M_A_CPU0_SB_RSP(0)     I1 @S9S_MB_2U_LIB.S9S_MB_2U(SCH_1):PAGE20
   G45 M_A_CPU0_CLK_DN<1> @S9S_MB_2U_LIB.S9S_MB_2U(SCH_1):M_A_CPU0_CLK_DN(1)     I1 @S9S_MB_2U_LIB.S9S_MB_2U(SCH_1):PAGE20
   B44 M_A_CPU0_CLK_DN<0> @S9S_MB_2U_LIB.S9S_MB_2U(SCH_1):M_A_CPU0_CLK_DN(0)     I1 @S9S_MB_2U_LIB.S9S_MB_2U(SCH_1):PAGE20
   E45 M_A_CPU0_CLK_DP<1> @S9S_MB_2U_LIB.S9S_MB_2U(SCH_1):M_A_CPU0_CLK_DP(1)     I1 @S9S_MB_2U_LIB.S9S_MB_2U(SCH_1):PAGE20
   C43 M_A_CPU0_CLK_DP<0> @S9S_MB_2U_LIB.S9S_MB_2U(SCH_1):M_A_CPU0_CLK_DP(0)     I1 @S9S_MB_2U_LIB.S9S_MB_2U(SCH_1):PAGE20
   C48 M_A_CPU0_SA_CA<6> @S9S_MB_2U_LIB.S9S_MB_2U(SCH_1):M_A_CPU0_SA_CA(6)     I1 @S9S_MB_2U_LIB.S9S_MB_2U(SCH_1):PAGE20
   E50 M_A_CPU0_SA_CA<5> @S9S_MB_2U_LIB.S9S_MB_2U(SCH_1):M_A_CPU0_SA_CA(5)     I1 @S9S_MB_2U_LIB.S9S_MB_2U(SCH_1):PAGE20
   C50 M_A_CPU0_SA_CA<4> @S9S_MB_2U_LIB.S9S_MB_2U(SCH_1):M_A_CPU0_SA_CA(4)     I1 @S9S_MB_2U_LIB.S9S_MB_2U(SCH_1):PAGE20
   F51 M_A_CPU0_SA_CA<3> @S9S_MB_2U_LIB.S9S_MB_2U(SCH_1):M_A_CPU0_SA_CA(3)     I1 @S9S_MB_2U_LIB.S9S_MB_2U(SCH_1):PAGE20
   B51 M_A_CPU0_SA_CA<2> @S9S_MB_2U_LIB.S9S_MB_2U(SCH_1):M_A_CPU0_SA_CA(2)     I1 @S9S_MB_2U_LIB.S9S_MB_2U(SCH_1):PAGE20
   G52 M_A_CPU0_SA_CA<1> @S9S_MB_2U_LIB.S9S_MB_2U(SCH_1):M_A_CPU0_SA_CA(1)     I1 @S9S_MB_2U_LIB.S9S_MB_2U(SCH_1):PAGE20
   A52 M_A_CPU0_SA_CA<0> @S9S_MB_2U_LIB.S9S_MB_2U(SCH_1):M_A_CPU0_SA_CA(0)     I1 @S9S_MB_2U_LIB.S9S_MB_2U(SCH_1):PAGE20
   F53 M_A_CPU0_SA_CS_N<3> @S9S_MB_2U_LIB.S9S_MB_2U(SCH_1):M_A_CPU0_SA_CS_N(3)     I1 @S9S_MB_2U_LIB.S9S_MB_2U(SCH_1):PAGE20
   E54 M_A_CPU0_SA_CS_N<2> @S9S_MB_2U_LIB.S9S_MB_2U(SCH_1):M_A_CPU0_SA_CS_N(2)     I1 @S9S_MB_2U_LIB.S9S_MB_2U(SCH_1):PAGE20
   B53 M_A_CPU0_SA_CS_N<1> @S9S_MB_2U_LIB.S9S_MB_2U(SCH_1):M_A_CPU0_SA_CS_N(1)     I1 @S9S_MB_2U_LIB.S9S_MB_2U(SCH_1):PAGE20
   C54 M_A_CPU0_SA_CS_N<0> @S9S_MB_2U_LIB.S9S_MB_2U(SCH_1):M_A_CPU0_SA_CS_N(0)     I1 @S9S_MB_2U_LIB.S9S_MB_2U(SCH_1):PAGE20
   E62 M_A_CPU0_SA_DQ<31> @S9S_MB_2U_LIB.S9S_MB_2U(SCH_1):M_A_CPU0_SA_DQ(31)     I1 @S9S_MB_2U_LIB.S9S_MB_2U(SCH_1):PAGE20
   F63 M_A_CPU0_SA_DQ<30> @S9S_MB_2U_LIB.S9S_MB_2U(SCH_1):M_A_CPU0_SA_DQ(30)     I1 @S9S_MB_2U_LIB.S9S_MB_2U(SCH_1):PAGE20
   C62 M_A_CPU0_SA_DQ<29> @S9S_MB_2U_LIB.S9S_MB_2U(SCH_1):M_A_CPU0_SA_DQ(29)     I1 @S9S_MB_2U_LIB.S9S_MB_2U(SCH_1):PAGE20
   B63 M_A_CPU0_SA_DQ<28> @S9S_MB_2U_LIB.S9S_MB_2U(SCH_1):M_A_CPU0_SA_DQ(28)     I1 @S9S_MB_2U_LIB.S9S_MB_2U(SCH_1):PAGE20
   F65 M_A_CPU0_SA_DQ<27> @S9S_MB_2U_LIB.S9S_MB_2U(SCH_1):M_A_CPU0_SA_DQ(27)     I1 @S9S_MB_2U_LIB.S9S_MB_2U(SCH_1):PAGE20
   E66 M_A_CPU0_SA_DQ<26> @S9S_MB_2U_LIB.S9S_MB_2U(SCH_1):M_A_CPU0_SA_DQ(26)     I1 @S9S_MB_2U_LIB.S9S_MB_2U(SCH_1):PAGE20
   B65 M_A_CPU0_SA_DQ<25> @S9S_MB_2U_LIB.S9S_MB_2U(SCH_1):M_A_CPU0_SA_DQ(25)     I1 @S9S_MB_2U_LIB.S9S_MB_2U(SCH_1):PAGE20
   C66 M_A_CPU0_SA_DQ<24> @S9S_MB_2U_LIB.S9S_MB_2U(SCH_1):M_A_CPU0_SA_DQ(24)     I1 @S9S_MB_2U_LIB.S9S_MB_2U(SCH_1):PAGE20
   E68 M_A_CPU0_SA_DQ<23> @S9S_MB_2U_LIB.S9S_MB_2U(SCH_1):M_A_CPU0_SA_DQ(23)     I1 @S9S_MB_2U_LIB.S9S_MB_2U(SCH_1):PAGE20
   F69 M_A_CPU0_SA_DQ<22> @S9S_MB_2U_LIB.S9S_MB_2U(SCH_1):M_A_CPU0_SA_DQ(22)     I1 @S9S_MB_2U_LIB.S9S_MB_2U(SCH_1):PAGE20
   C68 M_A_CPU0_SA_DQ<21> @S9S_MB_2U_LIB.S9S_MB_2U(SCH_1):M_A_CPU0_SA_DQ(21)     I1 @S9S_MB_2U_LIB.S9S_MB_2U(SCH_1):PAGE20
   B69 M_A_CPU0_SA_DQ<20> @S9S_MB_2U_LIB.S9S_MB_2U(SCH_1):M_A_CPU0_SA_DQ(20)     I1 @S9S_MB_2U_LIB.S9S_MB_2U(SCH_1):PAGE20
   F71 M_A_CPU0_SA_DQ<19> @S9S_MB_2U_LIB.S9S_MB_2U(SCH_1):M_A_CPU0_SA_DQ(19)     I1 @S9S_MB_2U_LIB.S9S_MB_2U(SCH_1):PAGE20
   D73 M_A_CPU0_SA_DQ<18> @S9S_MB_2U_LIB.S9S_MB_2U(SCH_1):M_A_CPU0_SA_DQ(18)     I1 @S9S_MB_2U_LIB.S9S_MB_2U(SCH_1):PAGE20
   E72 M_A_CPU0_SA_DQ<17> @S9S_MB_2U_LIB.S9S_MB_2U(SCH_1):M_A_CPU0_SA_DQ(17)     I1 @S9S_MB_2U_LIB.S9S_MB_2U(SCH_1):PAGE20
   B73 M_A_CPU0_SA_DQ<16> @S9S_MB_2U_LIB.S9S_MB_2U(SCH_1):M_A_CPU0_SA_DQ(16)     I1 @S9S_MB_2U_LIB.S9S_MB_2U(SCH_1):PAGE20
   M65 M_A_CPU0_SA_DQ<15> @S9S_MB_2U_LIB.S9S_MB_2U(SCH_1):M_A_CPU0_SA_DQ(15)     I1 @S9S_MB_2U_LIB.S9S_MB_2U(SCH_1):PAGE20
   N66 M_A_CPU0_SA_DQ<14> @S9S_MB_2U_LIB.S9S_MB_2U(SCH_1):M_A_CPU0_SA_DQ(14)     I1 @S9S_MB_2U_LIB.S9S_MB_2U(SCH_1):PAGE20
   K65 M_A_CPU0_SA_DQ<13> @S9S_MB_2U_LIB.S9S_MB_2U(SCH_1):M_A_CPU0_SA_DQ(13)     I1 @S9S_MB_2U_LIB.S9S_MB_2U(SCH_1):PAGE20
   J66 M_A_CPU0_SA_DQ<12> @S9S_MB_2U_LIB.S9S_MB_2U(SCH_1):M_A_CPU0_SA_DQ(12)     I1 @S9S_MB_2U_LIB.S9S_MB_2U(SCH_1):PAGE20
   N68 M_A_CPU0_SA_DQ<11> @S9S_MB_2U_LIB.S9S_MB_2U(SCH_1):M_A_CPU0_SA_DQ(11)     I1 @S9S_MB_2U_LIB.S9S_MB_2U(SCH_1):PAGE20
   M69 M_A_CPU0_SA_DQ<10> @S9S_MB_2U_LIB.S9S_MB_2U(SCH_1):M_A_CPU0_SA_DQ(10)     I1 @S9S_MB_2U_LIB.S9S_MB_2U(SCH_1):PAGE20
   J68 M_A_CPU0_SA_DQ<9> @S9S_MB_2U_LIB.S9S_MB_2U(SCH_1):M_A_CPU0_SA_DQ(9)     I1 @S9S_MB_2U_LIB.S9S_MB_2U(SCH_1):PAGE20
   K69 M_A_CPU0_SA_DQ<8> @S9S_MB_2U_LIB.S9S_MB_2U(SCH_1):M_A_CPU0_SA_DQ(8)     I1 @S9S_MB_2U_LIB.S9S_MB_2U(SCH_1):PAGE20
   F75 M_A_CPU0_SA_DQ<7> @S9S_MB_2U_LIB.S9S_MB_2U(SCH_1):M_A_CPU0_SA_DQ(7)     I1 @S9S_MB_2U_LIB.S9S_MB_2U(SCH_1):PAGE20
   G76 M_A_CPU0_SA_DQ<6> @S9S_MB_2U_LIB.S9S_MB_2U(SCH_1):M_A_CPU0_SA_DQ(6)     I1 @S9S_MB_2U_LIB.S9S_MB_2U(SCH_1):PAGE20
   D75 M_A_CPU0_SA_DQ<5> @S9S_MB_2U_LIB.S9S_MB_2U(SCH_1):M_A_CPU0_SA_DQ(5)     I1 @S9S_MB_2U_LIB.S9S_MB_2U(SCH_1):PAGE20
   C76 M_A_CPU0_SA_DQ<4> @S9S_MB_2U_LIB.S9S_MB_2U(SCH_1):M_A_CPU0_SA_DQ(4)     I1 @S9S_MB_2U_LIB.S9S_MB_2U(SCH_1):PAGE20
   G78 M_A_CPU0_SA_DQ<3> @S9S_MB_2U_LIB.S9S_MB_2U(SCH_1):M_A_CPU0_SA_DQ(3)     I1 @S9S_MB_2U_LIB.S9S_MB_2U(SCH_1):PAGE20
   M77 M_A_CPU0_SA_DQ<2> @S9S_MB_2U_LIB.S9S_MB_2U(SCH_1):M_A_CPU0_SA_DQ(2)     I1 @S9S_MB_2U_LIB.S9S_MB_2U(SCH_1):PAGE20
   B79 M_A_CPU0_SA_DQ<1> @S9S_MB_2U_LIB.S9S_MB_2U(SCH_1):M_A_CPU0_SA_DQ(1)     I1 @S9S_MB_2U_LIB.S9S_MB_2U(SCH_1):PAGE20
   B81 M_A_CPU0_SA_DQ<0> @S9S_MB_2U_LIB.S9S_MB_2U(SCH_1):M_A_CPU0_SA_DQ(0)     I1 @S9S_MB_2U_LIB.S9S_MB_2U(SCH_1):PAGE20
   G58 M_A_CPU0_SA_DQS_DN<9> @S9S_MB_2U_LIB.S9S_MB_2U(SCH_1):M_A_CPU0_SA_DQS_DN(9)     I1 @S9S_MB_2U_LIB.S9S_MB_2U(SCH_1):PAGE20
   G64 M_A_CPU0_SA_DQS_DN<8> @S9S_MB_2U_LIB.S9S_MB_2U(SCH_1):M_A_CPU0_SA_DQS_DN(8)     I1 @S9S_MB_2U_LIB.S9S_MB_2U(SCH_1):PAGE20
   G70 M_A_CPU0_SA_DQS_DN<7> @S9S_MB_2U_LIB.S9S_MB_2U(SCH_1):M_A_CPU0_SA_DQS_DN(7)     I1 @S9S_MB_2U_LIB.S9S_MB_2U(SCH_1):PAGE20
   P67 M_A_CPU0_SA_DQS_DN<6> @S9S_MB_2U_LIB.S9S_MB_2U(SCH_1):M_A_CPU0_SA_DQS_DN(6)     I1 @S9S_MB_2U_LIB.S9S_MB_2U(SCH_1):PAGE20
   H77 M_A_CPU0_SA_DQS_DN<5> @S9S_MB_2U_LIB.S9S_MB_2U(SCH_1):M_A_CPU0_SA_DQS_DN(5)     I1 @S9S_MB_2U_LIB.S9S_MB_2U(SCH_1):PAGE20
   A58 M_A_CPU0_SA_DQS_DN<4> @S9S_MB_2U_LIB.S9S_MB_2U(SCH_1):M_A_CPU0_SA_DQS_DN(4)     I1 @S9S_MB_2U_LIB.S9S_MB_2U(SCH_1):PAGE20
   A64 M_A_CPU0_SA_DQS_DN<3> @S9S_MB_2U_LIB.S9S_MB_2U(SCH_1):M_A_CPU0_SA_DQS_DN(3)     I1 @S9S_MB_2U_LIB.S9S_MB_2U(SCH_1):PAGE20
   B71 M_A_CPU0_SA_DQS_DN<2> @S9S_MB_2U_LIB.S9S_MB_2U(SCH_1):M_A_CPU0_SA_DQS_DN(2)     I1 @S9S_MB_2U_LIB.S9S_MB_2U(SCH_1):PAGE20
   H67 M_A_CPU0_SA_DQS_DN<1> @S9S_MB_2U_LIB.S9S_MB_2U(SCH_1):M_A_CPU0_SA_DQS_DN(1)     I1 @S9S_MB_2U_LIB.S9S_MB_2U(SCH_1):PAGE20
   B77 M_A_CPU0_SA_DQS_DN<0> @S9S_MB_2U_LIB.S9S_MB_2U(SCH_1):M_A_CPU0_SA_DQS_DN(0)     I1 @S9S_MB_2U_LIB.S9S_MB_2U(SCH_1):PAGE20
   E58 M_A_CPU0_SA_DQS_DP<9> @S9S_MB_2U_LIB.S9S_MB_2U(SCH_1):M_A_CPU0_SA_DQS_DP(9)     I1 @S9S_MB_2U_LIB.S9S_MB_2U(SCH_1):PAGE20
   E64 M_A_CPU0_SA_DQS_DP<8> @S9S_MB_2U_LIB.S9S_MB_2U(SCH_1):M_A_CPU0_SA_DQS_DP(8)     I1 @S9S_MB_2U_LIB.S9S_MB_2U(SCH_1):PAGE20
   E70 M_A_CPU0_SA_DQS_DP<7> @S9S_MB_2U_LIB.S9S_MB_2U(SCH_1):M_A_CPU0_SA_DQS_DP(7)     I1 @S9S_MB_2U_LIB.S9S_MB_2U(SCH_1):PAGE20
   M67 M_A_CPU0_SA_DQS_DP<6> @S9S_MB_2U_LIB.S9S_MB_2U(SCH_1):M_A_CPU0_SA_DQS_DP(6)     I1 @S9S_MB_2U_LIB.S9S_MB_2U(SCH_1):PAGE20
   F77 M_A_CPU0_SA_DQS_DP<5> @S9S_MB_2U_LIB.S9S_MB_2U(SCH_1):M_A_CPU0_SA_DQS_DP(5)     I1 @S9S_MB_2U_LIB.S9S_MB_2U(SCH_1):PAGE20
   C58 M_A_CPU0_SA_DQS_DP<4> @S9S_MB_2U_LIB.S9S_MB_2U(SCH_1):M_A_CPU0_SA_DQS_DP(4)     I1 @S9S_MB_2U_LIB.S9S_MB_2U(SCH_1):PAGE20
   C64 M_A_CPU0_SA_DQS_DP<3> @S9S_MB_2U_LIB.S9S_MB_2U(SCH_1):M_A_CPU0_SA_DQS_DP(3)     I1 @S9S_MB_2U_LIB.S9S_MB_2U(SCH_1):PAGE20
   C70 M_A_CPU0_SA_DQS_DP<2> @S9S_MB_2U_LIB.S9S_MB_2U(SCH_1):M_A_CPU0_SA_DQS_DP(2)     I1 @S9S_MB_2U_LIB.S9S_MB_2U(SCH_1):PAGE20
   K67 M_A_CPU0_SA_DQS_DP<1> @S9S_MB_2U_LIB.S9S_MB_2U(SCH_1):M_A_CPU0_SA_DQS_DP(1)     I1 @S9S_MB_2U_LIB.S9S_MB_2U(SCH_1):PAGE20
   D77 M_A_CPU0_SA_DQS_DP<0> @S9S_MB_2U_LIB.S9S_MB_2U(SCH_1):M_A_CPU0_SA_DQS_DP(0)     I1 @S9S_MB_2U_LIB.S9S_MB_2U(SCH_1):PAGE20
   E56 M_A_CPU0_SA_CB<7> @S9S_MB_2U_LIB.S9S_MB_2U(SCH_1):M_A_CPU0_SA_CB(7)     I1 @S9S_MB_2U_LIB.S9S_MB_2U(SCH_1):PAGE20
   F57 M_A_CPU0_SA_CB<6> @S9S_MB_2U_LIB.S9S_MB_2U(SCH_1):M_A_CPU0_SA_CB(6)     I1 @S9S_MB_2U_LIB.S9S_MB_2U(SCH_1):PAGE20
   C56 M_A_CPU0_SA_CB<5> @S9S_MB_2U_LIB.S9S_MB_2U(SCH_1):M_A_CPU0_SA_CB(5)     I1 @S9S_MB_2U_LIB.S9S_MB_2U(SCH_1):PAGE20
   B57 M_A_CPU0_SA_CB<4> @S9S_MB_2U_LIB.S9S_MB_2U(SCH_1):M_A_CPU0_SA_CB(4)     I1 @S9S_MB_2U_LIB.S9S_MB_2U(SCH_1):PAGE20
   F59 M_A_CPU0_SA_CB<3> @S9S_MB_2U_LIB.S9S_MB_2U(SCH_1):M_A_CPU0_SA_CB(3)     I1 @S9S_MB_2U_LIB.S9S_MB_2U(SCH_1):PAGE20
   E60 M_A_CPU0_SA_CB<2> @S9S_MB_2U_LIB.S9S_MB_2U(SCH_1):M_A_CPU0_SA_CB(2)     I1 @S9S_MB_2U_LIB.S9S_MB_2U(SCH_1):PAGE20
   B59 M_A_CPU0_SA_CB<1> @S9S_MB_2U_LIB.S9S_MB_2U(SCH_1):M_A_CPU0_SA_CB(1)     I1 @S9S_MB_2U_LIB.S9S_MB_2U(SCH_1):PAGE20
   C60 M_A_CPU0_SA_CB<0> @S9S_MB_2U_LIB.S9S_MB_2U(SCH_1):M_A_CPU0_SA_CB(0)     I1 @S9S_MB_2U_LIB.S9S_MB_2U(SCH_1):PAGE20
   E48 M_A_CPU0_SA_PAR @S9S_MB_2U_LIB.S9S_MB_2U(SCH_1):M_A_CPU0_SA_PAR     I1 @S9S_MB_2U_LIB.S9S_MB_2U(SCH_1):PAGE20
   A39 M_A_CPU0_SB_CA<6> @S9S_MB_2U_LIB.S9S_MB_2U(SCH_1):M_A_CPU0_SB_CA(6)     I1 @S9S_MB_2U_LIB.S9S_MB_2U(SCH_1):PAGE20
   F40 M_A_CPU0_SB_CA<5> @S9S_MB_2U_LIB.S9S_MB_2U(SCH_1):M_A_CPU0_SB_CA(5)     I1 @S9S_MB_2U_LIB.S9S_MB_2U(SCH_1):PAGE20
   B40 M_A_CPU0_SB_CA<4> @S9S_MB_2U_LIB.S9S_MB_2U(SCH_1):M_A_CPU0_SB_CA(4)     I1 @S9S_MB_2U_LIB.S9S_MB_2U(SCH_1):PAGE20
   E41 M_A_CPU0_SB_CA<3> @S9S_MB_2U_LIB.S9S_MB_2U(SCH_1):M_A_CPU0_SB_CA(3)     I1 @S9S_MB_2U_LIB.S9S_MB_2U(SCH_1):PAGE20
   C41 M_A_CPU0_SB_CA<2> @S9S_MB_2U_LIB.S9S_MB_2U(SCH_1):M_A_CPU0_SB_CA(2)     I1 @S9S_MB_2U_LIB.S9S_MB_2U(SCH_1):PAGE20
   F44 M_A_CPU0_SB_CA<1> @S9S_MB_2U_LIB.S9S_MB_2U(SCH_1):M_A_CPU0_SB_CA(1)     I1 @S9S_MB_2U_LIB.S9S_MB_2U(SCH_1):PAGE20
   E43 M_A_CPU0_SB_CA<0> @S9S_MB_2U_LIB.S9S_MB_2U(SCH_1):M_A_CPU0_SB_CA(0)     I1 @S9S_MB_2U_LIB.S9S_MB_2U(SCH_1):PAGE20
   E37 M_A_CPU0_SB_CS_N<3> @S9S_MB_2U_LIB.S9S_MB_2U(SCH_1):M_A_CPU0_SB_CS_N(3)     I1 @S9S_MB_2U_LIB.S9S_MB_2U(SCH_1):PAGE20
   F38 M_A_CPU0_SB_CS_N<2> @S9S_MB_2U_LIB.S9S_MB_2U(SCH_1):M_A_CPU0_SB_CS_N(2)     I1 @S9S_MB_2U_LIB.S9S_MB_2U(SCH_1):PAGE20
   C37 M_A_CPU0_SB_CS_N<1> @S9S_MB_2U_LIB.S9S_MB_2U(SCH_1):M_A_CPU0_SB_CS_N(1)     I1 @S9S_MB_2U_LIB.S9S_MB_2U(SCH_1):PAGE20
   B38 M_A_CPU0_SB_CS_N<0> @S9S_MB_2U_LIB.S9S_MB_2U(SCH_1):M_A_CPU0_SB_CS_N(0)     I1 @S9S_MB_2U_LIB.S9S_MB_2U(SCH_1):PAGE20
    E7 M_A_CPU0_SB_DQ<31> @S9S_MB_2U_LIB.S9S_MB_2U(SCH_1):M_A_CPU0_SB_DQ(31)     I1 @S9S_MB_2U_LIB.S9S_MB_2U(SCH_1):PAGE20
    F8 M_A_CPU0_SB_DQ<30> @S9S_MB_2U_LIB.S9S_MB_2U(SCH_1):M_A_CPU0_SB_DQ(30)     I1 @S9S_MB_2U_LIB.S9S_MB_2U(SCH_1):PAGE20
    C7 M_A_CPU0_SB_DQ<29> @S9S_MB_2U_LIB.S9S_MB_2U(SCH_1):M_A_CPU0_SB_DQ(29)     I1 @S9S_MB_2U_LIB.S9S_MB_2U(SCH_1):PAGE20
    B8 M_A_CPU0_SB_DQ<28> @S9S_MB_2U_LIB.S9S_MB_2U(SCH_1):M_A_CPU0_SB_DQ(28)     I1 @S9S_MB_2U_LIB.S9S_MB_2U(SCH_1):PAGE20
   F10 M_A_CPU0_SB_DQ<27> @S9S_MB_2U_LIB.S9S_MB_2U(SCH_1):M_A_CPU0_SB_DQ(27)     I1 @S9S_MB_2U_LIB.S9S_MB_2U(SCH_1):PAGE20
   E11 M_A_CPU0_SB_DQ<26> @S9S_MB_2U_LIB.S9S_MB_2U(SCH_1):M_A_CPU0_SB_DQ(26)     I1 @S9S_MB_2U_LIB.S9S_MB_2U(SCH_1):PAGE20
   B10 M_A_CPU0_SB_DQ<25> @S9S_MB_2U_LIB.S9S_MB_2U(SCH_1):M_A_CPU0_SB_DQ(25)     I1 @S9S_MB_2U_LIB.S9S_MB_2U(SCH_1):PAGE20
   C11 M_A_CPU0_SB_DQ<24> @S9S_MB_2U_LIB.S9S_MB_2U(SCH_1):M_A_CPU0_SB_DQ(24)     I1 @S9S_MB_2U_LIB.S9S_MB_2U(SCH_1):PAGE20
   E19 M_A_CPU0_SB_DQ<23> @S9S_MB_2U_LIB.S9S_MB_2U(SCH_1):M_A_CPU0_SB_DQ(23)     I1 @S9S_MB_2U_LIB.S9S_MB_2U(SCH_1):PAGE20
   F20 M_A_CPU0_SB_DQ<22> @S9S_MB_2U_LIB.S9S_MB_2U(SCH_1):M_A_CPU0_SB_DQ(22)     I1 @S9S_MB_2U_LIB.S9S_MB_2U(SCH_1):PAGE20
   C19 M_A_CPU0_SB_DQ<21> @S9S_MB_2U_LIB.S9S_MB_2U(SCH_1):M_A_CPU0_SB_DQ(21)     I1 @S9S_MB_2U_LIB.S9S_MB_2U(SCH_1):PAGE20
   B20 M_A_CPU0_SB_DQ<20> @S9S_MB_2U_LIB.S9S_MB_2U(SCH_1):M_A_CPU0_SB_DQ(20)     I1 @S9S_MB_2U_LIB.S9S_MB_2U(SCH_1):PAGE20
   F22 M_A_CPU0_SB_DQ<19> @S9S_MB_2U_LIB.S9S_MB_2U(SCH_1):M_A_CPU0_SB_DQ(19)     I1 @S9S_MB_2U_LIB.S9S_MB_2U(SCH_1):PAGE20
   E23 M_A_CPU0_SB_DQ<18> @S9S_MB_2U_LIB.S9S_MB_2U(SCH_1):M_A_CPU0_SB_DQ(18)     I1 @S9S_MB_2U_LIB.S9S_MB_2U(SCH_1):PAGE20
   B22 M_A_CPU0_SB_DQ<17> @S9S_MB_2U_LIB.S9S_MB_2U(SCH_1):M_A_CPU0_SB_DQ(17)     I1 @S9S_MB_2U_LIB.S9S_MB_2U(SCH_1):PAGE20
   C23 M_A_CPU0_SB_DQ<16> @S9S_MB_2U_LIB.S9S_MB_2U(SCH_1):M_A_CPU0_SB_DQ(16)     I1 @S9S_MB_2U_LIB.S9S_MB_2U(SCH_1):PAGE20
   E25 M_A_CPU0_SB_DQ<15> @S9S_MB_2U_LIB.S9S_MB_2U(SCH_1):M_A_CPU0_SB_DQ(15)     I1 @S9S_MB_2U_LIB.S9S_MB_2U(SCH_1):PAGE20
   F26 M_A_CPU0_SB_DQ<14> @S9S_MB_2U_LIB.S9S_MB_2U(SCH_1):M_A_CPU0_SB_DQ(14)     I1 @S9S_MB_2U_LIB.S9S_MB_2U(SCH_1):PAGE20
   C25 M_A_CPU0_SB_DQ<13> @S9S_MB_2U_LIB.S9S_MB_2U(SCH_1):M_A_CPU0_SB_DQ(13)     I1 @S9S_MB_2U_LIB.S9S_MB_2U(SCH_1):PAGE20
   B26 M_A_CPU0_SB_DQ<12> @S9S_MB_2U_LIB.S9S_MB_2U(SCH_1):M_A_CPU0_SB_DQ(12)     I1 @S9S_MB_2U_LIB.S9S_MB_2U(SCH_1):PAGE20
   F28 M_A_CPU0_SB_DQ<11> @S9S_MB_2U_LIB.S9S_MB_2U(SCH_1):M_A_CPU0_SB_DQ(11)     I1 @S9S_MB_2U_LIB.S9S_MB_2U(SCH_1):PAGE20
   E29 M_A_CPU0_SB_DQ<10> @S9S_MB_2U_LIB.S9S_MB_2U(SCH_1):M_A_CPU0_SB_DQ(10)     I1 @S9S_MB_2U_LIB.S9S_MB_2U(SCH_1):PAGE20
   B28 M_A_CPU0_SB_DQ<9> @S9S_MB_2U_LIB.S9S_MB_2U(SCH_1):M_A_CPU0_SB_DQ(9)     I1 @S9S_MB_2U_LIB.S9S_MB_2U(SCH_1):PAGE20
   C29 M_A_CPU0_SB_DQ<8> @S9S_MB_2U_LIB.S9S_MB_2U(SCH_1):M_A_CPU0_SB_DQ(8)     I1 @S9S_MB_2U_LIB.S9S_MB_2U(SCH_1):PAGE20
   M28 M_A_CPU0_SB_DQ<7> @S9S_MB_2U_LIB.S9S_MB_2U(SCH_1):M_A_CPU0_SB_DQ(7)     I1 @S9S_MB_2U_LIB.S9S_MB_2U(SCH_1):PAGE20
   N29 M_A_CPU0_SB_DQ<6> @S9S_MB_2U_LIB.S9S_MB_2U(SCH_1):M_A_CPU0_SB_DQ(6)     I1 @S9S_MB_2U_LIB.S9S_MB_2U(SCH_1):PAGE20
   K28 M_A_CPU0_SB_DQ<5> @S9S_MB_2U_LIB.S9S_MB_2U(SCH_1):M_A_CPU0_SB_DQ(5)     I1 @S9S_MB_2U_LIB.S9S_MB_2U(SCH_1):PAGE20
   J29 M_A_CPU0_SB_DQ<4> @S9S_MB_2U_LIB.S9S_MB_2U(SCH_1):M_A_CPU0_SB_DQ(4)     I1 @S9S_MB_2U_LIB.S9S_MB_2U(SCH_1):PAGE20
   N31 M_A_CPU0_SB_DQ<3> @S9S_MB_2U_LIB.S9S_MB_2U(SCH_1):M_A_CPU0_SB_DQ(3)     I1 @S9S_MB_2U_LIB.S9S_MB_2U(SCH_1):PAGE20
   M32 M_A_CPU0_SB_DQ<2> @S9S_MB_2U_LIB.S9S_MB_2U(SCH_1):M_A_CPU0_SB_DQ(2)     I1 @S9S_MB_2U_LIB.S9S_MB_2U(SCH_1):PAGE20
   J31 M_A_CPU0_SB_DQ<1> @S9S_MB_2U_LIB.S9S_MB_2U(SCH_1):M_A_CPU0_SB_DQ(1)     I1 @S9S_MB_2U_LIB.S9S_MB_2U(SCH_1):PAGE20
   K32 M_A_CPU0_SB_DQ<0> @S9S_MB_2U_LIB.S9S_MB_2U(SCH_1):M_A_CPU0_SB_DQ(0)     I1 @S9S_MB_2U_LIB.S9S_MB_2U(SCH_1):PAGE20
   A33 M_A_CPU0_SB_DQS_DN<9> @S9S_MB_2U_LIB.S9S_MB_2U(SCH_1):M_A_CPU0_SB_DQS_DN(9)     I1 @S9S_MB_2U_LIB.S9S_MB_2U(SCH_1):PAGE20
    G9 M_A_CPU0_SB_DQS_DN<8> @S9S_MB_2U_LIB.S9S_MB_2U(SCH_1):M_A_CPU0_SB_DQS_DN(8)     I1 @S9S_MB_2U_LIB.S9S_MB_2U(SCH_1):PAGE20
   G21 M_A_CPU0_SB_DQS_DN<7> @S9S_MB_2U_LIB.S9S_MB_2U(SCH_1):M_A_CPU0_SB_DQS_DN(7)     I1 @S9S_MB_2U_LIB.S9S_MB_2U(SCH_1):PAGE20
   G27 M_A_CPU0_SB_DQS_DN<6> @S9S_MB_2U_LIB.S9S_MB_2U(SCH_1):M_A_CPU0_SB_DQS_DN(6)     I1 @S9S_MB_2U_LIB.S9S_MB_2U(SCH_1):PAGE20
   M30 M_A_CPU0_SB_DQS_DN<5> @S9S_MB_2U_LIB.S9S_MB_2U(SCH_1):M_A_CPU0_SB_DQS_DN(5)     I1 @S9S_MB_2U_LIB.S9S_MB_2U(SCH_1):PAGE20
   G33 M_A_CPU0_SB_DQS_DN<4> @S9S_MB_2U_LIB.S9S_MB_2U(SCH_1):M_A_CPU0_SB_DQS_DN(4)     I1 @S9S_MB_2U_LIB.S9S_MB_2U(SCH_1):PAGE20
    A9 M_A_CPU0_SB_DQS_DN<3> @S9S_MB_2U_LIB.S9S_MB_2U(SCH_1):M_A_CPU0_SB_DQS_DN(3)     I1 @S9S_MB_2U_LIB.S9S_MB_2U(SCH_1):PAGE20
   A21 M_A_CPU0_SB_DQS_DN<2> @S9S_MB_2U_LIB.S9S_MB_2U(SCH_1):M_A_CPU0_SB_DQS_DN(2)     I1 @S9S_MB_2U_LIB.S9S_MB_2U(SCH_1):PAGE20
   A27 M_A_CPU0_SB_DQS_DN<1> @S9S_MB_2U_LIB.S9S_MB_2U(SCH_1):M_A_CPU0_SB_DQS_DN(1)     I1 @S9S_MB_2U_LIB.S9S_MB_2U(SCH_1):PAGE20
   H30 M_A_CPU0_SB_DQS_DN<0> @S9S_MB_2U_LIB.S9S_MB_2U(SCH_1):M_A_CPU0_SB_DQS_DN(0)     I1 @S9S_MB_2U_LIB.S9S_MB_2U(SCH_1):PAGE20
   C33 M_A_CPU0_SB_DQS_DP<9> @S9S_MB_2U_LIB.S9S_MB_2U(SCH_1):M_A_CPU0_SB_DQS_DP(9)     I1 @S9S_MB_2U_LIB.S9S_MB_2U(SCH_1):PAGE20
    E9 M_A_CPU0_SB_DQS_DP<8> @S9S_MB_2U_LIB.S9S_MB_2U(SCH_1):M_A_CPU0_SB_DQS_DP(8)     I1 @S9S_MB_2U_LIB.S9S_MB_2U(SCH_1):PAGE20
   E21 M_A_CPU0_SB_DQS_DP<7> @S9S_MB_2U_LIB.S9S_MB_2U(SCH_1):M_A_CPU0_SB_DQS_DP(7)     I1 @S9S_MB_2U_LIB.S9S_MB_2U(SCH_1):PAGE20
   E27 M_A_CPU0_SB_DQS_DP<6> @S9S_MB_2U_LIB.S9S_MB_2U(SCH_1):M_A_CPU0_SB_DQS_DP(6)     I1 @S9S_MB_2U_LIB.S9S_MB_2U(SCH_1):PAGE20
   P30 M_A_CPU0_SB_DQS_DP<5> @S9S_MB_2U_LIB.S9S_MB_2U(SCH_1):M_A_CPU0_SB_DQS_DP(5)     I1 @S9S_MB_2U_LIB.S9S_MB_2U(SCH_1):PAGE20
   E33 M_A_CPU0_SB_DQS_DP<4> @S9S_MB_2U_LIB.S9S_MB_2U(SCH_1):M_A_CPU0_SB_DQS_DP(4)     I1 @S9S_MB_2U_LIB.S9S_MB_2U(SCH_1):PAGE20
    C9 M_A_CPU0_SB_DQS_DP<3> @S9S_MB_2U_LIB.S9S_MB_2U(SCH_1):M_A_CPU0_SB_DQS_DP(3)     I1 @S9S_MB_2U_LIB.S9S_MB_2U(SCH_1):PAGE20
   C21 M_A_CPU0_SB_DQS_DP<2> @S9S_MB_2U_LIB.S9S_MB_2U(SCH_1):M_A_CPU0_SB_DQS_DP(2)     I1 @S9S_MB_2U_LIB.S9S_MB_2U(SCH_1):PAGE20
   C27 M_A_CPU0_SB_DQS_DP<1> @S9S_MB_2U_LIB.S9S_MB_2U(SCH_1):M_A_CPU0_SB_DQS_DP(1)     I1 @S9S_MB_2U_LIB.S9S_MB_2U(SCH_1):PAGE20
   K30 M_A_CPU0_SB_DQS_DP<0> @S9S_MB_2U_LIB.S9S_MB_2U(SCH_1):M_A_CPU0_SB_DQS_DP(0)     I1 @S9S_MB_2U_LIB.S9S_MB_2U(SCH_1):PAGE20
   F34 M_A_CPU0_SB_CB<7> @S9S_MB_2U_LIB.S9S_MB_2U(SCH_1):M_A_CPU0_SB_CB(7)     I1 @S9S_MB_2U_LIB.S9S_MB_2U(SCH_1):PAGE20
   E35 M_A_CPU0_SB_CB<6> @S9S_MB_2U_LIB.S9S_MB_2U(SCH_1):M_A_CPU0_SB_CB(6)     I1 @S9S_MB_2U_LIB.S9S_MB_2U(SCH_1):PAGE20
   B34 M_A_CPU0_SB_CB<5> @S9S_MB_2U_LIB.S9S_MB_2U(SCH_1):M_A_CPU0_SB_CB(5)     I1 @S9S_MB_2U_LIB.S9S_MB_2U(SCH_1):PAGE20
   C35 M_A_CPU0_SB_CB<4> @S9S_MB_2U_LIB.S9S_MB_2U(SCH_1):M_A_CPU0_SB_CB(4)     I1 @S9S_MB_2U_LIB.S9S_MB_2U(SCH_1):PAGE20
   E31 M_A_CPU0_SB_CB<3> @S9S_MB_2U_LIB.S9S_MB_2U(SCH_1):M_A_CPU0_SB_CB(3)     I1 @S9S_MB_2U_LIB.S9S_MB_2U(SCH_1):PAGE20
   F32 M_A_CPU0_SB_CB<2> @S9S_MB_2U_LIB.S9S_MB_2U(SCH_1):M_A_CPU0_SB_CB(2)     I1 @S9S_MB_2U_LIB.S9S_MB_2U(SCH_1):PAGE20
   C31 M_A_CPU0_SB_CB<1> @S9S_MB_2U_LIB.S9S_MB_2U(SCH_1):M_A_CPU0_SB_CB(1)     I1 @S9S_MB_2U_LIB.S9S_MB_2U(SCH_1):PAGE20
   B32 M_A_CPU0_SB_CB<0> @S9S_MB_2U_LIB.S9S_MB_2U(SCH_1):M_A_CPU0_SB_CB(0)     I1 @S9S_MB_2U_LIB.S9S_MB_2U(SCH_1):PAGE20
   G39 M_A_CPU0_SB_PAR @S9S_MB_2U_LIB.S9S_MB_2U(SCH_1):M_A_CPU0_SB_PAR     I1 @S9S_MB_2U_LIB.S9S_MB_2U(SCH_1):PAGE20
  AV49 M_B_CPU0_ALERT_N @S9S_MB_2U_LIB.S9S_MB_2U(SCH_1):M_B_CPU0_ALERT_N   I169 @S9S_MB_2U_LIB.S9S_MB_2U(SCH_1):PAGE21
  AK47 M_B_CPU0_SA_RSP<1> @S9S_MB_2U_LIB.S9S_MB_2U(SCH_1):M_B_CPU0_SA_RSP(1)   I169 @S9S_MB_2U_LIB.S9S_MB_2U(SCH_1):PAGE21
  AL48 M_B_CPU0_SA_RSP<0> @S9S_MB_2U_LIB.S9S_MB_2U(SCH_1):M_B_CPU0_SA_RSP(0)   I169 @S9S_MB_2U_LIB.S9S_MB_2U(SCH_1):PAGE21
  AP47 M_B_CPU0_SB_RSP<1> @S9S_MB_2U_LIB.S9S_MB_2U(SCH_1):M_B_CPU0_SB_RSP(1)   I169 @S9S_MB_2U_LIB.S9S_MB_2U(SCH_1):PAGE21
  AN48 M_B_CPU0_SB_RSP<0> @S9S_MB_2U_LIB.S9S_MB_2U(SCH_1):M_B_CPU0_SB_RSP(0)   I169 @S9S_MB_2U_LIB.S9S_MB_2U(SCH_1):PAGE21
   W45 M_B_CPU0_CLK_DN<1> @S9S_MB_2U_LIB.S9S_MB_2U(SCH_1):M_B_CPU0_CLK_DN(1)   I169 @S9S_MB_2U_LIB.S9S_MB_2U(SCH_1):PAGE21
   R45 M_B_CPU0_CLK_DN<0> @S9S_MB_2U_LIB.S9S_MB_2U(SCH_1):M_B_CPU0_CLK_DN(0)   I169 @S9S_MB_2U_LIB.S9S_MB_2U(SCH_1):PAGE21
  AA45 M_B_CPU0_CLK_DP<1> @S9S_MB_2U_LIB.S9S_MB_2U(SCH_1):M_B_CPU0_CLK_DP(1)   I169 @S9S_MB_2U_LIB.S9S_MB_2U(SCH_1):PAGE21
   U45 M_B_CPU0_CLK_DP<0> @S9S_MB_2U_LIB.S9S_MB_2U(SCH_1):M_B_CPU0_CLK_DP(0)   I169 @S9S_MB_2U_LIB.S9S_MB_2U(SCH_1):PAGE21
   Y44 M_B_CPU0_SA_CA<6> @S9S_MB_2U_LIB.S9S_MB_2U(SCH_1):M_B_CPU0_SA_CA(6)   I169 @S9S_MB_2U_LIB.S9S_MB_2U(SCH_1):PAGE21
   M47 M_B_CPU0_SA_CA<5> @S9S_MB_2U_LIB.S9S_MB_2U(SCH_1):M_B_CPU0_SA_CA(5)   I169 @S9S_MB_2U_LIB.S9S_MB_2U(SCH_1):PAGE21
   K47 M_B_CPU0_SA_CA<4> @S9S_MB_2U_LIB.S9S_MB_2U(SCH_1):M_B_CPU0_SA_CA(4)   I169 @S9S_MB_2U_LIB.S9S_MB_2U(SCH_1):PAGE21
   N48 M_B_CPU0_SA_CA<3> @S9S_MB_2U_LIB.S9S_MB_2U(SCH_1):M_B_CPU0_SA_CA(3)   I169 @S9S_MB_2U_LIB.S9S_MB_2U(SCH_1):PAGE21
   J48 M_B_CPU0_SA_CA<2> @S9S_MB_2U_LIB.S9S_MB_2U(SCH_1):M_B_CPU0_SA_CA(2)   I169 @S9S_MB_2U_LIB.S9S_MB_2U(SCH_1):PAGE21
   P49 M_B_CPU0_SA_CA<1> @S9S_MB_2U_LIB.S9S_MB_2U(SCH_1):M_B_CPU0_SA_CA(1)   I169 @S9S_MB_2U_LIB.S9S_MB_2U(SCH_1):PAGE21
   H49 M_B_CPU0_SA_CA<0> @S9S_MB_2U_LIB.S9S_MB_2U(SCH_1):M_B_CPU0_SA_CA(0)   I169 @S9S_MB_2U_LIB.S9S_MB_2U(SCH_1):PAGE21
   N50 M_B_CPU0_SA_CS_N<3> @S9S_MB_2U_LIB.S9S_MB_2U(SCH_1):M_B_CPU0_SA_CS_N(3)   I169 @S9S_MB_2U_LIB.S9S_MB_2U(SCH_1):PAGE21
   M51 M_B_CPU0_SA_CS_N<2> @S9S_MB_2U_LIB.S9S_MB_2U(SCH_1):M_B_CPU0_SA_CS_N(2)   I169 @S9S_MB_2U_LIB.S9S_MB_2U(SCH_1):PAGE21
   J50 M_B_CPU0_SA_CS_N<1> @S9S_MB_2U_LIB.S9S_MB_2U(SCH_1):M_B_CPU0_SA_CS_N(1)   I169 @S9S_MB_2U_LIB.S9S_MB_2U(SCH_1):PAGE21
   K51 M_B_CPU0_SA_CS_N<0> @S9S_MB_2U_LIB.S9S_MB_2U(SCH_1):M_B_CPU0_SA_CS_N(0)   I169 @S9S_MB_2U_LIB.S9S_MB_2U(SCH_1):PAGE21
   W56 M_B_CPU0_SA_DQ<31> @S9S_MB_2U_LIB.S9S_MB_2U(SCH_1):M_B_CPU0_SA_DQ(31)   I169 @S9S_MB_2U_LIB.S9S_MB_2U(SCH_1):PAGE21
   Y57 M_B_CPU0_SA_DQ<30> @S9S_MB_2U_LIB.S9S_MB_2U(SCH_1):M_B_CPU0_SA_DQ(30)   I169 @S9S_MB_2U_LIB.S9S_MB_2U(SCH_1):PAGE21
   U56 M_B_CPU0_SA_DQ<29> @S9S_MB_2U_LIB.S9S_MB_2U(SCH_1):M_B_CPU0_SA_DQ(29)   I169 @S9S_MB_2U_LIB.S9S_MB_2U(SCH_1):PAGE21
   T57 M_B_CPU0_SA_DQ<28> @S9S_MB_2U_LIB.S9S_MB_2U(SCH_1):M_B_CPU0_SA_DQ(28)   I169 @S9S_MB_2U_LIB.S9S_MB_2U(SCH_1):PAGE21
   Y59 M_B_CPU0_SA_DQ<27> @S9S_MB_2U_LIB.S9S_MB_2U(SCH_1):M_B_CPU0_SA_DQ(27)   I169 @S9S_MB_2U_LIB.S9S_MB_2U(SCH_1):PAGE21
   W60 M_B_CPU0_SA_DQ<26> @S9S_MB_2U_LIB.S9S_MB_2U(SCH_1):M_B_CPU0_SA_DQ(26)   I169 @S9S_MB_2U_LIB.S9S_MB_2U(SCH_1):PAGE21
   T59 M_B_CPU0_SA_DQ<25> @S9S_MB_2U_LIB.S9S_MB_2U(SCH_1):M_B_CPU0_SA_DQ(25)   I169 @S9S_MB_2U_LIB.S9S_MB_2U(SCH_1):PAGE21
   U60 M_B_CPU0_SA_DQ<24> @S9S_MB_2U_LIB.S9S_MB_2U(SCH_1):M_B_CPU0_SA_DQ(24)   I169 @S9S_MB_2U_LIB.S9S_MB_2U(SCH_1):PAGE21
   M59 M_B_CPU0_SA_DQ<23> @S9S_MB_2U_LIB.S9S_MB_2U(SCH_1):M_B_CPU0_SA_DQ(23)   I169 @S9S_MB_2U_LIB.S9S_MB_2U(SCH_1):PAGE21
   N60 M_B_CPU0_SA_DQ<22> @S9S_MB_2U_LIB.S9S_MB_2U(SCH_1):M_B_CPU0_SA_DQ(22)   I169 @S9S_MB_2U_LIB.S9S_MB_2U(SCH_1):PAGE21
   K59 M_B_CPU0_SA_DQ<21> @S9S_MB_2U_LIB.S9S_MB_2U(SCH_1):M_B_CPU0_SA_DQ(21)   I169 @S9S_MB_2U_LIB.S9S_MB_2U(SCH_1):PAGE21
   J60 M_B_CPU0_SA_DQ<20> @S9S_MB_2U_LIB.S9S_MB_2U(SCH_1):M_B_CPU0_SA_DQ(20)   I169 @S9S_MB_2U_LIB.S9S_MB_2U(SCH_1):PAGE21
   N62 M_B_CPU0_SA_DQ<19> @S9S_MB_2U_LIB.S9S_MB_2U(SCH_1):M_B_CPU0_SA_DQ(19)   I169 @S9S_MB_2U_LIB.S9S_MB_2U(SCH_1):PAGE21
   M63 M_B_CPU0_SA_DQ<18> @S9S_MB_2U_LIB.S9S_MB_2U(SCH_1):M_B_CPU0_SA_DQ(18)   I169 @S9S_MB_2U_LIB.S9S_MB_2U(SCH_1):PAGE21
   J62 M_B_CPU0_SA_DQ<17> @S9S_MB_2U_LIB.S9S_MB_2U(SCH_1):M_B_CPU0_SA_DQ(17)   I169 @S9S_MB_2U_LIB.S9S_MB_2U(SCH_1):PAGE21
   K63 M_B_CPU0_SA_DQ<16> @S9S_MB_2U_LIB.S9S_MB_2U(SCH_1):M_B_CPU0_SA_DQ(16)   I169 @S9S_MB_2U_LIB.S9S_MB_2U(SCH_1):PAGE21
   W68 M_B_CPU0_SA_DQ<15> @S9S_MB_2U_LIB.S9S_MB_2U(SCH_1):M_B_CPU0_SA_DQ(15)   I169 @S9S_MB_2U_LIB.S9S_MB_2U(SCH_1):PAGE21
   Y69 M_B_CPU0_SA_DQ<14> @S9S_MB_2U_LIB.S9S_MB_2U(SCH_1):M_B_CPU0_SA_DQ(14)   I169 @S9S_MB_2U_LIB.S9S_MB_2U(SCH_1):PAGE21
   U68 M_B_CPU0_SA_DQ<13> @S9S_MB_2U_LIB.S9S_MB_2U(SCH_1):M_B_CPU0_SA_DQ(13)   I169 @S9S_MB_2U_LIB.S9S_MB_2U(SCH_1):PAGE21
   T69 M_B_CPU0_SA_DQ<12> @S9S_MB_2U_LIB.S9S_MB_2U(SCH_1):M_B_CPU0_SA_DQ(12)   I169 @S9S_MB_2U_LIB.S9S_MB_2U(SCH_1):PAGE21
   Y71 M_B_CPU0_SA_DQ<11> @S9S_MB_2U_LIB.S9S_MB_2U(SCH_1):M_B_CPU0_SA_DQ(11)   I169 @S9S_MB_2U_LIB.S9S_MB_2U(SCH_1):PAGE21
   W72 M_B_CPU0_SA_DQ<10> @S9S_MB_2U_LIB.S9S_MB_2U(SCH_1):M_B_CPU0_SA_DQ(10)   I169 @S9S_MB_2U_LIB.S9S_MB_2U(SCH_1):PAGE21
   T71 M_B_CPU0_SA_DQ<9> @S9S_MB_2U_LIB.S9S_MB_2U(SCH_1):M_B_CPU0_SA_DQ(9)   I169 @S9S_MB_2U_LIB.S9S_MB_2U(SCH_1):PAGE21
   U72 M_B_CPU0_SA_DQ<8> @S9S_MB_2U_LIB.S9S_MB_2U(SCH_1):M_B_CPU0_SA_DQ(8)   I169 @S9S_MB_2U_LIB.S9S_MB_2U(SCH_1):PAGE21
   M71 M_B_CPU0_SA_DQ<7> @S9S_MB_2U_LIB.S9S_MB_2U(SCH_1):M_B_CPU0_SA_DQ(7)   I169 @S9S_MB_2U_LIB.S9S_MB_2U(SCH_1):PAGE21
   N72 M_B_CPU0_SA_DQ<6> @S9S_MB_2U_LIB.S9S_MB_2U(SCH_1):M_B_CPU0_SA_DQ(6)   I169 @S9S_MB_2U_LIB.S9S_MB_2U(SCH_1):PAGE21
   K71 M_B_CPU0_SA_DQ<5> @S9S_MB_2U_LIB.S9S_MB_2U(SCH_1):M_B_CPU0_SA_DQ(5)   I169 @S9S_MB_2U_LIB.S9S_MB_2U(SCH_1):PAGE21
   J72 M_B_CPU0_SA_DQ<4> @S9S_MB_2U_LIB.S9S_MB_2U(SCH_1):M_B_CPU0_SA_DQ(4)   I169 @S9S_MB_2U_LIB.S9S_MB_2U(SCH_1):PAGE21
   N74 M_B_CPU0_SA_DQ<3> @S9S_MB_2U_LIB.S9S_MB_2U(SCH_1):M_B_CPU0_SA_DQ(3)   I169 @S9S_MB_2U_LIB.S9S_MB_2U(SCH_1):PAGE21
   M75 M_B_CPU0_SA_DQ<2> @S9S_MB_2U_LIB.S9S_MB_2U(SCH_1):M_B_CPU0_SA_DQ(2)   I169 @S9S_MB_2U_LIB.S9S_MB_2U(SCH_1):PAGE21
   J74 M_B_CPU0_SA_DQ<1> @S9S_MB_2U_LIB.S9S_MB_2U(SCH_1):M_B_CPU0_SA_DQ(1)   I169 @S9S_MB_2U_LIB.S9S_MB_2U(SCH_1):PAGE21
   K75 M_B_CPU0_SA_DQ<0> @S9S_MB_2U_LIB.S9S_MB_2U(SCH_1):M_B_CPU0_SA_DQ(0)   I169 @S9S_MB_2U_LIB.S9S_MB_2U(SCH_1):PAGE21
   M55 M_B_CPU0_SA_DQS_DN<9> @S9S_MB_2U_LIB.S9S_MB_2U(SCH_1):M_B_CPU0_SA_DQS_DN(9)   I169 @S9S_MB_2U_LIB.S9S_MB_2U(SCH_1):PAGE21
  AA58 M_B_CPU0_SA_DQS_DN<8> @S9S_MB_2U_LIB.S9S_MB_2U(SCH_1):M_B_CPU0_SA_DQS_DN(8)   I169 @S9S_MB_2U_LIB.S9S_MB_2U(SCH_1):PAGE21
   M61 M_B_CPU0_SA_DQS_DN<7> @S9S_MB_2U_LIB.S9S_MB_2U(SCH_1):M_B_CPU0_SA_DQS_DN(7)   I169 @S9S_MB_2U_LIB.S9S_MB_2U(SCH_1):PAGE21
  AA70 M_B_CPU0_SA_DQS_DN<6> @S9S_MB_2U_LIB.S9S_MB_2U(SCH_1):M_B_CPU0_SA_DQS_DN(6)   I169 @S9S_MB_2U_LIB.S9S_MB_2U(SCH_1):PAGE21
   M73 M_B_CPU0_SA_DQS_DN<5> @S9S_MB_2U_LIB.S9S_MB_2U(SCH_1):M_B_CPU0_SA_DQS_DN(5)   I169 @S9S_MB_2U_LIB.S9S_MB_2U(SCH_1):PAGE21
   H55 M_B_CPU0_SA_DQS_DN<4> @S9S_MB_2U_LIB.S9S_MB_2U(SCH_1):M_B_CPU0_SA_DQS_DN(4)   I169 @S9S_MB_2U_LIB.S9S_MB_2U(SCH_1):PAGE21
   R58 M_B_CPU0_SA_DQS_DN<3> @S9S_MB_2U_LIB.S9S_MB_2U(SCH_1):M_B_CPU0_SA_DQS_DN(3)   I169 @S9S_MB_2U_LIB.S9S_MB_2U(SCH_1):PAGE21
   H61 M_B_CPU0_SA_DQS_DN<2> @S9S_MB_2U_LIB.S9S_MB_2U(SCH_1):M_B_CPU0_SA_DQS_DN(2)   I169 @S9S_MB_2U_LIB.S9S_MB_2U(SCH_1):PAGE21
   R70 M_B_CPU0_SA_DQS_DN<1> @S9S_MB_2U_LIB.S9S_MB_2U(SCH_1):M_B_CPU0_SA_DQS_DN(1)   I169 @S9S_MB_2U_LIB.S9S_MB_2U(SCH_1):PAGE21
   H73 M_B_CPU0_SA_DQS_DN<0> @S9S_MB_2U_LIB.S9S_MB_2U(SCH_1):M_B_CPU0_SA_DQS_DN(0)   I169 @S9S_MB_2U_LIB.S9S_MB_2U(SCH_1):PAGE21
   P55 M_B_CPU0_SA_DQS_DP<9> @S9S_MB_2U_LIB.S9S_MB_2U(SCH_1):M_B_CPU0_SA_DQS_DP(9)   I169 @S9S_MB_2U_LIB.S9S_MB_2U(SCH_1):PAGE21
   W58 M_B_CPU0_SA_DQS_DP<8> @S9S_MB_2U_LIB.S9S_MB_2U(SCH_1):M_B_CPU0_SA_DQS_DP(8)   I169 @S9S_MB_2U_LIB.S9S_MB_2U(SCH_1):PAGE21
   P61 M_B_CPU0_SA_DQS_DP<7> @S9S_MB_2U_LIB.S9S_MB_2U(SCH_1):M_B_CPU0_SA_DQS_DP(7)   I169 @S9S_MB_2U_LIB.S9S_MB_2U(SCH_1):PAGE21
   W70 M_B_CPU0_SA_DQS_DP<6> @S9S_MB_2U_LIB.S9S_MB_2U(SCH_1):M_B_CPU0_SA_DQS_DP(6)   I169 @S9S_MB_2U_LIB.S9S_MB_2U(SCH_1):PAGE21
   P73 M_B_CPU0_SA_DQS_DP<5> @S9S_MB_2U_LIB.S9S_MB_2U(SCH_1):M_B_CPU0_SA_DQS_DP(5)   I169 @S9S_MB_2U_LIB.S9S_MB_2U(SCH_1):PAGE21
   K55 M_B_CPU0_SA_DQS_DP<4> @S9S_MB_2U_LIB.S9S_MB_2U(SCH_1):M_B_CPU0_SA_DQS_DP(4)   I169 @S9S_MB_2U_LIB.S9S_MB_2U(SCH_1):PAGE21
   U58 M_B_CPU0_SA_DQS_DP<3> @S9S_MB_2U_LIB.S9S_MB_2U(SCH_1):M_B_CPU0_SA_DQS_DP(3)   I169 @S9S_MB_2U_LIB.S9S_MB_2U(SCH_1):PAGE21
   K61 M_B_CPU0_SA_DQS_DP<2> @S9S_MB_2U_LIB.S9S_MB_2U(SCH_1):M_B_CPU0_SA_DQS_DP(2)   I169 @S9S_MB_2U_LIB.S9S_MB_2U(SCH_1):PAGE21
   U70 M_B_CPU0_SA_DQS_DP<1> @S9S_MB_2U_LIB.S9S_MB_2U(SCH_1):M_B_CPU0_SA_DQS_DP(1)   I169 @S9S_MB_2U_LIB.S9S_MB_2U(SCH_1):PAGE21
   K73 M_B_CPU0_SA_DQS_DP<0> @S9S_MB_2U_LIB.S9S_MB_2U(SCH_1):M_B_CPU0_SA_DQS_DP(0)   I169 @S9S_MB_2U_LIB.S9S_MB_2U(SCH_1):PAGE21
   M53 M_B_CPU0_SA_CB<7> @S9S_MB_2U_LIB.S9S_MB_2U(SCH_1):M_B_CPU0_SA_CB(7)   I169 @S9S_MB_2U_LIB.S9S_MB_2U(SCH_1):PAGE21
   N54 M_B_CPU0_SA_CB<6> @S9S_MB_2U_LIB.S9S_MB_2U(SCH_1):M_B_CPU0_SA_CB(6)   I169 @S9S_MB_2U_LIB.S9S_MB_2U(SCH_1):PAGE21
   K53 M_B_CPU0_SA_CB<5> @S9S_MB_2U_LIB.S9S_MB_2U(SCH_1):M_B_CPU0_SA_CB(5)   I169 @S9S_MB_2U_LIB.S9S_MB_2U(SCH_1):PAGE21
   J54 M_B_CPU0_SA_CB<4> @S9S_MB_2U_LIB.S9S_MB_2U(SCH_1):M_B_CPU0_SA_CB(4)   I169 @S9S_MB_2U_LIB.S9S_MB_2U(SCH_1):PAGE21
   N56 M_B_CPU0_SA_CB<3> @S9S_MB_2U_LIB.S9S_MB_2U(SCH_1):M_B_CPU0_SA_CB(3)   I169 @S9S_MB_2U_LIB.S9S_MB_2U(SCH_1):PAGE21
   M57 M_B_CPU0_SA_CB<2> @S9S_MB_2U_LIB.S9S_MB_2U(SCH_1):M_B_CPU0_SA_CB(2)   I169 @S9S_MB_2U_LIB.S9S_MB_2U(SCH_1):PAGE21
   J56 M_B_CPU0_SA_CB<1> @S9S_MB_2U_LIB.S9S_MB_2U(SCH_1):M_B_CPU0_SA_CB(1)   I169 @S9S_MB_2U_LIB.S9S_MB_2U(SCH_1):PAGE21
   K57 M_B_CPU0_SA_CB<0> @S9S_MB_2U_LIB.S9S_MB_2U(SCH_1):M_B_CPU0_SA_CB(0)   I169 @S9S_MB_2U_LIB.S9S_MB_2U(SCH_1):PAGE21
   W43 M_B_CPU0_SA_PAR @S9S_MB_2U_LIB.S9S_MB_2U(SCH_1):M_B_CPU0_SA_PAR   I169 @S9S_MB_2U_LIB.S9S_MB_2U(SCH_1):PAGE21
   H42 M_B_CPU0_SB_CA<6> @S9S_MB_2U_LIB.S9S_MB_2U(SCH_1):M_B_CPU0_SB_CA(6)   I169 @S9S_MB_2U_LIB.S9S_MB_2U(SCH_1):PAGE21
   N43 M_B_CPU0_SB_CA<5> @S9S_MB_2U_LIB.S9S_MB_2U(SCH_1):M_B_CPU0_SB_CA(5)   I169 @S9S_MB_2U_LIB.S9S_MB_2U(SCH_1):PAGE21
   J43 M_B_CPU0_SB_CA<4> @S9S_MB_2U_LIB.S9S_MB_2U(SCH_1):M_B_CPU0_SB_CA(4)   I169 @S9S_MB_2U_LIB.S9S_MB_2U(SCH_1):PAGE21
   M44 M_B_CPU0_SB_CA<3> @S9S_MB_2U_LIB.S9S_MB_2U(SCH_1):M_B_CPU0_SB_CA(3)   I169 @S9S_MB_2U_LIB.S9S_MB_2U(SCH_1):PAGE21
   K44 M_B_CPU0_SB_CA<2> @S9S_MB_2U_LIB.S9S_MB_2U(SCH_1):M_B_CPU0_SB_CA(2)   I169 @S9S_MB_2U_LIB.S9S_MB_2U(SCH_1):PAGE21
   U43 M_B_CPU0_SB_CA<1> @S9S_MB_2U_LIB.S9S_MB_2U(SCH_1):M_B_CPU0_SB_CA(1)   I169 @S9S_MB_2U_LIB.S9S_MB_2U(SCH_1):PAGE21
   T44 M_B_CPU0_SB_CA<0> @S9S_MB_2U_LIB.S9S_MB_2U(SCH_1):M_B_CPU0_SB_CA(0)   I169 @S9S_MB_2U_LIB.S9S_MB_2U(SCH_1):PAGE21
   M40 M_B_CPU0_SB_CS_N<3> @S9S_MB_2U_LIB.S9S_MB_2U(SCH_1):M_B_CPU0_SB_CS_N(3)   I169 @S9S_MB_2U_LIB.S9S_MB_2U(SCH_1):PAGE21
   N41 M_B_CPU0_SB_CS_N<2> @S9S_MB_2U_LIB.S9S_MB_2U(SCH_1):M_B_CPU0_SB_CS_N(2)   I169 @S9S_MB_2U_LIB.S9S_MB_2U(SCH_1):PAGE21
   K40 M_B_CPU0_SB_CS_N<1> @S9S_MB_2U_LIB.S9S_MB_2U(SCH_1):M_B_CPU0_SB_CS_N(1)   I169 @S9S_MB_2U_LIB.S9S_MB_2U(SCH_1):PAGE21
   J41 M_B_CPU0_SB_CS_N<0> @S9S_MB_2U_LIB.S9S_MB_2U(SCH_1):M_B_CPU0_SB_CS_N(0)   I169 @S9S_MB_2U_LIB.S9S_MB_2U(SCH_1):PAGE21
   F14 M_B_CPU0_SB_DQ<31> @S9S_MB_2U_LIB.S9S_MB_2U(SCH_1):M_B_CPU0_SB_DQ(31)   I169 @S9S_MB_2U_LIB.S9S_MB_2U(SCH_1):PAGE21
   B14 M_B_CPU0_SB_DQ<30> @S9S_MB_2U_LIB.S9S_MB_2U(SCH_1):M_B_CPU0_SB_DQ(30)   I169 @S9S_MB_2U_LIB.S9S_MB_2U(SCH_1):PAGE21
   E13 M_B_CPU0_SB_DQ<29> @S9S_MB_2U_LIB.S9S_MB_2U(SCH_1):M_B_CPU0_SB_DQ(29)   I169 @S9S_MB_2U_LIB.S9S_MB_2U(SCH_1):PAGE21
   C13 M_B_CPU0_SB_DQ<28> @S9S_MB_2U_LIB.S9S_MB_2U(SCH_1):M_B_CPU0_SB_DQ(28)   I169 @S9S_MB_2U_LIB.S9S_MB_2U(SCH_1):PAGE21
   F16 M_B_CPU0_SB_DQ<27> @S9S_MB_2U_LIB.S9S_MB_2U(SCH_1):M_B_CPU0_SB_DQ(27)   I169 @S9S_MB_2U_LIB.S9S_MB_2U(SCH_1):PAGE21
   E17 M_B_CPU0_SB_DQ<26> @S9S_MB_2U_LIB.S9S_MB_2U(SCH_1):M_B_CPU0_SB_DQ(26)   I169 @S9S_MB_2U_LIB.S9S_MB_2U(SCH_1):PAGE21
   B16 M_B_CPU0_SB_DQ<25> @S9S_MB_2U_LIB.S9S_MB_2U(SCH_1):M_B_CPU0_SB_DQ(25)   I169 @S9S_MB_2U_LIB.S9S_MB_2U(SCH_1):PAGE21
   C17 M_B_CPU0_SB_DQ<24> @S9S_MB_2U_LIB.S9S_MB_2U(SCH_1):M_B_CPU0_SB_DQ(24)   I169 @S9S_MB_2U_LIB.S9S_MB_2U(SCH_1):PAGE21
   M16 M_B_CPU0_SB_DQ<23> @S9S_MB_2U_LIB.S9S_MB_2U(SCH_1):M_B_CPU0_SB_DQ(23)   I169 @S9S_MB_2U_LIB.S9S_MB_2U(SCH_1):PAGE21
   N17 M_B_CPU0_SB_DQ<22> @S9S_MB_2U_LIB.S9S_MB_2U(SCH_1):M_B_CPU0_SB_DQ(22)   I169 @S9S_MB_2U_LIB.S9S_MB_2U(SCH_1):PAGE21
   K16 M_B_CPU0_SB_DQ<21> @S9S_MB_2U_LIB.S9S_MB_2U(SCH_1):M_B_CPU0_SB_DQ(21)   I169 @S9S_MB_2U_LIB.S9S_MB_2U(SCH_1):PAGE21
   J17 M_B_CPU0_SB_DQ<20> @S9S_MB_2U_LIB.S9S_MB_2U(SCH_1):M_B_CPU0_SB_DQ(20)   I169 @S9S_MB_2U_LIB.S9S_MB_2U(SCH_1):PAGE21
   N19 M_B_CPU0_SB_DQ<19> @S9S_MB_2U_LIB.S9S_MB_2U(SCH_1):M_B_CPU0_SB_DQ(19)   I169 @S9S_MB_2U_LIB.S9S_MB_2U(SCH_1):PAGE21
   M20 M_B_CPU0_SB_DQ<18> @S9S_MB_2U_LIB.S9S_MB_2U(SCH_1):M_B_CPU0_SB_DQ(18)   I169 @S9S_MB_2U_LIB.S9S_MB_2U(SCH_1):PAGE21
   J19 M_B_CPU0_SB_DQ<17> @S9S_MB_2U_LIB.S9S_MB_2U(SCH_1):M_B_CPU0_SB_DQ(17)   I169 @S9S_MB_2U_LIB.S9S_MB_2U(SCH_1):PAGE21
   K20 M_B_CPU0_SB_DQ<16> @S9S_MB_2U_LIB.S9S_MB_2U(SCH_1):M_B_CPU0_SB_DQ(16)   I169 @S9S_MB_2U_LIB.S9S_MB_2U(SCH_1):PAGE21
   M22 M_B_CPU0_SB_DQ<15> @S9S_MB_2U_LIB.S9S_MB_2U(SCH_1):M_B_CPU0_SB_DQ(15)   I169 @S9S_MB_2U_LIB.S9S_MB_2U(SCH_1):PAGE21
   N23 M_B_CPU0_SB_DQ<14> @S9S_MB_2U_LIB.S9S_MB_2U(SCH_1):M_B_CPU0_SB_DQ(14)   I169 @S9S_MB_2U_LIB.S9S_MB_2U(SCH_1):PAGE21
   K22 M_B_CPU0_SB_DQ<13> @S9S_MB_2U_LIB.S9S_MB_2U(SCH_1):M_B_CPU0_SB_DQ(13)   I169 @S9S_MB_2U_LIB.S9S_MB_2U(SCH_1):PAGE21
   J23 M_B_CPU0_SB_DQ<12> @S9S_MB_2U_LIB.S9S_MB_2U(SCH_1):M_B_CPU0_SB_DQ(12)   I169 @S9S_MB_2U_LIB.S9S_MB_2U(SCH_1):PAGE21
   N25 M_B_CPU0_SB_DQ<11> @S9S_MB_2U_LIB.S9S_MB_2U(SCH_1):M_B_CPU0_SB_DQ(11)   I169 @S9S_MB_2U_LIB.S9S_MB_2U(SCH_1):PAGE21
   M26 M_B_CPU0_SB_DQ<10> @S9S_MB_2U_LIB.S9S_MB_2U(SCH_1):M_B_CPU0_SB_DQ(10)   I169 @S9S_MB_2U_LIB.S9S_MB_2U(SCH_1):PAGE21
   J25 M_B_CPU0_SB_DQ<9> @S9S_MB_2U_LIB.S9S_MB_2U(SCH_1):M_B_CPU0_SB_DQ(9)   I169 @S9S_MB_2U_LIB.S9S_MB_2U(SCH_1):PAGE21
   K26 M_B_CPU0_SB_DQ<8> @S9S_MB_2U_LIB.S9S_MB_2U(SCH_1):M_B_CPU0_SB_DQ(8)   I169 @S9S_MB_2U_LIB.S9S_MB_2U(SCH_1):PAGE21
   W25 M_B_CPU0_SB_DQ<7> @S9S_MB_2U_LIB.S9S_MB_2U(SCH_1):M_B_CPU0_SB_DQ(7)   I169 @S9S_MB_2U_LIB.S9S_MB_2U(SCH_1):PAGE21
   Y26 M_B_CPU0_SB_DQ<6> @S9S_MB_2U_LIB.S9S_MB_2U(SCH_1):M_B_CPU0_SB_DQ(6)   I169 @S9S_MB_2U_LIB.S9S_MB_2U(SCH_1):PAGE21
   U25 M_B_CPU0_SB_DQ<5> @S9S_MB_2U_LIB.S9S_MB_2U(SCH_1):M_B_CPU0_SB_DQ(5)   I169 @S9S_MB_2U_LIB.S9S_MB_2U(SCH_1):PAGE21
   T26 M_B_CPU0_SB_DQ<4> @S9S_MB_2U_LIB.S9S_MB_2U(SCH_1):M_B_CPU0_SB_DQ(4)   I169 @S9S_MB_2U_LIB.S9S_MB_2U(SCH_1):PAGE21
   Y28 M_B_CPU0_SB_DQ<3> @S9S_MB_2U_LIB.S9S_MB_2U(SCH_1):M_B_CPU0_SB_DQ(3)   I169 @S9S_MB_2U_LIB.S9S_MB_2U(SCH_1):PAGE21
   W29 M_B_CPU0_SB_DQ<2> @S9S_MB_2U_LIB.S9S_MB_2U(SCH_1):M_B_CPU0_SB_DQ(2)   I169 @S9S_MB_2U_LIB.S9S_MB_2U(SCH_1):PAGE21
   T28 M_B_CPU0_SB_DQ<1> @S9S_MB_2U_LIB.S9S_MB_2U(SCH_1):M_B_CPU0_SB_DQ(1)   I169 @S9S_MB_2U_LIB.S9S_MB_2U(SCH_1):PAGE21
   U29 M_B_CPU0_SB_DQ<0> @S9S_MB_2U_LIB.S9S_MB_2U(SCH_1):M_B_CPU0_SB_DQ(0)   I169 @S9S_MB_2U_LIB.S9S_MB_2U(SCH_1):PAGE21
   K36 M_B_CPU0_SB_DQS_DN<9> @S9S_MB_2U_LIB.S9S_MB_2U(SCH_1):M_B_CPU0_SB_DQS_DN(9)   I169 @S9S_MB_2U_LIB.S9S_MB_2U(SCH_1):PAGE21
   E15 M_B_CPU0_SB_DQS_DN<8> @S9S_MB_2U_LIB.S9S_MB_2U(SCH_1):M_B_CPU0_SB_DQS_DN(8)   I169 @S9S_MB_2U_LIB.S9S_MB_2U(SCH_1):PAGE21
   M18 M_B_CPU0_SB_DQS_DN<7> @S9S_MB_2U_LIB.S9S_MB_2U(SCH_1):M_B_CPU0_SB_DQS_DN(7)   I169 @S9S_MB_2U_LIB.S9S_MB_2U(SCH_1):PAGE21
   M24 M_B_CPU0_SB_DQS_DN<6> @S9S_MB_2U_LIB.S9S_MB_2U(SCH_1):M_B_CPU0_SB_DQS_DN(6)   I169 @S9S_MB_2U_LIB.S9S_MB_2U(SCH_1):PAGE21
   W27 M_B_CPU0_SB_DQS_DN<5> @S9S_MB_2U_LIB.S9S_MB_2U(SCH_1):M_B_CPU0_SB_DQS_DN(5)   I169 @S9S_MB_2U_LIB.S9S_MB_2U(SCH_1):PAGE21
   P36 M_B_CPU0_SB_DQS_DN<4> @S9S_MB_2U_LIB.S9S_MB_2U(SCH_1):M_B_CPU0_SB_DQS_DN(4)   I169 @S9S_MB_2U_LIB.S9S_MB_2U(SCH_1):PAGE21
   A15 M_B_CPU0_SB_DQS_DN<3> @S9S_MB_2U_LIB.S9S_MB_2U(SCH_1):M_B_CPU0_SB_DQS_DN(3)   I169 @S9S_MB_2U_LIB.S9S_MB_2U(SCH_1):PAGE21
   H18 M_B_CPU0_SB_DQS_DN<2> @S9S_MB_2U_LIB.S9S_MB_2U(SCH_1):M_B_CPU0_SB_DQS_DN(2)   I169 @S9S_MB_2U_LIB.S9S_MB_2U(SCH_1):PAGE21
   H24 M_B_CPU0_SB_DQS_DN<1> @S9S_MB_2U_LIB.S9S_MB_2U(SCH_1):M_B_CPU0_SB_DQS_DN(1)   I169 @S9S_MB_2U_LIB.S9S_MB_2U(SCH_1):PAGE21
   R27 M_B_CPU0_SB_DQS_DN<0> @S9S_MB_2U_LIB.S9S_MB_2U(SCH_1):M_B_CPU0_SB_DQS_DN(0)   I169 @S9S_MB_2U_LIB.S9S_MB_2U(SCH_1):PAGE21
   H36 M_B_CPU0_SB_DQS_DP<9> @S9S_MB_2U_LIB.S9S_MB_2U(SCH_1):M_B_CPU0_SB_DQS_DP(9)   I169 @S9S_MB_2U_LIB.S9S_MB_2U(SCH_1):PAGE21
   G15 M_B_CPU0_SB_DQS_DP<8> @S9S_MB_2U_LIB.S9S_MB_2U(SCH_1):M_B_CPU0_SB_DQS_DP(8)   I169 @S9S_MB_2U_LIB.S9S_MB_2U(SCH_1):PAGE21
   P18 M_B_CPU0_SB_DQS_DP<7> @S9S_MB_2U_LIB.S9S_MB_2U(SCH_1):M_B_CPU0_SB_DQS_DP(7)   I169 @S9S_MB_2U_LIB.S9S_MB_2U(SCH_1):PAGE21
   P24 M_B_CPU0_SB_DQS_DP<6> @S9S_MB_2U_LIB.S9S_MB_2U(SCH_1):M_B_CPU0_SB_DQS_DP(6)   I169 @S9S_MB_2U_LIB.S9S_MB_2U(SCH_1):PAGE21
  AA27 M_B_CPU0_SB_DQS_DP<5> @S9S_MB_2U_LIB.S9S_MB_2U(SCH_1):M_B_CPU0_SB_DQS_DP(5)   I169 @S9S_MB_2U_LIB.S9S_MB_2U(SCH_1):PAGE21
   M36 M_B_CPU0_SB_DQS_DP<4> @S9S_MB_2U_LIB.S9S_MB_2U(SCH_1):M_B_CPU0_SB_DQS_DP(4)   I169 @S9S_MB_2U_LIB.S9S_MB_2U(SCH_1):PAGE21
   C15 M_B_CPU0_SB_DQS_DP<3> @S9S_MB_2U_LIB.S9S_MB_2U(SCH_1):M_B_CPU0_SB_DQS_DP(3)   I169 @S9S_MB_2U_LIB.S9S_MB_2U(SCH_1):PAGE21
   K18 M_B_CPU0_SB_DQS_DP<2> @S9S_MB_2U_LIB.S9S_MB_2U(SCH_1):M_B_CPU0_SB_DQS_DP(2)   I169 @S9S_MB_2U_LIB.S9S_MB_2U(SCH_1):PAGE21
   K24 M_B_CPU0_SB_DQS_DP<1> @S9S_MB_2U_LIB.S9S_MB_2U(SCH_1):M_B_CPU0_SB_DQS_DP(1)   I169 @S9S_MB_2U_LIB.S9S_MB_2U(SCH_1):PAGE21
   U27 M_B_CPU0_SB_DQS_DP<0> @S9S_MB_2U_LIB.S9S_MB_2U(SCH_1):M_B_CPU0_SB_DQS_DP(0)   I169 @S9S_MB_2U_LIB.S9S_MB_2U(SCH_1):PAGE21
   N37 M_B_CPU0_SB_CB<7> @S9S_MB_2U_LIB.S9S_MB_2U(SCH_1):M_B_CPU0_SB_CB(7)   I169 @S9S_MB_2U_LIB.S9S_MB_2U(SCH_1):PAGE21
   M38 M_B_CPU0_SB_CB<6> @S9S_MB_2U_LIB.S9S_MB_2U(SCH_1):M_B_CPU0_SB_CB(6)   I169 @S9S_MB_2U_LIB.S9S_MB_2U(SCH_1):PAGE21
   J37 M_B_CPU0_SB_CB<5> @S9S_MB_2U_LIB.S9S_MB_2U(SCH_1):M_B_CPU0_SB_CB(5)   I169 @S9S_MB_2U_LIB.S9S_MB_2U(SCH_1):PAGE21
   K38 M_B_CPU0_SB_CB<4> @S9S_MB_2U_LIB.S9S_MB_2U(SCH_1):M_B_CPU0_SB_CB(4)   I169 @S9S_MB_2U_LIB.S9S_MB_2U(SCH_1):PAGE21
   M34 M_B_CPU0_SB_CB<3> @S9S_MB_2U_LIB.S9S_MB_2U(SCH_1):M_B_CPU0_SB_CB(3)   I169 @S9S_MB_2U_LIB.S9S_MB_2U(SCH_1):PAGE21
   N35 M_B_CPU0_SB_CB<2> @S9S_MB_2U_LIB.S9S_MB_2U(SCH_1):M_B_CPU0_SB_CB(2)   I169 @S9S_MB_2U_LIB.S9S_MB_2U(SCH_1):PAGE21
   K34 M_B_CPU0_SB_CB<1> @S9S_MB_2U_LIB.S9S_MB_2U(SCH_1):M_B_CPU0_SB_CB(1)   I169 @S9S_MB_2U_LIB.S9S_MB_2U(SCH_1):PAGE21
   J35 M_B_CPU0_SB_CB<0> @S9S_MB_2U_LIB.S9S_MB_2U(SCH_1):M_B_CPU0_SB_CB(0)   I169 @S9S_MB_2U_LIB.S9S_MB_2U(SCH_1):PAGE21
   P42 M_B_CPU0_SB_PAR @S9S_MB_2U_LIB.S9S_MB_2U(SCH_1):M_B_CPU0_SB_PAR   I169 @S9S_MB_2U_LIB.S9S_MB_2U(SCH_1):PAGE21
  AT47 M_C_CPU0_ALERT_N @S9S_MB_2U_LIB.S9S_MB_2U(SCH_1):M_C_CPU0_ALERT_N   I169 @S9S_MB_2U_LIB.S9S_MB_2U(SCH_1):PAGE22
  AD47 M_C_CPU0_SA_RSP<1> @S9S_MB_2U_LIB.S9S_MB_2U(SCH_1):M_C_CPU0_SA_RSP(1)   I169 @S9S_MB_2U_LIB.S9S_MB_2U(SCH_1):PAGE22
  AC48 M_C_CPU0_SA_RSP<0> @S9S_MB_2U_LIB.S9S_MB_2U(SCH_1):M_C_CPU0_SA_RSP(0)   I169 @S9S_MB_2U_LIB.S9S_MB_2U(SCH_1):PAGE22
  AF47 M_C_CPU0_SB_RSP<1> @S9S_MB_2U_LIB.S9S_MB_2U(SCH_1):M_C_CPU0_SB_RSP(1)   I169 @S9S_MB_2U_LIB.S9S_MB_2U(SCH_1):PAGE22
  AG48 M_C_CPU0_SB_RSP<0> @S9S_MB_2U_LIB.S9S_MB_2U(SCH_1):M_C_CPU0_SB_RSP(0)   I169 @S9S_MB_2U_LIB.S9S_MB_2U(SCH_1):PAGE22
  AF49 M_C_CPU0_CLK_DN<1> @S9S_MB_2U_LIB.S9S_MB_2U(SCH_1):M_C_CPU0_CLK_DN(1)   I169 @S9S_MB_2U_LIB.S9S_MB_2U(SCH_1):PAGE22
  AB49 M_C_CPU0_CLK_DN<0> @S9S_MB_2U_LIB.S9S_MB_2U(SCH_1):M_C_CPU0_CLK_DN(0)   I169 @S9S_MB_2U_LIB.S9S_MB_2U(SCH_1):PAGE22
  AH49 M_C_CPU0_CLK_DP<1> @S9S_MB_2U_LIB.S9S_MB_2U(SCH_1):M_C_CPU0_CLK_DP(1)   I169 @S9S_MB_2U_LIB.S9S_MB_2U(SCH_1):PAGE22
  AD49 M_C_CPU0_CLK_DP<0> @S9S_MB_2U_LIB.S9S_MB_2U(SCH_1):M_C_CPU0_CLK_DP(0)   I169 @S9S_MB_2U_LIB.S9S_MB_2U(SCH_1):PAGE22
   U48 M_C_CPU0_SA_CA<6> @S9S_MB_2U_LIB.S9S_MB_2U(SCH_1):M_C_CPU0_SA_CA(6)   I169 @S9S_MB_2U_LIB.S9S_MB_2U(SCH_1):PAGE22
   W50 M_C_CPU0_SA_CA<5> @S9S_MB_2U_LIB.S9S_MB_2U(SCH_1):M_C_CPU0_SA_CA(5)   I169 @S9S_MB_2U_LIB.S9S_MB_2U(SCH_1):PAGE22
   U50 M_C_CPU0_SA_CA<4> @S9S_MB_2U_LIB.S9S_MB_2U(SCH_1):M_C_CPU0_SA_CA(4)   I169 @S9S_MB_2U_LIB.S9S_MB_2U(SCH_1):PAGE22
   Y51 M_C_CPU0_SA_CA<3> @S9S_MB_2U_LIB.S9S_MB_2U(SCH_1):M_C_CPU0_SA_CA(3)   I169 @S9S_MB_2U_LIB.S9S_MB_2U(SCH_1):PAGE22
   T51 M_C_CPU0_SA_CA<2> @S9S_MB_2U_LIB.S9S_MB_2U(SCH_1):M_C_CPU0_SA_CA(2)   I169 @S9S_MB_2U_LIB.S9S_MB_2U(SCH_1):PAGE22
  AA52 M_C_CPU0_SA_CA<1> @S9S_MB_2U_LIB.S9S_MB_2U(SCH_1):M_C_CPU0_SA_CA(1)   I169 @S9S_MB_2U_LIB.S9S_MB_2U(SCH_1):PAGE22
   R52 M_C_CPU0_SA_CA<0> @S9S_MB_2U_LIB.S9S_MB_2U(SCH_1):M_C_CPU0_SA_CA(0)   I169 @S9S_MB_2U_LIB.S9S_MB_2U(SCH_1):PAGE22
   Y53 M_C_CPU0_SA_CS_N<3> @S9S_MB_2U_LIB.S9S_MB_2U(SCH_1):M_C_CPU0_SA_CS_N(3)   I169 @S9S_MB_2U_LIB.S9S_MB_2U(SCH_1):PAGE22
   W54 M_C_CPU0_SA_CS_N<2> @S9S_MB_2U_LIB.S9S_MB_2U(SCH_1):M_C_CPU0_SA_CS_N(2)   I169 @S9S_MB_2U_LIB.S9S_MB_2U(SCH_1):PAGE22
   T53 M_C_CPU0_SA_CS_N<1> @S9S_MB_2U_LIB.S9S_MB_2U(SCH_1):M_C_CPU0_SA_CS_N(1)   I169 @S9S_MB_2U_LIB.S9S_MB_2U(SCH_1):PAGE22
   U54 M_C_CPU0_SA_CS_N<0> @S9S_MB_2U_LIB.S9S_MB_2U(SCH_1):M_C_CPU0_SA_CS_N(0)   I169 @S9S_MB_2U_LIB.S9S_MB_2U(SCH_1):PAGE22
  AF59 M_C_CPU0_SA_DQ<31> @S9S_MB_2U_LIB.S9S_MB_2U(SCH_1):M_C_CPU0_SA_DQ(31)   I169 @S9S_MB_2U_LIB.S9S_MB_2U(SCH_1):PAGE22
  AG60 M_C_CPU0_SA_DQ<30> @S9S_MB_2U_LIB.S9S_MB_2U(SCH_1):M_C_CPU0_SA_DQ(30)   I169 @S9S_MB_2U_LIB.S9S_MB_2U(SCH_1):PAGE22
  AD59 M_C_CPU0_SA_DQ<29> @S9S_MB_2U_LIB.S9S_MB_2U(SCH_1):M_C_CPU0_SA_DQ(29)   I169 @S9S_MB_2U_LIB.S9S_MB_2U(SCH_1):PAGE22
  AC60 M_C_CPU0_SA_DQ<28> @S9S_MB_2U_LIB.S9S_MB_2U(SCH_1):M_C_CPU0_SA_DQ(28)   I169 @S9S_MB_2U_LIB.S9S_MB_2U(SCH_1):PAGE22
  AG62 M_C_CPU0_SA_DQ<27> @S9S_MB_2U_LIB.S9S_MB_2U(SCH_1):M_C_CPU0_SA_DQ(27)   I169 @S9S_MB_2U_LIB.S9S_MB_2U(SCH_1):PAGE22
  AF63 M_C_CPU0_SA_DQ<26> @S9S_MB_2U_LIB.S9S_MB_2U(SCH_1):M_C_CPU0_SA_DQ(26)   I169 @S9S_MB_2U_LIB.S9S_MB_2U(SCH_1):PAGE22
  AC62 M_C_CPU0_SA_DQ<25> @S9S_MB_2U_LIB.S9S_MB_2U(SCH_1):M_C_CPU0_SA_DQ(25)   I169 @S9S_MB_2U_LIB.S9S_MB_2U(SCH_1):PAGE22
  AD63 M_C_CPU0_SA_DQ<24> @S9S_MB_2U_LIB.S9S_MB_2U(SCH_1):M_C_CPU0_SA_DQ(24)   I169 @S9S_MB_2U_LIB.S9S_MB_2U(SCH_1):PAGE22
   W62 M_C_CPU0_SA_DQ<23> @S9S_MB_2U_LIB.S9S_MB_2U(SCH_1):M_C_CPU0_SA_DQ(23)   I169 @S9S_MB_2U_LIB.S9S_MB_2U(SCH_1):PAGE22
   Y63 M_C_CPU0_SA_DQ<22> @S9S_MB_2U_LIB.S9S_MB_2U(SCH_1):M_C_CPU0_SA_DQ(22)   I169 @S9S_MB_2U_LIB.S9S_MB_2U(SCH_1):PAGE22
   U62 M_C_CPU0_SA_DQ<21> @S9S_MB_2U_LIB.S9S_MB_2U(SCH_1):M_C_CPU0_SA_DQ(21)   I169 @S9S_MB_2U_LIB.S9S_MB_2U(SCH_1):PAGE22
   T63 M_C_CPU0_SA_DQ<20> @S9S_MB_2U_LIB.S9S_MB_2U(SCH_1):M_C_CPU0_SA_DQ(20)   I169 @S9S_MB_2U_LIB.S9S_MB_2U(SCH_1):PAGE22
   Y65 M_C_CPU0_SA_DQ<19> @S9S_MB_2U_LIB.S9S_MB_2U(SCH_1):M_C_CPU0_SA_DQ(19)   I169 @S9S_MB_2U_LIB.S9S_MB_2U(SCH_1):PAGE22
   W66 M_C_CPU0_SA_DQ<18> @S9S_MB_2U_LIB.S9S_MB_2U(SCH_1):M_C_CPU0_SA_DQ(18)   I169 @S9S_MB_2U_LIB.S9S_MB_2U(SCH_1):PAGE22
   T65 M_C_CPU0_SA_DQ<17> @S9S_MB_2U_LIB.S9S_MB_2U(SCH_1):M_C_CPU0_SA_DQ(17)   I169 @S9S_MB_2U_LIB.S9S_MB_2U(SCH_1):PAGE22
   U66 M_C_CPU0_SA_DQ<16> @S9S_MB_2U_LIB.S9S_MB_2U(SCH_1):M_C_CPU0_SA_DQ(16)   I169 @S9S_MB_2U_LIB.S9S_MB_2U(SCH_1):PAGE22
  AF65 M_C_CPU0_SA_DQ<15> @S9S_MB_2U_LIB.S9S_MB_2U(SCH_1):M_C_CPU0_SA_DQ(15)   I169 @S9S_MB_2U_LIB.S9S_MB_2U(SCH_1):PAGE22
  AG66 M_C_CPU0_SA_DQ<14> @S9S_MB_2U_LIB.S9S_MB_2U(SCH_1):M_C_CPU0_SA_DQ(14)   I169 @S9S_MB_2U_LIB.S9S_MB_2U(SCH_1):PAGE22
  AD65 M_C_CPU0_SA_DQ<13> @S9S_MB_2U_LIB.S9S_MB_2U(SCH_1):M_C_CPU0_SA_DQ(13)   I169 @S9S_MB_2U_LIB.S9S_MB_2U(SCH_1):PAGE22
  AC66 M_C_CPU0_SA_DQ<12> @S9S_MB_2U_LIB.S9S_MB_2U(SCH_1):M_C_CPU0_SA_DQ(12)   I169 @S9S_MB_2U_LIB.S9S_MB_2U(SCH_1):PAGE22
  AG68 M_C_CPU0_SA_DQ<11> @S9S_MB_2U_LIB.S9S_MB_2U(SCH_1):M_C_CPU0_SA_DQ(11)   I169 @S9S_MB_2U_LIB.S9S_MB_2U(SCH_1):PAGE22
  AF69 M_C_CPU0_SA_DQ<10> @S9S_MB_2U_LIB.S9S_MB_2U(SCH_1):M_C_CPU0_SA_DQ(10)   I169 @S9S_MB_2U_LIB.S9S_MB_2U(SCH_1):PAGE22
  AC68 M_C_CPU0_SA_DQ<9> @S9S_MB_2U_LIB.S9S_MB_2U(SCH_1):M_C_CPU0_SA_DQ(9)   I169 @S9S_MB_2U_LIB.S9S_MB_2U(SCH_1):PAGE22
  AD69 M_C_CPU0_SA_DQ<8> @S9S_MB_2U_LIB.S9S_MB_2U(SCH_1):M_C_CPU0_SA_DQ(8)   I169 @S9S_MB_2U_LIB.S9S_MB_2U(SCH_1):PAGE22
   W74 M_C_CPU0_SA_DQ<7> @S9S_MB_2U_LIB.S9S_MB_2U(SCH_1):M_C_CPU0_SA_DQ(7)   I169 @S9S_MB_2U_LIB.S9S_MB_2U(SCH_1):PAGE22
   Y75 M_C_CPU0_SA_DQ<6> @S9S_MB_2U_LIB.S9S_MB_2U(SCH_1):M_C_CPU0_SA_DQ(6)   I169 @S9S_MB_2U_LIB.S9S_MB_2U(SCH_1):PAGE22
   U74 M_C_CPU0_SA_DQ<5> @S9S_MB_2U_LIB.S9S_MB_2U(SCH_1):M_C_CPU0_SA_DQ(5)   I169 @S9S_MB_2U_LIB.S9S_MB_2U(SCH_1):PAGE22
   T75 M_C_CPU0_SA_DQ<4> @S9S_MB_2U_LIB.S9S_MB_2U(SCH_1):M_C_CPU0_SA_DQ(4)   I169 @S9S_MB_2U_LIB.S9S_MB_2U(SCH_1):PAGE22
   Y77 M_C_CPU0_SA_DQ<3> @S9S_MB_2U_LIB.S9S_MB_2U(SCH_1):M_C_CPU0_SA_DQ(3)   I169 @S9S_MB_2U_LIB.S9S_MB_2U(SCH_1):PAGE22
   W78 M_C_CPU0_SA_DQ<2> @S9S_MB_2U_LIB.S9S_MB_2U(SCH_1):M_C_CPU0_SA_DQ(2)   I169 @S9S_MB_2U_LIB.S9S_MB_2U(SCH_1):PAGE22
   T77 M_C_CPU0_SA_DQ<1> @S9S_MB_2U_LIB.S9S_MB_2U(SCH_1):M_C_CPU0_SA_DQ(1)   I169 @S9S_MB_2U_LIB.S9S_MB_2U(SCH_1):PAGE22
   U78 M_C_CPU0_SA_DQ<0> @S9S_MB_2U_LIB.S9S_MB_2U(SCH_1):M_C_CPU0_SA_DQ(0)   I169 @S9S_MB_2U_LIB.S9S_MB_2U(SCH_1):PAGE22
  AH55 M_C_CPU0_SA_DQS_DN<9> @S9S_MB_2U_LIB.S9S_MB_2U(SCH_1):M_C_CPU0_SA_DQS_DN(9)   I169 @S9S_MB_2U_LIB.S9S_MB_2U(SCH_1):PAGE22
  AF61 M_C_CPU0_SA_DQS_DN<8> @S9S_MB_2U_LIB.S9S_MB_2U(SCH_1):M_C_CPU0_SA_DQS_DN(8)   I169 @S9S_MB_2U_LIB.S9S_MB_2U(SCH_1):PAGE22
  AA64 M_C_CPU0_SA_DQS_DN<7> @S9S_MB_2U_LIB.S9S_MB_2U(SCH_1):M_C_CPU0_SA_DQS_DN(7)   I169 @S9S_MB_2U_LIB.S9S_MB_2U(SCH_1):PAGE22
  AH67 M_C_CPU0_SA_DQS_DN<6> @S9S_MB_2U_LIB.S9S_MB_2U(SCH_1):M_C_CPU0_SA_DQS_DN(6)   I169 @S9S_MB_2U_LIB.S9S_MB_2U(SCH_1):PAGE22
   W76 M_C_CPU0_SA_DQS_DN<5> @S9S_MB_2U_LIB.S9S_MB_2U(SCH_1):M_C_CPU0_SA_DQS_DN(5)   I169 @S9S_MB_2U_LIB.S9S_MB_2U(SCH_1):PAGE22
  AD55 M_C_CPU0_SA_DQS_DN<4> @S9S_MB_2U_LIB.S9S_MB_2U(SCH_1):M_C_CPU0_SA_DQS_DN(4)   I169 @S9S_MB_2U_LIB.S9S_MB_2U(SCH_1):PAGE22
  AB61 M_C_CPU0_SA_DQS_DN<3> @S9S_MB_2U_LIB.S9S_MB_2U(SCH_1):M_C_CPU0_SA_DQS_DN(3)   I169 @S9S_MB_2U_LIB.S9S_MB_2U(SCH_1):PAGE22
   R64 M_C_CPU0_SA_DQS_DN<2> @S9S_MB_2U_LIB.S9S_MB_2U(SCH_1):M_C_CPU0_SA_DQS_DN(2)   I169 @S9S_MB_2U_LIB.S9S_MB_2U(SCH_1):PAGE22
  AB67 M_C_CPU0_SA_DQS_DN<1> @S9S_MB_2U_LIB.S9S_MB_2U(SCH_1):M_C_CPU0_SA_DQS_DN(1)   I169 @S9S_MB_2U_LIB.S9S_MB_2U(SCH_1):PAGE22
   R76 M_C_CPU0_SA_DQS_DN<0> @S9S_MB_2U_LIB.S9S_MB_2U(SCH_1):M_C_CPU0_SA_DQS_DN(0)   I169 @S9S_MB_2U_LIB.S9S_MB_2U(SCH_1):PAGE22
  AF55 M_C_CPU0_SA_DQS_DP<9> @S9S_MB_2U_LIB.S9S_MB_2U(SCH_1):M_C_CPU0_SA_DQS_DP(9)   I169 @S9S_MB_2U_LIB.S9S_MB_2U(SCH_1):PAGE22
  AH61 M_C_CPU0_SA_DQS_DP<8> @S9S_MB_2U_LIB.S9S_MB_2U(SCH_1):M_C_CPU0_SA_DQS_DP(8)   I169 @S9S_MB_2U_LIB.S9S_MB_2U(SCH_1):PAGE22
   W64 M_C_CPU0_SA_DQS_DP<7> @S9S_MB_2U_LIB.S9S_MB_2U(SCH_1):M_C_CPU0_SA_DQS_DP(7)   I169 @S9S_MB_2U_LIB.S9S_MB_2U(SCH_1):PAGE22
  AF67 M_C_CPU0_SA_DQS_DP<6> @S9S_MB_2U_LIB.S9S_MB_2U(SCH_1):M_C_CPU0_SA_DQS_DP(6)   I169 @S9S_MB_2U_LIB.S9S_MB_2U(SCH_1):PAGE22
  AA76 M_C_CPU0_SA_DQS_DP<5> @S9S_MB_2U_LIB.S9S_MB_2U(SCH_1):M_C_CPU0_SA_DQS_DP(5)   I169 @S9S_MB_2U_LIB.S9S_MB_2U(SCH_1):PAGE22
  AB55 M_C_CPU0_SA_DQS_DP<4> @S9S_MB_2U_LIB.S9S_MB_2U(SCH_1):M_C_CPU0_SA_DQS_DP(4)   I169 @S9S_MB_2U_LIB.S9S_MB_2U(SCH_1):PAGE22
  AD61 M_C_CPU0_SA_DQS_DP<3> @S9S_MB_2U_LIB.S9S_MB_2U(SCH_1):M_C_CPU0_SA_DQS_DP(3)   I169 @S9S_MB_2U_LIB.S9S_MB_2U(SCH_1):PAGE22
   U64 M_C_CPU0_SA_DQS_DP<2> @S9S_MB_2U_LIB.S9S_MB_2U(SCH_1):M_C_CPU0_SA_DQS_DP(2)   I169 @S9S_MB_2U_LIB.S9S_MB_2U(SCH_1):PAGE22
  AD67 M_C_CPU0_SA_DQS_DP<1> @S9S_MB_2U_LIB.S9S_MB_2U(SCH_1):M_C_CPU0_SA_DQS_DP(1)   I169 @S9S_MB_2U_LIB.S9S_MB_2U(SCH_1):PAGE22
   U76 M_C_CPU0_SA_DQS_DP<0> @S9S_MB_2U_LIB.S9S_MB_2U(SCH_1):M_C_CPU0_SA_DQS_DP(0)   I169 @S9S_MB_2U_LIB.S9S_MB_2U(SCH_1):PAGE22
  AF53 M_C_CPU0_SA_CB<7> @S9S_MB_2U_LIB.S9S_MB_2U(SCH_1):M_C_CPU0_SA_CB(7)   I169 @S9S_MB_2U_LIB.S9S_MB_2U(SCH_1):PAGE22
  AG54 M_C_CPU0_SA_CB<6> @S9S_MB_2U_LIB.S9S_MB_2U(SCH_1):M_C_CPU0_SA_CB(6)   I169 @S9S_MB_2U_LIB.S9S_MB_2U(SCH_1):PAGE22
  AD53 M_C_CPU0_SA_CB<5> @S9S_MB_2U_LIB.S9S_MB_2U(SCH_1):M_C_CPU0_SA_CB(5)   I169 @S9S_MB_2U_LIB.S9S_MB_2U(SCH_1):PAGE22
  AC54 M_C_CPU0_SA_CB<4> @S9S_MB_2U_LIB.S9S_MB_2U(SCH_1):M_C_CPU0_SA_CB(4)   I169 @S9S_MB_2U_LIB.S9S_MB_2U(SCH_1):PAGE22
  AG56 M_C_CPU0_SA_CB<3> @S9S_MB_2U_LIB.S9S_MB_2U(SCH_1):M_C_CPU0_SA_CB(3)   I169 @S9S_MB_2U_LIB.S9S_MB_2U(SCH_1):PAGE22
  AF57 M_C_CPU0_SA_CB<2> @S9S_MB_2U_LIB.S9S_MB_2U(SCH_1):M_C_CPU0_SA_CB(2)   I169 @S9S_MB_2U_LIB.S9S_MB_2U(SCH_1):PAGE22
  AC56 M_C_CPU0_SA_CB<1> @S9S_MB_2U_LIB.S9S_MB_2U(SCH_1):M_C_CPU0_SA_CB(1)   I169 @S9S_MB_2U_LIB.S9S_MB_2U(SCH_1):PAGE22
  AD57 M_C_CPU0_SA_CB<0> @S9S_MB_2U_LIB.S9S_MB_2U(SCH_1):M_C_CPU0_SA_CB(0)   I169 @S9S_MB_2U_LIB.S9S_MB_2U(SCH_1):PAGE22
   T47 M_C_CPU0_SA_PAR @S9S_MB_2U_LIB.S9S_MB_2U(SCH_1):M_C_CPU0_SA_PAR   I169 @S9S_MB_2U_LIB.S9S_MB_2U(SCH_1):PAGE22
   R39 M_C_CPU0_SB_CA<6> @S9S_MB_2U_LIB.S9S_MB_2U(SCH_1):M_C_CPU0_SB_CA(6)   I169 @S9S_MB_2U_LIB.S9S_MB_2U(SCH_1):PAGE22
   Y40 M_C_CPU0_SB_CA<5> @S9S_MB_2U_LIB.S9S_MB_2U(SCH_1):M_C_CPU0_SB_CA(5)   I169 @S9S_MB_2U_LIB.S9S_MB_2U(SCH_1):PAGE22
   T40 M_C_CPU0_SB_CA<4> @S9S_MB_2U_LIB.S9S_MB_2U(SCH_1):M_C_CPU0_SB_CA(4)   I169 @S9S_MB_2U_LIB.S9S_MB_2U(SCH_1):PAGE22
   W41 M_C_CPU0_SB_CA<3> @S9S_MB_2U_LIB.S9S_MB_2U(SCH_1):M_C_CPU0_SB_CA(3)   I169 @S9S_MB_2U_LIB.S9S_MB_2U(SCH_1):PAGE22
   U41 M_C_CPU0_SB_CA<2> @S9S_MB_2U_LIB.S9S_MB_2U(SCH_1):M_C_CPU0_SB_CA(2)   I169 @S9S_MB_2U_LIB.S9S_MB_2U(SCH_1):PAGE22
   Y47 M_C_CPU0_SB_CA<1> @S9S_MB_2U_LIB.S9S_MB_2U(SCH_1):M_C_CPU0_SB_CA(1)   I169 @S9S_MB_2U_LIB.S9S_MB_2U(SCH_1):PAGE22
   W48 M_C_CPU0_SB_CA<0> @S9S_MB_2U_LIB.S9S_MB_2U(SCH_1):M_C_CPU0_SB_CA(0)   I169 @S9S_MB_2U_LIB.S9S_MB_2U(SCH_1):PAGE22
   W37 M_C_CPU0_SB_CS_N<3> @S9S_MB_2U_LIB.S9S_MB_2U(SCH_1):M_C_CPU0_SB_CS_N(3)   I169 @S9S_MB_2U_LIB.S9S_MB_2U(SCH_1):PAGE22
   Y38 M_C_CPU0_SB_CS_N<2> @S9S_MB_2U_LIB.S9S_MB_2U(SCH_1):M_C_CPU0_SB_CS_N(2)   I169 @S9S_MB_2U_LIB.S9S_MB_2U(SCH_1):PAGE22
   U37 M_C_CPU0_SB_CS_N<1> @S9S_MB_2U_LIB.S9S_MB_2U(SCH_1):M_C_CPU0_SB_CS_N(1)   I169 @S9S_MB_2U_LIB.S9S_MB_2U(SCH_1):PAGE22
   T38 M_C_CPU0_SB_CS_N<0> @S9S_MB_2U_LIB.S9S_MB_2U(SCH_1):M_C_CPU0_SB_CS_N(0)   I169 @S9S_MB_2U_LIB.S9S_MB_2U(SCH_1):PAGE22
  AJ17 M_C_CPU0_SB_DQ<31> @S9S_MB_2U_LIB.S9S_MB_2U(SCH_1):M_C_CPU0_SB_DQ(31)   I169 @S9S_MB_2U_LIB.S9S_MB_2U(SCH_1):PAGE22
  AC17 M_C_CPU0_SB_DQ<30> @S9S_MB_2U_LIB.S9S_MB_2U(SCH_1):M_C_CPU0_SB_DQ(30)   I169 @S9S_MB_2U_LIB.S9S_MB_2U(SCH_1):PAGE22
  AG17 M_C_CPU0_SB_DQ<29> @S9S_MB_2U_LIB.S9S_MB_2U(SCH_1):M_C_CPU0_SB_DQ(29)   I169 @S9S_MB_2U_LIB.S9S_MB_2U(SCH_1):PAGE22
  AA17 M_C_CPU0_SB_DQ<28> @S9S_MB_2U_LIB.S9S_MB_2U(SCH_1):M_C_CPU0_SB_DQ(28)   I169 @S9S_MB_2U_LIB.S9S_MB_2U(SCH_1):PAGE22
  AG19 M_C_CPU0_SB_DQ<27> @S9S_MB_2U_LIB.S9S_MB_2U(SCH_1):M_C_CPU0_SB_DQ(27)   I169 @S9S_MB_2U_LIB.S9S_MB_2U(SCH_1):PAGE22
  AF20 M_C_CPU0_SB_DQ<26> @S9S_MB_2U_LIB.S9S_MB_2U(SCH_1):M_C_CPU0_SB_DQ(26)   I169 @S9S_MB_2U_LIB.S9S_MB_2U(SCH_1):PAGE22
  AC19 M_C_CPU0_SB_DQ<25> @S9S_MB_2U_LIB.S9S_MB_2U(SCH_1):M_C_CPU0_SB_DQ(25)   I169 @S9S_MB_2U_LIB.S9S_MB_2U(SCH_1):PAGE22
  AD20 M_C_CPU0_SB_DQ<24> @S9S_MB_2U_LIB.S9S_MB_2U(SCH_1):M_C_CPU0_SB_DQ(24)   I169 @S9S_MB_2U_LIB.S9S_MB_2U(SCH_1):PAGE22
   W19 M_C_CPU0_SB_DQ<23> @S9S_MB_2U_LIB.S9S_MB_2U(SCH_1):M_C_CPU0_SB_DQ(23)   I169 @S9S_MB_2U_LIB.S9S_MB_2U(SCH_1):PAGE22
   Y20 M_C_CPU0_SB_DQ<22> @S9S_MB_2U_LIB.S9S_MB_2U(SCH_1):M_C_CPU0_SB_DQ(22)   I169 @S9S_MB_2U_LIB.S9S_MB_2U(SCH_1):PAGE22
   U19 M_C_CPU0_SB_DQ<21> @S9S_MB_2U_LIB.S9S_MB_2U(SCH_1):M_C_CPU0_SB_DQ(21)   I169 @S9S_MB_2U_LIB.S9S_MB_2U(SCH_1):PAGE22
   T20 M_C_CPU0_SB_DQ<20> @S9S_MB_2U_LIB.S9S_MB_2U(SCH_1):M_C_CPU0_SB_DQ(20)   I169 @S9S_MB_2U_LIB.S9S_MB_2U(SCH_1):PAGE22
   Y22 M_C_CPU0_SB_DQ<19> @S9S_MB_2U_LIB.S9S_MB_2U(SCH_1):M_C_CPU0_SB_DQ(19)   I169 @S9S_MB_2U_LIB.S9S_MB_2U(SCH_1):PAGE22
   W23 M_C_CPU0_SB_DQ<18> @S9S_MB_2U_LIB.S9S_MB_2U(SCH_1):M_C_CPU0_SB_DQ(18)   I169 @S9S_MB_2U_LIB.S9S_MB_2U(SCH_1):PAGE22
   T22 M_C_CPU0_SB_DQ<17> @S9S_MB_2U_LIB.S9S_MB_2U(SCH_1):M_C_CPU0_SB_DQ(17)   I169 @S9S_MB_2U_LIB.S9S_MB_2U(SCH_1):PAGE22
   U23 M_C_CPU0_SB_DQ<16> @S9S_MB_2U_LIB.S9S_MB_2U(SCH_1):M_C_CPU0_SB_DQ(16)   I169 @S9S_MB_2U_LIB.S9S_MB_2U(SCH_1):PAGE22
  AF28 M_C_CPU0_SB_DQ<15> @S9S_MB_2U_LIB.S9S_MB_2U(SCH_1):M_C_CPU0_SB_DQ(15)   I169 @S9S_MB_2U_LIB.S9S_MB_2U(SCH_1):PAGE22
  AG29 M_C_CPU0_SB_DQ<14> @S9S_MB_2U_LIB.S9S_MB_2U(SCH_1):M_C_CPU0_SB_DQ(14)   I169 @S9S_MB_2U_LIB.S9S_MB_2U(SCH_1):PAGE22
  AD28 M_C_CPU0_SB_DQ<13> @S9S_MB_2U_LIB.S9S_MB_2U(SCH_1):M_C_CPU0_SB_DQ(13)   I169 @S9S_MB_2U_LIB.S9S_MB_2U(SCH_1):PAGE22
  AC29 M_C_CPU0_SB_DQ<12> @S9S_MB_2U_LIB.S9S_MB_2U(SCH_1):M_C_CPU0_SB_DQ(12)   I169 @S9S_MB_2U_LIB.S9S_MB_2U(SCH_1):PAGE22
  AG31 M_C_CPU0_SB_DQ<11> @S9S_MB_2U_LIB.S9S_MB_2U(SCH_1):M_C_CPU0_SB_DQ(11)   I169 @S9S_MB_2U_LIB.S9S_MB_2U(SCH_1):PAGE22
  AF32 M_C_CPU0_SB_DQ<10> @S9S_MB_2U_LIB.S9S_MB_2U(SCH_1):M_C_CPU0_SB_DQ(10)   I169 @S9S_MB_2U_LIB.S9S_MB_2U(SCH_1):PAGE22
  AC31 M_C_CPU0_SB_DQ<9> @S9S_MB_2U_LIB.S9S_MB_2U(SCH_1):M_C_CPU0_SB_DQ(9)   I169 @S9S_MB_2U_LIB.S9S_MB_2U(SCH_1):PAGE22
  AD32 M_C_CPU0_SB_DQ<8> @S9S_MB_2U_LIB.S9S_MB_2U(SCH_1):M_C_CPU0_SB_DQ(8)   I169 @S9S_MB_2U_LIB.S9S_MB_2U(SCH_1):PAGE22
  AF34 M_C_CPU0_SB_DQ<7> @S9S_MB_2U_LIB.S9S_MB_2U(SCH_1):M_C_CPU0_SB_DQ(7)   I169 @S9S_MB_2U_LIB.S9S_MB_2U(SCH_1):PAGE22
  AG35 M_C_CPU0_SB_DQ<6> @S9S_MB_2U_LIB.S9S_MB_2U(SCH_1):M_C_CPU0_SB_DQ(6)   I169 @S9S_MB_2U_LIB.S9S_MB_2U(SCH_1):PAGE22
  AD34 M_C_CPU0_SB_DQ<5> @S9S_MB_2U_LIB.S9S_MB_2U(SCH_1):M_C_CPU0_SB_DQ(5)   I169 @S9S_MB_2U_LIB.S9S_MB_2U(SCH_1):PAGE22
  AC35 M_C_CPU0_SB_DQ<4> @S9S_MB_2U_LIB.S9S_MB_2U(SCH_1):M_C_CPU0_SB_DQ(4)   I169 @S9S_MB_2U_LIB.S9S_MB_2U(SCH_1):PAGE22
  AG37 M_C_CPU0_SB_DQ<3> @S9S_MB_2U_LIB.S9S_MB_2U(SCH_1):M_C_CPU0_SB_DQ(3)   I169 @S9S_MB_2U_LIB.S9S_MB_2U(SCH_1):PAGE22
  AF38 M_C_CPU0_SB_DQ<2> @S9S_MB_2U_LIB.S9S_MB_2U(SCH_1):M_C_CPU0_SB_DQ(2)   I169 @S9S_MB_2U_LIB.S9S_MB_2U(SCH_1):PAGE22
  AC37 M_C_CPU0_SB_DQ<1> @S9S_MB_2U_LIB.S9S_MB_2U(SCH_1):M_C_CPU0_SB_DQ(1)   I169 @S9S_MB_2U_LIB.S9S_MB_2U(SCH_1):PAGE22
  AD38 M_C_CPU0_SB_DQ<0> @S9S_MB_2U_LIB.S9S_MB_2U(SCH_1):M_C_CPU0_SB_DQ(0)   I169 @S9S_MB_2U_LIB.S9S_MB_2U(SCH_1):PAGE22
   R33 M_C_CPU0_SB_DQS_DN<9> @S9S_MB_2U_LIB.S9S_MB_2U(SCH_1):M_C_CPU0_SB_DQS_DN(9)   I169 @S9S_MB_2U_LIB.S9S_MB_2U(SCH_1):PAGE22
  AF18 M_C_CPU0_SB_DQS_DN<8> @S9S_MB_2U_LIB.S9S_MB_2U(SCH_1):M_C_CPU0_SB_DQS_DN(8)   I169 @S9S_MB_2U_LIB.S9S_MB_2U(SCH_1):PAGE22
   W21 M_C_CPU0_SB_DQS_DN<7> @S9S_MB_2U_LIB.S9S_MB_2U(SCH_1):M_C_CPU0_SB_DQS_DN(7)   I169 @S9S_MB_2U_LIB.S9S_MB_2U(SCH_1):PAGE22
  AF30 M_C_CPU0_SB_DQS_DN<6> @S9S_MB_2U_LIB.S9S_MB_2U(SCH_1):M_C_CPU0_SB_DQS_DN(6)   I169 @S9S_MB_2U_LIB.S9S_MB_2U(SCH_1):PAGE22
  AF36 M_C_CPU0_SB_DQS_DN<5> @S9S_MB_2U_LIB.S9S_MB_2U(SCH_1):M_C_CPU0_SB_DQS_DN(5)   I169 @S9S_MB_2U_LIB.S9S_MB_2U(SCH_1):PAGE22
   W33 M_C_CPU0_SB_DQS_DN<4> @S9S_MB_2U_LIB.S9S_MB_2U(SCH_1):M_C_CPU0_SB_DQS_DN(4)   I169 @S9S_MB_2U_LIB.S9S_MB_2U(SCH_1):PAGE22
  AB18 M_C_CPU0_SB_DQS_DN<3> @S9S_MB_2U_LIB.S9S_MB_2U(SCH_1):M_C_CPU0_SB_DQS_DN(3)   I169 @S9S_MB_2U_LIB.S9S_MB_2U(SCH_1):PAGE22
   R21 M_C_CPU0_SB_DQS_DN<2> @S9S_MB_2U_LIB.S9S_MB_2U(SCH_1):M_C_CPU0_SB_DQS_DN(2)   I169 @S9S_MB_2U_LIB.S9S_MB_2U(SCH_1):PAGE22
  AB30 M_C_CPU0_SB_DQS_DN<1> @S9S_MB_2U_LIB.S9S_MB_2U(SCH_1):M_C_CPU0_SB_DQS_DN(1)   I169 @S9S_MB_2U_LIB.S9S_MB_2U(SCH_1):PAGE22
  AB36 M_C_CPU0_SB_DQS_DN<0> @S9S_MB_2U_LIB.S9S_MB_2U(SCH_1):M_C_CPU0_SB_DQS_DN(0)   I169 @S9S_MB_2U_LIB.S9S_MB_2U(SCH_1):PAGE22
   U33 M_C_CPU0_SB_DQS_DP<9> @S9S_MB_2U_LIB.S9S_MB_2U(SCH_1):M_C_CPU0_SB_DQS_DP(9)   I169 @S9S_MB_2U_LIB.S9S_MB_2U(SCH_1):PAGE22
  AH18 M_C_CPU0_SB_DQS_DP<8> @S9S_MB_2U_LIB.S9S_MB_2U(SCH_1):M_C_CPU0_SB_DQS_DP(8)   I169 @S9S_MB_2U_LIB.S9S_MB_2U(SCH_1):PAGE22
  AA21 M_C_CPU0_SB_DQS_DP<7> @S9S_MB_2U_LIB.S9S_MB_2U(SCH_1):M_C_CPU0_SB_DQS_DP(7)   I169 @S9S_MB_2U_LIB.S9S_MB_2U(SCH_1):PAGE22
  AH30 M_C_CPU0_SB_DQS_DP<6> @S9S_MB_2U_LIB.S9S_MB_2U(SCH_1):M_C_CPU0_SB_DQS_DP(6)   I169 @S9S_MB_2U_LIB.S9S_MB_2U(SCH_1):PAGE22
  AH36 M_C_CPU0_SB_DQS_DP<5> @S9S_MB_2U_LIB.S9S_MB_2U(SCH_1):M_C_CPU0_SB_DQS_DP(5)   I169 @S9S_MB_2U_LIB.S9S_MB_2U(SCH_1):PAGE22
  AA33 M_C_CPU0_SB_DQS_DP<4> @S9S_MB_2U_LIB.S9S_MB_2U(SCH_1):M_C_CPU0_SB_DQS_DP(4)   I169 @S9S_MB_2U_LIB.S9S_MB_2U(SCH_1):PAGE22
  AD18 M_C_CPU0_SB_DQS_DP<3> @S9S_MB_2U_LIB.S9S_MB_2U(SCH_1):M_C_CPU0_SB_DQS_DP(3)   I169 @S9S_MB_2U_LIB.S9S_MB_2U(SCH_1):PAGE22
   U21 M_C_CPU0_SB_DQS_DP<2> @S9S_MB_2U_LIB.S9S_MB_2U(SCH_1):M_C_CPU0_SB_DQS_DP(2)   I169 @S9S_MB_2U_LIB.S9S_MB_2U(SCH_1):PAGE22
  AD30 M_C_CPU0_SB_DQS_DP<1> @S9S_MB_2U_LIB.S9S_MB_2U(SCH_1):M_C_CPU0_SB_DQS_DP(1)   I169 @S9S_MB_2U_LIB.S9S_MB_2U(SCH_1):PAGE22
  AD36 M_C_CPU0_SB_DQS_DP<0> @S9S_MB_2U_LIB.S9S_MB_2U(SCH_1):M_C_CPU0_SB_DQS_DP(0)   I169 @S9S_MB_2U_LIB.S9S_MB_2U(SCH_1):PAGE22
   Y34 M_C_CPU0_SB_CB<7> @S9S_MB_2U_LIB.S9S_MB_2U(SCH_1):M_C_CPU0_SB_CB(7)   I169 @S9S_MB_2U_LIB.S9S_MB_2U(SCH_1):PAGE22
   W35 M_C_CPU0_SB_CB<6> @S9S_MB_2U_LIB.S9S_MB_2U(SCH_1):M_C_CPU0_SB_CB(6)   I169 @S9S_MB_2U_LIB.S9S_MB_2U(SCH_1):PAGE22
   T34 M_C_CPU0_SB_CB<5> @S9S_MB_2U_LIB.S9S_MB_2U(SCH_1):M_C_CPU0_SB_CB(5)   I169 @S9S_MB_2U_LIB.S9S_MB_2U(SCH_1):PAGE22
   U35 M_C_CPU0_SB_CB<4> @S9S_MB_2U_LIB.S9S_MB_2U(SCH_1):M_C_CPU0_SB_CB(4)   I169 @S9S_MB_2U_LIB.S9S_MB_2U(SCH_1):PAGE22
   W31 M_C_CPU0_SB_CB<3> @S9S_MB_2U_LIB.S9S_MB_2U(SCH_1):M_C_CPU0_SB_CB(3)   I169 @S9S_MB_2U_LIB.S9S_MB_2U(SCH_1):PAGE22
   Y32 M_C_CPU0_SB_CB<2> @S9S_MB_2U_LIB.S9S_MB_2U(SCH_1):M_C_CPU0_SB_CB(2)   I169 @S9S_MB_2U_LIB.S9S_MB_2U(SCH_1):PAGE22
   U31 M_C_CPU0_SB_CB<1> @S9S_MB_2U_LIB.S9S_MB_2U(SCH_1):M_C_CPU0_SB_CB(1)   I169 @S9S_MB_2U_LIB.S9S_MB_2U(SCH_1):PAGE22
   T32 M_C_CPU0_SB_CB<0> @S9S_MB_2U_LIB.S9S_MB_2U(SCH_1):M_C_CPU0_SB_CB(0)   I169 @S9S_MB_2U_LIB.S9S_MB_2U(SCH_1):PAGE22
  AA39 M_C_CPU0_SB_PAR @S9S_MB_2U_LIB.S9S_MB_2U(SCH_1):M_C_CPU0_SB_PAR   I169 @S9S_MB_2U_LIB.S9S_MB_2U(SCH_1):PAGE22
  AV47 M_D_CPU0_ALERT_N @S9S_MB_2U_LIB.S9S_MB_2U(SCH_1):M_D_CPU0_ALERT_N   I169 @S9S_MB_2U_LIB.S9S_MB_2U(SCH_1):PAGE23
  AC50 M_D_CPU0_SA_RSP<1> @S9S_MB_2U_LIB.S9S_MB_2U(SCH_1):M_D_CPU0_SA_RSP(1)   I169 @S9S_MB_2U_LIB.S9S_MB_2U(SCH_1):PAGE23
  AD51 M_D_CPU0_SA_RSP<0> @S9S_MB_2U_LIB.S9S_MB_2U(SCH_1):M_D_CPU0_SA_RSP(0)   I169 @S9S_MB_2U_LIB.S9S_MB_2U(SCH_1):PAGE23
  AG50 M_D_CPU0_SB_RSP<1> @S9S_MB_2U_LIB.S9S_MB_2U(SCH_1):M_D_CPU0_SB_RSP(1)   I169 @S9S_MB_2U_LIB.S9S_MB_2U(SCH_1):PAGE23
  AF51 M_D_CPU0_SB_RSP<0> @S9S_MB_2U_LIB.S9S_MB_2U(SCH_1):M_D_CPU0_SB_RSP(0)   I169 @S9S_MB_2U_LIB.S9S_MB_2U(SCH_1):PAGE23
  AN45 M_D_CPU0_CLK_DN<1> @S9S_MB_2U_LIB.S9S_MB_2U(SCH_1):M_D_CPU0_CLK_DN(1)   I169 @S9S_MB_2U_LIB.S9S_MB_2U(SCH_1):PAGE23
  AJ45 M_D_CPU0_CLK_DN<0> @S9S_MB_2U_LIB.S9S_MB_2U(SCH_1):M_D_CPU0_CLK_DN(0)   I169 @S9S_MB_2U_LIB.S9S_MB_2U(SCH_1):PAGE23
  AR45 M_D_CPU0_CLK_DP<1> @S9S_MB_2U_LIB.S9S_MB_2U(SCH_1):M_D_CPU0_CLK_DP(1)   I169 @S9S_MB_2U_LIB.S9S_MB_2U(SCH_1):PAGE23
  AL45 M_D_CPU0_CLK_DP<0> @S9S_MB_2U_LIB.S9S_MB_2U(SCH_1):M_D_CPU0_CLK_DP(0)   I169 @S9S_MB_2U_LIB.S9S_MB_2U(SCH_1):PAGE23
  AN43 M_D_CPU0_SA_CA<6> @S9S_MB_2U_LIB.S9S_MB_2U(SCH_1):M_D_CPU0_SA_CA(6)   I169 @S9S_MB_2U_LIB.S9S_MB_2U(SCH_1):PAGE23
  AN50 M_D_CPU0_SA_CA<5> @S9S_MB_2U_LIB.S9S_MB_2U(SCH_1):M_D_CPU0_SA_CA(5)   I169 @S9S_MB_2U_LIB.S9S_MB_2U(SCH_1):PAGE23
  AL50 M_D_CPU0_SA_CA<4> @S9S_MB_2U_LIB.S9S_MB_2U(SCH_1):M_D_CPU0_SA_CA(4)   I169 @S9S_MB_2U_LIB.S9S_MB_2U(SCH_1):PAGE23
  AP51 M_D_CPU0_SA_CA<3> @S9S_MB_2U_LIB.S9S_MB_2U(SCH_1):M_D_CPU0_SA_CA(3)   I169 @S9S_MB_2U_LIB.S9S_MB_2U(SCH_1):PAGE23
  AK51 M_D_CPU0_SA_CA<2> @S9S_MB_2U_LIB.S9S_MB_2U(SCH_1):M_D_CPU0_SA_CA(2)   I169 @S9S_MB_2U_LIB.S9S_MB_2U(SCH_1):PAGE23
  AR52 M_D_CPU0_SA_CA<1> @S9S_MB_2U_LIB.S9S_MB_2U(SCH_1):M_D_CPU0_SA_CA(1)   I169 @S9S_MB_2U_LIB.S9S_MB_2U(SCH_1):PAGE23
  AJ52 M_D_CPU0_SA_CA<0> @S9S_MB_2U_LIB.S9S_MB_2U(SCH_1):M_D_CPU0_SA_CA(0)   I169 @S9S_MB_2U_LIB.S9S_MB_2U(SCH_1):PAGE23
  AP53 M_D_CPU0_SA_CS_N<3> @S9S_MB_2U_LIB.S9S_MB_2U(SCH_1):M_D_CPU0_SA_CS_N(3)   I169 @S9S_MB_2U_LIB.S9S_MB_2U(SCH_1):PAGE23
  AN54 M_D_CPU0_SA_CS_N<2> @S9S_MB_2U_LIB.S9S_MB_2U(SCH_1):M_D_CPU0_SA_CS_N(2)   I169 @S9S_MB_2U_LIB.S9S_MB_2U(SCH_1):PAGE23
  AK53 M_D_CPU0_SA_CS_N<1> @S9S_MB_2U_LIB.S9S_MB_2U(SCH_1):M_D_CPU0_SA_CS_N(1)   I169 @S9S_MB_2U_LIB.S9S_MB_2U(SCH_1):PAGE23
  AL54 M_D_CPU0_SA_CS_N<0> @S9S_MB_2U_LIB.S9S_MB_2U(SCH_1):M_D_CPU0_SA_CS_N(0)   I169 @S9S_MB_2U_LIB.S9S_MB_2U(SCH_1):PAGE23
  AN62 M_D_CPU0_SA_DQ<31> @S9S_MB_2U_LIB.S9S_MB_2U(SCH_1):M_D_CPU0_SA_DQ(31)   I169 @S9S_MB_2U_LIB.S9S_MB_2U(SCH_1):PAGE23
  AP63 M_D_CPU0_SA_DQ<30> @S9S_MB_2U_LIB.S9S_MB_2U(SCH_1):M_D_CPU0_SA_DQ(30)   I169 @S9S_MB_2U_LIB.S9S_MB_2U(SCH_1):PAGE23
  AL62 M_D_CPU0_SA_DQ<29> @S9S_MB_2U_LIB.S9S_MB_2U(SCH_1):M_D_CPU0_SA_DQ(29)   I169 @S9S_MB_2U_LIB.S9S_MB_2U(SCH_1):PAGE23
  AK63 M_D_CPU0_SA_DQ<28> @S9S_MB_2U_LIB.S9S_MB_2U(SCH_1):M_D_CPU0_SA_DQ(28)   I169 @S9S_MB_2U_LIB.S9S_MB_2U(SCH_1):PAGE23
  AP65 M_D_CPU0_SA_DQ<27> @S9S_MB_2U_LIB.S9S_MB_2U(SCH_1):M_D_CPU0_SA_DQ(27)   I169 @S9S_MB_2U_LIB.S9S_MB_2U(SCH_1):PAGE23
  AN66 M_D_CPU0_SA_DQ<26> @S9S_MB_2U_LIB.S9S_MB_2U(SCH_1):M_D_CPU0_SA_DQ(26)   I169 @S9S_MB_2U_LIB.S9S_MB_2U(SCH_1):PAGE23
  AK65 M_D_CPU0_SA_DQ<25> @S9S_MB_2U_LIB.S9S_MB_2U(SCH_1):M_D_CPU0_SA_DQ(25)   I169 @S9S_MB_2U_LIB.S9S_MB_2U(SCH_1):PAGE23
  AL66 M_D_CPU0_SA_DQ<24> @S9S_MB_2U_LIB.S9S_MB_2U(SCH_1):M_D_CPU0_SA_DQ(24)   I169 @S9S_MB_2U_LIB.S9S_MB_2U(SCH_1):PAGE23
  AN68 M_D_CPU0_SA_DQ<23> @S9S_MB_2U_LIB.S9S_MB_2U(SCH_1):M_D_CPU0_SA_DQ(23)   I169 @S9S_MB_2U_LIB.S9S_MB_2U(SCH_1):PAGE23
  AP69 M_D_CPU0_SA_DQ<22> @S9S_MB_2U_LIB.S9S_MB_2U(SCH_1):M_D_CPU0_SA_DQ(22)   I169 @S9S_MB_2U_LIB.S9S_MB_2U(SCH_1):PAGE23
  AL68 M_D_CPU0_SA_DQ<21> @S9S_MB_2U_LIB.S9S_MB_2U(SCH_1):M_D_CPU0_SA_DQ(21)   I169 @S9S_MB_2U_LIB.S9S_MB_2U(SCH_1):PAGE23
  AK69 M_D_CPU0_SA_DQ<20> @S9S_MB_2U_LIB.S9S_MB_2U(SCH_1):M_D_CPU0_SA_DQ(20)   I169 @S9S_MB_2U_LIB.S9S_MB_2U(SCH_1):PAGE23
  AP71 M_D_CPU0_SA_DQ<19> @S9S_MB_2U_LIB.S9S_MB_2U(SCH_1):M_D_CPU0_SA_DQ(19)   I169 @S9S_MB_2U_LIB.S9S_MB_2U(SCH_1):PAGE23
  AN72 M_D_CPU0_SA_DQ<18> @S9S_MB_2U_LIB.S9S_MB_2U(SCH_1):M_D_CPU0_SA_DQ(18)   I169 @S9S_MB_2U_LIB.S9S_MB_2U(SCH_1):PAGE23
  AK71 M_D_CPU0_SA_DQ<17> @S9S_MB_2U_LIB.S9S_MB_2U(SCH_1):M_D_CPU0_SA_DQ(17)   I169 @S9S_MB_2U_LIB.S9S_MB_2U(SCH_1):PAGE23
  AL72 M_D_CPU0_SA_DQ<16> @S9S_MB_2U_LIB.S9S_MB_2U(SCH_1):M_D_CPU0_SA_DQ(16)   I169 @S9S_MB_2U_LIB.S9S_MB_2U(SCH_1):PAGE23
  AN74 M_D_CPU0_SA_DQ<15> @S9S_MB_2U_LIB.S9S_MB_2U(SCH_1):M_D_CPU0_SA_DQ(15)   I169 @S9S_MB_2U_LIB.S9S_MB_2U(SCH_1):PAGE23
  AP75 M_D_CPU0_SA_DQ<14> @S9S_MB_2U_LIB.S9S_MB_2U(SCH_1):M_D_CPU0_SA_DQ(14)   I169 @S9S_MB_2U_LIB.S9S_MB_2U(SCH_1):PAGE23
  AL74 M_D_CPU0_SA_DQ<13> @S9S_MB_2U_LIB.S9S_MB_2U(SCH_1):M_D_CPU0_SA_DQ(13)   I169 @S9S_MB_2U_LIB.S9S_MB_2U(SCH_1):PAGE23
  AK75 M_D_CPU0_SA_DQ<12> @S9S_MB_2U_LIB.S9S_MB_2U(SCH_1):M_D_CPU0_SA_DQ(12)   I169 @S9S_MB_2U_LIB.S9S_MB_2U(SCH_1):PAGE23
  AP77 M_D_CPU0_SA_DQ<11> @S9S_MB_2U_LIB.S9S_MB_2U(SCH_1):M_D_CPU0_SA_DQ(11)   I169 @S9S_MB_2U_LIB.S9S_MB_2U(SCH_1):PAGE23
  AN78 M_D_CPU0_SA_DQ<10> @S9S_MB_2U_LIB.S9S_MB_2U(SCH_1):M_D_CPU0_SA_DQ(10)   I169 @S9S_MB_2U_LIB.S9S_MB_2U(SCH_1):PAGE23
  AK77 M_D_CPU0_SA_DQ<9> @S9S_MB_2U_LIB.S9S_MB_2U(SCH_1):M_D_CPU0_SA_DQ(9)   I169 @S9S_MB_2U_LIB.S9S_MB_2U(SCH_1):PAGE23
  AL78 M_D_CPU0_SA_DQ<8> @S9S_MB_2U_LIB.S9S_MB_2U(SCH_1):M_D_CPU0_SA_DQ(8)   I169 @S9S_MB_2U_LIB.S9S_MB_2U(SCH_1):PAGE23
  AF71 M_D_CPU0_SA_DQ<7> @S9S_MB_2U_LIB.S9S_MB_2U(SCH_1):M_D_CPU0_SA_DQ(7)   I169 @S9S_MB_2U_LIB.S9S_MB_2U(SCH_1):PAGE23
  AG72 M_D_CPU0_SA_DQ<6> @S9S_MB_2U_LIB.S9S_MB_2U(SCH_1):M_D_CPU0_SA_DQ(6)   I169 @S9S_MB_2U_LIB.S9S_MB_2U(SCH_1):PAGE23
  AD71 M_D_CPU0_SA_DQ<5> @S9S_MB_2U_LIB.S9S_MB_2U(SCH_1):M_D_CPU0_SA_DQ(5)   I169 @S9S_MB_2U_LIB.S9S_MB_2U(SCH_1):PAGE23
  AC72 M_D_CPU0_SA_DQ<4> @S9S_MB_2U_LIB.S9S_MB_2U(SCH_1):M_D_CPU0_SA_DQ(4)   I169 @S9S_MB_2U_LIB.S9S_MB_2U(SCH_1):PAGE23
  AG74 M_D_CPU0_SA_DQ<3> @S9S_MB_2U_LIB.S9S_MB_2U(SCH_1):M_D_CPU0_SA_DQ(3)   I169 @S9S_MB_2U_LIB.S9S_MB_2U(SCH_1):PAGE23
  AF75 M_D_CPU0_SA_DQ<2> @S9S_MB_2U_LIB.S9S_MB_2U(SCH_1):M_D_CPU0_SA_DQ(2)   I169 @S9S_MB_2U_LIB.S9S_MB_2U(SCH_1):PAGE23
  AC74 M_D_CPU0_SA_DQ<1> @S9S_MB_2U_LIB.S9S_MB_2U(SCH_1):M_D_CPU0_SA_DQ(1)   I169 @S9S_MB_2U_LIB.S9S_MB_2U(SCH_1):PAGE23
  AD75 M_D_CPU0_SA_DQ<0> @S9S_MB_2U_LIB.S9S_MB_2U(SCH_1):M_D_CPU0_SA_DQ(0)   I169 @S9S_MB_2U_LIB.S9S_MB_2U(SCH_1):PAGE23
  AN58 M_D_CPU0_SA_DQS_DN<9> @S9S_MB_2U_LIB.S9S_MB_2U(SCH_1):M_D_CPU0_SA_DQS_DN(9)   I169 @S9S_MB_2U_LIB.S9S_MB_2U(SCH_1):PAGE23
  AN64 M_D_CPU0_SA_DQS_DN<8> @S9S_MB_2U_LIB.S9S_MB_2U(SCH_1):M_D_CPU0_SA_DQS_DN(8)   I169 @S9S_MB_2U_LIB.S9S_MB_2U(SCH_1):PAGE23
  AN70 M_D_CPU0_SA_DQS_DN<7> @S9S_MB_2U_LIB.S9S_MB_2U(SCH_1):M_D_CPU0_SA_DQS_DN(7)   I169 @S9S_MB_2U_LIB.S9S_MB_2U(SCH_1):PAGE23
  AN76 M_D_CPU0_SA_DQS_DN<6> @S9S_MB_2U_LIB.S9S_MB_2U(SCH_1):M_D_CPU0_SA_DQS_DN(6)   I169 @S9S_MB_2U_LIB.S9S_MB_2U(SCH_1):PAGE23
  AH73 M_D_CPU0_SA_DQS_DN<5> @S9S_MB_2U_LIB.S9S_MB_2U(SCH_1):M_D_CPU0_SA_DQS_DN(5)   I169 @S9S_MB_2U_LIB.S9S_MB_2U(SCH_1):PAGE23
  AJ58 M_D_CPU0_SA_DQS_DN<4> @S9S_MB_2U_LIB.S9S_MB_2U(SCH_1):M_D_CPU0_SA_DQS_DN(4)   I169 @S9S_MB_2U_LIB.S9S_MB_2U(SCH_1):PAGE23
  AJ64 M_D_CPU0_SA_DQS_DN<3> @S9S_MB_2U_LIB.S9S_MB_2U(SCH_1):M_D_CPU0_SA_DQS_DN(3)   I169 @S9S_MB_2U_LIB.S9S_MB_2U(SCH_1):PAGE23
  AJ70 M_D_CPU0_SA_DQS_DN<2> @S9S_MB_2U_LIB.S9S_MB_2U(SCH_1):M_D_CPU0_SA_DQS_DN(2)   I169 @S9S_MB_2U_LIB.S9S_MB_2U(SCH_1):PAGE23
  AJ76 M_D_CPU0_SA_DQS_DN<1> @S9S_MB_2U_LIB.S9S_MB_2U(SCH_1):M_D_CPU0_SA_DQS_DN(1)   I169 @S9S_MB_2U_LIB.S9S_MB_2U(SCH_1):PAGE23
  AB73 M_D_CPU0_SA_DQS_DN<0> @S9S_MB_2U_LIB.S9S_MB_2U(SCH_1):M_D_CPU0_SA_DQS_DN(0)   I169 @S9S_MB_2U_LIB.S9S_MB_2U(SCH_1):PAGE23
  AR58 M_D_CPU0_SA_DQS_DP<9> @S9S_MB_2U_LIB.S9S_MB_2U(SCH_1):M_D_CPU0_SA_DQS_DP(9)   I169 @S9S_MB_2U_LIB.S9S_MB_2U(SCH_1):PAGE23
  AR64 M_D_CPU0_SA_DQS_DP<8> @S9S_MB_2U_LIB.S9S_MB_2U(SCH_1):M_D_CPU0_SA_DQS_DP(8)   I169 @S9S_MB_2U_LIB.S9S_MB_2U(SCH_1):PAGE23
  AR70 M_D_CPU0_SA_DQS_DP<7> @S9S_MB_2U_LIB.S9S_MB_2U(SCH_1):M_D_CPU0_SA_DQS_DP(7)   I169 @S9S_MB_2U_LIB.S9S_MB_2U(SCH_1):PAGE23
  AR76 M_D_CPU0_SA_DQS_DP<6> @S9S_MB_2U_LIB.S9S_MB_2U(SCH_1):M_D_CPU0_SA_DQS_DP(6)   I169 @S9S_MB_2U_LIB.S9S_MB_2U(SCH_1):PAGE23
  AF73 M_D_CPU0_SA_DQS_DP<5> @S9S_MB_2U_LIB.S9S_MB_2U(SCH_1):M_D_CPU0_SA_DQS_DP(5)   I169 @S9S_MB_2U_LIB.S9S_MB_2U(SCH_1):PAGE23
  AL58 M_D_CPU0_SA_DQS_DP<4> @S9S_MB_2U_LIB.S9S_MB_2U(SCH_1):M_D_CPU0_SA_DQS_DP(4)   I169 @S9S_MB_2U_LIB.S9S_MB_2U(SCH_1):PAGE23
  AL64 M_D_CPU0_SA_DQS_DP<3> @S9S_MB_2U_LIB.S9S_MB_2U(SCH_1):M_D_CPU0_SA_DQS_DP(3)   I169 @S9S_MB_2U_LIB.S9S_MB_2U(SCH_1):PAGE23
  AL70 M_D_CPU0_SA_DQS_DP<2> @S9S_MB_2U_LIB.S9S_MB_2U(SCH_1):M_D_CPU0_SA_DQS_DP(2)   I169 @S9S_MB_2U_LIB.S9S_MB_2U(SCH_1):PAGE23
  AL76 M_D_CPU0_SA_DQS_DP<1> @S9S_MB_2U_LIB.S9S_MB_2U(SCH_1):M_D_CPU0_SA_DQS_DP(1)   I169 @S9S_MB_2U_LIB.S9S_MB_2U(SCH_1):PAGE23
  AD73 M_D_CPU0_SA_DQS_DP<0> @S9S_MB_2U_LIB.S9S_MB_2U(SCH_1):M_D_CPU0_SA_DQS_DP(0)   I169 @S9S_MB_2U_LIB.S9S_MB_2U(SCH_1):PAGE23
  AN56 M_D_CPU0_SA_CB<7> @S9S_MB_2U_LIB.S9S_MB_2U(SCH_1):M_D_CPU0_SA_CB(7)   I169 @S9S_MB_2U_LIB.S9S_MB_2U(SCH_1):PAGE23
  AP57 M_D_CPU0_SA_CB<6> @S9S_MB_2U_LIB.S9S_MB_2U(SCH_1):M_D_CPU0_SA_CB(6)   I169 @S9S_MB_2U_LIB.S9S_MB_2U(SCH_1):PAGE23
  AL56 M_D_CPU0_SA_CB<5> @S9S_MB_2U_LIB.S9S_MB_2U(SCH_1):M_D_CPU0_SA_CB(5)   I169 @S9S_MB_2U_LIB.S9S_MB_2U(SCH_1):PAGE23
  AK57 M_D_CPU0_SA_CB<4> @S9S_MB_2U_LIB.S9S_MB_2U(SCH_1):M_D_CPU0_SA_CB(4)   I169 @S9S_MB_2U_LIB.S9S_MB_2U(SCH_1):PAGE23
  AP59 M_D_CPU0_SA_CB<3> @S9S_MB_2U_LIB.S9S_MB_2U(SCH_1):M_D_CPU0_SA_CB(3)   I169 @S9S_MB_2U_LIB.S9S_MB_2U(SCH_1):PAGE23
  AN60 M_D_CPU0_SA_CB<2> @S9S_MB_2U_LIB.S9S_MB_2U(SCH_1):M_D_CPU0_SA_CB(2)   I169 @S9S_MB_2U_LIB.S9S_MB_2U(SCH_1):PAGE23
  AK59 M_D_CPU0_SA_CB<1> @S9S_MB_2U_LIB.S9S_MB_2U(SCH_1):M_D_CPU0_SA_CB(1)   I169 @S9S_MB_2U_LIB.S9S_MB_2U(SCH_1):PAGE23
  AL60 M_D_CPU0_SA_CB<0> @S9S_MB_2U_LIB.S9S_MB_2U(SCH_1):M_D_CPU0_SA_CB(0)   I169 @S9S_MB_2U_LIB.S9S_MB_2U(SCH_1):PAGE23
  AP44 M_D_CPU0_SA_PAR @S9S_MB_2U_LIB.S9S_MB_2U(SCH_1):M_D_CPU0_SA_PAR   I169 @S9S_MB_2U_LIB.S9S_MB_2U(SCH_1):PAGE23
  AB42 M_D_CPU0_SB_CA<6> @S9S_MB_2U_LIB.S9S_MB_2U(SCH_1):M_D_CPU0_SB_CA(6)   I169 @S9S_MB_2U_LIB.S9S_MB_2U(SCH_1):PAGE23
  AG43 M_D_CPU0_SB_CA<5> @S9S_MB_2U_LIB.S9S_MB_2U(SCH_1):M_D_CPU0_SB_CA(5)   I169 @S9S_MB_2U_LIB.S9S_MB_2U(SCH_1):PAGE23
  AC43 M_D_CPU0_SB_CA<4> @S9S_MB_2U_LIB.S9S_MB_2U(SCH_1):M_D_CPU0_SB_CA(4)   I169 @S9S_MB_2U_LIB.S9S_MB_2U(SCH_1):PAGE23
  AF44 M_D_CPU0_SB_CA<3> @S9S_MB_2U_LIB.S9S_MB_2U(SCH_1):M_D_CPU0_SB_CA(3)   I169 @S9S_MB_2U_LIB.S9S_MB_2U(SCH_1):PAGE23
  AD44 M_D_CPU0_SB_CA<2> @S9S_MB_2U_LIB.S9S_MB_2U(SCH_1):M_D_CPU0_SB_CA(2)   I169 @S9S_MB_2U_LIB.S9S_MB_2U(SCH_1):PAGE23
  AL43 M_D_CPU0_SB_CA<1> @S9S_MB_2U_LIB.S9S_MB_2U(SCH_1):M_D_CPU0_SB_CA(1)   I169 @S9S_MB_2U_LIB.S9S_MB_2U(SCH_1):PAGE23
  AK44 M_D_CPU0_SB_CA<0> @S9S_MB_2U_LIB.S9S_MB_2U(SCH_1):M_D_CPU0_SB_CA(0)   I169 @S9S_MB_2U_LIB.S9S_MB_2U(SCH_1):PAGE23
  AD40 M_D_CPU0_SB_CS_N<3> @S9S_MB_2U_LIB.S9S_MB_2U(SCH_1):M_D_CPU0_SB_CS_N(3)   I169 @S9S_MB_2U_LIB.S9S_MB_2U(SCH_1):PAGE23
  AF40 M_D_CPU0_SB_CS_N<2> @S9S_MB_2U_LIB.S9S_MB_2U(SCH_1):M_D_CPU0_SB_CS_N(2)   I169 @S9S_MB_2U_LIB.S9S_MB_2U(SCH_1):PAGE23
  AG41 M_D_CPU0_SB_CS_N<1> @S9S_MB_2U_LIB.S9S_MB_2U(SCH_1):M_D_CPU0_SB_CS_N(1)   I169 @S9S_MB_2U_LIB.S9S_MB_2U(SCH_1):PAGE23
  AC41 M_D_CPU0_SB_CS_N<0> @S9S_MB_2U_LIB.S9S_MB_2U(SCH_1):M_D_CPU0_SB_CS_N(0)   I169 @S9S_MB_2U_LIB.S9S_MB_2U(SCH_1):PAGE23
  AN19 M_D_CPU0_SB_DQ<31> @S9S_MB_2U_LIB.S9S_MB_2U(SCH_1):M_D_CPU0_SB_DQ(31)   I169 @S9S_MB_2U_LIB.S9S_MB_2U(SCH_1):PAGE23
  AP20 M_D_CPU0_SB_DQ<30> @S9S_MB_2U_LIB.S9S_MB_2U(SCH_1):M_D_CPU0_SB_DQ(30)   I169 @S9S_MB_2U_LIB.S9S_MB_2U(SCH_1):PAGE23
  AL19 M_D_CPU0_SB_DQ<29> @S9S_MB_2U_LIB.S9S_MB_2U(SCH_1):M_D_CPU0_SB_DQ(29)   I169 @S9S_MB_2U_LIB.S9S_MB_2U(SCH_1):PAGE23
  AK20 M_D_CPU0_SB_DQ<28> @S9S_MB_2U_LIB.S9S_MB_2U(SCH_1):M_D_CPU0_SB_DQ(28)   I169 @S9S_MB_2U_LIB.S9S_MB_2U(SCH_1):PAGE23
  AP22 M_D_CPU0_SB_DQ<27> @S9S_MB_2U_LIB.S9S_MB_2U(SCH_1):M_D_CPU0_SB_DQ(27)   I169 @S9S_MB_2U_LIB.S9S_MB_2U(SCH_1):PAGE23
  AN23 M_D_CPU0_SB_DQ<26> @S9S_MB_2U_LIB.S9S_MB_2U(SCH_1):M_D_CPU0_SB_DQ(26)   I169 @S9S_MB_2U_LIB.S9S_MB_2U(SCH_1):PAGE23
  AK22 M_D_CPU0_SB_DQ<25> @S9S_MB_2U_LIB.S9S_MB_2U(SCH_1):M_D_CPU0_SB_DQ(25)   I169 @S9S_MB_2U_LIB.S9S_MB_2U(SCH_1):PAGE23
  AL23 M_D_CPU0_SB_DQ<24> @S9S_MB_2U_LIB.S9S_MB_2U(SCH_1):M_D_CPU0_SB_DQ(24)   I169 @S9S_MB_2U_LIB.S9S_MB_2U(SCH_1):PAGE23
  AF22 M_D_CPU0_SB_DQ<23> @S9S_MB_2U_LIB.S9S_MB_2U(SCH_1):M_D_CPU0_SB_DQ(23)   I169 @S9S_MB_2U_LIB.S9S_MB_2U(SCH_1):PAGE23
  AG23 M_D_CPU0_SB_DQ<22> @S9S_MB_2U_LIB.S9S_MB_2U(SCH_1):M_D_CPU0_SB_DQ(22)   I169 @S9S_MB_2U_LIB.S9S_MB_2U(SCH_1):PAGE23
  AD22 M_D_CPU0_SB_DQ<21> @S9S_MB_2U_LIB.S9S_MB_2U(SCH_1):M_D_CPU0_SB_DQ(21)   I169 @S9S_MB_2U_LIB.S9S_MB_2U(SCH_1):PAGE23
  AC23 M_D_CPU0_SB_DQ<20> @S9S_MB_2U_LIB.S9S_MB_2U(SCH_1):M_D_CPU0_SB_DQ(20)   I169 @S9S_MB_2U_LIB.S9S_MB_2U(SCH_1):PAGE23
  AG25 M_D_CPU0_SB_DQ<19> @S9S_MB_2U_LIB.S9S_MB_2U(SCH_1):M_D_CPU0_SB_DQ(19)   I169 @S9S_MB_2U_LIB.S9S_MB_2U(SCH_1):PAGE23
  AF26 M_D_CPU0_SB_DQ<18> @S9S_MB_2U_LIB.S9S_MB_2U(SCH_1):M_D_CPU0_SB_DQ(18)   I169 @S9S_MB_2U_LIB.S9S_MB_2U(SCH_1):PAGE23
  AC25 M_D_CPU0_SB_DQ<17> @S9S_MB_2U_LIB.S9S_MB_2U(SCH_1):M_D_CPU0_SB_DQ(17)   I169 @S9S_MB_2U_LIB.S9S_MB_2U(SCH_1):PAGE23
  AD26 M_D_CPU0_SB_DQ<16> @S9S_MB_2U_LIB.S9S_MB_2U(SCH_1):M_D_CPU0_SB_DQ(16)   I169 @S9S_MB_2U_LIB.S9S_MB_2U(SCH_1):PAGE23
  AN25 M_D_CPU0_SB_DQ<15> @S9S_MB_2U_LIB.S9S_MB_2U(SCH_1):M_D_CPU0_SB_DQ(15)   I169 @S9S_MB_2U_LIB.S9S_MB_2U(SCH_1):PAGE23
  AP26 M_D_CPU0_SB_DQ<14> @S9S_MB_2U_LIB.S9S_MB_2U(SCH_1):M_D_CPU0_SB_DQ(14)   I169 @S9S_MB_2U_LIB.S9S_MB_2U(SCH_1):PAGE23
  AL25 M_D_CPU0_SB_DQ<13> @S9S_MB_2U_LIB.S9S_MB_2U(SCH_1):M_D_CPU0_SB_DQ(13)   I169 @S9S_MB_2U_LIB.S9S_MB_2U(SCH_1):PAGE23
  AK26 M_D_CPU0_SB_DQ<12> @S9S_MB_2U_LIB.S9S_MB_2U(SCH_1):M_D_CPU0_SB_DQ(12)   I169 @S9S_MB_2U_LIB.S9S_MB_2U(SCH_1):PAGE23
  AP28 M_D_CPU0_SB_DQ<11> @S9S_MB_2U_LIB.S9S_MB_2U(SCH_1):M_D_CPU0_SB_DQ(11)   I169 @S9S_MB_2U_LIB.S9S_MB_2U(SCH_1):PAGE23
  AN29 M_D_CPU0_SB_DQ<10> @S9S_MB_2U_LIB.S9S_MB_2U(SCH_1):M_D_CPU0_SB_DQ(10)   I169 @S9S_MB_2U_LIB.S9S_MB_2U(SCH_1):PAGE23
  AK28 M_D_CPU0_SB_DQ<9> @S9S_MB_2U_LIB.S9S_MB_2U(SCH_1):M_D_CPU0_SB_DQ(9)   I169 @S9S_MB_2U_LIB.S9S_MB_2U(SCH_1):PAGE23
  AL29 M_D_CPU0_SB_DQ<8> @S9S_MB_2U_LIB.S9S_MB_2U(SCH_1):M_D_CPU0_SB_DQ(8)   I169 @S9S_MB_2U_LIB.S9S_MB_2U(SCH_1):PAGE23
  AN31 M_D_CPU0_SB_DQ<7> @S9S_MB_2U_LIB.S9S_MB_2U(SCH_1):M_D_CPU0_SB_DQ(7)   I169 @S9S_MB_2U_LIB.S9S_MB_2U(SCH_1):PAGE23
  AP32 M_D_CPU0_SB_DQ<6> @S9S_MB_2U_LIB.S9S_MB_2U(SCH_1):M_D_CPU0_SB_DQ(6)   I169 @S9S_MB_2U_LIB.S9S_MB_2U(SCH_1):PAGE23
  AL31 M_D_CPU0_SB_DQ<5> @S9S_MB_2U_LIB.S9S_MB_2U(SCH_1):M_D_CPU0_SB_DQ(5)   I169 @S9S_MB_2U_LIB.S9S_MB_2U(SCH_1):PAGE23
  AK32 M_D_CPU0_SB_DQ<4> @S9S_MB_2U_LIB.S9S_MB_2U(SCH_1):M_D_CPU0_SB_DQ(4)   I169 @S9S_MB_2U_LIB.S9S_MB_2U(SCH_1):PAGE23
  AP34 M_D_CPU0_SB_DQ<3> @S9S_MB_2U_LIB.S9S_MB_2U(SCH_1):M_D_CPU0_SB_DQ(3)   I169 @S9S_MB_2U_LIB.S9S_MB_2U(SCH_1):PAGE23
  AN35 M_D_CPU0_SB_DQ<2> @S9S_MB_2U_LIB.S9S_MB_2U(SCH_1):M_D_CPU0_SB_DQ(2)   I169 @S9S_MB_2U_LIB.S9S_MB_2U(SCH_1):PAGE23
  AK34 M_D_CPU0_SB_DQ<1> @S9S_MB_2U_LIB.S9S_MB_2U(SCH_1):M_D_CPU0_SB_DQ(1)   I169 @S9S_MB_2U_LIB.S9S_MB_2U(SCH_1):PAGE23
  AL35 M_D_CPU0_SB_DQ<0> @S9S_MB_2U_LIB.S9S_MB_2U(SCH_1):M_D_CPU0_SB_DQ(0)   I169 @S9S_MB_2U_LIB.S9S_MB_2U(SCH_1):PAGE23
  AJ39 M_D_CPU0_SB_DQS_DN<9> @S9S_MB_2U_LIB.S9S_MB_2U(SCH_1):M_D_CPU0_SB_DQS_DN(9)   I169 @S9S_MB_2U_LIB.S9S_MB_2U(SCH_1):PAGE23
  AN21 M_D_CPU0_SB_DQS_DN<8> @S9S_MB_2U_LIB.S9S_MB_2U(SCH_1):M_D_CPU0_SB_DQS_DN(8)   I169 @S9S_MB_2U_LIB.S9S_MB_2U(SCH_1):PAGE23
  AF24 M_D_CPU0_SB_DQS_DN<7> @S9S_MB_2U_LIB.S9S_MB_2U(SCH_1):M_D_CPU0_SB_DQS_DN(7)   I169 @S9S_MB_2U_LIB.S9S_MB_2U(SCH_1):PAGE23
  AN27 M_D_CPU0_SB_DQS_DN<6> @S9S_MB_2U_LIB.S9S_MB_2U(SCH_1):M_D_CPU0_SB_DQS_DN(6)   I169 @S9S_MB_2U_LIB.S9S_MB_2U(SCH_1):PAGE23
  AN33 M_D_CPU0_SB_DQS_DN<5> @S9S_MB_2U_LIB.S9S_MB_2U(SCH_1):M_D_CPU0_SB_DQS_DN(5)   I169 @S9S_MB_2U_LIB.S9S_MB_2U(SCH_1):PAGE23
  AR39 M_D_CPU0_SB_DQS_DN<4> @S9S_MB_2U_LIB.S9S_MB_2U(SCH_1):M_D_CPU0_SB_DQS_DN(4)   I169 @S9S_MB_2U_LIB.S9S_MB_2U(SCH_1):PAGE23
  AJ21 M_D_CPU0_SB_DQS_DN<3> @S9S_MB_2U_LIB.S9S_MB_2U(SCH_1):M_D_CPU0_SB_DQS_DN(3)   I169 @S9S_MB_2U_LIB.S9S_MB_2U(SCH_1):PAGE23
  AB24 M_D_CPU0_SB_DQS_DN<2> @S9S_MB_2U_LIB.S9S_MB_2U(SCH_1):M_D_CPU0_SB_DQS_DN(2)   I169 @S9S_MB_2U_LIB.S9S_MB_2U(SCH_1):PAGE23
  AJ27 M_D_CPU0_SB_DQS_DN<1> @S9S_MB_2U_LIB.S9S_MB_2U(SCH_1):M_D_CPU0_SB_DQS_DN(1)   I169 @S9S_MB_2U_LIB.S9S_MB_2U(SCH_1):PAGE23
  AJ33 M_D_CPU0_SB_DQS_DN<0> @S9S_MB_2U_LIB.S9S_MB_2U(SCH_1):M_D_CPU0_SB_DQS_DN(0)   I169 @S9S_MB_2U_LIB.S9S_MB_2U(SCH_1):PAGE23
  AL39 M_D_CPU0_SB_DQS_DP<9> @S9S_MB_2U_LIB.S9S_MB_2U(SCH_1):M_D_CPU0_SB_DQS_DP(9)   I169 @S9S_MB_2U_LIB.S9S_MB_2U(SCH_1):PAGE23
  AR21 M_D_CPU0_SB_DQS_DP<8> @S9S_MB_2U_LIB.S9S_MB_2U(SCH_1):M_D_CPU0_SB_DQS_DP(8)   I169 @S9S_MB_2U_LIB.S9S_MB_2U(SCH_1):PAGE23
  AH24 M_D_CPU0_SB_DQS_DP<7> @S9S_MB_2U_LIB.S9S_MB_2U(SCH_1):M_D_CPU0_SB_DQS_DP(7)   I169 @S9S_MB_2U_LIB.S9S_MB_2U(SCH_1):PAGE23
  AR27 M_D_CPU0_SB_DQS_DP<6> @S9S_MB_2U_LIB.S9S_MB_2U(SCH_1):M_D_CPU0_SB_DQS_DP(6)   I169 @S9S_MB_2U_LIB.S9S_MB_2U(SCH_1):PAGE23
  AR33 M_D_CPU0_SB_DQS_DP<5> @S9S_MB_2U_LIB.S9S_MB_2U(SCH_1):M_D_CPU0_SB_DQS_DP(5)   I169 @S9S_MB_2U_LIB.S9S_MB_2U(SCH_1):PAGE23
  AN39 M_D_CPU0_SB_DQS_DP<4> @S9S_MB_2U_LIB.S9S_MB_2U(SCH_1):M_D_CPU0_SB_DQS_DP(4)   I169 @S9S_MB_2U_LIB.S9S_MB_2U(SCH_1):PAGE23
  AL21 M_D_CPU0_SB_DQS_DP<3> @S9S_MB_2U_LIB.S9S_MB_2U(SCH_1):M_D_CPU0_SB_DQS_DP(3)   I169 @S9S_MB_2U_LIB.S9S_MB_2U(SCH_1):PAGE23
  AD24 M_D_CPU0_SB_DQS_DP<2> @S9S_MB_2U_LIB.S9S_MB_2U(SCH_1):M_D_CPU0_SB_DQS_DP(2)   I169 @S9S_MB_2U_LIB.S9S_MB_2U(SCH_1):PAGE23
  AL27 M_D_CPU0_SB_DQS_DP<1> @S9S_MB_2U_LIB.S9S_MB_2U(SCH_1):M_D_CPU0_SB_DQS_DP(1)   I169 @S9S_MB_2U_LIB.S9S_MB_2U(SCH_1):PAGE23
  AL33 M_D_CPU0_SB_DQS_DP<0> @S9S_MB_2U_LIB.S9S_MB_2U(SCH_1):M_D_CPU0_SB_DQS_DP(0)   I169 @S9S_MB_2U_LIB.S9S_MB_2U(SCH_1):PAGE23
  AP40 M_D_CPU0_SB_CB<7> @S9S_MB_2U_LIB.S9S_MB_2U(SCH_1):M_D_CPU0_SB_CB(7)   I169 @S9S_MB_2U_LIB.S9S_MB_2U(SCH_1):PAGE23
  AN41 M_D_CPU0_SB_CB<6> @S9S_MB_2U_LIB.S9S_MB_2U(SCH_1):M_D_CPU0_SB_CB(6)   I169 @S9S_MB_2U_LIB.S9S_MB_2U(SCH_1):PAGE23
  AK40 M_D_CPU0_SB_CB<5> @S9S_MB_2U_LIB.S9S_MB_2U(SCH_1):M_D_CPU0_SB_CB(5)   I169 @S9S_MB_2U_LIB.S9S_MB_2U(SCH_1):PAGE23
  AL41 M_D_CPU0_SB_CB<4> @S9S_MB_2U_LIB.S9S_MB_2U(SCH_1):M_D_CPU0_SB_CB(4)   I169 @S9S_MB_2U_LIB.S9S_MB_2U(SCH_1):PAGE23
  AN37 M_D_CPU0_SB_CB<3> @S9S_MB_2U_LIB.S9S_MB_2U(SCH_1):M_D_CPU0_SB_CB(3)   I169 @S9S_MB_2U_LIB.S9S_MB_2U(SCH_1):PAGE23
  AP38 M_D_CPU0_SB_CB<2> @S9S_MB_2U_LIB.S9S_MB_2U(SCH_1):M_D_CPU0_SB_CB(2)   I169 @S9S_MB_2U_LIB.S9S_MB_2U(SCH_1):PAGE23
  AL37 M_D_CPU0_SB_CB<1> @S9S_MB_2U_LIB.S9S_MB_2U(SCH_1):M_D_CPU0_SB_CB(1)   I169 @S9S_MB_2U_LIB.S9S_MB_2U(SCH_1):PAGE23
  AK38 M_D_CPU0_SB_CB<0> @S9S_MB_2U_LIB.S9S_MB_2U(SCH_1):M_D_CPU0_SB_CB(0)   I169 @S9S_MB_2U_LIB.S9S_MB_2U(SCH_1):PAGE23
  AH42 M_D_CPU0_SB_PAR @S9S_MB_2U_LIB.S9S_MB_2U(SCH_1):M_D_CPU0_SB_PAR   I169 @S9S_MB_2U_LIB.S9S_MB_2U(SCH_1):PAGE23
  CY47 M_E_CPU0_ALERT_N @S9S_MB_2U_LIB.S9S_MB_2U(SCH_1):M_E_CPU0_ALERT_N   I169 @S9S_MB_2U_LIB.S9S_MB_2U(SCH_1):PAGE24
  DC43 M_E_CPU0_SA_RSP<1> @S9S_MB_2U_LIB.S9S_MB_2U(SCH_1):M_E_CPU0_SA_RSP(1)   I169 @S9S_MB_2U_LIB.S9S_MB_2U(SCH_1):PAGE24
  DD44 M_E_CPU0_SA_RSP<0> @S9S_MB_2U_LIB.S9S_MB_2U(SCH_1):M_E_CPU0_SA_RSP(0)   I169 @S9S_MB_2U_LIB.S9S_MB_2U(SCH_1):PAGE24
  DG43 M_E_CPU0_SB_RSP<1> @S9S_MB_2U_LIB.S9S_MB_2U(SCH_1):M_E_CPU0_SB_RSP(1)   I169 @S9S_MB_2U_LIB.S9S_MB_2U(SCH_1):PAGE24
  DF44 M_E_CPU0_SB_RSP<0> @S9S_MB_2U_LIB.S9S_MB_2U(SCH_1):M_E_CPU0_SB_RSP(0)   I169 @S9S_MB_2U_LIB.S9S_MB_2U(SCH_1):PAGE24
  EE45 M_E_CPU0_CLK_DN<1> @S9S_MB_2U_LIB.S9S_MB_2U(SCH_1):M_E_CPU0_CLK_DN(1)   I169 @S9S_MB_2U_LIB.S9S_MB_2U(SCH_1):PAGE24
  EJ45 M_E_CPU0_CLK_DN<0> @S9S_MB_2U_LIB.S9S_MB_2U(SCH_1):M_E_CPU0_CLK_DN(0)   I169 @S9S_MB_2U_LIB.S9S_MB_2U(SCH_1):PAGE24
  EC45 M_E_CPU0_CLK_DP<1> @S9S_MB_2U_LIB.S9S_MB_2U(SCH_1):M_E_CPU0_CLK_DP(1)   I169 @S9S_MB_2U_LIB.S9S_MB_2U(SCH_1):PAGE24
  EG45 M_E_CPU0_CLK_DP<0> @S9S_MB_2U_LIB.S9S_MB_2U(SCH_1):M_E_CPU0_CLK_DP(0)   I169 @S9S_MB_2U_LIB.S9S_MB_2U(SCH_1):PAGE24
  ED44 M_E_CPU0_SA_CA<6> @S9S_MB_2U_LIB.S9S_MB_2U(SCH_1):M_E_CPU0_SA_CA(6)   I169 @S9S_MB_2U_LIB.S9S_MB_2U(SCH_1):PAGE24
  EP47 M_E_CPU0_SA_CA<5> @S9S_MB_2U_LIB.S9S_MB_2U(SCH_1):M_E_CPU0_SA_CA(5)   I169 @S9S_MB_2U_LIB.S9S_MB_2U(SCH_1):PAGE24
  EM47 M_E_CPU0_SA_CA<4> @S9S_MB_2U_LIB.S9S_MB_2U(SCH_1):M_E_CPU0_SA_CA(4)   I169 @S9S_MB_2U_LIB.S9S_MB_2U(SCH_1):PAGE24
  EL48 M_E_CPU0_SA_CA<3> @S9S_MB_2U_LIB.S9S_MB_2U(SCH_1):M_E_CPU0_SA_CA(3)   I169 @S9S_MB_2U_LIB.S9S_MB_2U(SCH_1):PAGE24
  EK49 M_E_CPU0_SA_CA<2> @S9S_MB_2U_LIB.S9S_MB_2U(SCH_1):M_E_CPU0_SA_CA(2)   I169 @S9S_MB_2U_LIB.S9S_MB_2U(SCH_1):PAGE24
  ET49 M_E_CPU0_SA_CA<1> @S9S_MB_2U_LIB.S9S_MB_2U(SCH_1):M_E_CPU0_SA_CA(1)   I169 @S9S_MB_2U_LIB.S9S_MB_2U(SCH_1):PAGE24
  EP49 M_E_CPU0_SA_CA<0> @S9S_MB_2U_LIB.S9S_MB_2U(SCH_1):M_E_CPU0_SA_CA(0)   I169 @S9S_MB_2U_LIB.S9S_MB_2U(SCH_1):PAGE24
  EL50 M_E_CPU0_SA_CS_N<3> @S9S_MB_2U_LIB.S9S_MB_2U(SCH_1):M_E_CPU0_SA_CS_N(3)   I169 @S9S_MB_2U_LIB.S9S_MB_2U(SCH_1):PAGE24
  EM51 M_E_CPU0_SA_CS_N<2> @S9S_MB_2U_LIB.S9S_MB_2U(SCH_1):M_E_CPU0_SA_CS_N(2)   I169 @S9S_MB_2U_LIB.S9S_MB_2U(SCH_1):PAGE24
  ET51 M_E_CPU0_SA_CS_N<1> @S9S_MB_2U_LIB.S9S_MB_2U(SCH_1):M_E_CPU0_SA_CS_N(1)   I169 @S9S_MB_2U_LIB.S9S_MB_2U(SCH_1):PAGE24
  EP51 M_E_CPU0_SA_CS_N<0> @S9S_MB_2U_LIB.S9S_MB_2U(SCH_1):M_E_CPU0_SA_CS_N(0)   I169 @S9S_MB_2U_LIB.S9S_MB_2U(SCH_1):PAGE24
  EP59 M_E_CPU0_SA_DQ<31> @S9S_MB_2U_LIB.S9S_MB_2U(SCH_1):M_E_CPU0_SA_DQ(31)   I169 @S9S_MB_2U_LIB.S9S_MB_2U(SCH_1):PAGE24
  ER60 M_E_CPU0_SA_DQ<30> @S9S_MB_2U_LIB.S9S_MB_2U(SCH_1):M_E_CPU0_SA_DQ(30)   I169 @S9S_MB_2U_LIB.S9S_MB_2U(SCH_1):PAGE24
  EM59 M_E_CPU0_SA_DQ<29> @S9S_MB_2U_LIB.S9S_MB_2U(SCH_1):M_E_CPU0_SA_DQ(29)   I169 @S9S_MB_2U_LIB.S9S_MB_2U(SCH_1):PAGE24
  EL60 M_E_CPU0_SA_DQ<28> @S9S_MB_2U_LIB.S9S_MB_2U(SCH_1):M_E_CPU0_SA_DQ(28)   I169 @S9S_MB_2U_LIB.S9S_MB_2U(SCH_1):PAGE24
  ER62 M_E_CPU0_SA_DQ<27> @S9S_MB_2U_LIB.S9S_MB_2U(SCH_1):M_E_CPU0_SA_DQ(27)   I169 @S9S_MB_2U_LIB.S9S_MB_2U(SCH_1):PAGE24
  EP63 M_E_CPU0_SA_DQ<26> @S9S_MB_2U_LIB.S9S_MB_2U(SCH_1):M_E_CPU0_SA_DQ(26)   I169 @S9S_MB_2U_LIB.S9S_MB_2U(SCH_1):PAGE24
  EL62 M_E_CPU0_SA_DQ<25> @S9S_MB_2U_LIB.S9S_MB_2U(SCH_1):M_E_CPU0_SA_DQ(25)   I169 @S9S_MB_2U_LIB.S9S_MB_2U(SCH_1):PAGE24
  EM63 M_E_CPU0_SA_DQ<24> @S9S_MB_2U_LIB.S9S_MB_2U(SCH_1):M_E_CPU0_SA_DQ(24)   I169 @S9S_MB_2U_LIB.S9S_MB_2U(SCH_1):PAGE24
  EP65 M_E_CPU0_SA_DQ<23> @S9S_MB_2U_LIB.S9S_MB_2U(SCH_1):M_E_CPU0_SA_DQ(23)   I169 @S9S_MB_2U_LIB.S9S_MB_2U(SCH_1):PAGE24
  EL66 M_E_CPU0_SA_DQ<22> @S9S_MB_2U_LIB.S9S_MB_2U(SCH_1):M_E_CPU0_SA_DQ(22)   I169 @S9S_MB_2U_LIB.S9S_MB_2U(SCH_1):PAGE24
  EM65 M_E_CPU0_SA_DQ<21> @S9S_MB_2U_LIB.S9S_MB_2U(SCH_1):M_E_CPU0_SA_DQ(21)   I169 @S9S_MB_2U_LIB.S9S_MB_2U(SCH_1):PAGE24
  ER66 M_E_CPU0_SA_DQ<20> @S9S_MB_2U_LIB.S9S_MB_2U(SCH_1):M_E_CPU0_SA_DQ(20)   I169 @S9S_MB_2U_LIB.S9S_MB_2U(SCH_1):PAGE24
  ER68 M_E_CPU0_SA_DQ<19> @S9S_MB_2U_LIB.S9S_MB_2U(SCH_1):M_E_CPU0_SA_DQ(19)   I169 @S9S_MB_2U_LIB.S9S_MB_2U(SCH_1):PAGE24
  EN70 M_E_CPU0_SA_DQ<18> @S9S_MB_2U_LIB.S9S_MB_2U(SCH_1):M_E_CPU0_SA_DQ(18)   I169 @S9S_MB_2U_LIB.S9S_MB_2U(SCH_1):PAGE24
  EM69 M_E_CPU0_SA_DQ<17> @S9S_MB_2U_LIB.S9S_MB_2U(SCH_1):M_E_CPU0_SA_DQ(17)   I169 @S9S_MB_2U_LIB.S9S_MB_2U(SCH_1):PAGE24
  EM71 M_E_CPU0_SA_DQ<16> @S9S_MB_2U_LIB.S9S_MB_2U(SCH_1):M_E_CPU0_SA_DQ(16)   I169 @S9S_MB_2U_LIB.S9S_MB_2U(SCH_1):PAGE24
  EG68 M_E_CPU0_SA_DQ<15> @S9S_MB_2U_LIB.S9S_MB_2U(SCH_1):M_E_CPU0_SA_DQ(15)   I169 @S9S_MB_2U_LIB.S9S_MB_2U(SCH_1):PAGE24
  EH69 M_E_CPU0_SA_DQ<14> @S9S_MB_2U_LIB.S9S_MB_2U(SCH_1):M_E_CPU0_SA_DQ(14)   I169 @S9S_MB_2U_LIB.S9S_MB_2U(SCH_1):PAGE24
  EE68 M_E_CPU0_SA_DQ<13> @S9S_MB_2U_LIB.S9S_MB_2U(SCH_1):M_E_CPU0_SA_DQ(13)   I169 @S9S_MB_2U_LIB.S9S_MB_2U(SCH_1):PAGE24
  ED69 M_E_CPU0_SA_DQ<12> @S9S_MB_2U_LIB.S9S_MB_2U(SCH_1):M_E_CPU0_SA_DQ(12)   I169 @S9S_MB_2U_LIB.S9S_MB_2U(SCH_1):PAGE24
  EH71 M_E_CPU0_SA_DQ<11> @S9S_MB_2U_LIB.S9S_MB_2U(SCH_1):M_E_CPU0_SA_DQ(11)   I169 @S9S_MB_2U_LIB.S9S_MB_2U(SCH_1):PAGE24
  EG72 M_E_CPU0_SA_DQ<10> @S9S_MB_2U_LIB.S9S_MB_2U(SCH_1):M_E_CPU0_SA_DQ(10)   I169 @S9S_MB_2U_LIB.S9S_MB_2U(SCH_1):PAGE24
  ED71 M_E_CPU0_SA_DQ<9> @S9S_MB_2U_LIB.S9S_MB_2U(SCH_1):M_E_CPU0_SA_DQ(9)   I169 @S9S_MB_2U_LIB.S9S_MB_2U(SCH_1):PAGE24
  EE72 M_E_CPU0_SA_DQ<8> @S9S_MB_2U_LIB.S9S_MB_2U(SCH_1):M_E_CPU0_SA_DQ(8)   I169 @S9S_MB_2U_LIB.S9S_MB_2U(SCH_1):PAGE24
  ER72 M_E_CPU0_SA_DQ<7> @S9S_MB_2U_LIB.S9S_MB_2U(SCH_1):M_E_CPU0_SA_DQ(7)   I169 @S9S_MB_2U_LIB.S9S_MB_2U(SCH_1):PAGE24
  EP73 M_E_CPU0_SA_DQ<6> @S9S_MB_2U_LIB.S9S_MB_2U(SCH_1):M_E_CPU0_SA_DQ(6)   I169 @S9S_MB_2U_LIB.S9S_MB_2U(SCH_1):PAGE24
  EK73 M_E_CPU0_SA_DQ<5> @S9S_MB_2U_LIB.S9S_MB_2U(SCH_1):M_E_CPU0_SA_DQ(5)   I169 @S9S_MB_2U_LIB.S9S_MB_2U(SCH_1):PAGE24
  EL74 M_E_CPU0_SA_DQ<4> @S9S_MB_2U_LIB.S9S_MB_2U(SCH_1):M_E_CPU0_SA_DQ(4)   I169 @S9S_MB_2U_LIB.S9S_MB_2U(SCH_1):PAGE24
  ER76 M_E_CPU0_SA_DQ<3> @S9S_MB_2U_LIB.S9S_MB_2U(SCH_1):M_E_CPU0_SA_DQ(3)   I169 @S9S_MB_2U_LIB.S9S_MB_2U(SCH_1):PAGE24
  EP79 M_E_CPU0_SA_DQ<2> @S9S_MB_2U_LIB.S9S_MB_2U(SCH_1):M_E_CPU0_SA_DQ(2)   I169 @S9S_MB_2U_LIB.S9S_MB_2U(SCH_1):PAGE24
  EM77 M_E_CPU0_SA_DQ<1> @S9S_MB_2U_LIB.S9S_MB_2U(SCH_1):M_E_CPU0_SA_DQ(1)   I169 @S9S_MB_2U_LIB.S9S_MB_2U(SCH_1):PAGE24
  EL78 M_E_CPU0_SA_DQ<0> @S9S_MB_2U_LIB.S9S_MB_2U(SCH_1):M_E_CPU0_SA_DQ(0)   I169 @S9S_MB_2U_LIB.S9S_MB_2U(SCH_1):PAGE24
  ET55 M_E_CPU0_SA_DQS_DN<9> @S9S_MB_2U_LIB.S9S_MB_2U(SCH_1):M_E_CPU0_SA_DQS_DN(9)   I169 @S9S_MB_2U_LIB.S9S_MB_2U(SCH_1):PAGE24
  ET61 M_E_CPU0_SA_DQS_DN<8> @S9S_MB_2U_LIB.S9S_MB_2U(SCH_1):M_E_CPU0_SA_DQS_DN(8)   I169 @S9S_MB_2U_LIB.S9S_MB_2U(SCH_1):PAGE24
  EN68 M_E_CPU0_SA_DQS_DN<7> @S9S_MB_2U_LIB.S9S_MB_2U(SCH_1):M_E_CPU0_SA_DQS_DN(7)   I169 @S9S_MB_2U_LIB.S9S_MB_2U(SCH_1):PAGE24
  EJ70 M_E_CPU0_SA_DQS_DN<6> @S9S_MB_2U_LIB.S9S_MB_2U(SCH_1):M_E_CPU0_SA_DQS_DN(6)   I169 @S9S_MB_2U_LIB.S9S_MB_2U(SCH_1):PAGE24
  EM75 M_E_CPU0_SA_DQS_DN<5> @S9S_MB_2U_LIB.S9S_MB_2U(SCH_1):M_E_CPU0_SA_DQS_DN(5)   I169 @S9S_MB_2U_LIB.S9S_MB_2U(SCH_1):PAGE24
  EM55 M_E_CPU0_SA_DQS_DN<4> @S9S_MB_2U_LIB.S9S_MB_2U(SCH_1):M_E_CPU0_SA_DQS_DN(4)   I169 @S9S_MB_2U_LIB.S9S_MB_2U(SCH_1):PAGE24
  EK61 M_E_CPU0_SA_DQS_DN<3> @S9S_MB_2U_LIB.S9S_MB_2U(SCH_1):M_E_CPU0_SA_DQS_DN(3)   I169 @S9S_MB_2U_LIB.S9S_MB_2U(SCH_1):PAGE24
  EK67 M_E_CPU0_SA_DQS_DN<2> @S9S_MB_2U_LIB.S9S_MB_2U(SCH_1):M_E_CPU0_SA_DQS_DN(2)   I169 @S9S_MB_2U_LIB.S9S_MB_2U(SCH_1):PAGE24
  EC70 M_E_CPU0_SA_DQS_DN<1> @S9S_MB_2U_LIB.S9S_MB_2U(SCH_1):M_E_CPU0_SA_DQS_DN(1)   I169 @S9S_MB_2U_LIB.S9S_MB_2U(SCH_1):PAGE24
  EP75 M_E_CPU0_SA_DQS_DN<0> @S9S_MB_2U_LIB.S9S_MB_2U(SCH_1):M_E_CPU0_SA_DQS_DN(0)   I169 @S9S_MB_2U_LIB.S9S_MB_2U(SCH_1):PAGE24
  EP55 M_E_CPU0_SA_DQS_DP<9> @S9S_MB_2U_LIB.S9S_MB_2U(SCH_1):M_E_CPU0_SA_DQS_DP(9)   I169 @S9S_MB_2U_LIB.S9S_MB_2U(SCH_1):PAGE24
  EP61 M_E_CPU0_SA_DQS_DP<8> @S9S_MB_2U_LIB.S9S_MB_2U(SCH_1):M_E_CPU0_SA_DQS_DP(8)   I169 @S9S_MB_2U_LIB.S9S_MB_2U(SCH_1):PAGE24
  EM67 M_E_CPU0_SA_DQS_DP<7> @S9S_MB_2U_LIB.S9S_MB_2U(SCH_1):M_E_CPU0_SA_DQS_DP(7)   I169 @S9S_MB_2U_LIB.S9S_MB_2U(SCH_1):PAGE24
  EG70 M_E_CPU0_SA_DQS_DP<6> @S9S_MB_2U_LIB.S9S_MB_2U(SCH_1):M_E_CPU0_SA_DQS_DP(6)   I169 @S9S_MB_2U_LIB.S9S_MB_2U(SCH_1):PAGE24
  EN74 M_E_CPU0_SA_DQS_DP<5> @S9S_MB_2U_LIB.S9S_MB_2U(SCH_1):M_E_CPU0_SA_DQS_DP(5)   I169 @S9S_MB_2U_LIB.S9S_MB_2U(SCH_1):PAGE24
  EK55 M_E_CPU0_SA_DQS_DP<4> @S9S_MB_2U_LIB.S9S_MB_2U(SCH_1):M_E_CPU0_SA_DQS_DP(4)   I169 @S9S_MB_2U_LIB.S9S_MB_2U(SCH_1):PAGE24
  EM61 M_E_CPU0_SA_DQS_DP<3> @S9S_MB_2U_LIB.S9S_MB_2U(SCH_1):M_E_CPU0_SA_DQS_DP(3)   I169 @S9S_MB_2U_LIB.S9S_MB_2U(SCH_1):PAGE24
  EL68 M_E_CPU0_SA_DQS_DP<2> @S9S_MB_2U_LIB.S9S_MB_2U(SCH_1):M_E_CPU0_SA_DQS_DP(2)   I169 @S9S_MB_2U_LIB.S9S_MB_2U(SCH_1):PAGE24
  EE70 M_E_CPU0_SA_DQS_DP<1> @S9S_MB_2U_LIB.S9S_MB_2U(SCH_1):M_E_CPU0_SA_DQS_DP(1)   I169 @S9S_MB_2U_LIB.S9S_MB_2U(SCH_1):PAGE24
  EN76 M_E_CPU0_SA_DQS_DP<0> @S9S_MB_2U_LIB.S9S_MB_2U(SCH_1):M_E_CPU0_SA_DQS_DP(0)   I169 @S9S_MB_2U_LIB.S9S_MB_2U(SCH_1):PAGE24
  EP53 M_E_CPU0_SA_CB<7> @S9S_MB_2U_LIB.S9S_MB_2U(SCH_1):M_E_CPU0_SA_CB(7)   I169 @S9S_MB_2U_LIB.S9S_MB_2U(SCH_1):PAGE24
  ER54 M_E_CPU0_SA_CB<6> @S9S_MB_2U_LIB.S9S_MB_2U(SCH_1):M_E_CPU0_SA_CB(6)   I169 @S9S_MB_2U_LIB.S9S_MB_2U(SCH_1):PAGE24
  EM53 M_E_CPU0_SA_CB<5> @S9S_MB_2U_LIB.S9S_MB_2U(SCH_1):M_E_CPU0_SA_CB(5)   I169 @S9S_MB_2U_LIB.S9S_MB_2U(SCH_1):PAGE24
  EL54 M_E_CPU0_SA_CB<4> @S9S_MB_2U_LIB.S9S_MB_2U(SCH_1):M_E_CPU0_SA_CB(4)   I169 @S9S_MB_2U_LIB.S9S_MB_2U(SCH_1):PAGE24
  ER56 M_E_CPU0_SA_CB<3> @S9S_MB_2U_LIB.S9S_MB_2U(SCH_1):M_E_CPU0_SA_CB(3)   I169 @S9S_MB_2U_LIB.S9S_MB_2U(SCH_1):PAGE24
  EP57 M_E_CPU0_SA_CB<2> @S9S_MB_2U_LIB.S9S_MB_2U(SCH_1):M_E_CPU0_SA_CB(2)   I169 @S9S_MB_2U_LIB.S9S_MB_2U(SCH_1):PAGE24
  EL56 M_E_CPU0_SA_CB<1> @S9S_MB_2U_LIB.S9S_MB_2U(SCH_1):M_E_CPU0_SA_CB(1)   I169 @S9S_MB_2U_LIB.S9S_MB_2U(SCH_1):PAGE24
  EM57 M_E_CPU0_SA_CB<0> @S9S_MB_2U_LIB.S9S_MB_2U(SCH_1):M_E_CPU0_SA_CB(0)   I169 @S9S_MB_2U_LIB.S9S_MB_2U(SCH_1):PAGE24
  EE43 M_E_CPU0_SA_PAR @S9S_MB_2U_LIB.S9S_MB_2U(SCH_1):M_E_CPU0_SA_PAR   I169 @S9S_MB_2U_LIB.S9S_MB_2U(SCH_1):PAGE24
  EK42 M_E_CPU0_SB_CA<6> @S9S_MB_2U_LIB.S9S_MB_2U(SCH_1):M_E_CPU0_SB_CA(6)   I169 @S9S_MB_2U_LIB.S9S_MB_2U(SCH_1):PAGE24
  ET42 M_E_CPU0_SB_CA<5> @S9S_MB_2U_LIB.S9S_MB_2U(SCH_1):M_E_CPU0_SB_CA(5)   I169 @S9S_MB_2U_LIB.S9S_MB_2U(SCH_1):PAGE24
  EL43 M_E_CPU0_SB_CA<4> @S9S_MB_2U_LIB.S9S_MB_2U(SCH_1):M_E_CPU0_SB_CA(4)   I169 @S9S_MB_2U_LIB.S9S_MB_2U(SCH_1):PAGE24
  EP44 M_E_CPU0_SB_CA<3> @S9S_MB_2U_LIB.S9S_MB_2U(SCH_1):M_E_CPU0_SB_CA(3)   I169 @S9S_MB_2U_LIB.S9S_MB_2U(SCH_1):PAGE24
  EM44 M_E_CPU0_SB_CA<2> @S9S_MB_2U_LIB.S9S_MB_2U(SCH_1):M_E_CPU0_SB_CA(2)   I169 @S9S_MB_2U_LIB.S9S_MB_2U(SCH_1):PAGE24
  EH44 M_E_CPU0_SB_CA<1> @S9S_MB_2U_LIB.S9S_MB_2U(SCH_1):M_E_CPU0_SB_CA(1)   I169 @S9S_MB_2U_LIB.S9S_MB_2U(SCH_1):PAGE24
  EG43 M_E_CPU0_SB_CA<0> @S9S_MB_2U_LIB.S9S_MB_2U(SCH_1):M_E_CPU0_SB_CA(0)   I169 @S9S_MB_2U_LIB.S9S_MB_2U(SCH_1):PAGE24
  EL41 M_E_CPU0_SB_CS_N<3> @S9S_MB_2U_LIB.S9S_MB_2U(SCH_1):M_E_CPU0_SB_CS_N(3)   I169 @S9S_MB_2U_LIB.S9S_MB_2U(SCH_1):PAGE24
  EM40 M_E_CPU0_SB_CS_N<2> @S9S_MB_2U_LIB.S9S_MB_2U(SCH_1):M_E_CPU0_SB_CS_N(2)   I169 @S9S_MB_2U_LIB.S9S_MB_2U(SCH_1):PAGE24
  ET40 M_E_CPU0_SB_CS_N<1> @S9S_MB_2U_LIB.S9S_MB_2U(SCH_1):M_E_CPU0_SB_CS_N(1)   I169 @S9S_MB_2U_LIB.S9S_MB_2U(SCH_1):PAGE24
  EP40 M_E_CPU0_SB_CS_N<0> @S9S_MB_2U_LIB.S9S_MB_2U(SCH_1):M_E_CPU0_SB_CS_N(0)   I169 @S9S_MB_2U_LIB.S9S_MB_2U(SCH_1):PAGE24
  EP16 M_E_CPU0_SB_DQ<31> @S9S_MB_2U_LIB.S9S_MB_2U(SCH_1):M_E_CPU0_SB_DQ(31)   I169 @S9S_MB_2U_LIB.S9S_MB_2U(SCH_1):PAGE24
  ER17 M_E_CPU0_SB_DQ<30> @S9S_MB_2U_LIB.S9S_MB_2U(SCH_1):M_E_CPU0_SB_DQ(30)   I169 @S9S_MB_2U_LIB.S9S_MB_2U(SCH_1):PAGE24
  EM16 M_E_CPU0_SB_DQ<29> @S9S_MB_2U_LIB.S9S_MB_2U(SCH_1):M_E_CPU0_SB_DQ(29)   I169 @S9S_MB_2U_LIB.S9S_MB_2U(SCH_1):PAGE24
  EL17 M_E_CPU0_SB_DQ<28> @S9S_MB_2U_LIB.S9S_MB_2U(SCH_1):M_E_CPU0_SB_DQ(28)   I169 @S9S_MB_2U_LIB.S9S_MB_2U(SCH_1):PAGE24
  ER19 M_E_CPU0_SB_DQ<27> @S9S_MB_2U_LIB.S9S_MB_2U(SCH_1):M_E_CPU0_SB_DQ(27)   I169 @S9S_MB_2U_LIB.S9S_MB_2U(SCH_1):PAGE24
  EP20 M_E_CPU0_SB_DQ<26> @S9S_MB_2U_LIB.S9S_MB_2U(SCH_1):M_E_CPU0_SB_DQ(26)   I169 @S9S_MB_2U_LIB.S9S_MB_2U(SCH_1):PAGE24
  EL19 M_E_CPU0_SB_DQ<25> @S9S_MB_2U_LIB.S9S_MB_2U(SCH_1):M_E_CPU0_SB_DQ(25)   I169 @S9S_MB_2U_LIB.S9S_MB_2U(SCH_1):PAGE24
  EM20 M_E_CPU0_SB_DQ<24> @S9S_MB_2U_LIB.S9S_MB_2U(SCH_1):M_E_CPU0_SB_DQ(24)   I169 @S9S_MB_2U_LIB.S9S_MB_2U(SCH_1):PAGE24
  EP22 M_E_CPU0_SB_DQ<23> @S9S_MB_2U_LIB.S9S_MB_2U(SCH_1):M_E_CPU0_SB_DQ(23)   I169 @S9S_MB_2U_LIB.S9S_MB_2U(SCH_1):PAGE24
  ER23 M_E_CPU0_SB_DQ<22> @S9S_MB_2U_LIB.S9S_MB_2U(SCH_1):M_E_CPU0_SB_DQ(22)   I169 @S9S_MB_2U_LIB.S9S_MB_2U(SCH_1):PAGE24
  EM22 M_E_CPU0_SB_DQ<21> @S9S_MB_2U_LIB.S9S_MB_2U(SCH_1):M_E_CPU0_SB_DQ(21)   I169 @S9S_MB_2U_LIB.S9S_MB_2U(SCH_1):PAGE24
  EL23 M_E_CPU0_SB_DQ<20> @S9S_MB_2U_LIB.S9S_MB_2U(SCH_1):M_E_CPU0_SB_DQ(20)   I169 @S9S_MB_2U_LIB.S9S_MB_2U(SCH_1):PAGE24
  ER25 M_E_CPU0_SB_DQ<19> @S9S_MB_2U_LIB.S9S_MB_2U(SCH_1):M_E_CPU0_SB_DQ(19)   I169 @S9S_MB_2U_LIB.S9S_MB_2U(SCH_1):PAGE24
  EP26 M_E_CPU0_SB_DQ<18> @S9S_MB_2U_LIB.S9S_MB_2U(SCH_1):M_E_CPU0_SB_DQ(18)   I169 @S9S_MB_2U_LIB.S9S_MB_2U(SCH_1):PAGE24
  EL25 M_E_CPU0_SB_DQ<17> @S9S_MB_2U_LIB.S9S_MB_2U(SCH_1):M_E_CPU0_SB_DQ(17)   I169 @S9S_MB_2U_LIB.S9S_MB_2U(SCH_1):PAGE24
  EM26 M_E_CPU0_SB_DQ<16> @S9S_MB_2U_LIB.S9S_MB_2U(SCH_1):M_E_CPU0_SB_DQ(16)   I169 @S9S_MB_2U_LIB.S9S_MB_2U(SCH_1):PAGE24
  EP28 M_E_CPU0_SB_DQ<15> @S9S_MB_2U_LIB.S9S_MB_2U(SCH_1):M_E_CPU0_SB_DQ(15)   I169 @S9S_MB_2U_LIB.S9S_MB_2U(SCH_1):PAGE24
  ER29 M_E_CPU0_SB_DQ<14> @S9S_MB_2U_LIB.S9S_MB_2U(SCH_1):M_E_CPU0_SB_DQ(14)   I169 @S9S_MB_2U_LIB.S9S_MB_2U(SCH_1):PAGE24
  EM28 M_E_CPU0_SB_DQ<13> @S9S_MB_2U_LIB.S9S_MB_2U(SCH_1):M_E_CPU0_SB_DQ(13)   I169 @S9S_MB_2U_LIB.S9S_MB_2U(SCH_1):PAGE24
  EL29 M_E_CPU0_SB_DQ<12> @S9S_MB_2U_LIB.S9S_MB_2U(SCH_1):M_E_CPU0_SB_DQ(12)   I169 @S9S_MB_2U_LIB.S9S_MB_2U(SCH_1):PAGE24
  ER31 M_E_CPU0_SB_DQ<11> @S9S_MB_2U_LIB.S9S_MB_2U(SCH_1):M_E_CPU0_SB_DQ(11)   I169 @S9S_MB_2U_LIB.S9S_MB_2U(SCH_1):PAGE24
  EP32 M_E_CPU0_SB_DQ<10> @S9S_MB_2U_LIB.S9S_MB_2U(SCH_1):M_E_CPU0_SB_DQ(10)   I169 @S9S_MB_2U_LIB.S9S_MB_2U(SCH_1):PAGE24
  EL31 M_E_CPU0_SB_DQ<9> @S9S_MB_2U_LIB.S9S_MB_2U(SCH_1):M_E_CPU0_SB_DQ(9)   I169 @S9S_MB_2U_LIB.S9S_MB_2U(SCH_1):PAGE24
  EM32 M_E_CPU0_SB_DQ<8> @S9S_MB_2U_LIB.S9S_MB_2U(SCH_1):M_E_CPU0_SB_DQ(8)   I169 @S9S_MB_2U_LIB.S9S_MB_2U(SCH_1):PAGE24
  EG25 M_E_CPU0_SB_DQ<7> @S9S_MB_2U_LIB.S9S_MB_2U(SCH_1):M_E_CPU0_SB_DQ(7)   I169 @S9S_MB_2U_LIB.S9S_MB_2U(SCH_1):PAGE24
  EH26 M_E_CPU0_SB_DQ<6> @S9S_MB_2U_LIB.S9S_MB_2U(SCH_1):M_E_CPU0_SB_DQ(6)   I169 @S9S_MB_2U_LIB.S9S_MB_2U(SCH_1):PAGE24
  EE25 M_E_CPU0_SB_DQ<5> @S9S_MB_2U_LIB.S9S_MB_2U(SCH_1):M_E_CPU0_SB_DQ(5)   I169 @S9S_MB_2U_LIB.S9S_MB_2U(SCH_1):PAGE24
  ED26 M_E_CPU0_SB_DQ<4> @S9S_MB_2U_LIB.S9S_MB_2U(SCH_1):M_E_CPU0_SB_DQ(4)   I169 @S9S_MB_2U_LIB.S9S_MB_2U(SCH_1):PAGE24
  EH28 M_E_CPU0_SB_DQ<3> @S9S_MB_2U_LIB.S9S_MB_2U(SCH_1):M_E_CPU0_SB_DQ(3)   I169 @S9S_MB_2U_LIB.S9S_MB_2U(SCH_1):PAGE24
  EG29 M_E_CPU0_SB_DQ<2> @S9S_MB_2U_LIB.S9S_MB_2U(SCH_1):M_E_CPU0_SB_DQ(2)   I169 @S9S_MB_2U_LIB.S9S_MB_2U(SCH_1):PAGE24
  ED28 M_E_CPU0_SB_DQ<1> @S9S_MB_2U_LIB.S9S_MB_2U(SCH_1):M_E_CPU0_SB_DQ(1)   I169 @S9S_MB_2U_LIB.S9S_MB_2U(SCH_1):PAGE24
  EE29 M_E_CPU0_SB_DQ<0> @S9S_MB_2U_LIB.S9S_MB_2U(SCH_1):M_E_CPU0_SB_DQ(0)   I169 @S9S_MB_2U_LIB.S9S_MB_2U(SCH_1):PAGE24
  EK36 M_E_CPU0_SB_DQS_DN<9> @S9S_MB_2U_LIB.S9S_MB_2U(SCH_1):M_E_CPU0_SB_DQS_DN(9)   I169 @S9S_MB_2U_LIB.S9S_MB_2U(SCH_1):PAGE24
  ET18 M_E_CPU0_SB_DQS_DN<8> @S9S_MB_2U_LIB.S9S_MB_2U(SCH_1):M_E_CPU0_SB_DQS_DN(8)   I169 @S9S_MB_2U_LIB.S9S_MB_2U(SCH_1):PAGE24
  ET24 M_E_CPU0_SB_DQS_DN<7> @S9S_MB_2U_LIB.S9S_MB_2U(SCH_1):M_E_CPU0_SB_DQS_DN(7)   I169 @S9S_MB_2U_LIB.S9S_MB_2U(SCH_1):PAGE24
  ET30 M_E_CPU0_SB_DQS_DN<6> @S9S_MB_2U_LIB.S9S_MB_2U(SCH_1):M_E_CPU0_SB_DQS_DN(6)   I169 @S9S_MB_2U_LIB.S9S_MB_2U(SCH_1):PAGE24
  EJ27 M_E_CPU0_SB_DQS_DN<5> @S9S_MB_2U_LIB.S9S_MB_2U(SCH_1):M_E_CPU0_SB_DQS_DN(5)   I169 @S9S_MB_2U_LIB.S9S_MB_2U(SCH_1):PAGE24
  ET36 M_E_CPU0_SB_DQS_DN<4> @S9S_MB_2U_LIB.S9S_MB_2U(SCH_1):M_E_CPU0_SB_DQS_DN(4)   I169 @S9S_MB_2U_LIB.S9S_MB_2U(SCH_1):PAGE24
  EK18 M_E_CPU0_SB_DQS_DN<3> @S9S_MB_2U_LIB.S9S_MB_2U(SCH_1):M_E_CPU0_SB_DQS_DN(3)   I169 @S9S_MB_2U_LIB.S9S_MB_2U(SCH_1):PAGE24
  EK24 M_E_CPU0_SB_DQS_DN<2> @S9S_MB_2U_LIB.S9S_MB_2U(SCH_1):M_E_CPU0_SB_DQS_DN(2)   I169 @S9S_MB_2U_LIB.S9S_MB_2U(SCH_1):PAGE24
  EK30 M_E_CPU0_SB_DQS_DN<1> @S9S_MB_2U_LIB.S9S_MB_2U(SCH_1):M_E_CPU0_SB_DQS_DN(1)   I169 @S9S_MB_2U_LIB.S9S_MB_2U(SCH_1):PAGE24
  EE27 M_E_CPU0_SB_DQS_DN<0> @S9S_MB_2U_LIB.S9S_MB_2U(SCH_1):M_E_CPU0_SB_DQS_DN(0)   I169 @S9S_MB_2U_LIB.S9S_MB_2U(SCH_1):PAGE24
  EM36 M_E_CPU0_SB_DQS_DP<9> @S9S_MB_2U_LIB.S9S_MB_2U(SCH_1):M_E_CPU0_SB_DQS_DP(9)   I169 @S9S_MB_2U_LIB.S9S_MB_2U(SCH_1):PAGE24
  EP18 M_E_CPU0_SB_DQS_DP<8> @S9S_MB_2U_LIB.S9S_MB_2U(SCH_1):M_E_CPU0_SB_DQS_DP(8)   I169 @S9S_MB_2U_LIB.S9S_MB_2U(SCH_1):PAGE24
  EP24 M_E_CPU0_SB_DQS_DP<7> @S9S_MB_2U_LIB.S9S_MB_2U(SCH_1):M_E_CPU0_SB_DQS_DP(7)   I169 @S9S_MB_2U_LIB.S9S_MB_2U(SCH_1):PAGE24
  EP30 M_E_CPU0_SB_DQS_DP<6> @S9S_MB_2U_LIB.S9S_MB_2U(SCH_1):M_E_CPU0_SB_DQS_DP(6)   I169 @S9S_MB_2U_LIB.S9S_MB_2U(SCH_1):PAGE24
  EG27 M_E_CPU0_SB_DQS_DP<5> @S9S_MB_2U_LIB.S9S_MB_2U(SCH_1):M_E_CPU0_SB_DQS_DP(5)   I169 @S9S_MB_2U_LIB.S9S_MB_2U(SCH_1):PAGE24
  EP36 M_E_CPU0_SB_DQS_DP<4> @S9S_MB_2U_LIB.S9S_MB_2U(SCH_1):M_E_CPU0_SB_DQS_DP(4)   I169 @S9S_MB_2U_LIB.S9S_MB_2U(SCH_1):PAGE24
  EM18 M_E_CPU0_SB_DQS_DP<3> @S9S_MB_2U_LIB.S9S_MB_2U(SCH_1):M_E_CPU0_SB_DQS_DP(3)   I169 @S9S_MB_2U_LIB.S9S_MB_2U(SCH_1):PAGE24
  EM24 M_E_CPU0_SB_DQS_DP<2> @S9S_MB_2U_LIB.S9S_MB_2U(SCH_1):M_E_CPU0_SB_DQS_DP(2)   I169 @S9S_MB_2U_LIB.S9S_MB_2U(SCH_1):PAGE24
  EM30 M_E_CPU0_SB_DQS_DP<1> @S9S_MB_2U_LIB.S9S_MB_2U(SCH_1):M_E_CPU0_SB_DQS_DP(1)   I169 @S9S_MB_2U_LIB.S9S_MB_2U(SCH_1):PAGE24
  EC27 M_E_CPU0_SB_DQS_DP<0> @S9S_MB_2U_LIB.S9S_MB_2U(SCH_1):M_E_CPU0_SB_DQS_DP(0)   I169 @S9S_MB_2U_LIB.S9S_MB_2U(SCH_1):PAGE24
  ER37 M_E_CPU0_SB_CB<7> @S9S_MB_2U_LIB.S9S_MB_2U(SCH_1):M_E_CPU0_SB_CB(7)   I169 @S9S_MB_2U_LIB.S9S_MB_2U(SCH_1):PAGE24
  EP38 M_E_CPU0_SB_CB<6> @S9S_MB_2U_LIB.S9S_MB_2U(SCH_1):M_E_CPU0_SB_CB(6)   I169 @S9S_MB_2U_LIB.S9S_MB_2U(SCH_1):PAGE24
  EL37 M_E_CPU0_SB_CB<5> @S9S_MB_2U_LIB.S9S_MB_2U(SCH_1):M_E_CPU0_SB_CB(5)   I169 @S9S_MB_2U_LIB.S9S_MB_2U(SCH_1):PAGE24
  EM38 M_E_CPU0_SB_CB<4> @S9S_MB_2U_LIB.S9S_MB_2U(SCH_1):M_E_CPU0_SB_CB(4)   I169 @S9S_MB_2U_LIB.S9S_MB_2U(SCH_1):PAGE24
  EP34 M_E_CPU0_SB_CB<3> @S9S_MB_2U_LIB.S9S_MB_2U(SCH_1):M_E_CPU0_SB_CB(3)   I169 @S9S_MB_2U_LIB.S9S_MB_2U(SCH_1):PAGE24
  ER35 M_E_CPU0_SB_CB<2> @S9S_MB_2U_LIB.S9S_MB_2U(SCH_1):M_E_CPU0_SB_CB(2)   I169 @S9S_MB_2U_LIB.S9S_MB_2U(SCH_1):PAGE24
  EM34 M_E_CPU0_SB_CB<1> @S9S_MB_2U_LIB.S9S_MB_2U(SCH_1):M_E_CPU0_SB_CB(1)   I169 @S9S_MB_2U_LIB.S9S_MB_2U(SCH_1):PAGE24
  EL35 M_E_CPU0_SB_CB<0> @S9S_MB_2U_LIB.S9S_MB_2U(SCH_1):M_E_CPU0_SB_CB(0)   I169 @S9S_MB_2U_LIB.S9S_MB_2U(SCH_1):PAGE24
  EP42 M_E_CPU0_SB_PAR @S9S_MB_2U_LIB.S9S_MB_2U(SCH_1):M_E_CPU0_SB_PAR   I169 @S9S_MB_2U_LIB.S9S_MB_2U(SCH_1):PAGE24
  CW48 M_F_CPU0_ALERT_N @S9S_MB_2U_LIB.S9S_MB_2U(SCH_1):M_F_CPU0_ALERT_N   I169 @S9S_MB_2U_LIB.S9S_MB_2U(SCH_1):PAGE25
  DP47 M_F_CPU0_SA_RSP<1> @S9S_MB_2U_LIB.S9S_MB_2U(SCH_1):M_F_CPU0_SA_RSP(1)   I169 @S9S_MB_2U_LIB.S9S_MB_2U(SCH_1):PAGE25
  DN48 M_F_CPU0_SA_RSP<0> @S9S_MB_2U_LIB.S9S_MB_2U(SCH_1):M_F_CPU0_SA_RSP(0)   I169 @S9S_MB_2U_LIB.S9S_MB_2U(SCH_1):PAGE25
  DK47 M_F_CPU0_SB_RSP<1> @S9S_MB_2U_LIB.S9S_MB_2U(SCH_1):M_F_CPU0_SB_RSP(1)   I169 @S9S_MB_2U_LIB.S9S_MB_2U(SCH_1):PAGE25
  DL48 M_F_CPU0_SB_RSP<0> @S9S_MB_2U_LIB.S9S_MB_2U(SCH_1):M_F_CPU0_SB_RSP(0)   I169 @S9S_MB_2U_LIB.S9S_MB_2U(SCH_1):PAGE25
  DV49 M_F_CPU0_CLK_DN<1> @S9S_MB_2U_LIB.S9S_MB_2U(SCH_1):M_F_CPU0_CLK_DN(1)   I169 @S9S_MB_2U_LIB.S9S_MB_2U(SCH_1):PAGE25
  DY49 M_F_CPU0_CLK_DN<0> @S9S_MB_2U_LIB.S9S_MB_2U(SCH_1):M_F_CPU0_CLK_DN(0)   I169 @S9S_MB_2U_LIB.S9S_MB_2U(SCH_1):PAGE25
  DT49 M_F_CPU0_CLK_DP<1> @S9S_MB_2U_LIB.S9S_MB_2U(SCH_1):M_F_CPU0_CLK_DP(1)   I169 @S9S_MB_2U_LIB.S9S_MB_2U(SCH_1):PAGE25
  EB49 M_F_CPU0_CLK_DP<0> @S9S_MB_2U_LIB.S9S_MB_2U(SCH_1):M_F_CPU0_CLK_DP(0)   I169 @S9S_MB_2U_LIB.S9S_MB_2U(SCH_1):PAGE25
  DY51 M_F_CPU0_SA_CA<6> @S9S_MB_2U_LIB.S9S_MB_2U(SCH_1):M_F_CPU0_SA_CA(6)   I169 @S9S_MB_2U_LIB.S9S_MB_2U(SCH_1):PAGE25
  EG50 M_F_CPU0_SA_CA<5> @S9S_MB_2U_LIB.S9S_MB_2U(SCH_1):M_F_CPU0_SA_CA(5)   I169 @S9S_MB_2U_LIB.S9S_MB_2U(SCH_1):PAGE25
  EE50 M_F_CPU0_SA_CA<4> @S9S_MB_2U_LIB.S9S_MB_2U(SCH_1):M_F_CPU0_SA_CA(4)   I169 @S9S_MB_2U_LIB.S9S_MB_2U(SCH_1):PAGE25
  EH51 M_F_CPU0_SA_CA<3> @S9S_MB_2U_LIB.S9S_MB_2U(SCH_1):M_F_CPU0_SA_CA(3)   I169 @S9S_MB_2U_LIB.S9S_MB_2U(SCH_1):PAGE25
  ED51 M_F_CPU0_SA_CA<2> @S9S_MB_2U_LIB.S9S_MB_2U(SCH_1):M_F_CPU0_SA_CA(2)   I169 @S9S_MB_2U_LIB.S9S_MB_2U(SCH_1):PAGE25
  EJ52 M_F_CPU0_SA_CA<1> @S9S_MB_2U_LIB.S9S_MB_2U(SCH_1):M_F_CPU0_SA_CA(1)   I169 @S9S_MB_2U_LIB.S9S_MB_2U(SCH_1):PAGE25
  EC52 M_F_CPU0_SA_CA<0> @S9S_MB_2U_LIB.S9S_MB_2U(SCH_1):M_F_CPU0_SA_CA(0)   I169 @S9S_MB_2U_LIB.S9S_MB_2U(SCH_1):PAGE25
  ED53 M_F_CPU0_SA_CS_N<3> @S9S_MB_2U_LIB.S9S_MB_2U(SCH_1):M_F_CPU0_SA_CS_N(3)   I169 @S9S_MB_2U_LIB.S9S_MB_2U(SCH_1):PAGE25
  EE54 M_F_CPU0_SA_CS_N<2> @S9S_MB_2U_LIB.S9S_MB_2U(SCH_1):M_F_CPU0_SA_CS_N(2)   I169 @S9S_MB_2U_LIB.S9S_MB_2U(SCH_1):PAGE25
  EH53 M_F_CPU0_SA_CS_N<1> @S9S_MB_2U_LIB.S9S_MB_2U(SCH_1):M_F_CPU0_SA_CS_N(1)   I169 @S9S_MB_2U_LIB.S9S_MB_2U(SCH_1):PAGE25
  EG54 M_F_CPU0_SA_CS_N<0> @S9S_MB_2U_LIB.S9S_MB_2U(SCH_1):M_F_CPU0_SA_CS_N(0)   I169 @S9S_MB_2U_LIB.S9S_MB_2U(SCH_1):PAGE25
  DY53 M_F_CPU0_SA_DQ<31> @S9S_MB_2U_LIB.S9S_MB_2U(SCH_1):M_F_CPU0_SA_DQ(31)   I169 @S9S_MB_2U_LIB.S9S_MB_2U(SCH_1):PAGE25
  EA54 M_F_CPU0_SA_DQ<30> @S9S_MB_2U_LIB.S9S_MB_2U(SCH_1):M_F_CPU0_SA_DQ(30)   I169 @S9S_MB_2U_LIB.S9S_MB_2U(SCH_1):PAGE25
  DV53 M_F_CPU0_SA_DQ<29> @S9S_MB_2U_LIB.S9S_MB_2U(SCH_1):M_F_CPU0_SA_DQ(29)   I169 @S9S_MB_2U_LIB.S9S_MB_2U(SCH_1):PAGE25
  DU54 M_F_CPU0_SA_DQ<28> @S9S_MB_2U_LIB.S9S_MB_2U(SCH_1):M_F_CPU0_SA_DQ(28)   I169 @S9S_MB_2U_LIB.S9S_MB_2U(SCH_1):PAGE25
  EA56 M_F_CPU0_SA_DQ<27> @S9S_MB_2U_LIB.S9S_MB_2U(SCH_1):M_F_CPU0_SA_DQ(27)   I169 @S9S_MB_2U_LIB.S9S_MB_2U(SCH_1):PAGE25
  DY57 M_F_CPU0_SA_DQ<26> @S9S_MB_2U_LIB.S9S_MB_2U(SCH_1):M_F_CPU0_SA_DQ(26)   I169 @S9S_MB_2U_LIB.S9S_MB_2U(SCH_1):PAGE25
  DU56 M_F_CPU0_SA_DQ<25> @S9S_MB_2U_LIB.S9S_MB_2U(SCH_1):M_F_CPU0_SA_DQ(25)   I169 @S9S_MB_2U_LIB.S9S_MB_2U(SCH_1):PAGE25
  DV57 M_F_CPU0_SA_DQ<24> @S9S_MB_2U_LIB.S9S_MB_2U(SCH_1):M_F_CPU0_SA_DQ(24)   I169 @S9S_MB_2U_LIB.S9S_MB_2U(SCH_1):PAGE25
  EG62 M_F_CPU0_SA_DQ<23> @S9S_MB_2U_LIB.S9S_MB_2U(SCH_1):M_F_CPU0_SA_DQ(23)   I169 @S9S_MB_2U_LIB.S9S_MB_2U(SCH_1):PAGE25
  EH63 M_F_CPU0_SA_DQ<22> @S9S_MB_2U_LIB.S9S_MB_2U(SCH_1):M_F_CPU0_SA_DQ(22)   I169 @S9S_MB_2U_LIB.S9S_MB_2U(SCH_1):PAGE25
  EE62 M_F_CPU0_SA_DQ<21> @S9S_MB_2U_LIB.S9S_MB_2U(SCH_1):M_F_CPU0_SA_DQ(21)   I169 @S9S_MB_2U_LIB.S9S_MB_2U(SCH_1):PAGE25
  ED63 M_F_CPU0_SA_DQ<20> @S9S_MB_2U_LIB.S9S_MB_2U(SCH_1):M_F_CPU0_SA_DQ(20)   I169 @S9S_MB_2U_LIB.S9S_MB_2U(SCH_1):PAGE25
  EH65 M_F_CPU0_SA_DQ<19> @S9S_MB_2U_LIB.S9S_MB_2U(SCH_1):M_F_CPU0_SA_DQ(19)   I169 @S9S_MB_2U_LIB.S9S_MB_2U(SCH_1):PAGE25
  EG66 M_F_CPU0_SA_DQ<18> @S9S_MB_2U_LIB.S9S_MB_2U(SCH_1):M_F_CPU0_SA_DQ(18)   I169 @S9S_MB_2U_LIB.S9S_MB_2U(SCH_1):PAGE25
  ED65 M_F_CPU0_SA_DQ<17> @S9S_MB_2U_LIB.S9S_MB_2U(SCH_1):M_F_CPU0_SA_DQ(17)   I169 @S9S_MB_2U_LIB.S9S_MB_2U(SCH_1):PAGE25
  EE66 M_F_CPU0_SA_DQ<16> @S9S_MB_2U_LIB.S9S_MB_2U(SCH_1):M_F_CPU0_SA_DQ(16)   I169 @S9S_MB_2U_LIB.S9S_MB_2U(SCH_1):PAGE25
  DY65 M_F_CPU0_SA_DQ<15> @S9S_MB_2U_LIB.S9S_MB_2U(SCH_1):M_F_CPU0_SA_DQ(15)   I169 @S9S_MB_2U_LIB.S9S_MB_2U(SCH_1):PAGE25
  EA66 M_F_CPU0_SA_DQ<14> @S9S_MB_2U_LIB.S9S_MB_2U(SCH_1):M_F_CPU0_SA_DQ(14)   I169 @S9S_MB_2U_LIB.S9S_MB_2U(SCH_1):PAGE25
  DV65 M_F_CPU0_SA_DQ<13> @S9S_MB_2U_LIB.S9S_MB_2U(SCH_1):M_F_CPU0_SA_DQ(13)   I169 @S9S_MB_2U_LIB.S9S_MB_2U(SCH_1):PAGE25
  DU66 M_F_CPU0_SA_DQ<12> @S9S_MB_2U_LIB.S9S_MB_2U(SCH_1):M_F_CPU0_SA_DQ(12)   I169 @S9S_MB_2U_LIB.S9S_MB_2U(SCH_1):PAGE25
  EA68 M_F_CPU0_SA_DQ<11> @S9S_MB_2U_LIB.S9S_MB_2U(SCH_1):M_F_CPU0_SA_DQ(11)   I169 @S9S_MB_2U_LIB.S9S_MB_2U(SCH_1):PAGE25
  DY69 M_F_CPU0_SA_DQ<10> @S9S_MB_2U_LIB.S9S_MB_2U(SCH_1):M_F_CPU0_SA_DQ(10)   I169 @S9S_MB_2U_LIB.S9S_MB_2U(SCH_1):PAGE25
  DU68 M_F_CPU0_SA_DQ<9> @S9S_MB_2U_LIB.S9S_MB_2U(SCH_1):M_F_CPU0_SA_DQ(9)   I169 @S9S_MB_2U_LIB.S9S_MB_2U(SCH_1):PAGE25
  DV69 M_F_CPU0_SA_DQ<8> @S9S_MB_2U_LIB.S9S_MB_2U(SCH_1):M_F_CPU0_SA_DQ(8)   I169 @S9S_MB_2U_LIB.S9S_MB_2U(SCH_1):PAGE25
  EG74 M_F_CPU0_SA_DQ<7> @S9S_MB_2U_LIB.S9S_MB_2U(SCH_1):M_F_CPU0_SA_DQ(7)   I169 @S9S_MB_2U_LIB.S9S_MB_2U(SCH_1):PAGE25
  EH75 M_F_CPU0_SA_DQ<6> @S9S_MB_2U_LIB.S9S_MB_2U(SCH_1):M_F_CPU0_SA_DQ(6)   I169 @S9S_MB_2U_LIB.S9S_MB_2U(SCH_1):PAGE25
  EE74 M_F_CPU0_SA_DQ<5> @S9S_MB_2U_LIB.S9S_MB_2U(SCH_1):M_F_CPU0_SA_DQ(5)   I169 @S9S_MB_2U_LIB.S9S_MB_2U(SCH_1):PAGE25
  ED75 M_F_CPU0_SA_DQ<4> @S9S_MB_2U_LIB.S9S_MB_2U(SCH_1):M_F_CPU0_SA_DQ(4)   I169 @S9S_MB_2U_LIB.S9S_MB_2U(SCH_1):PAGE25
  EG78 M_F_CPU0_SA_DQ<3> @S9S_MB_2U_LIB.S9S_MB_2U(SCH_1):M_F_CPU0_SA_DQ(3)   I169 @S9S_MB_2U_LIB.S9S_MB_2U(SCH_1):PAGE25
  ED77 M_F_CPU0_SA_DQ<2> @S9S_MB_2U_LIB.S9S_MB_2U(SCH_1):M_F_CPU0_SA_DQ(2)   I169 @S9S_MB_2U_LIB.S9S_MB_2U(SCH_1):PAGE25
  EH77 M_F_CPU0_SA_DQ<1> @S9S_MB_2U_LIB.S9S_MB_2U(SCH_1):M_F_CPU0_SA_DQ(1)   I169 @S9S_MB_2U_LIB.S9S_MB_2U(SCH_1):PAGE25
  EB77 M_F_CPU0_SA_DQ<0> @S9S_MB_2U_LIB.S9S_MB_2U(SCH_1):M_F_CPU0_SA_DQ(0)   I169 @S9S_MB_2U_LIB.S9S_MB_2U(SCH_1):PAGE25
  EJ58 M_F_CPU0_SA_DQS_DN<9> @S9S_MB_2U_LIB.S9S_MB_2U(SCH_1):M_F_CPU0_SA_DQS_DN(9)   I169 @S9S_MB_2U_LIB.S9S_MB_2U(SCH_1):PAGE25
  EB55 M_F_CPU0_SA_DQS_DN<8> @S9S_MB_2U_LIB.S9S_MB_2U(SCH_1):M_F_CPU0_SA_DQS_DN(8)   I169 @S9S_MB_2U_LIB.S9S_MB_2U(SCH_1):PAGE25
  EJ64 M_F_CPU0_SA_DQS_DN<7> @S9S_MB_2U_LIB.S9S_MB_2U(SCH_1):M_F_CPU0_SA_DQS_DN(7)   I169 @S9S_MB_2U_LIB.S9S_MB_2U(SCH_1):PAGE25
  EB67 M_F_CPU0_SA_DQS_DN<6> @S9S_MB_2U_LIB.S9S_MB_2U(SCH_1):M_F_CPU0_SA_DQS_DN(6)   I169 @S9S_MB_2U_LIB.S9S_MB_2U(SCH_1):PAGE25
  EJ76 M_F_CPU0_SA_DQS_DN<5> @S9S_MB_2U_LIB.S9S_MB_2U(SCH_1):M_F_CPU0_SA_DQS_DN(5)   I169 @S9S_MB_2U_LIB.S9S_MB_2U(SCH_1):PAGE25
  EE58 M_F_CPU0_SA_DQS_DN<4> @S9S_MB_2U_LIB.S9S_MB_2U(SCH_1):M_F_CPU0_SA_DQS_DN(4)   I169 @S9S_MB_2U_LIB.S9S_MB_2U(SCH_1):PAGE25
  DV55 M_F_CPU0_SA_DQS_DN<3> @S9S_MB_2U_LIB.S9S_MB_2U(SCH_1):M_F_CPU0_SA_DQS_DN(3)   I169 @S9S_MB_2U_LIB.S9S_MB_2U(SCH_1):PAGE25
  EC64 M_F_CPU0_SA_DQS_DN<2> @S9S_MB_2U_LIB.S9S_MB_2U(SCH_1):M_F_CPU0_SA_DQS_DN(2)   I169 @S9S_MB_2U_LIB.S9S_MB_2U(SCH_1):PAGE25
  DT67 M_F_CPU0_SA_DQS_DN<1> @S9S_MB_2U_LIB.S9S_MB_2U(SCH_1):M_F_CPU0_SA_DQS_DN(1)   I169 @S9S_MB_2U_LIB.S9S_MB_2U(SCH_1):PAGE25
  EE76 M_F_CPU0_SA_DQS_DN<0> @S9S_MB_2U_LIB.S9S_MB_2U(SCH_1):M_F_CPU0_SA_DQS_DN(0)   I169 @S9S_MB_2U_LIB.S9S_MB_2U(SCH_1):PAGE25
  EG58 M_F_CPU0_SA_DQS_DP<9> @S9S_MB_2U_LIB.S9S_MB_2U(SCH_1):M_F_CPU0_SA_DQS_DP(9)   I169 @S9S_MB_2U_LIB.S9S_MB_2U(SCH_1):PAGE25
  DY55 M_F_CPU0_SA_DQS_DP<8> @S9S_MB_2U_LIB.S9S_MB_2U(SCH_1):M_F_CPU0_SA_DQS_DP(8)   I169 @S9S_MB_2U_LIB.S9S_MB_2U(SCH_1):PAGE25
  EG64 M_F_CPU0_SA_DQS_DP<7> @S9S_MB_2U_LIB.S9S_MB_2U(SCH_1):M_F_CPU0_SA_DQS_DP(7)   I169 @S9S_MB_2U_LIB.S9S_MB_2U(SCH_1):PAGE25
  DY67 M_F_CPU0_SA_DQS_DP<6> @S9S_MB_2U_LIB.S9S_MB_2U(SCH_1):M_F_CPU0_SA_DQS_DP(6)   I169 @S9S_MB_2U_LIB.S9S_MB_2U(SCH_1):PAGE25
  EG76 M_F_CPU0_SA_DQS_DP<5> @S9S_MB_2U_LIB.S9S_MB_2U(SCH_1):M_F_CPU0_SA_DQS_DP(5)   I169 @S9S_MB_2U_LIB.S9S_MB_2U(SCH_1):PAGE25
  EC58 M_F_CPU0_SA_DQS_DP<4> @S9S_MB_2U_LIB.S9S_MB_2U(SCH_1):M_F_CPU0_SA_DQS_DP(4)   I169 @S9S_MB_2U_LIB.S9S_MB_2U(SCH_1):PAGE25
  DT55 M_F_CPU0_SA_DQS_DP<3> @S9S_MB_2U_LIB.S9S_MB_2U(SCH_1):M_F_CPU0_SA_DQS_DP(3)   I169 @S9S_MB_2U_LIB.S9S_MB_2U(SCH_1):PAGE25
  EE64 M_F_CPU0_SA_DQS_DP<2> @S9S_MB_2U_LIB.S9S_MB_2U(SCH_1):M_F_CPU0_SA_DQS_DP(2)   I169 @S9S_MB_2U_LIB.S9S_MB_2U(SCH_1):PAGE25
  DV67 M_F_CPU0_SA_DQS_DP<1> @S9S_MB_2U_LIB.S9S_MB_2U(SCH_1):M_F_CPU0_SA_DQS_DP(1)   I169 @S9S_MB_2U_LIB.S9S_MB_2U(SCH_1):PAGE25
  EC76 M_F_CPU0_SA_DQS_DP<0> @S9S_MB_2U_LIB.S9S_MB_2U(SCH_1):M_F_CPU0_SA_DQS_DP(0)   I169 @S9S_MB_2U_LIB.S9S_MB_2U(SCH_1):PAGE25
  EG56 M_F_CPU0_SA_CB<7> @S9S_MB_2U_LIB.S9S_MB_2U(SCH_1):M_F_CPU0_SA_CB(7)   I169 @S9S_MB_2U_LIB.S9S_MB_2U(SCH_1):PAGE25
  EH57 M_F_CPU0_SA_CB<6> @S9S_MB_2U_LIB.S9S_MB_2U(SCH_1):M_F_CPU0_SA_CB(6)   I169 @S9S_MB_2U_LIB.S9S_MB_2U(SCH_1):PAGE25
  EE56 M_F_CPU0_SA_CB<5> @S9S_MB_2U_LIB.S9S_MB_2U(SCH_1):M_F_CPU0_SA_CB(5)   I169 @S9S_MB_2U_LIB.S9S_MB_2U(SCH_1):PAGE25
  ED57 M_F_CPU0_SA_CB<4> @S9S_MB_2U_LIB.S9S_MB_2U(SCH_1):M_F_CPU0_SA_CB(4)   I169 @S9S_MB_2U_LIB.S9S_MB_2U(SCH_1):PAGE25
  EH59 M_F_CPU0_SA_CB<3> @S9S_MB_2U_LIB.S9S_MB_2U(SCH_1):M_F_CPU0_SA_CB(3)   I169 @S9S_MB_2U_LIB.S9S_MB_2U(SCH_1):PAGE25
  EG60 M_F_CPU0_SA_CB<2> @S9S_MB_2U_LIB.S9S_MB_2U(SCH_1):M_F_CPU0_SA_CB(2)   I169 @S9S_MB_2U_LIB.S9S_MB_2U(SCH_1):PAGE25
  ED59 M_F_CPU0_SA_CB<1> @S9S_MB_2U_LIB.S9S_MB_2U(SCH_1):M_F_CPU0_SA_CB(1)   I169 @S9S_MB_2U_LIB.S9S_MB_2U(SCH_1):PAGE25
  EE60 M_F_CPU0_SA_CB<0> @S9S_MB_2U_LIB.S9S_MB_2U(SCH_1):M_F_CPU0_SA_CB(0)   I169 @S9S_MB_2U_LIB.S9S_MB_2U(SCH_1):PAGE25
  EA50 M_F_CPU0_SA_PAR @S9S_MB_2U_LIB.S9S_MB_2U(SCH_1):M_F_CPU0_SA_PAR   I169 @S9S_MB_2U_LIB.S9S_MB_2U(SCH_1):PAGE25
  EC39 M_F_CPU0_SB_CA<6> @S9S_MB_2U_LIB.S9S_MB_2U(SCH_1):M_F_CPU0_SB_CA(6)   I169 @S9S_MB_2U_LIB.S9S_MB_2U(SCH_1):PAGE25
  EH40 M_F_CPU0_SB_CA<5> @S9S_MB_2U_LIB.S9S_MB_2U(SCH_1):M_F_CPU0_SB_CA(5)   I169 @S9S_MB_2U_LIB.S9S_MB_2U(SCH_1):PAGE25
  ED40 M_F_CPU0_SB_CA<4> @S9S_MB_2U_LIB.S9S_MB_2U(SCH_1):M_F_CPU0_SB_CA(4)   I169 @S9S_MB_2U_LIB.S9S_MB_2U(SCH_1):PAGE25
  EG41 M_F_CPU0_SB_CA<3> @S9S_MB_2U_LIB.S9S_MB_2U(SCH_1):M_F_CPU0_SB_CA(3)   I169 @S9S_MB_2U_LIB.S9S_MB_2U(SCH_1):PAGE25
  EE41 M_F_CPU0_SB_CA<2> @S9S_MB_2U_LIB.S9S_MB_2U(SCH_1):M_F_CPU0_SB_CA(2)   I169 @S9S_MB_2U_LIB.S9S_MB_2U(SCH_1):PAGE25
  DU50 M_F_CPU0_SB_CA<1> @S9S_MB_2U_LIB.S9S_MB_2U(SCH_1):M_F_CPU0_SB_CA(1)   I169 @S9S_MB_2U_LIB.S9S_MB_2U(SCH_1):PAGE25
  DV51 M_F_CPU0_SB_CA<0> @S9S_MB_2U_LIB.S9S_MB_2U(SCH_1):M_F_CPU0_SB_CA(0)   I169 @S9S_MB_2U_LIB.S9S_MB_2U(SCH_1):PAGE25
  EE37 M_F_CPU0_SB_CS_N<3> @S9S_MB_2U_LIB.S9S_MB_2U(SCH_1):M_F_CPU0_SB_CS_N(3)   I169 @S9S_MB_2U_LIB.S9S_MB_2U(SCH_1):PAGE25
  ED38 M_F_CPU0_SB_CS_N<2> @S9S_MB_2U_LIB.S9S_MB_2U(SCH_1):M_F_CPU0_SB_CS_N(2)   I169 @S9S_MB_2U_LIB.S9S_MB_2U(SCH_1):PAGE25
  EG37 M_F_CPU0_SB_CS_N<1> @S9S_MB_2U_LIB.S9S_MB_2U(SCH_1):M_F_CPU0_SB_CS_N(1)   I169 @S9S_MB_2U_LIB.S9S_MB_2U(SCH_1):PAGE25
  EH38 M_F_CPU0_SB_CS_N<0> @S9S_MB_2U_LIB.S9S_MB_2U(SCH_1):M_F_CPU0_SB_CS_N(0)   I169 @S9S_MB_2U_LIB.S9S_MB_2U(SCH_1):PAGE25
  DR17 M_F_CPU0_SB_DQ<31> @S9S_MB_2U_LIB.S9S_MB_2U(SCH_1):M_F_CPU0_SB_DQ(31)   I169 @S9S_MB_2U_LIB.S9S_MB_2U(SCH_1):PAGE25
  EC17 M_F_CPU0_SB_DQ<30> @S9S_MB_2U_LIB.S9S_MB_2U(SCH_1):M_F_CPU0_SB_DQ(30)   I169 @S9S_MB_2U_LIB.S9S_MB_2U(SCH_1):PAGE25
  DU17 M_F_CPU0_SB_DQ<29> @S9S_MB_2U_LIB.S9S_MB_2U(SCH_1):M_F_CPU0_SB_DQ(29)   I169 @S9S_MB_2U_LIB.S9S_MB_2U(SCH_1):PAGE25
  EA17 M_F_CPU0_SB_DQ<28> @S9S_MB_2U_LIB.S9S_MB_2U(SCH_1):M_F_CPU0_SB_DQ(28)   I169 @S9S_MB_2U_LIB.S9S_MB_2U(SCH_1):PAGE25
  EA19 M_F_CPU0_SB_DQ<27> @S9S_MB_2U_LIB.S9S_MB_2U(SCH_1):M_F_CPU0_SB_DQ(27)   I169 @S9S_MB_2U_LIB.S9S_MB_2U(SCH_1):PAGE25
  DY20 M_F_CPU0_SB_DQ<26> @S9S_MB_2U_LIB.S9S_MB_2U(SCH_1):M_F_CPU0_SB_DQ(26)   I169 @S9S_MB_2U_LIB.S9S_MB_2U(SCH_1):PAGE25
  DU19 M_F_CPU0_SB_DQ<25> @S9S_MB_2U_LIB.S9S_MB_2U(SCH_1):M_F_CPU0_SB_DQ(25)   I169 @S9S_MB_2U_LIB.S9S_MB_2U(SCH_1):PAGE25
  DV20 M_F_CPU0_SB_DQ<24> @S9S_MB_2U_LIB.S9S_MB_2U(SCH_1):M_F_CPU0_SB_DQ(24)   I169 @S9S_MB_2U_LIB.S9S_MB_2U(SCH_1):PAGE25
  EP10 M_F_CPU0_SB_DQ<23> @S9S_MB_2U_LIB.S9S_MB_2U(SCH_1):M_F_CPU0_SB_DQ(23)   I169 @S9S_MB_2U_LIB.S9S_MB_2U(SCH_1):PAGE25
  ER11 M_F_CPU0_SB_DQ<22> @S9S_MB_2U_LIB.S9S_MB_2U(SCH_1):M_F_CPU0_SB_DQ(22)   I169 @S9S_MB_2U_LIB.S9S_MB_2U(SCH_1):PAGE25
  EM10 M_F_CPU0_SB_DQ<21> @S9S_MB_2U_LIB.S9S_MB_2U(SCH_1):M_F_CPU0_SB_DQ(21)   I169 @S9S_MB_2U_LIB.S9S_MB_2U(SCH_1):PAGE25
  EL11 M_F_CPU0_SB_DQ<20> @S9S_MB_2U_LIB.S9S_MB_2U(SCH_1):M_F_CPU0_SB_DQ(20)   I169 @S9S_MB_2U_LIB.S9S_MB_2U(SCH_1):PAGE25
  ER13 M_F_CPU0_SB_DQ<19> @S9S_MB_2U_LIB.S9S_MB_2U(SCH_1):M_F_CPU0_SB_DQ(19)   I169 @S9S_MB_2U_LIB.S9S_MB_2U(SCH_1):PAGE25
  EP14 M_F_CPU0_SB_DQ<18> @S9S_MB_2U_LIB.S9S_MB_2U(SCH_1):M_F_CPU0_SB_DQ(18)   I169 @S9S_MB_2U_LIB.S9S_MB_2U(SCH_1):PAGE25
  EL13 M_F_CPU0_SB_DQ<17> @S9S_MB_2U_LIB.S9S_MB_2U(SCH_1):M_F_CPU0_SB_DQ(17)   I169 @S9S_MB_2U_LIB.S9S_MB_2U(SCH_1):PAGE25
  EM14 M_F_CPU0_SB_DQ<16> @S9S_MB_2U_LIB.S9S_MB_2U(SCH_1):M_F_CPU0_SB_DQ(16)   I169 @S9S_MB_2U_LIB.S9S_MB_2U(SCH_1):PAGE25
  EG19 M_F_CPU0_SB_DQ<15> @S9S_MB_2U_LIB.S9S_MB_2U(SCH_1):M_F_CPU0_SB_DQ(15)   I169 @S9S_MB_2U_LIB.S9S_MB_2U(SCH_1):PAGE25
  EH20 M_F_CPU0_SB_DQ<14> @S9S_MB_2U_LIB.S9S_MB_2U(SCH_1):M_F_CPU0_SB_DQ(14)   I169 @S9S_MB_2U_LIB.S9S_MB_2U(SCH_1):PAGE25
  EE19 M_F_CPU0_SB_DQ<13> @S9S_MB_2U_LIB.S9S_MB_2U(SCH_1):M_F_CPU0_SB_DQ(13)   I169 @S9S_MB_2U_LIB.S9S_MB_2U(SCH_1):PAGE25
  ED20 M_F_CPU0_SB_DQ<12> @S9S_MB_2U_LIB.S9S_MB_2U(SCH_1):M_F_CPU0_SB_DQ(12)   I169 @S9S_MB_2U_LIB.S9S_MB_2U(SCH_1):PAGE25
  EH22 M_F_CPU0_SB_DQ<11> @S9S_MB_2U_LIB.S9S_MB_2U(SCH_1):M_F_CPU0_SB_DQ(11)   I169 @S9S_MB_2U_LIB.S9S_MB_2U(SCH_1):PAGE25
  EG23 M_F_CPU0_SB_DQ<10> @S9S_MB_2U_LIB.S9S_MB_2U(SCH_1):M_F_CPU0_SB_DQ(10)   I169 @S9S_MB_2U_LIB.S9S_MB_2U(SCH_1):PAGE25
  ED22 M_F_CPU0_SB_DQ<9> @S9S_MB_2U_LIB.S9S_MB_2U(SCH_1):M_F_CPU0_SB_DQ(9)   I169 @S9S_MB_2U_LIB.S9S_MB_2U(SCH_1):PAGE25
  EE23 M_F_CPU0_SB_DQ<8> @S9S_MB_2U_LIB.S9S_MB_2U(SCH_1):M_F_CPU0_SB_DQ(8)   I169 @S9S_MB_2U_LIB.S9S_MB_2U(SCH_1):PAGE25
  DY28 M_F_CPU0_SB_DQ<7> @S9S_MB_2U_LIB.S9S_MB_2U(SCH_1):M_F_CPU0_SB_DQ(7)   I169 @S9S_MB_2U_LIB.S9S_MB_2U(SCH_1):PAGE25
  EA29 M_F_CPU0_SB_DQ<6> @S9S_MB_2U_LIB.S9S_MB_2U(SCH_1):M_F_CPU0_SB_DQ(6)   I169 @S9S_MB_2U_LIB.S9S_MB_2U(SCH_1):PAGE25
  DV28 M_F_CPU0_SB_DQ<5> @S9S_MB_2U_LIB.S9S_MB_2U(SCH_1):M_F_CPU0_SB_DQ(5)   I169 @S9S_MB_2U_LIB.S9S_MB_2U(SCH_1):PAGE25
  DU29 M_F_CPU0_SB_DQ<4> @S9S_MB_2U_LIB.S9S_MB_2U(SCH_1):M_F_CPU0_SB_DQ(4)   I169 @S9S_MB_2U_LIB.S9S_MB_2U(SCH_1):PAGE25
  EA31 M_F_CPU0_SB_DQ<3> @S9S_MB_2U_LIB.S9S_MB_2U(SCH_1):M_F_CPU0_SB_DQ(3)   I169 @S9S_MB_2U_LIB.S9S_MB_2U(SCH_1):PAGE25
  DY32 M_F_CPU0_SB_DQ<2> @S9S_MB_2U_LIB.S9S_MB_2U(SCH_1):M_F_CPU0_SB_DQ(2)   I169 @S9S_MB_2U_LIB.S9S_MB_2U(SCH_1):PAGE25
  DU31 M_F_CPU0_SB_DQ<1> @S9S_MB_2U_LIB.S9S_MB_2U(SCH_1):M_F_CPU0_SB_DQ(1)   I169 @S9S_MB_2U_LIB.S9S_MB_2U(SCH_1):PAGE25
  DV32 M_F_CPU0_SB_DQ<0> @S9S_MB_2U_LIB.S9S_MB_2U(SCH_1):M_F_CPU0_SB_DQ(0)   I169 @S9S_MB_2U_LIB.S9S_MB_2U(SCH_1):PAGE25
  EE33 M_F_CPU0_SB_DQS_DN<9> @S9S_MB_2U_LIB.S9S_MB_2U(SCH_1):M_F_CPU0_SB_DQS_DN(9)   I169 @S9S_MB_2U_LIB.S9S_MB_2U(SCH_1):PAGE25
  DY18 M_F_CPU0_SB_DQS_DN<8> @S9S_MB_2U_LIB.S9S_MB_2U(SCH_1):M_F_CPU0_SB_DQS_DN(8)   I169 @S9S_MB_2U_LIB.S9S_MB_2U(SCH_1):PAGE25
  ET12 M_F_CPU0_SB_DQS_DN<7> @S9S_MB_2U_LIB.S9S_MB_2U(SCH_1):M_F_CPU0_SB_DQS_DN(7)   I169 @S9S_MB_2U_LIB.S9S_MB_2U(SCH_1):PAGE25
  EJ21 M_F_CPU0_SB_DQS_DN<6> @S9S_MB_2U_LIB.S9S_MB_2U(SCH_1):M_F_CPU0_SB_DQS_DN(6)   I169 @S9S_MB_2U_LIB.S9S_MB_2U(SCH_1):PAGE25
  EB30 M_F_CPU0_SB_DQS_DN<5> @S9S_MB_2U_LIB.S9S_MB_2U(SCH_1):M_F_CPU0_SB_DQS_DN(5)   I169 @S9S_MB_2U_LIB.S9S_MB_2U(SCH_1):PAGE25
  EJ33 M_F_CPU0_SB_DQS_DN<4> @S9S_MB_2U_LIB.S9S_MB_2U(SCH_1):M_F_CPU0_SB_DQS_DN(4)   I169 @S9S_MB_2U_LIB.S9S_MB_2U(SCH_1):PAGE25
  DT18 M_F_CPU0_SB_DQS_DN<3> @S9S_MB_2U_LIB.S9S_MB_2U(SCH_1):M_F_CPU0_SB_DQS_DN(3)   I169 @S9S_MB_2U_LIB.S9S_MB_2U(SCH_1):PAGE25
  EM12 M_F_CPU0_SB_DQS_DN<2> @S9S_MB_2U_LIB.S9S_MB_2U(SCH_1):M_F_CPU0_SB_DQS_DN(2)   I169 @S9S_MB_2U_LIB.S9S_MB_2U(SCH_1):PAGE25
  EE21 M_F_CPU0_SB_DQS_DN<1> @S9S_MB_2U_LIB.S9S_MB_2U(SCH_1):M_F_CPU0_SB_DQS_DN(1)   I169 @S9S_MB_2U_LIB.S9S_MB_2U(SCH_1):PAGE25
  DV30 M_F_CPU0_SB_DQS_DN<0> @S9S_MB_2U_LIB.S9S_MB_2U(SCH_1):M_F_CPU0_SB_DQS_DN(0)   I169 @S9S_MB_2U_LIB.S9S_MB_2U(SCH_1):PAGE25
  EC33 M_F_CPU0_SB_DQS_DP<9> @S9S_MB_2U_LIB.S9S_MB_2U(SCH_1):M_F_CPU0_SB_DQS_DP(9)   I169 @S9S_MB_2U_LIB.S9S_MB_2U(SCH_1):PAGE25
  EB18 M_F_CPU0_SB_DQS_DP<8> @S9S_MB_2U_LIB.S9S_MB_2U(SCH_1):M_F_CPU0_SB_DQS_DP(8)   I169 @S9S_MB_2U_LIB.S9S_MB_2U(SCH_1):PAGE25
  EP12 M_F_CPU0_SB_DQS_DP<7> @S9S_MB_2U_LIB.S9S_MB_2U(SCH_1):M_F_CPU0_SB_DQS_DP(7)   I169 @S9S_MB_2U_LIB.S9S_MB_2U(SCH_1):PAGE25
  EG21 M_F_CPU0_SB_DQS_DP<6> @S9S_MB_2U_LIB.S9S_MB_2U(SCH_1):M_F_CPU0_SB_DQS_DP(6)   I169 @S9S_MB_2U_LIB.S9S_MB_2U(SCH_1):PAGE25
  DY30 M_F_CPU0_SB_DQS_DP<5> @S9S_MB_2U_LIB.S9S_MB_2U(SCH_1):M_F_CPU0_SB_DQS_DP(5)   I169 @S9S_MB_2U_LIB.S9S_MB_2U(SCH_1):PAGE25
  EG33 M_F_CPU0_SB_DQS_DP<4> @S9S_MB_2U_LIB.S9S_MB_2U(SCH_1):M_F_CPU0_SB_DQS_DP(4)   I169 @S9S_MB_2U_LIB.S9S_MB_2U(SCH_1):PAGE25
  DV18 M_F_CPU0_SB_DQS_DP<3> @S9S_MB_2U_LIB.S9S_MB_2U(SCH_1):M_F_CPU0_SB_DQS_DP(3)   I169 @S9S_MB_2U_LIB.S9S_MB_2U(SCH_1):PAGE25
  EK12 M_F_CPU0_SB_DQS_DP<2> @S9S_MB_2U_LIB.S9S_MB_2U(SCH_1):M_F_CPU0_SB_DQS_DP(2)   I169 @S9S_MB_2U_LIB.S9S_MB_2U(SCH_1):PAGE25
  EC21 M_F_CPU0_SB_DQS_DP<1> @S9S_MB_2U_LIB.S9S_MB_2U(SCH_1):M_F_CPU0_SB_DQS_DP(1)   I169 @S9S_MB_2U_LIB.S9S_MB_2U(SCH_1):PAGE25
  DT30 M_F_CPU0_SB_DQS_DP<0> @S9S_MB_2U_LIB.S9S_MB_2U(SCH_1):M_F_CPU0_SB_DQS_DP(0)   I169 @S9S_MB_2U_LIB.S9S_MB_2U(SCH_1):PAGE25
  EH34 M_F_CPU0_SB_CB<7> @S9S_MB_2U_LIB.S9S_MB_2U(SCH_1):M_F_CPU0_SB_CB(7)   I169 @S9S_MB_2U_LIB.S9S_MB_2U(SCH_1):PAGE25
  EG35 M_F_CPU0_SB_CB<6> @S9S_MB_2U_LIB.S9S_MB_2U(SCH_1):M_F_CPU0_SB_CB(6)   I169 @S9S_MB_2U_LIB.S9S_MB_2U(SCH_1):PAGE25
  ED34 M_F_CPU0_SB_CB<5> @S9S_MB_2U_LIB.S9S_MB_2U(SCH_1):M_F_CPU0_SB_CB(5)   I169 @S9S_MB_2U_LIB.S9S_MB_2U(SCH_1):PAGE25
  EE35 M_F_CPU0_SB_CB<4> @S9S_MB_2U_LIB.S9S_MB_2U(SCH_1):M_F_CPU0_SB_CB(4)   I169 @S9S_MB_2U_LIB.S9S_MB_2U(SCH_1):PAGE25
  EG31 M_F_CPU0_SB_CB<3> @S9S_MB_2U_LIB.S9S_MB_2U(SCH_1):M_F_CPU0_SB_CB(3)   I169 @S9S_MB_2U_LIB.S9S_MB_2U(SCH_1):PAGE25
  EH32 M_F_CPU0_SB_CB<2> @S9S_MB_2U_LIB.S9S_MB_2U(SCH_1):M_F_CPU0_SB_CB(2)   I169 @S9S_MB_2U_LIB.S9S_MB_2U(SCH_1):PAGE25
  EE31 M_F_CPU0_SB_CB<1> @S9S_MB_2U_LIB.S9S_MB_2U(SCH_1):M_F_CPU0_SB_CB(1)   I169 @S9S_MB_2U_LIB.S9S_MB_2U(SCH_1):PAGE25
  ED32 M_F_CPU0_SB_CB<0> @S9S_MB_2U_LIB.S9S_MB_2U(SCH_1):M_F_CPU0_SB_CB(0)   I169 @S9S_MB_2U_LIB.S9S_MB_2U(SCH_1):PAGE25
  EJ39 M_F_CPU0_SB_PAR @S9S_MB_2U_LIB.S9S_MB_2U(SCH_1):M_F_CPU0_SB_PAR   I169 @S9S_MB_2U_LIB.S9S_MB_2U(SCH_1):PAGE25
  CW50 M_G_CPU0_ALERT_N @S9S_MB_2U_LIB.S9S_MB_2U(SCH_1):M_G_CPU0_ALERT_N   I169 @S9S_MB_2U_LIB.S9S_MB_2U(SCH_1):PAGE26
  DY47 M_G_CPU0_SA_RSP<1> @S9S_MB_2U_LIB.S9S_MB_2U(SCH_1):M_G_CPU0_SA_RSP(1)   I169 @S9S_MB_2U_LIB.S9S_MB_2U(SCH_1):PAGE26
  EA48 M_G_CPU0_SA_RSP<0> @S9S_MB_2U_LIB.S9S_MB_2U(SCH_1):M_G_CPU0_SA_RSP(0)   I169 @S9S_MB_2U_LIB.S9S_MB_2U(SCH_1):PAGE26
  DV47 M_G_CPU0_SB_RSP<1> @S9S_MB_2U_LIB.S9S_MB_2U(SCH_1):M_G_CPU0_SB_RSP(1)   I169 @S9S_MB_2U_LIB.S9S_MB_2U(SCH_1):PAGE26
  DU48 M_G_CPU0_SB_RSP<0> @S9S_MB_2U_LIB.S9S_MB_2U(SCH_1):M_G_CPU0_SB_RSP(0)   I169 @S9S_MB_2U_LIB.S9S_MB_2U(SCH_1):PAGE26
  DL45 M_G_CPU0_CLK_DN<1> @S9S_MB_2U_LIB.S9S_MB_2U(SCH_1):M_G_CPU0_CLK_DN(1)   I169 @S9S_MB_2U_LIB.S9S_MB_2U(SCH_1):PAGE26
  DR45 M_G_CPU0_CLK_DN<0> @S9S_MB_2U_LIB.S9S_MB_2U(SCH_1):M_G_CPU0_CLK_DN(0)   I169 @S9S_MB_2U_LIB.S9S_MB_2U(SCH_1):PAGE26
  DJ45 M_G_CPU0_CLK_DP<1> @S9S_MB_2U_LIB.S9S_MB_2U(SCH_1):M_G_CPU0_CLK_DP(1)   I169 @S9S_MB_2U_LIB.S9S_MB_2U(SCH_1):PAGE26
  DN45 M_G_CPU0_CLK_DP<0> @S9S_MB_2U_LIB.S9S_MB_2U(SCH_1):M_G_CPU0_CLK_DP(0)   I169 @S9S_MB_2U_LIB.S9S_MB_2U(SCH_1):PAGE26
  DK44 M_G_CPU0_SA_CA<6> @S9S_MB_2U_LIB.S9S_MB_2U(SCH_1):M_G_CPU0_SA_CA(6)   I169 @S9S_MB_2U_LIB.S9S_MB_2U(SCH_1):PAGE26
  DN50 M_G_CPU0_SA_CA<5> @S9S_MB_2U_LIB.S9S_MB_2U(SCH_1):M_G_CPU0_SA_CA(5)   I169 @S9S_MB_2U_LIB.S9S_MB_2U(SCH_1):PAGE26
  DL50 M_G_CPU0_SA_CA<4> @S9S_MB_2U_LIB.S9S_MB_2U(SCH_1):M_G_CPU0_SA_CA(4)   I169 @S9S_MB_2U_LIB.S9S_MB_2U(SCH_1):PAGE26
  DP51 M_G_CPU0_SA_CA<3> @S9S_MB_2U_LIB.S9S_MB_2U(SCH_1):M_G_CPU0_SA_CA(3)   I169 @S9S_MB_2U_LIB.S9S_MB_2U(SCH_1):PAGE26
  DK51 M_G_CPU0_SA_CA<2> @S9S_MB_2U_LIB.S9S_MB_2U(SCH_1):M_G_CPU0_SA_CA(2)   I169 @S9S_MB_2U_LIB.S9S_MB_2U(SCH_1):PAGE26
  DR52 M_G_CPU0_SA_CA<1> @S9S_MB_2U_LIB.S9S_MB_2U(SCH_1):M_G_CPU0_SA_CA(1)   I169 @S9S_MB_2U_LIB.S9S_MB_2U(SCH_1):PAGE26
  DJ52 M_G_CPU0_SA_CA<0> @S9S_MB_2U_LIB.S9S_MB_2U(SCH_1):M_G_CPU0_SA_CA(0)   I169 @S9S_MB_2U_LIB.S9S_MB_2U(SCH_1):PAGE26
  DK53 M_G_CPU0_SA_CS_N<3> @S9S_MB_2U_LIB.S9S_MB_2U(SCH_1):M_G_CPU0_SA_CS_N(3)   I169 @S9S_MB_2U_LIB.S9S_MB_2U(SCH_1):PAGE26
  DL54 M_G_CPU0_SA_CS_N<2> @S9S_MB_2U_LIB.S9S_MB_2U(SCH_1):M_G_CPU0_SA_CS_N(2)   I169 @S9S_MB_2U_LIB.S9S_MB_2U(SCH_1):PAGE26
  DP53 M_G_CPU0_SA_CS_N<1> @S9S_MB_2U_LIB.S9S_MB_2U(SCH_1):M_G_CPU0_SA_CS_N(1)   I169 @S9S_MB_2U_LIB.S9S_MB_2U(SCH_1):PAGE26
  DN54 M_G_CPU0_SA_CS_N<0> @S9S_MB_2U_LIB.S9S_MB_2U(SCH_1):M_G_CPU0_SA_CS_N(0)   I169 @S9S_MB_2U_LIB.S9S_MB_2U(SCH_1):PAGE26
  DN62 M_G_CPU0_SA_DQ<31> @S9S_MB_2U_LIB.S9S_MB_2U(SCH_1):M_G_CPU0_SA_DQ(31)   I169 @S9S_MB_2U_LIB.S9S_MB_2U(SCH_1):PAGE26
  DP63 M_G_CPU0_SA_DQ<30> @S9S_MB_2U_LIB.S9S_MB_2U(SCH_1):M_G_CPU0_SA_DQ(30)   I169 @S9S_MB_2U_LIB.S9S_MB_2U(SCH_1):PAGE26
  DL62 M_G_CPU0_SA_DQ<29> @S9S_MB_2U_LIB.S9S_MB_2U(SCH_1):M_G_CPU0_SA_DQ(29)   I169 @S9S_MB_2U_LIB.S9S_MB_2U(SCH_1):PAGE26
  DK63 M_G_CPU0_SA_DQ<28> @S9S_MB_2U_LIB.S9S_MB_2U(SCH_1):M_G_CPU0_SA_DQ(28)   I169 @S9S_MB_2U_LIB.S9S_MB_2U(SCH_1):PAGE26
  DP65 M_G_CPU0_SA_DQ<27> @S9S_MB_2U_LIB.S9S_MB_2U(SCH_1):M_G_CPU0_SA_DQ(27)   I169 @S9S_MB_2U_LIB.S9S_MB_2U(SCH_1):PAGE26
  DN66 M_G_CPU0_SA_DQ<26> @S9S_MB_2U_LIB.S9S_MB_2U(SCH_1):M_G_CPU0_SA_DQ(26)   I169 @S9S_MB_2U_LIB.S9S_MB_2U(SCH_1):PAGE26
  DK65 M_G_CPU0_SA_DQ<25> @S9S_MB_2U_LIB.S9S_MB_2U(SCH_1):M_G_CPU0_SA_DQ(25)   I169 @S9S_MB_2U_LIB.S9S_MB_2U(SCH_1):PAGE26
  DL66 M_G_CPU0_SA_DQ<24> @S9S_MB_2U_LIB.S9S_MB_2U(SCH_1):M_G_CPU0_SA_DQ(24)   I169 @S9S_MB_2U_LIB.S9S_MB_2U(SCH_1):PAGE26
  DY59 M_G_CPU0_SA_DQ<23> @S9S_MB_2U_LIB.S9S_MB_2U(SCH_1):M_G_CPU0_SA_DQ(23)   I169 @S9S_MB_2U_LIB.S9S_MB_2U(SCH_1):PAGE26
  EA60 M_G_CPU0_SA_DQ<22> @S9S_MB_2U_LIB.S9S_MB_2U(SCH_1):M_G_CPU0_SA_DQ(22)   I169 @S9S_MB_2U_LIB.S9S_MB_2U(SCH_1):PAGE26
  DV59 M_G_CPU0_SA_DQ<21> @S9S_MB_2U_LIB.S9S_MB_2U(SCH_1):M_G_CPU0_SA_DQ(21)   I169 @S9S_MB_2U_LIB.S9S_MB_2U(SCH_1):PAGE26
  DU60 M_G_CPU0_SA_DQ<20> @S9S_MB_2U_LIB.S9S_MB_2U(SCH_1):M_G_CPU0_SA_DQ(20)   I169 @S9S_MB_2U_LIB.S9S_MB_2U(SCH_1):PAGE26
  EA62 M_G_CPU0_SA_DQ<19> @S9S_MB_2U_LIB.S9S_MB_2U(SCH_1):M_G_CPU0_SA_DQ(19)   I169 @S9S_MB_2U_LIB.S9S_MB_2U(SCH_1):PAGE26
  DY63 M_G_CPU0_SA_DQ<18> @S9S_MB_2U_LIB.S9S_MB_2U(SCH_1):M_G_CPU0_SA_DQ(18)   I169 @S9S_MB_2U_LIB.S9S_MB_2U(SCH_1):PAGE26
  DU62 M_G_CPU0_SA_DQ<17> @S9S_MB_2U_LIB.S9S_MB_2U(SCH_1):M_G_CPU0_SA_DQ(17)   I169 @S9S_MB_2U_LIB.S9S_MB_2U(SCH_1):PAGE26
  DV63 M_G_CPU0_SA_DQ<16> @S9S_MB_2U_LIB.S9S_MB_2U(SCH_1):M_G_CPU0_SA_DQ(16)   I169 @S9S_MB_2U_LIB.S9S_MB_2U(SCH_1):PAGE26
  DN68 M_G_CPU0_SA_DQ<15> @S9S_MB_2U_LIB.S9S_MB_2U(SCH_1):M_G_CPU0_SA_DQ(15)   I169 @S9S_MB_2U_LIB.S9S_MB_2U(SCH_1):PAGE26
  DP69 M_G_CPU0_SA_DQ<14> @S9S_MB_2U_LIB.S9S_MB_2U(SCH_1):M_G_CPU0_SA_DQ(14)   I169 @S9S_MB_2U_LIB.S9S_MB_2U(SCH_1):PAGE26
  DL68 M_G_CPU0_SA_DQ<13> @S9S_MB_2U_LIB.S9S_MB_2U(SCH_1):M_G_CPU0_SA_DQ(13)   I169 @S9S_MB_2U_LIB.S9S_MB_2U(SCH_1):PAGE26
  DK69 M_G_CPU0_SA_DQ<12> @S9S_MB_2U_LIB.S9S_MB_2U(SCH_1):M_G_CPU0_SA_DQ(12)   I169 @S9S_MB_2U_LIB.S9S_MB_2U(SCH_1):PAGE26
  DP71 M_G_CPU0_SA_DQ<11> @S9S_MB_2U_LIB.S9S_MB_2U(SCH_1):M_G_CPU0_SA_DQ(11)   I169 @S9S_MB_2U_LIB.S9S_MB_2U(SCH_1):PAGE26
  DN72 M_G_CPU0_SA_DQ<10> @S9S_MB_2U_LIB.S9S_MB_2U(SCH_1):M_G_CPU0_SA_DQ(10)   I169 @S9S_MB_2U_LIB.S9S_MB_2U(SCH_1):PAGE26
  DK71 M_G_CPU0_SA_DQ<9> @S9S_MB_2U_LIB.S9S_MB_2U(SCH_1):M_G_CPU0_SA_DQ(9)   I169 @S9S_MB_2U_LIB.S9S_MB_2U(SCH_1):PAGE26
  DL72 M_G_CPU0_SA_DQ<8> @S9S_MB_2U_LIB.S9S_MB_2U(SCH_1):M_G_CPU0_SA_DQ(8)   I169 @S9S_MB_2U_LIB.S9S_MB_2U(SCH_1):PAGE26
  DY71 M_G_CPU0_SA_DQ<7> @S9S_MB_2U_LIB.S9S_MB_2U(SCH_1):M_G_CPU0_SA_DQ(7)   I169 @S9S_MB_2U_LIB.S9S_MB_2U(SCH_1):PAGE26
  EA72 M_G_CPU0_SA_DQ<6> @S9S_MB_2U_LIB.S9S_MB_2U(SCH_1):M_G_CPU0_SA_DQ(6)   I169 @S9S_MB_2U_LIB.S9S_MB_2U(SCH_1):PAGE26
  DV71 M_G_CPU0_SA_DQ<5> @S9S_MB_2U_LIB.S9S_MB_2U(SCH_1):M_G_CPU0_SA_DQ(5)   I169 @S9S_MB_2U_LIB.S9S_MB_2U(SCH_1):PAGE26
  DU72 M_G_CPU0_SA_DQ<4> @S9S_MB_2U_LIB.S9S_MB_2U(SCH_1):M_G_CPU0_SA_DQ(4)   I169 @S9S_MB_2U_LIB.S9S_MB_2U(SCH_1):PAGE26
  EA74 M_G_CPU0_SA_DQ<3> @S9S_MB_2U_LIB.S9S_MB_2U(SCH_1):M_G_CPU0_SA_DQ(3)   I169 @S9S_MB_2U_LIB.S9S_MB_2U(SCH_1):PAGE26
  DY75 M_G_CPU0_SA_DQ<2> @S9S_MB_2U_LIB.S9S_MB_2U(SCH_1):M_G_CPU0_SA_DQ(2)   I169 @S9S_MB_2U_LIB.S9S_MB_2U(SCH_1):PAGE26
  DU74 M_G_CPU0_SA_DQ<1> @S9S_MB_2U_LIB.S9S_MB_2U(SCH_1):M_G_CPU0_SA_DQ(1)   I169 @S9S_MB_2U_LIB.S9S_MB_2U(SCH_1):PAGE26
  DV75 M_G_CPU0_SA_DQ<0> @S9S_MB_2U_LIB.S9S_MB_2U(SCH_1):M_G_CPU0_SA_DQ(0)   I169 @S9S_MB_2U_LIB.S9S_MB_2U(SCH_1):PAGE26
  DR58 M_G_CPU0_SA_DQS_DN<9> @S9S_MB_2U_LIB.S9S_MB_2U(SCH_1):M_G_CPU0_SA_DQS_DN(9)   I169 @S9S_MB_2U_LIB.S9S_MB_2U(SCH_1):PAGE26
  DR64 M_G_CPU0_SA_DQS_DN<8> @S9S_MB_2U_LIB.S9S_MB_2U(SCH_1):M_G_CPU0_SA_DQS_DN(8)   I169 @S9S_MB_2U_LIB.S9S_MB_2U(SCH_1):PAGE26
  EB61 M_G_CPU0_SA_DQS_DN<7> @S9S_MB_2U_LIB.S9S_MB_2U(SCH_1):M_G_CPU0_SA_DQS_DN(7)   I169 @S9S_MB_2U_LIB.S9S_MB_2U(SCH_1):PAGE26
  DR70 M_G_CPU0_SA_DQS_DN<6> @S9S_MB_2U_LIB.S9S_MB_2U(SCH_1):M_G_CPU0_SA_DQS_DN(6)   I169 @S9S_MB_2U_LIB.S9S_MB_2U(SCH_1):PAGE26
  EB73 M_G_CPU0_SA_DQS_DN<5> @S9S_MB_2U_LIB.S9S_MB_2U(SCH_1):M_G_CPU0_SA_DQS_DN(5)   I169 @S9S_MB_2U_LIB.S9S_MB_2U(SCH_1):PAGE26
  DL58 M_G_CPU0_SA_DQS_DN<4> @S9S_MB_2U_LIB.S9S_MB_2U(SCH_1):M_G_CPU0_SA_DQS_DN(4)   I169 @S9S_MB_2U_LIB.S9S_MB_2U(SCH_1):PAGE26
  DL64 M_G_CPU0_SA_DQS_DN<3> @S9S_MB_2U_LIB.S9S_MB_2U(SCH_1):M_G_CPU0_SA_DQS_DN(3)   I169 @S9S_MB_2U_LIB.S9S_MB_2U(SCH_1):PAGE26
  DT61 M_G_CPU0_SA_DQS_DN<2> @S9S_MB_2U_LIB.S9S_MB_2U(SCH_1):M_G_CPU0_SA_DQS_DN(2)   I169 @S9S_MB_2U_LIB.S9S_MB_2U(SCH_1):PAGE26
  DJ70 M_G_CPU0_SA_DQS_DN<1> @S9S_MB_2U_LIB.S9S_MB_2U(SCH_1):M_G_CPU0_SA_DQS_DN(1)   I169 @S9S_MB_2U_LIB.S9S_MB_2U(SCH_1):PAGE26
  DV73 M_G_CPU0_SA_DQS_DN<0> @S9S_MB_2U_LIB.S9S_MB_2U(SCH_1):M_G_CPU0_SA_DQS_DN(0)   I169 @S9S_MB_2U_LIB.S9S_MB_2U(SCH_1):PAGE26
  DN58 M_G_CPU0_SA_DQS_DP<9> @S9S_MB_2U_LIB.S9S_MB_2U(SCH_1):M_G_CPU0_SA_DQS_DP(9)   I169 @S9S_MB_2U_LIB.S9S_MB_2U(SCH_1):PAGE26
  DN64 M_G_CPU0_SA_DQS_DP<8> @S9S_MB_2U_LIB.S9S_MB_2U(SCH_1):M_G_CPU0_SA_DQS_DP(8)   I169 @S9S_MB_2U_LIB.S9S_MB_2U(SCH_1):PAGE26
  DY61 M_G_CPU0_SA_DQS_DP<7> @S9S_MB_2U_LIB.S9S_MB_2U(SCH_1):M_G_CPU0_SA_DQS_DP(7)   I169 @S9S_MB_2U_LIB.S9S_MB_2U(SCH_1):PAGE26
  DN70 M_G_CPU0_SA_DQS_DP<6> @S9S_MB_2U_LIB.S9S_MB_2U(SCH_1):M_G_CPU0_SA_DQS_DP(6)   I169 @S9S_MB_2U_LIB.S9S_MB_2U(SCH_1):PAGE26
  DY73 M_G_CPU0_SA_DQS_DP<5> @S9S_MB_2U_LIB.S9S_MB_2U(SCH_1):M_G_CPU0_SA_DQS_DP(5)   I169 @S9S_MB_2U_LIB.S9S_MB_2U(SCH_1):PAGE26
  DJ58 M_G_CPU0_SA_DQS_DP<4> @S9S_MB_2U_LIB.S9S_MB_2U(SCH_1):M_G_CPU0_SA_DQS_DP(4)   I169 @S9S_MB_2U_LIB.S9S_MB_2U(SCH_1):PAGE26
  DJ64 M_G_CPU0_SA_DQS_DP<3> @S9S_MB_2U_LIB.S9S_MB_2U(SCH_1):M_G_CPU0_SA_DQS_DP(3)   I169 @S9S_MB_2U_LIB.S9S_MB_2U(SCH_1):PAGE26
  DV61 M_G_CPU0_SA_DQS_DP<2> @S9S_MB_2U_LIB.S9S_MB_2U(SCH_1):M_G_CPU0_SA_DQS_DP(2)   I169 @S9S_MB_2U_LIB.S9S_MB_2U(SCH_1):PAGE26
  DL70 M_G_CPU0_SA_DQS_DP<1> @S9S_MB_2U_LIB.S9S_MB_2U(SCH_1):M_G_CPU0_SA_DQS_DP(1)   I169 @S9S_MB_2U_LIB.S9S_MB_2U(SCH_1):PAGE26
  DT73 M_G_CPU0_SA_DQS_DP<0> @S9S_MB_2U_LIB.S9S_MB_2U(SCH_1):M_G_CPU0_SA_DQS_DP(0)   I169 @S9S_MB_2U_LIB.S9S_MB_2U(SCH_1):PAGE26
  DN56 M_G_CPU0_SA_CB<7> @S9S_MB_2U_LIB.S9S_MB_2U(SCH_1):M_G_CPU0_SA_CB(7)   I169 @S9S_MB_2U_LIB.S9S_MB_2U(SCH_1):PAGE26
  DP57 M_G_CPU0_SA_CB<6> @S9S_MB_2U_LIB.S9S_MB_2U(SCH_1):M_G_CPU0_SA_CB(6)   I169 @S9S_MB_2U_LIB.S9S_MB_2U(SCH_1):PAGE26
  DL56 M_G_CPU0_SA_CB<5> @S9S_MB_2U_LIB.S9S_MB_2U(SCH_1):M_G_CPU0_SA_CB(5)   I169 @S9S_MB_2U_LIB.S9S_MB_2U(SCH_1):PAGE26
  DK57 M_G_CPU0_SA_CB<4> @S9S_MB_2U_LIB.S9S_MB_2U(SCH_1):M_G_CPU0_SA_CB(4)   I169 @S9S_MB_2U_LIB.S9S_MB_2U(SCH_1):PAGE26
  DP59 M_G_CPU0_SA_CB<3> @S9S_MB_2U_LIB.S9S_MB_2U(SCH_1):M_G_CPU0_SA_CB(3)   I169 @S9S_MB_2U_LIB.S9S_MB_2U(SCH_1):PAGE26
  DN60 M_G_CPU0_SA_CB<2> @S9S_MB_2U_LIB.S9S_MB_2U(SCH_1):M_G_CPU0_SA_CB(2)   I169 @S9S_MB_2U_LIB.S9S_MB_2U(SCH_1):PAGE26
  DK59 M_G_CPU0_SA_CB<1> @S9S_MB_2U_LIB.S9S_MB_2U(SCH_1):M_G_CPU0_SA_CB(1)   I169 @S9S_MB_2U_LIB.S9S_MB_2U(SCH_1):PAGE26
  DL60 M_G_CPU0_SA_CB<0> @S9S_MB_2U_LIB.S9S_MB_2U(SCH_1):M_G_CPU0_SA_CB(0)   I169 @S9S_MB_2U_LIB.S9S_MB_2U(SCH_1):PAGE26
  DL43 M_G_CPU0_SA_PAR @S9S_MB_2U_LIB.S9S_MB_2U(SCH_1):M_G_CPU0_SA_PAR   I169 @S9S_MB_2U_LIB.S9S_MB_2U(SCH_1):PAGE26
  DT42 M_G_CPU0_SB_CA<6> @S9S_MB_2U_LIB.S9S_MB_2U(SCH_1):M_G_CPU0_SB_CA(6)   I169 @S9S_MB_2U_LIB.S9S_MB_2U(SCH_1):PAGE26
  EA43 M_G_CPU0_SB_CA<5> @S9S_MB_2U_LIB.S9S_MB_2U(SCH_1):M_G_CPU0_SB_CA(5)   I169 @S9S_MB_2U_LIB.S9S_MB_2U(SCH_1):PAGE26
  DU43 M_G_CPU0_SB_CA<4> @S9S_MB_2U_LIB.S9S_MB_2U(SCH_1):M_G_CPU0_SB_CA(4)   I169 @S9S_MB_2U_LIB.S9S_MB_2U(SCH_1):PAGE26
  DY44 M_G_CPU0_SB_CA<3> @S9S_MB_2U_LIB.S9S_MB_2U(SCH_1):M_G_CPU0_SB_CA(3)   I169 @S9S_MB_2U_LIB.S9S_MB_2U(SCH_1):PAGE26
  DV44 M_G_CPU0_SB_CA<2> @S9S_MB_2U_LIB.S9S_MB_2U(SCH_1):M_G_CPU0_SB_CA(2)   I169 @S9S_MB_2U_LIB.S9S_MB_2U(SCH_1):PAGE26
  DP44 M_G_CPU0_SB_CA<1> @S9S_MB_2U_LIB.S9S_MB_2U(SCH_1):M_G_CPU0_SB_CA(1)   I169 @S9S_MB_2U_LIB.S9S_MB_2U(SCH_1):PAGE26
  DN43 M_G_CPU0_SB_CA<0> @S9S_MB_2U_LIB.S9S_MB_2U(SCH_1):M_G_CPU0_SB_CA(0)   I169 @S9S_MB_2U_LIB.S9S_MB_2U(SCH_1):PAGE26
  DV40 M_G_CPU0_SB_CS_N<3> @S9S_MB_2U_LIB.S9S_MB_2U(SCH_1):M_G_CPU0_SB_CS_N(3)   I169 @S9S_MB_2U_LIB.S9S_MB_2U(SCH_1):PAGE26
  DU41 M_G_CPU0_SB_CS_N<2> @S9S_MB_2U_LIB.S9S_MB_2U(SCH_1):M_G_CPU0_SB_CS_N(2)   I169 @S9S_MB_2U_LIB.S9S_MB_2U(SCH_1):PAGE26
  DY40 M_G_CPU0_SB_CS_N<1> @S9S_MB_2U_LIB.S9S_MB_2U(SCH_1):M_G_CPU0_SB_CS_N(1)   I169 @S9S_MB_2U_LIB.S9S_MB_2U(SCH_1):PAGE26
  EA41 M_G_CPU0_SB_CS_N<0> @S9S_MB_2U_LIB.S9S_MB_2U(SCH_1):M_G_CPU0_SB_CS_N(0)   I169 @S9S_MB_2U_LIB.S9S_MB_2U(SCH_1):PAGE26
   EM4 M_G_CPU0_SB_DQ<31> @S9S_MB_2U_LIB.S9S_MB_2U(SCH_1):M_G_CPU0_SB_DQ(31)   I169 @S9S_MB_2U_LIB.S9S_MB_2U(SCH_1):PAGE26
   EP4 M_G_CPU0_SB_DQ<30> @S9S_MB_2U_LIB.S9S_MB_2U(SCH_1):M_G_CPU0_SB_DQ(30)   I169 @S9S_MB_2U_LIB.S9S_MB_2U(SCH_1):PAGE26
   EJ5 M_G_CPU0_SB_DQ<29> @S9S_MB_2U_LIB.S9S_MB_2U(SCH_1):M_G_CPU0_SB_DQ(29)   I169 @S9S_MB_2U_LIB.S9S_MB_2U(SCH_1):PAGE26
   EK6 M_G_CPU0_SB_DQ<28> @S9S_MB_2U_LIB.S9S_MB_2U(SCH_1):M_G_CPU0_SB_DQ(28)   I169 @S9S_MB_2U_LIB.S9S_MB_2U(SCH_1):PAGE26
   ET8 M_G_CPU0_SB_DQ<27> @S9S_MB_2U_LIB.S9S_MB_2U(SCH_1):M_G_CPU0_SB_DQ(27)   I169 @S9S_MB_2U_LIB.S9S_MB_2U(SCH_1):PAGE26
   EP8 M_G_CPU0_SB_DQ<26> @S9S_MB_2U_LIB.S9S_MB_2U(SCH_1):M_G_CPU0_SB_DQ(26)   I169 @S9S_MB_2U_LIB.S9S_MB_2U(SCH_1):PAGE26
   EH8 M_G_CPU0_SB_DQ<25> @S9S_MB_2U_LIB.S9S_MB_2U(SCH_1):M_G_CPU0_SB_DQ(25)   I169 @S9S_MB_2U_LIB.S9S_MB_2U(SCH_1):PAGE26
   EK8 M_G_CPU0_SB_DQ<24> @S9S_MB_2U_LIB.S9S_MB_2U(SCH_1):M_G_CPU0_SB_DQ(24)   I169 @S9S_MB_2U_LIB.S9S_MB_2U(SCH_1):PAGE26
  DY22 M_G_CPU0_SB_DQ<23> @S9S_MB_2U_LIB.S9S_MB_2U(SCH_1):M_G_CPU0_SB_DQ(23)   I169 @S9S_MB_2U_LIB.S9S_MB_2U(SCH_1):PAGE26
  EA23 M_G_CPU0_SB_DQ<22> @S9S_MB_2U_LIB.S9S_MB_2U(SCH_1):M_G_CPU0_SB_DQ(22)   I169 @S9S_MB_2U_LIB.S9S_MB_2U(SCH_1):PAGE26
  DV22 M_G_CPU0_SB_DQ<21> @S9S_MB_2U_LIB.S9S_MB_2U(SCH_1):M_G_CPU0_SB_DQ(21)   I169 @S9S_MB_2U_LIB.S9S_MB_2U(SCH_1):PAGE26
  DU23 M_G_CPU0_SB_DQ<20> @S9S_MB_2U_LIB.S9S_MB_2U(SCH_1):M_G_CPU0_SB_DQ(20)   I169 @S9S_MB_2U_LIB.S9S_MB_2U(SCH_1):PAGE26
  EA25 M_G_CPU0_SB_DQ<19> @S9S_MB_2U_LIB.S9S_MB_2U(SCH_1):M_G_CPU0_SB_DQ(19)   I169 @S9S_MB_2U_LIB.S9S_MB_2U(SCH_1):PAGE26
  DY26 M_G_CPU0_SB_DQ<18> @S9S_MB_2U_LIB.S9S_MB_2U(SCH_1):M_G_CPU0_SB_DQ(18)   I169 @S9S_MB_2U_LIB.S9S_MB_2U(SCH_1):PAGE26
  DU25 M_G_CPU0_SB_DQ<17> @S9S_MB_2U_LIB.S9S_MB_2U(SCH_1):M_G_CPU0_SB_DQ(17)   I169 @S9S_MB_2U_LIB.S9S_MB_2U(SCH_1):PAGE26
  DV26 M_G_CPU0_SB_DQ<16> @S9S_MB_2U_LIB.S9S_MB_2U(SCH_1):M_G_CPU0_SB_DQ(16)   I169 @S9S_MB_2U_LIB.S9S_MB_2U(SCH_1):PAGE26
  DN25 M_G_CPU0_SB_DQ<15> @S9S_MB_2U_LIB.S9S_MB_2U(SCH_1):M_G_CPU0_SB_DQ(15)   I169 @S9S_MB_2U_LIB.S9S_MB_2U(SCH_1):PAGE26
  DP26 M_G_CPU0_SB_DQ<14> @S9S_MB_2U_LIB.S9S_MB_2U(SCH_1):M_G_CPU0_SB_DQ(14)   I169 @S9S_MB_2U_LIB.S9S_MB_2U(SCH_1):PAGE26
  DL25 M_G_CPU0_SB_DQ<13> @S9S_MB_2U_LIB.S9S_MB_2U(SCH_1):M_G_CPU0_SB_DQ(13)   I169 @S9S_MB_2U_LIB.S9S_MB_2U(SCH_1):PAGE26
  DK26 M_G_CPU0_SB_DQ<12> @S9S_MB_2U_LIB.S9S_MB_2U(SCH_1):M_G_CPU0_SB_DQ(12)   I169 @S9S_MB_2U_LIB.S9S_MB_2U(SCH_1):PAGE26
  DP28 M_G_CPU0_SB_DQ<11> @S9S_MB_2U_LIB.S9S_MB_2U(SCH_1):M_G_CPU0_SB_DQ(11)   I169 @S9S_MB_2U_LIB.S9S_MB_2U(SCH_1):PAGE26
  DL29 M_G_CPU0_SB_DQ<10> @S9S_MB_2U_LIB.S9S_MB_2U(SCH_1):M_G_CPU0_SB_DQ(10)   I169 @S9S_MB_2U_LIB.S9S_MB_2U(SCH_1):PAGE26
  DK28 M_G_CPU0_SB_DQ<9> @S9S_MB_2U_LIB.S9S_MB_2U(SCH_1):M_G_CPU0_SB_DQ(9)   I169 @S9S_MB_2U_LIB.S9S_MB_2U(SCH_1):PAGE26
  DN29 M_G_CPU0_SB_DQ<8> @S9S_MB_2U_LIB.S9S_MB_2U(SCH_1):M_G_CPU0_SB_DQ(8)   I169 @S9S_MB_2U_LIB.S9S_MB_2U(SCH_1):PAGE26
  DN31 M_G_CPU0_SB_DQ<7> @S9S_MB_2U_LIB.S9S_MB_2U(SCH_1):M_G_CPU0_SB_DQ(7)   I169 @S9S_MB_2U_LIB.S9S_MB_2U(SCH_1):PAGE26
  DP32 M_G_CPU0_SB_DQ<6> @S9S_MB_2U_LIB.S9S_MB_2U(SCH_1):M_G_CPU0_SB_DQ(6)   I169 @S9S_MB_2U_LIB.S9S_MB_2U(SCH_1):PAGE26
  DL31 M_G_CPU0_SB_DQ<5> @S9S_MB_2U_LIB.S9S_MB_2U(SCH_1):M_G_CPU0_SB_DQ(5)   I169 @S9S_MB_2U_LIB.S9S_MB_2U(SCH_1):PAGE26
  DK32 M_G_CPU0_SB_DQ<4> @S9S_MB_2U_LIB.S9S_MB_2U(SCH_1):M_G_CPU0_SB_DQ(4)   I169 @S9S_MB_2U_LIB.S9S_MB_2U(SCH_1):PAGE26
  DP34 M_G_CPU0_SB_DQ<3> @S9S_MB_2U_LIB.S9S_MB_2U(SCH_1):M_G_CPU0_SB_DQ(3)   I169 @S9S_MB_2U_LIB.S9S_MB_2U(SCH_1):PAGE26
  DN35 M_G_CPU0_SB_DQ<2> @S9S_MB_2U_LIB.S9S_MB_2U(SCH_1):M_G_CPU0_SB_DQ(2)   I169 @S9S_MB_2U_LIB.S9S_MB_2U(SCH_1):PAGE26
  DK34 M_G_CPU0_SB_DQ<1> @S9S_MB_2U_LIB.S9S_MB_2U(SCH_1):M_G_CPU0_SB_DQ(1)   I169 @S9S_MB_2U_LIB.S9S_MB_2U(SCH_1):PAGE26
  DL35 M_G_CPU0_SB_DQ<0> @S9S_MB_2U_LIB.S9S_MB_2U(SCH_1):M_G_CPU0_SB_DQ(0)   I169 @S9S_MB_2U_LIB.S9S_MB_2U(SCH_1):PAGE26
  DV36 M_G_CPU0_SB_DQS_DN<9> @S9S_MB_2U_LIB.S9S_MB_2U(SCH_1):M_G_CPU0_SB_DQS_DN(9)   I169 @S9S_MB_2U_LIB.S9S_MB_2U(SCH_1):PAGE26
   EM6 M_G_CPU0_SB_DQS_DN<8> @S9S_MB_2U_LIB.S9S_MB_2U(SCH_1):M_G_CPU0_SB_DQS_DN(8)   I169 @S9S_MB_2U_LIB.S9S_MB_2U(SCH_1):PAGE26
  EB24 M_G_CPU0_SB_DQS_DN<7> @S9S_MB_2U_LIB.S9S_MB_2U(SCH_1):M_G_CPU0_SB_DQS_DN(7)   I169 @S9S_MB_2U_LIB.S9S_MB_2U(SCH_1):PAGE26
  DN27 M_G_CPU0_SB_DQS_DN<6> @S9S_MB_2U_LIB.S9S_MB_2U(SCH_1):M_G_CPU0_SB_DQS_DN(6)   I169 @S9S_MB_2U_LIB.S9S_MB_2U(SCH_1):PAGE26
  DR33 M_G_CPU0_SB_DQS_DN<5> @S9S_MB_2U_LIB.S9S_MB_2U(SCH_1):M_G_CPU0_SB_DQS_DN(5)   I169 @S9S_MB_2U_LIB.S9S_MB_2U(SCH_1):PAGE26
  EB36 M_G_CPU0_SB_DQS_DN<4> @S9S_MB_2U_LIB.S9S_MB_2U(SCH_1):M_G_CPU0_SB_DQS_DN(4)   I169 @S9S_MB_2U_LIB.S9S_MB_2U(SCH_1):PAGE26
   EP6 M_G_CPU0_SB_DQS_DN<3> @S9S_MB_2U_LIB.S9S_MB_2U(SCH_1):M_G_CPU0_SB_DQS_DN(3)   I169 @S9S_MB_2U_LIB.S9S_MB_2U(SCH_1):PAGE26
  DV24 M_G_CPU0_SB_DQS_DN<2> @S9S_MB_2U_LIB.S9S_MB_2U(SCH_1):M_G_CPU0_SB_DQS_DN(2)   I169 @S9S_MB_2U_LIB.S9S_MB_2U(SCH_1):PAGE26
  DJ27 M_G_CPU0_SB_DQS_DN<1> @S9S_MB_2U_LIB.S9S_MB_2U(SCH_1):M_G_CPU0_SB_DQS_DN(1)   I169 @S9S_MB_2U_LIB.S9S_MB_2U(SCH_1):PAGE26
  DJ33 M_G_CPU0_SB_DQS_DN<0> @S9S_MB_2U_LIB.S9S_MB_2U(SCH_1):M_G_CPU0_SB_DQS_DN(0)   I169 @S9S_MB_2U_LIB.S9S_MB_2U(SCH_1):PAGE26
  DT36 M_G_CPU0_SB_DQS_DP<9> @S9S_MB_2U_LIB.S9S_MB_2U(SCH_1):M_G_CPU0_SB_DQS_DP(9)   I169 @S9S_MB_2U_LIB.S9S_MB_2U(SCH_1):PAGE26
   EN5 M_G_CPU0_SB_DQS_DP<8> @S9S_MB_2U_LIB.S9S_MB_2U(SCH_1):M_G_CPU0_SB_DQS_DP(8)   I169 @S9S_MB_2U_LIB.S9S_MB_2U(SCH_1):PAGE26
  DY24 M_G_CPU0_SB_DQS_DP<7> @S9S_MB_2U_LIB.S9S_MB_2U(SCH_1):M_G_CPU0_SB_DQS_DP(7)   I169 @S9S_MB_2U_LIB.S9S_MB_2U(SCH_1):PAGE26
  DR27 M_G_CPU0_SB_DQS_DP<6> @S9S_MB_2U_LIB.S9S_MB_2U(SCH_1):M_G_CPU0_SB_DQS_DP(6)   I169 @S9S_MB_2U_LIB.S9S_MB_2U(SCH_1):PAGE26
  DN33 M_G_CPU0_SB_DQS_DP<5> @S9S_MB_2U_LIB.S9S_MB_2U(SCH_1):M_G_CPU0_SB_DQS_DP(5)   I169 @S9S_MB_2U_LIB.S9S_MB_2U(SCH_1):PAGE26
  DY36 M_G_CPU0_SB_DQS_DP<4> @S9S_MB_2U_LIB.S9S_MB_2U(SCH_1):M_G_CPU0_SB_DQS_DP(4)   I169 @S9S_MB_2U_LIB.S9S_MB_2U(SCH_1):PAGE26
   EN7 M_G_CPU0_SB_DQS_DP<3> @S9S_MB_2U_LIB.S9S_MB_2U(SCH_1):M_G_CPU0_SB_DQS_DP(3)   I169 @S9S_MB_2U_LIB.S9S_MB_2U(SCH_1):PAGE26
  DT24 M_G_CPU0_SB_DQS_DP<2> @S9S_MB_2U_LIB.S9S_MB_2U(SCH_1):M_G_CPU0_SB_DQS_DP(2)   I169 @S9S_MB_2U_LIB.S9S_MB_2U(SCH_1):PAGE26
  DL27 M_G_CPU0_SB_DQS_DP<1> @S9S_MB_2U_LIB.S9S_MB_2U(SCH_1):M_G_CPU0_SB_DQS_DP(1)   I169 @S9S_MB_2U_LIB.S9S_MB_2U(SCH_1):PAGE26
  DL33 M_G_CPU0_SB_DQS_DP<0> @S9S_MB_2U_LIB.S9S_MB_2U(SCH_1):M_G_CPU0_SB_DQS_DP(0)   I169 @S9S_MB_2U_LIB.S9S_MB_2U(SCH_1):PAGE26
  EA37 M_G_CPU0_SB_CB<7> @S9S_MB_2U_LIB.S9S_MB_2U(SCH_1):M_G_CPU0_SB_CB(7)   I169 @S9S_MB_2U_LIB.S9S_MB_2U(SCH_1):PAGE26
  DY38 M_G_CPU0_SB_CB<6> @S9S_MB_2U_LIB.S9S_MB_2U(SCH_1):M_G_CPU0_SB_CB(6)   I169 @S9S_MB_2U_LIB.S9S_MB_2U(SCH_1):PAGE26
  DU37 M_G_CPU0_SB_CB<5> @S9S_MB_2U_LIB.S9S_MB_2U(SCH_1):M_G_CPU0_SB_CB(5)   I169 @S9S_MB_2U_LIB.S9S_MB_2U(SCH_1):PAGE26
  DV38 M_G_CPU0_SB_CB<4> @S9S_MB_2U_LIB.S9S_MB_2U(SCH_1):M_G_CPU0_SB_CB(4)   I169 @S9S_MB_2U_LIB.S9S_MB_2U(SCH_1):PAGE26
  DY34 M_G_CPU0_SB_CB<3> @S9S_MB_2U_LIB.S9S_MB_2U(SCH_1):M_G_CPU0_SB_CB(3)   I169 @S9S_MB_2U_LIB.S9S_MB_2U(SCH_1):PAGE26
  EA35 M_G_CPU0_SB_CB<2> @S9S_MB_2U_LIB.S9S_MB_2U(SCH_1):M_G_CPU0_SB_CB(2)   I169 @S9S_MB_2U_LIB.S9S_MB_2U(SCH_1):PAGE26
  DV34 M_G_CPU0_SB_CB<1> @S9S_MB_2U_LIB.S9S_MB_2U(SCH_1):M_G_CPU0_SB_CB(1)   I169 @S9S_MB_2U_LIB.S9S_MB_2U(SCH_1):PAGE26
  DU35 M_G_CPU0_SB_CB<0> @S9S_MB_2U_LIB.S9S_MB_2U(SCH_1):M_G_CPU0_SB_CB(0)   I169 @S9S_MB_2U_LIB.S9S_MB_2U(SCH_1):PAGE26
  EB42 M_G_CPU0_SB_PAR @S9S_MB_2U_LIB.S9S_MB_2U(SCH_1):M_G_CPU0_SB_PAR   I169 @S9S_MB_2U_LIB.S9S_MB_2U(SCH_1):PAGE26
  CY51 M_H_CPU0_ALERT_N @S9S_MB_2U_LIB.S9S_MB_2U(SCH_1):M_H_CPU0_ALERT_N   I169 @S9S_MB_2U_LIB.S9S_MB_2U(SCH_1):PAGE27
  EH47 M_H_CPU0_SA_RSP<1> @S9S_MB_2U_LIB.S9S_MB_2U(SCH_1):M_H_CPU0_SA_RSP(1)   I169 @S9S_MB_2U_LIB.S9S_MB_2U(SCH_1):PAGE27
  EG48 M_H_CPU0_SA_RSP<0> @S9S_MB_2U_LIB.S9S_MB_2U(SCH_1):M_H_CPU0_SA_RSP(0)   I169 @S9S_MB_2U_LIB.S9S_MB_2U(SCH_1):PAGE27
  ED47 M_H_CPU0_SB_RSP<1> @S9S_MB_2U_LIB.S9S_MB_2U(SCH_1):M_H_CPU0_SB_RSP(1)   I169 @S9S_MB_2U_LIB.S9S_MB_2U(SCH_1):PAGE27
  EE48 M_H_CPU0_SB_RSP<0> @S9S_MB_2U_LIB.S9S_MB_2U(SCH_1):M_H_CPU0_SB_RSP(0)   I169 @S9S_MB_2U_LIB.S9S_MB_2U(SCH_1):PAGE27
  DD42 M_H_CPU0_CLK_DN<1> @S9S_MB_2U_LIB.S9S_MB_2U(SCH_1):M_H_CPU0_CLK_DN(1)   I169 @S9S_MB_2U_LIB.S9S_MB_2U(SCH_1):PAGE27
  DH42 M_H_CPU0_CLK_DN<0> @S9S_MB_2U_LIB.S9S_MB_2U(SCH_1):M_H_CPU0_CLK_DN(0)   I169 @S9S_MB_2U_LIB.S9S_MB_2U(SCH_1):PAGE27
  DB42 M_H_CPU0_CLK_DP<1> @S9S_MB_2U_LIB.S9S_MB_2U(SCH_1):M_H_CPU0_CLK_DP(1)   I169 @S9S_MB_2U_LIB.S9S_MB_2U(SCH_1):PAGE27
  DF42 M_H_CPU0_CLK_DP<0> @S9S_MB_2U_LIB.S9S_MB_2U(SCH_1):M_H_CPU0_CLK_DP(0)   I169 @S9S_MB_2U_LIB.S9S_MB_2U(SCH_1):PAGE27
  DC41 M_H_CPU0_SA_CA<6> @S9S_MB_2U_LIB.S9S_MB_2U(SCH_1):M_H_CPU0_SA_CA(6)   I169 @S9S_MB_2U_LIB.S9S_MB_2U(SCH_1):PAGE27
  DF47 M_H_CPU0_SA_CA<5> @S9S_MB_2U_LIB.S9S_MB_2U(SCH_1):M_H_CPU0_SA_CA(5)   I169 @S9S_MB_2U_LIB.S9S_MB_2U(SCH_1):PAGE27
  DD47 M_H_CPU0_SA_CA<4> @S9S_MB_2U_LIB.S9S_MB_2U(SCH_1):M_H_CPU0_SA_CA(4)   I169 @S9S_MB_2U_LIB.S9S_MB_2U(SCH_1):PAGE27
  DG48 M_H_CPU0_SA_CA<3> @S9S_MB_2U_LIB.S9S_MB_2U(SCH_1):M_H_CPU0_SA_CA(3)   I169 @S9S_MB_2U_LIB.S9S_MB_2U(SCH_1):PAGE27
  DC48 M_H_CPU0_SA_CA<2> @S9S_MB_2U_LIB.S9S_MB_2U(SCH_1):M_H_CPU0_SA_CA(2)   I169 @S9S_MB_2U_LIB.S9S_MB_2U(SCH_1):PAGE27
  DH49 M_H_CPU0_SA_CA<1> @S9S_MB_2U_LIB.S9S_MB_2U(SCH_1):M_H_CPU0_SA_CA(1)   I169 @S9S_MB_2U_LIB.S9S_MB_2U(SCH_1):PAGE27
  DB49 M_H_CPU0_SA_CA<0> @S9S_MB_2U_LIB.S9S_MB_2U(SCH_1):M_H_CPU0_SA_CA(0)   I169 @S9S_MB_2U_LIB.S9S_MB_2U(SCH_1):PAGE27
  DC50 M_H_CPU0_SA_CS_N<3> @S9S_MB_2U_LIB.S9S_MB_2U(SCH_1):M_H_CPU0_SA_CS_N(3)   I169 @S9S_MB_2U_LIB.S9S_MB_2U(SCH_1):PAGE27
  DD51 M_H_CPU0_SA_CS_N<2> @S9S_MB_2U_LIB.S9S_MB_2U(SCH_1):M_H_CPU0_SA_CS_N(2)   I169 @S9S_MB_2U_LIB.S9S_MB_2U(SCH_1):PAGE27
  DG50 M_H_CPU0_SA_CS_N<1> @S9S_MB_2U_LIB.S9S_MB_2U(SCH_1):M_H_CPU0_SA_CS_N(1)   I169 @S9S_MB_2U_LIB.S9S_MB_2U(SCH_1):PAGE27
  DF51 M_H_CPU0_SA_CS_N<0> @S9S_MB_2U_LIB.S9S_MB_2U(SCH_1):M_H_CPU0_SA_CS_N(0)   I169 @S9S_MB_2U_LIB.S9S_MB_2U(SCH_1):PAGE27
  DF59 M_H_CPU0_SA_DQ<31> @S9S_MB_2U_LIB.S9S_MB_2U(SCH_1):M_H_CPU0_SA_DQ(31)   I169 @S9S_MB_2U_LIB.S9S_MB_2U(SCH_1):PAGE27
  DG60 M_H_CPU0_SA_DQ<30> @S9S_MB_2U_LIB.S9S_MB_2U(SCH_1):M_H_CPU0_SA_DQ(30)   I169 @S9S_MB_2U_LIB.S9S_MB_2U(SCH_1):PAGE27
  DD59 M_H_CPU0_SA_DQ<29> @S9S_MB_2U_LIB.S9S_MB_2U(SCH_1):M_H_CPU0_SA_DQ(29)   I169 @S9S_MB_2U_LIB.S9S_MB_2U(SCH_1):PAGE27
  DC60 M_H_CPU0_SA_DQ<28> @S9S_MB_2U_LIB.S9S_MB_2U(SCH_1):M_H_CPU0_SA_DQ(28)   I169 @S9S_MB_2U_LIB.S9S_MB_2U(SCH_1):PAGE27
  DG62 M_H_CPU0_SA_DQ<27> @S9S_MB_2U_LIB.S9S_MB_2U(SCH_1):M_H_CPU0_SA_DQ(27)   I169 @S9S_MB_2U_LIB.S9S_MB_2U(SCH_1):PAGE27
  DF63 M_H_CPU0_SA_DQ<26> @S9S_MB_2U_LIB.S9S_MB_2U(SCH_1):M_H_CPU0_SA_DQ(26)   I169 @S9S_MB_2U_LIB.S9S_MB_2U(SCH_1):PAGE27
  DC62 M_H_CPU0_SA_DQ<25> @S9S_MB_2U_LIB.S9S_MB_2U(SCH_1):M_H_CPU0_SA_DQ(25)   I169 @S9S_MB_2U_LIB.S9S_MB_2U(SCH_1):PAGE27
  DD63 M_H_CPU0_SA_DQ<24> @S9S_MB_2U_LIB.S9S_MB_2U(SCH_1):M_H_CPU0_SA_DQ(24)   I169 @S9S_MB_2U_LIB.S9S_MB_2U(SCH_1):PAGE27
  DF65 M_H_CPU0_SA_DQ<23> @S9S_MB_2U_LIB.S9S_MB_2U(SCH_1):M_H_CPU0_SA_DQ(23)   I169 @S9S_MB_2U_LIB.S9S_MB_2U(SCH_1):PAGE27
  DG66 M_H_CPU0_SA_DQ<22> @S9S_MB_2U_LIB.S9S_MB_2U(SCH_1):M_H_CPU0_SA_DQ(22)   I169 @S9S_MB_2U_LIB.S9S_MB_2U(SCH_1):PAGE27
  DD65 M_H_CPU0_SA_DQ<21> @S9S_MB_2U_LIB.S9S_MB_2U(SCH_1):M_H_CPU0_SA_DQ(21)   I169 @S9S_MB_2U_LIB.S9S_MB_2U(SCH_1):PAGE27
  DC66 M_H_CPU0_SA_DQ<20> @S9S_MB_2U_LIB.S9S_MB_2U(SCH_1):M_H_CPU0_SA_DQ(20)   I169 @S9S_MB_2U_LIB.S9S_MB_2U(SCH_1):PAGE27
  DG68 M_H_CPU0_SA_DQ<19> @S9S_MB_2U_LIB.S9S_MB_2U(SCH_1):M_H_CPU0_SA_DQ(19)   I169 @S9S_MB_2U_LIB.S9S_MB_2U(SCH_1):PAGE27
  DF69 M_H_CPU0_SA_DQ<18> @S9S_MB_2U_LIB.S9S_MB_2U(SCH_1):M_H_CPU0_SA_DQ(18)   I169 @S9S_MB_2U_LIB.S9S_MB_2U(SCH_1):PAGE27
  DC68 M_H_CPU0_SA_DQ<17> @S9S_MB_2U_LIB.S9S_MB_2U(SCH_1):M_H_CPU0_SA_DQ(17)   I169 @S9S_MB_2U_LIB.S9S_MB_2U(SCH_1):PAGE27
  DD69 M_H_CPU0_SA_DQ<16> @S9S_MB_2U_LIB.S9S_MB_2U(SCH_1):M_H_CPU0_SA_DQ(16)   I169 @S9S_MB_2U_LIB.S9S_MB_2U(SCH_1):PAGE27
  DF71 M_H_CPU0_SA_DQ<15> @S9S_MB_2U_LIB.S9S_MB_2U(SCH_1):M_H_CPU0_SA_DQ(15)   I169 @S9S_MB_2U_LIB.S9S_MB_2U(SCH_1):PAGE27
  DG72 M_H_CPU0_SA_DQ<14> @S9S_MB_2U_LIB.S9S_MB_2U(SCH_1):M_H_CPU0_SA_DQ(14)   I169 @S9S_MB_2U_LIB.S9S_MB_2U(SCH_1):PAGE27
  DD71 M_H_CPU0_SA_DQ<13> @S9S_MB_2U_LIB.S9S_MB_2U(SCH_1):M_H_CPU0_SA_DQ(13)   I169 @S9S_MB_2U_LIB.S9S_MB_2U(SCH_1):PAGE27
  DC72 M_H_CPU0_SA_DQ<12> @S9S_MB_2U_LIB.S9S_MB_2U(SCH_1):M_H_CPU0_SA_DQ(12)   I169 @S9S_MB_2U_LIB.S9S_MB_2U(SCH_1):PAGE27
  DG74 M_H_CPU0_SA_DQ<11> @S9S_MB_2U_LIB.S9S_MB_2U(SCH_1):M_H_CPU0_SA_DQ(11)   I169 @S9S_MB_2U_LIB.S9S_MB_2U(SCH_1):PAGE27
  DF75 M_H_CPU0_SA_DQ<10> @S9S_MB_2U_LIB.S9S_MB_2U(SCH_1):M_H_CPU0_SA_DQ(10)   I169 @S9S_MB_2U_LIB.S9S_MB_2U(SCH_1):PAGE27
  DC74 M_H_CPU0_SA_DQ<9> @S9S_MB_2U_LIB.S9S_MB_2U(SCH_1):M_H_CPU0_SA_DQ(9)   I169 @S9S_MB_2U_LIB.S9S_MB_2U(SCH_1):PAGE27
  DD75 M_H_CPU0_SA_DQ<8> @S9S_MB_2U_LIB.S9S_MB_2U(SCH_1):M_H_CPU0_SA_DQ(8)   I169 @S9S_MB_2U_LIB.S9S_MB_2U(SCH_1):PAGE27
  DN74 M_H_CPU0_SA_DQ<7> @S9S_MB_2U_LIB.S9S_MB_2U(SCH_1):M_H_CPU0_SA_DQ(7)   I169 @S9S_MB_2U_LIB.S9S_MB_2U(SCH_1):PAGE27
  DP75 M_H_CPU0_SA_DQ<6> @S9S_MB_2U_LIB.S9S_MB_2U(SCH_1):M_H_CPU0_SA_DQ(6)   I169 @S9S_MB_2U_LIB.S9S_MB_2U(SCH_1):PAGE27
  DL74 M_H_CPU0_SA_DQ<5> @S9S_MB_2U_LIB.S9S_MB_2U(SCH_1):M_H_CPU0_SA_DQ(5)   I169 @S9S_MB_2U_LIB.S9S_MB_2U(SCH_1):PAGE27
  DK75 M_H_CPU0_SA_DQ<4> @S9S_MB_2U_LIB.S9S_MB_2U(SCH_1):M_H_CPU0_SA_DQ(4)   I169 @S9S_MB_2U_LIB.S9S_MB_2U(SCH_1):PAGE27
  DP77 M_H_CPU0_SA_DQ<3> @S9S_MB_2U_LIB.S9S_MB_2U(SCH_1):M_H_CPU0_SA_DQ(3)   I169 @S9S_MB_2U_LIB.S9S_MB_2U(SCH_1):PAGE27
  DW78 M_H_CPU0_SA_DQ<2> @S9S_MB_2U_LIB.S9S_MB_2U(SCH_1):M_H_CPU0_SA_DQ(2)   I169 @S9S_MB_2U_LIB.S9S_MB_2U(SCH_1):PAGE27
  DT77 M_H_CPU0_SA_DQ<1> @S9S_MB_2U_LIB.S9S_MB_2U(SCH_1):M_H_CPU0_SA_DQ(1)   I169 @S9S_MB_2U_LIB.S9S_MB_2U(SCH_1):PAGE27
  DY79 M_H_CPU0_SA_DQ<0> @S9S_MB_2U_LIB.S9S_MB_2U(SCH_1):M_H_CPU0_SA_DQ(0)   I169 @S9S_MB_2U_LIB.S9S_MB_2U(SCH_1):PAGE27
  DH55 M_H_CPU0_SA_DQS_DN<9> @S9S_MB_2U_LIB.S9S_MB_2U(SCH_1):M_H_CPU0_SA_DQS_DN(9)   I169 @S9S_MB_2U_LIB.S9S_MB_2U(SCH_1):PAGE27
  DH61 M_H_CPU0_SA_DQS_DN<8> @S9S_MB_2U_LIB.S9S_MB_2U(SCH_1):M_H_CPU0_SA_DQS_DN(8)   I169 @S9S_MB_2U_LIB.S9S_MB_2U(SCH_1):PAGE27
  DH67 M_H_CPU0_SA_DQS_DN<7> @S9S_MB_2U_LIB.S9S_MB_2U(SCH_1):M_H_CPU0_SA_DQS_DN(7)   I169 @S9S_MB_2U_LIB.S9S_MB_2U(SCH_1):PAGE27
  DH73 M_H_CPU0_SA_DQS_DN<6> @S9S_MB_2U_LIB.S9S_MB_2U(SCH_1):M_H_CPU0_SA_DQS_DN(6)   I169 @S9S_MB_2U_LIB.S9S_MB_2U(SCH_1):PAGE27
  DR76 M_H_CPU0_SA_DQS_DN<5> @S9S_MB_2U_LIB.S9S_MB_2U(SCH_1):M_H_CPU0_SA_DQS_DN(5)   I169 @S9S_MB_2U_LIB.S9S_MB_2U(SCH_1):PAGE27
  DD55 M_H_CPU0_SA_DQS_DN<4> @S9S_MB_2U_LIB.S9S_MB_2U(SCH_1):M_H_CPU0_SA_DQS_DN(4)   I169 @S9S_MB_2U_LIB.S9S_MB_2U(SCH_1):PAGE27
  DD61 M_H_CPU0_SA_DQS_DN<3> @S9S_MB_2U_LIB.S9S_MB_2U(SCH_1):M_H_CPU0_SA_DQS_DN(3)   I169 @S9S_MB_2U_LIB.S9S_MB_2U(SCH_1):PAGE27
  DD67 M_H_CPU0_SA_DQS_DN<2> @S9S_MB_2U_LIB.S9S_MB_2U(SCH_1):M_H_CPU0_SA_DQS_DN(2)   I169 @S9S_MB_2U_LIB.S9S_MB_2U(SCH_1):PAGE27
  DB73 M_H_CPU0_SA_DQS_DN<1> @S9S_MB_2U_LIB.S9S_MB_2U(SCH_1):M_H_CPU0_SA_DQS_DN(1)   I169 @S9S_MB_2U_LIB.S9S_MB_2U(SCH_1):PAGE27
  DJ76 M_H_CPU0_SA_DQS_DN<0> @S9S_MB_2U_LIB.S9S_MB_2U(SCH_1):M_H_CPU0_SA_DQS_DN(0)   I169 @S9S_MB_2U_LIB.S9S_MB_2U(SCH_1):PAGE27
  DF55 M_H_CPU0_SA_DQS_DP<9> @S9S_MB_2U_LIB.S9S_MB_2U(SCH_1):M_H_CPU0_SA_DQS_DP(9)   I169 @S9S_MB_2U_LIB.S9S_MB_2U(SCH_1):PAGE27
  DF61 M_H_CPU0_SA_DQS_DP<8> @S9S_MB_2U_LIB.S9S_MB_2U(SCH_1):M_H_CPU0_SA_DQS_DP(8)   I169 @S9S_MB_2U_LIB.S9S_MB_2U(SCH_1):PAGE27
  DF67 M_H_CPU0_SA_DQS_DP<7> @S9S_MB_2U_LIB.S9S_MB_2U(SCH_1):M_H_CPU0_SA_DQS_DP(7)   I169 @S9S_MB_2U_LIB.S9S_MB_2U(SCH_1):PAGE27
  DF73 M_H_CPU0_SA_DQS_DP<6> @S9S_MB_2U_LIB.S9S_MB_2U(SCH_1):M_H_CPU0_SA_DQS_DP(6)   I169 @S9S_MB_2U_LIB.S9S_MB_2U(SCH_1):PAGE27
  DN76 M_H_CPU0_SA_DQS_DP<5> @S9S_MB_2U_LIB.S9S_MB_2U(SCH_1):M_H_CPU0_SA_DQS_DP(5)   I169 @S9S_MB_2U_LIB.S9S_MB_2U(SCH_1):PAGE27
  DB55 M_H_CPU0_SA_DQS_DP<4> @S9S_MB_2U_LIB.S9S_MB_2U(SCH_1):M_H_CPU0_SA_DQS_DP(4)   I169 @S9S_MB_2U_LIB.S9S_MB_2U(SCH_1):PAGE27
  DB61 M_H_CPU0_SA_DQS_DP<3> @S9S_MB_2U_LIB.S9S_MB_2U(SCH_1):M_H_CPU0_SA_DQS_DP(3)   I169 @S9S_MB_2U_LIB.S9S_MB_2U(SCH_1):PAGE27
  DB67 M_H_CPU0_SA_DQS_DP<2> @S9S_MB_2U_LIB.S9S_MB_2U(SCH_1):M_H_CPU0_SA_DQS_DP(2)   I169 @S9S_MB_2U_LIB.S9S_MB_2U(SCH_1):PAGE27
  DD73 M_H_CPU0_SA_DQS_DP<1> @S9S_MB_2U_LIB.S9S_MB_2U(SCH_1):M_H_CPU0_SA_DQS_DP(1)   I169 @S9S_MB_2U_LIB.S9S_MB_2U(SCH_1):PAGE27
  DL76 M_H_CPU0_SA_DQS_DP<0> @S9S_MB_2U_LIB.S9S_MB_2U(SCH_1):M_H_CPU0_SA_DQS_DP(0)   I169 @S9S_MB_2U_LIB.S9S_MB_2U(SCH_1):PAGE27
  DF53 M_H_CPU0_SA_CB<7> @S9S_MB_2U_LIB.S9S_MB_2U(SCH_1):M_H_CPU0_SA_CB(7)   I169 @S9S_MB_2U_LIB.S9S_MB_2U(SCH_1):PAGE27
  DG54 M_H_CPU0_SA_CB<6> @S9S_MB_2U_LIB.S9S_MB_2U(SCH_1):M_H_CPU0_SA_CB(6)   I169 @S9S_MB_2U_LIB.S9S_MB_2U(SCH_1):PAGE27
  DD53 M_H_CPU0_SA_CB<5> @S9S_MB_2U_LIB.S9S_MB_2U(SCH_1):M_H_CPU0_SA_CB(5)   I169 @S9S_MB_2U_LIB.S9S_MB_2U(SCH_1):PAGE27
  DC54 M_H_CPU0_SA_CB<4> @S9S_MB_2U_LIB.S9S_MB_2U(SCH_1):M_H_CPU0_SA_CB(4)   I169 @S9S_MB_2U_LIB.S9S_MB_2U(SCH_1):PAGE27
  DG56 M_H_CPU0_SA_CB<3> @S9S_MB_2U_LIB.S9S_MB_2U(SCH_1):M_H_CPU0_SA_CB(3)   I169 @S9S_MB_2U_LIB.S9S_MB_2U(SCH_1):PAGE27
  DF57 M_H_CPU0_SA_CB<2> @S9S_MB_2U_LIB.S9S_MB_2U(SCH_1):M_H_CPU0_SA_CB(2)   I169 @S9S_MB_2U_LIB.S9S_MB_2U(SCH_1):PAGE27
  DC56 M_H_CPU0_SA_CB<1> @S9S_MB_2U_LIB.S9S_MB_2U(SCH_1):M_H_CPU0_SA_CB(1)   I169 @S9S_MB_2U_LIB.S9S_MB_2U(SCH_1):PAGE27
  DD57 M_H_CPU0_SA_CB<0> @S9S_MB_2U_LIB.S9S_MB_2U(SCH_1):M_H_CPU0_SA_CB(0)   I169 @S9S_MB_2U_LIB.S9S_MB_2U(SCH_1):PAGE27
  DD40 M_H_CPU0_SA_PAR @S9S_MB_2U_LIB.S9S_MB_2U(SCH_1):M_H_CPU0_SA_PAR   I169 @S9S_MB_2U_LIB.S9S_MB_2U(SCH_1):PAGE27
  DJ39 M_H_CPU0_SB_CA<6> @S9S_MB_2U_LIB.S9S_MB_2U(SCH_1):M_H_CPU0_SB_CA(6)   I169 @S9S_MB_2U_LIB.S9S_MB_2U(SCH_1):PAGE27
  DP40 M_H_CPU0_SB_CA<5> @S9S_MB_2U_LIB.S9S_MB_2U(SCH_1):M_H_CPU0_SB_CA(5)   I169 @S9S_MB_2U_LIB.S9S_MB_2U(SCH_1):PAGE27
  DK40 M_H_CPU0_SB_CA<4> @S9S_MB_2U_LIB.S9S_MB_2U(SCH_1):M_H_CPU0_SB_CA(4)   I169 @S9S_MB_2U_LIB.S9S_MB_2U(SCH_1):PAGE27
  DN41 M_H_CPU0_SB_CA<3> @S9S_MB_2U_LIB.S9S_MB_2U(SCH_1):M_H_CPU0_SB_CA(3)   I169 @S9S_MB_2U_LIB.S9S_MB_2U(SCH_1):PAGE27
  DL41 M_H_CPU0_SB_CA<2> @S9S_MB_2U_LIB.S9S_MB_2U(SCH_1):M_H_CPU0_SB_CA(2)   I169 @S9S_MB_2U_LIB.S9S_MB_2U(SCH_1):PAGE27
  DG41 M_H_CPU0_SB_CA<1> @S9S_MB_2U_LIB.S9S_MB_2U(SCH_1):M_H_CPU0_SB_CA(1)   I169 @S9S_MB_2U_LIB.S9S_MB_2U(SCH_1):PAGE27
  DF40 M_H_CPU0_SB_CA<0> @S9S_MB_2U_LIB.S9S_MB_2U(SCH_1):M_H_CPU0_SB_CA(0)   I169 @S9S_MB_2U_LIB.S9S_MB_2U(SCH_1):PAGE27
  DP38 M_H_CPU0_SB_CS_N<3> @S9S_MB_2U_LIB.S9S_MB_2U(SCH_1):M_H_CPU0_SB_CS_N(3)   I169 @S9S_MB_2U_LIB.S9S_MB_2U(SCH_1):PAGE27
  DK38 M_H_CPU0_SB_CS_N<2> @S9S_MB_2U_LIB.S9S_MB_2U(SCH_1):M_H_CPU0_SB_CS_N(2)   I169 @S9S_MB_2U_LIB.S9S_MB_2U(SCH_1):PAGE27
  DN37 M_H_CPU0_SB_CS_N<1> @S9S_MB_2U_LIB.S9S_MB_2U(SCH_1):M_H_CPU0_SB_CS_N(1)   I169 @S9S_MB_2U_LIB.S9S_MB_2U(SCH_1):PAGE27
  DL37 M_H_CPU0_SB_CS_N<0> @S9S_MB_2U_LIB.S9S_MB_2U(SCH_1):M_H_CPU0_SB_CS_N(0)   I169 @S9S_MB_2U_LIB.S9S_MB_2U(SCH_1):PAGE27
  DC17 M_H_CPU0_SB_DQ<31> @S9S_MB_2U_LIB.S9S_MB_2U(SCH_1):M_H_CPU0_SB_DQ(31)   I169 @S9S_MB_2U_LIB.S9S_MB_2U(SCH_1):PAGE27
  DJ17 M_H_CPU0_SB_DQ<30> @S9S_MB_2U_LIB.S9S_MB_2U(SCH_1):M_H_CPU0_SB_DQ(30)   I169 @S9S_MB_2U_LIB.S9S_MB_2U(SCH_1):PAGE27
  DA17 M_H_CPU0_SB_DQ<29> @S9S_MB_2U_LIB.S9S_MB_2U(SCH_1):M_H_CPU0_SB_DQ(29)   I169 @S9S_MB_2U_LIB.S9S_MB_2U(SCH_1):PAGE27
  DG17 M_H_CPU0_SB_DQ<28> @S9S_MB_2U_LIB.S9S_MB_2U(SCH_1):M_H_CPU0_SB_DQ(28)   I169 @S9S_MB_2U_LIB.S9S_MB_2U(SCH_1):PAGE27
  DG19 M_H_CPU0_SB_DQ<27> @S9S_MB_2U_LIB.S9S_MB_2U(SCH_1):M_H_CPU0_SB_DQ(27)   I169 @S9S_MB_2U_LIB.S9S_MB_2U(SCH_1):PAGE27
  DF20 M_H_CPU0_SB_DQ<26> @S9S_MB_2U_LIB.S9S_MB_2U(SCH_1):M_H_CPU0_SB_DQ(26)   I169 @S9S_MB_2U_LIB.S9S_MB_2U(SCH_1):PAGE27
  DC19 M_H_CPU0_SB_DQ<25> @S9S_MB_2U_LIB.S9S_MB_2U(SCH_1):M_H_CPU0_SB_DQ(25)   I169 @S9S_MB_2U_LIB.S9S_MB_2U(SCH_1):PAGE27
  DD20 M_H_CPU0_SB_DQ<24> @S9S_MB_2U_LIB.S9S_MB_2U(SCH_1):M_H_CPU0_SB_DQ(24)   I169 @S9S_MB_2U_LIB.S9S_MB_2U(SCH_1):PAGE27
  DN19 M_H_CPU0_SB_DQ<23> @S9S_MB_2U_LIB.S9S_MB_2U(SCH_1):M_H_CPU0_SB_DQ(23)   I169 @S9S_MB_2U_LIB.S9S_MB_2U(SCH_1):PAGE27
  DP20 M_H_CPU0_SB_DQ<22> @S9S_MB_2U_LIB.S9S_MB_2U(SCH_1):M_H_CPU0_SB_DQ(22)   I169 @S9S_MB_2U_LIB.S9S_MB_2U(SCH_1):PAGE27
  DL19 M_H_CPU0_SB_DQ<21> @S9S_MB_2U_LIB.S9S_MB_2U(SCH_1):M_H_CPU0_SB_DQ(21)   I169 @S9S_MB_2U_LIB.S9S_MB_2U(SCH_1):PAGE27
  DK20 M_H_CPU0_SB_DQ<20> @S9S_MB_2U_LIB.S9S_MB_2U(SCH_1):M_H_CPU0_SB_DQ(20)   I169 @S9S_MB_2U_LIB.S9S_MB_2U(SCH_1):PAGE27
  DP22 M_H_CPU0_SB_DQ<19> @S9S_MB_2U_LIB.S9S_MB_2U(SCH_1):M_H_CPU0_SB_DQ(19)   I169 @S9S_MB_2U_LIB.S9S_MB_2U(SCH_1):PAGE27
  DN23 M_H_CPU0_SB_DQ<18> @S9S_MB_2U_LIB.S9S_MB_2U(SCH_1):M_H_CPU0_SB_DQ(18)   I169 @S9S_MB_2U_LIB.S9S_MB_2U(SCH_1):PAGE27
  DK22 M_H_CPU0_SB_DQ<17> @S9S_MB_2U_LIB.S9S_MB_2U(SCH_1):M_H_CPU0_SB_DQ(17)   I169 @S9S_MB_2U_LIB.S9S_MB_2U(SCH_1):PAGE27
  DL23 M_H_CPU0_SB_DQ<16> @S9S_MB_2U_LIB.S9S_MB_2U(SCH_1):M_H_CPU0_SB_DQ(16)   I169 @S9S_MB_2U_LIB.S9S_MB_2U(SCH_1):PAGE27
  DF22 M_H_CPU0_SB_DQ<15> @S9S_MB_2U_LIB.S9S_MB_2U(SCH_1):M_H_CPU0_SB_DQ(15)   I169 @S9S_MB_2U_LIB.S9S_MB_2U(SCH_1):PAGE27
  DG23 M_H_CPU0_SB_DQ<14> @S9S_MB_2U_LIB.S9S_MB_2U(SCH_1):M_H_CPU0_SB_DQ(14)   I169 @S9S_MB_2U_LIB.S9S_MB_2U(SCH_1):PAGE27
  DD22 M_H_CPU0_SB_DQ<13> @S9S_MB_2U_LIB.S9S_MB_2U(SCH_1):M_H_CPU0_SB_DQ(13)   I169 @S9S_MB_2U_LIB.S9S_MB_2U(SCH_1):PAGE27
  DC23 M_H_CPU0_SB_DQ<12> @S9S_MB_2U_LIB.S9S_MB_2U(SCH_1):M_H_CPU0_SB_DQ(12)   I169 @S9S_MB_2U_LIB.S9S_MB_2U(SCH_1):PAGE27
  DG25 M_H_CPU0_SB_DQ<11> @S9S_MB_2U_LIB.S9S_MB_2U(SCH_1):M_H_CPU0_SB_DQ(11)   I169 @S9S_MB_2U_LIB.S9S_MB_2U(SCH_1):PAGE27
  DF26 M_H_CPU0_SB_DQ<10> @S9S_MB_2U_LIB.S9S_MB_2U(SCH_1):M_H_CPU0_SB_DQ(10)   I169 @S9S_MB_2U_LIB.S9S_MB_2U(SCH_1):PAGE27
  DC25 M_H_CPU0_SB_DQ<9> @S9S_MB_2U_LIB.S9S_MB_2U(SCH_1):M_H_CPU0_SB_DQ(9)   I169 @S9S_MB_2U_LIB.S9S_MB_2U(SCH_1):PAGE27
  DD26 M_H_CPU0_SB_DQ<8> @S9S_MB_2U_LIB.S9S_MB_2U(SCH_1):M_H_CPU0_SB_DQ(8)   I169 @S9S_MB_2U_LIB.S9S_MB_2U(SCH_1):PAGE27
  DD28 M_H_CPU0_SB_DQ<7> @S9S_MB_2U_LIB.S9S_MB_2U(SCH_1):M_H_CPU0_SB_DQ(7)   I169 @S9S_MB_2U_LIB.S9S_MB_2U(SCH_1):PAGE27
  DG29 M_H_CPU0_SB_DQ<6> @S9S_MB_2U_LIB.S9S_MB_2U(SCH_1):M_H_CPU0_SB_DQ(6)   I169 @S9S_MB_2U_LIB.S9S_MB_2U(SCH_1):PAGE27
  DF28 M_H_CPU0_SB_DQ<5> @S9S_MB_2U_LIB.S9S_MB_2U(SCH_1):M_H_CPU0_SB_DQ(5)   I169 @S9S_MB_2U_LIB.S9S_MB_2U(SCH_1):PAGE27
  DC29 M_H_CPU0_SB_DQ<4> @S9S_MB_2U_LIB.S9S_MB_2U(SCH_1):M_H_CPU0_SB_DQ(4)   I169 @S9S_MB_2U_LIB.S9S_MB_2U(SCH_1):PAGE27
  DG31 M_H_CPU0_SB_DQ<3> @S9S_MB_2U_LIB.S9S_MB_2U(SCH_1):M_H_CPU0_SB_DQ(3)   I169 @S9S_MB_2U_LIB.S9S_MB_2U(SCH_1):PAGE27
  DF32 M_H_CPU0_SB_DQ<2> @S9S_MB_2U_LIB.S9S_MB_2U(SCH_1):M_H_CPU0_SB_DQ(2)   I169 @S9S_MB_2U_LIB.S9S_MB_2U(SCH_1):PAGE27
  DC31 M_H_CPU0_SB_DQ<1> @S9S_MB_2U_LIB.S9S_MB_2U(SCH_1):M_H_CPU0_SB_DQ(1)   I169 @S9S_MB_2U_LIB.S9S_MB_2U(SCH_1):PAGE27
  DD32 M_H_CPU0_SB_DQ<0> @S9S_MB_2U_LIB.S9S_MB_2U(SCH_1):M_H_CPU0_SB_DQ(0)   I169 @S9S_MB_2U_LIB.S9S_MB_2U(SCH_1):PAGE27
  DD36 M_H_CPU0_SB_DQS_DN<9> @S9S_MB_2U_LIB.S9S_MB_2U(SCH_1):M_H_CPU0_SB_DQS_DN(9)   I169 @S9S_MB_2U_LIB.S9S_MB_2U(SCH_1):PAGE27
  DF18 M_H_CPU0_SB_DQS_DN<8> @S9S_MB_2U_LIB.S9S_MB_2U(SCH_1):M_H_CPU0_SB_DQS_DN(8)   I169 @S9S_MB_2U_LIB.S9S_MB_2U(SCH_1):PAGE27
  DR21 M_H_CPU0_SB_DQS_DN<7> @S9S_MB_2U_LIB.S9S_MB_2U(SCH_1):M_H_CPU0_SB_DQS_DN(7)   I169 @S9S_MB_2U_LIB.S9S_MB_2U(SCH_1):PAGE27
  DH24 M_H_CPU0_SB_DQS_DN<6> @S9S_MB_2U_LIB.S9S_MB_2U(SCH_1):M_H_CPU0_SB_DQS_DN(6)   I169 @S9S_MB_2U_LIB.S9S_MB_2U(SCH_1):PAGE27
  DH30 M_H_CPU0_SB_DQS_DN<5> @S9S_MB_2U_LIB.S9S_MB_2U(SCH_1):M_H_CPU0_SB_DQS_DN(5)   I169 @S9S_MB_2U_LIB.S9S_MB_2U(SCH_1):PAGE27
  DH36 M_H_CPU0_SB_DQS_DN<4> @S9S_MB_2U_LIB.S9S_MB_2U(SCH_1):M_H_CPU0_SB_DQS_DN(4)   I169 @S9S_MB_2U_LIB.S9S_MB_2U(SCH_1):PAGE27
  DB18 M_H_CPU0_SB_DQS_DN<3> @S9S_MB_2U_LIB.S9S_MB_2U(SCH_1):M_H_CPU0_SB_DQS_DN(3)   I169 @S9S_MB_2U_LIB.S9S_MB_2U(SCH_1):PAGE27
  DL21 M_H_CPU0_SB_DQS_DN<2> @S9S_MB_2U_LIB.S9S_MB_2U(SCH_1):M_H_CPU0_SB_DQS_DN(2)   I169 @S9S_MB_2U_LIB.S9S_MB_2U(SCH_1):PAGE27
  DD24 M_H_CPU0_SB_DQS_DN<1> @S9S_MB_2U_LIB.S9S_MB_2U(SCH_1):M_H_CPU0_SB_DQS_DN(1)   I169 @S9S_MB_2U_LIB.S9S_MB_2U(SCH_1):PAGE27
  DD30 M_H_CPU0_SB_DQS_DN<0> @S9S_MB_2U_LIB.S9S_MB_2U(SCH_1):M_H_CPU0_SB_DQS_DN(0)   I169 @S9S_MB_2U_LIB.S9S_MB_2U(SCH_1):PAGE27
  DB36 M_H_CPU0_SB_DQS_DP<9> @S9S_MB_2U_LIB.S9S_MB_2U(SCH_1):M_H_CPU0_SB_DQS_DP(9)   I169 @S9S_MB_2U_LIB.S9S_MB_2U(SCH_1):PAGE27
  DH18 M_H_CPU0_SB_DQS_DP<8> @S9S_MB_2U_LIB.S9S_MB_2U(SCH_1):M_H_CPU0_SB_DQS_DP(8)   I169 @S9S_MB_2U_LIB.S9S_MB_2U(SCH_1):PAGE27
  DN21 M_H_CPU0_SB_DQS_DP<7> @S9S_MB_2U_LIB.S9S_MB_2U(SCH_1):M_H_CPU0_SB_DQS_DP(7)   I169 @S9S_MB_2U_LIB.S9S_MB_2U(SCH_1):PAGE27
  DF24 M_H_CPU0_SB_DQS_DP<6> @S9S_MB_2U_LIB.S9S_MB_2U(SCH_1):M_H_CPU0_SB_DQS_DP(6)   I169 @S9S_MB_2U_LIB.S9S_MB_2U(SCH_1):PAGE27
  DF30 M_H_CPU0_SB_DQS_DP<5> @S9S_MB_2U_LIB.S9S_MB_2U(SCH_1):M_H_CPU0_SB_DQS_DP(5)   I169 @S9S_MB_2U_LIB.S9S_MB_2U(SCH_1):PAGE27
  DF36 M_H_CPU0_SB_DQS_DP<4> @S9S_MB_2U_LIB.S9S_MB_2U(SCH_1):M_H_CPU0_SB_DQS_DP(4)   I169 @S9S_MB_2U_LIB.S9S_MB_2U(SCH_1):PAGE27
  DD18 M_H_CPU0_SB_DQS_DP<3> @S9S_MB_2U_LIB.S9S_MB_2U(SCH_1):M_H_CPU0_SB_DQS_DP(3)   I169 @S9S_MB_2U_LIB.S9S_MB_2U(SCH_1):PAGE27
  DJ21 M_H_CPU0_SB_DQS_DP<2> @S9S_MB_2U_LIB.S9S_MB_2U(SCH_1):M_H_CPU0_SB_DQS_DP(2)   I169 @S9S_MB_2U_LIB.S9S_MB_2U(SCH_1):PAGE27
  DB24 M_H_CPU0_SB_DQS_DP<1> @S9S_MB_2U_LIB.S9S_MB_2U(SCH_1):M_H_CPU0_SB_DQS_DP(1)   I169 @S9S_MB_2U_LIB.S9S_MB_2U(SCH_1):PAGE27
  DB30 M_H_CPU0_SB_DQS_DP<0> @S9S_MB_2U_LIB.S9S_MB_2U(SCH_1):M_H_CPU0_SB_DQS_DP(0)   I169 @S9S_MB_2U_LIB.S9S_MB_2U(SCH_1):PAGE27
  DC37 M_H_CPU0_SB_CB<7> @S9S_MB_2U_LIB.S9S_MB_2U(SCH_1):M_H_CPU0_SB_CB(7)   I169 @S9S_MB_2U_LIB.S9S_MB_2U(SCH_1):PAGE27
  DD38 M_H_CPU0_SB_CB<6> @S9S_MB_2U_LIB.S9S_MB_2U(SCH_1):M_H_CPU0_SB_CB(6)   I169 @S9S_MB_2U_LIB.S9S_MB_2U(SCH_1):PAGE27
  DG37 M_H_CPU0_SB_CB<5> @S9S_MB_2U_LIB.S9S_MB_2U(SCH_1):M_H_CPU0_SB_CB(5)   I169 @S9S_MB_2U_LIB.S9S_MB_2U(SCH_1):PAGE27
  DF38 M_H_CPU0_SB_CB<4> @S9S_MB_2U_LIB.S9S_MB_2U(SCH_1):M_H_CPU0_SB_CB(4)   I169 @S9S_MB_2U_LIB.S9S_MB_2U(SCH_1):PAGE27
  DF34 M_H_CPU0_SB_CB<3> @S9S_MB_2U_LIB.S9S_MB_2U(SCH_1):M_H_CPU0_SB_CB(3)   I169 @S9S_MB_2U_LIB.S9S_MB_2U(SCH_1):PAGE27
  DG35 M_H_CPU0_SB_CB<2> @S9S_MB_2U_LIB.S9S_MB_2U(SCH_1):M_H_CPU0_SB_CB(2)   I169 @S9S_MB_2U_LIB.S9S_MB_2U(SCH_1):PAGE27
  DD34 M_H_CPU0_SB_CB<1> @S9S_MB_2U_LIB.S9S_MB_2U(SCH_1):M_H_CPU0_SB_CB(1)   I169 @S9S_MB_2U_LIB.S9S_MB_2U(SCH_1):PAGE27
  DC35 M_H_CPU0_SB_CB<0> @S9S_MB_2U_LIB.S9S_MB_2U(SCH_1):M_H_CPU0_SB_CB(0)   I169 @S9S_MB_2U_LIB.S9S_MB_2U(SCH_1):PAGE27
  DR39 M_H_CPU0_SB_PAR @S9S_MB_2U_LIB.S9S_MB_2U(SCH_1):M_H_CPU0_SB_PAR   I169 @S9S_MB_2U_LIB.S9S_MB_2U(SCH_1):PAGE27
  BU17 DMI_CPU0_PCH_RX_C_DN<7> @S9S_MB_2U_LIB.S9S_MB_2U(SCH_1):DMI_CPU0_PCH_RX_C_DN(7)   I169 @S9S_MB_2U_LIB.S9S_MB_2U(SCH_1):PAGE28
  BP18 DMI_CPU0_PCH_RX_C_DP<6> @S9S_MB_2U_LIB.S9S_MB_2U(SCH_1):DMI_CPU0_PCH_RX_C_DP(6)   I169 @S9S_MB_2U_LIB.S9S_MB_2U(SCH_1):PAGE28
  BN17 DMI_CPU0_PCH_RX_C_DP<5> @S9S_MB_2U_LIB.S9S_MB_2U(SCH_1):DMI_CPU0_PCH_RX_C_DP(5)   I169 @S9S_MB_2U_LIB.S9S_MB_2U(SCH_1):PAGE28
  BK18 DMI_CPU0_PCH_RX_C_DP<4> @S9S_MB_2U_LIB.S9S_MB_2U(SCH_1):DMI_CPU0_PCH_RX_C_DP(4)   I169 @S9S_MB_2U_LIB.S9S_MB_2U(SCH_1):PAGE28
  BJ17 DMI_CPU0_PCH_RX_C_DP<3> @S9S_MB_2U_LIB.S9S_MB_2U(SCH_1):DMI_CPU0_PCH_RX_C_DP(3)   I169 @S9S_MB_2U_LIB.S9S_MB_2U(SCH_1):PAGE28
  BF18 DMI_CPU0_PCH_RX_C_DN<2> @S9S_MB_2U_LIB.S9S_MB_2U(SCH_1):DMI_CPU0_PCH_RX_C_DN(2)   I169 @S9S_MB_2U_LIB.S9S_MB_2U(SCH_1):PAGE28
  BE17 DMI_CPU0_PCH_RX_C_DP<1> @S9S_MB_2U_LIB.S9S_MB_2U(SCH_1):DMI_CPU0_PCH_RX_C_DP(1)   I169 @S9S_MB_2U_LIB.S9S_MB_2U(SCH_1):PAGE28
  BB18 DMI_CPU0_PCH_RX_C_DN<0> @S9S_MB_2U_LIB.S9S_MB_2U(SCH_1):DMI_CPU0_PCH_RX_C_DN(0)   I169 @S9S_MB_2U_LIB.S9S_MB_2U(SCH_1):PAGE28
  BT18 DMI_CPU0_PCH_RX_C_DP<7> @S9S_MB_2U_LIB.S9S_MB_2U(SCH_1):DMI_CPU0_PCH_RX_C_DP(7)   I169 @S9S_MB_2U_LIB.S9S_MB_2U(SCH_1):PAGE28
  BR19 DMI_CPU0_PCH_RX_C_DN<6> @S9S_MB_2U_LIB.S9S_MB_2U(SCH_1):DMI_CPU0_PCH_RX_C_DN(6)   I169 @S9S_MB_2U_LIB.S9S_MB_2U(SCH_1):PAGE28
  BM18 DMI_CPU0_PCH_RX_C_DN<5> @S9S_MB_2U_LIB.S9S_MB_2U(SCH_1):DMI_CPU0_PCH_RX_C_DN(5)   I169 @S9S_MB_2U_LIB.S9S_MB_2U(SCH_1):PAGE28
  BL19 DMI_CPU0_PCH_RX_C_DN<4> @S9S_MB_2U_LIB.S9S_MB_2U(SCH_1):DMI_CPU0_PCH_RX_C_DN(4)   I169 @S9S_MB_2U_LIB.S9S_MB_2U(SCH_1):PAGE28
  BH18 DMI_CPU0_PCH_RX_C_DN<3> @S9S_MB_2U_LIB.S9S_MB_2U(SCH_1):DMI_CPU0_PCH_RX_C_DN(3)   I169 @S9S_MB_2U_LIB.S9S_MB_2U(SCH_1):PAGE28
  BG19 DMI_CPU0_PCH_RX_C_DP<2> @S9S_MB_2U_LIB.S9S_MB_2U(SCH_1):DMI_CPU0_PCH_RX_C_DP(2)   I169 @S9S_MB_2U_LIB.S9S_MB_2U(SCH_1):PAGE28
  BD18 DMI_CPU0_PCH_RX_C_DN<1> @S9S_MB_2U_LIB.S9S_MB_2U(SCH_1):DMI_CPU0_PCH_RX_C_DN(1)   I169 @S9S_MB_2U_LIB.S9S_MB_2U(SCH_1):PAGE28
  BC19 DMI_CPU0_PCH_RX_C_DP<0> @S9S_MB_2U_LIB.S9S_MB_2U(SCH_1):DMI_CPU0_PCH_RX_C_DP(0)   I169 @S9S_MB_2U_LIB.S9S_MB_2U(SCH_1):PAGE28
  CN17 DMI_CPU0_PCH_TX_DP<7> @S9S_MB_2U_LIB.S9S_MB_2U(SCH_1):DMI_CPU0_PCH_TX_DP(7)   I169 @S9S_MB_2U_LIB.S9S_MB_2U(SCH_1):PAGE28
  CK18 DMI_CPU0_PCH_TX_DN<6> @S9S_MB_2U_LIB.S9S_MB_2U(SCH_1):DMI_CPU0_PCH_TX_DN(6)   I169 @S9S_MB_2U_LIB.S9S_MB_2U(SCH_1):PAGE28
  CJ17 DMI_CPU0_PCH_TX_DN<5> @S9S_MB_2U_LIB.S9S_MB_2U(SCH_1):DMI_CPU0_PCH_TX_DN(5)   I169 @S9S_MB_2U_LIB.S9S_MB_2U(SCH_1):PAGE28
  CF18 DMI_CPU0_PCH_TX_DN<4> @S9S_MB_2U_LIB.S9S_MB_2U(SCH_1):DMI_CPU0_PCH_TX_DN(4)   I169 @S9S_MB_2U_LIB.S9S_MB_2U(SCH_1):PAGE28
  CE17 DMI_CPU0_PCH_TX_DP<3> @S9S_MB_2U_LIB.S9S_MB_2U(SCH_1):DMI_CPU0_PCH_TX_DP(3)   I169 @S9S_MB_2U_LIB.S9S_MB_2U(SCH_1):PAGE28
  CB18 DMI_CPU0_PCH_TX_DP<2> @S9S_MB_2U_LIB.S9S_MB_2U(SCH_1):DMI_CPU0_PCH_TX_DP(2)   I169 @S9S_MB_2U_LIB.S9S_MB_2U(SCH_1):PAGE28
  CA17 DMI_CPU0_PCH_TX_DP<1> @S9S_MB_2U_LIB.S9S_MB_2U(SCH_1):DMI_CPU0_PCH_TX_DP(1)   I169 @S9S_MB_2U_LIB.S9S_MB_2U(SCH_1):PAGE28
  BW19 DMI_CPU0_PCH_TX_DP<0> @S9S_MB_2U_LIB.S9S_MB_2U(SCH_1):DMI_CPU0_PCH_TX_DP(0)   I169 @S9S_MB_2U_LIB.S9S_MB_2U(SCH_1):PAGE28
  CM18 DMI_CPU0_PCH_TX_DN<7> @S9S_MB_2U_LIB.S9S_MB_2U(SCH_1):DMI_CPU0_PCH_TX_DN(7)   I169 @S9S_MB_2U_LIB.S9S_MB_2U(SCH_1):PAGE28
  CL19 DMI_CPU0_PCH_TX_DP<6> @S9S_MB_2U_LIB.S9S_MB_2U(SCH_1):DMI_CPU0_PCH_TX_DP(6)   I169 @S9S_MB_2U_LIB.S9S_MB_2U(SCH_1):PAGE28
  CH18 DMI_CPU0_PCH_TX_DP<5> @S9S_MB_2U_LIB.S9S_MB_2U(SCH_1):DMI_CPU0_PCH_TX_DP(5)   I169 @S9S_MB_2U_LIB.S9S_MB_2U(SCH_1):PAGE28
  CG19 DMI_CPU0_PCH_TX_DP<4> @S9S_MB_2U_LIB.S9S_MB_2U(SCH_1):DMI_CPU0_PCH_TX_DP(4)   I169 @S9S_MB_2U_LIB.S9S_MB_2U(SCH_1):PAGE28
  CD18 DMI_CPU0_PCH_TX_DN<3> @S9S_MB_2U_LIB.S9S_MB_2U(SCH_1):DMI_CPU0_PCH_TX_DN(3)   I169 @S9S_MB_2U_LIB.S9S_MB_2U(SCH_1):PAGE28
  CC19 DMI_CPU0_PCH_TX_DN<2> @S9S_MB_2U_LIB.S9S_MB_2U(SCH_1):DMI_CPU0_PCH_TX_DN(2)   I169 @S9S_MB_2U_LIB.S9S_MB_2U(SCH_1):PAGE28
  BY18 DMI_CPU0_PCH_TX_DN<1> @S9S_MB_2U_LIB.S9S_MB_2U(SCH_1):DMI_CPU0_PCH_TX_DN(1)   I169 @S9S_MB_2U_LIB.S9S_MB_2U(SCH_1):PAGE28
  CA19 DMI_CPU0_PCH_TX_DN<0> @S9S_MB_2U_LIB.S9S_MB_2U(SCH_1):DMI_CPU0_PCH_TX_DN(0)   I169 @S9S_MB_2U_LIB.S9S_MB_2U(SCH_1):PAGE28
   BA9 P5E_CPU0_PE0_RX_DN<15> @S9S_MB_2U_LIB.S9S_MB_2U(SCH_1):P5E_CPU0_PE0_RX_DN(15)    I37 @S9S_MB_2U_LIB.S9S_MB_2U(SCH_1):PAGE29
  AV10 P5E_CPU0_PE0_RX_DN<14> @S9S_MB_2U_LIB.S9S_MB_2U(SCH_1):P5E_CPU0_PE0_RX_DN(14)    I37 @S9S_MB_2U_LIB.S9S_MB_2U(SCH_1):PAGE29
   AU9 P5E_CPU0_PE0_RX_DN<13> @S9S_MB_2U_LIB.S9S_MB_2U(SCH_1):P5E_CPU0_PE0_RX_DN(13)    I37 @S9S_MB_2U_LIB.S9S_MB_2U(SCH_1):PAGE29
  AP10 P5E_CPU0_PE0_RX_DN<12> @S9S_MB_2U_LIB.S9S_MB_2U(SCH_1):P5E_CPU0_PE0_RX_DN(12)    I37 @S9S_MB_2U_LIB.S9S_MB_2U(SCH_1):PAGE29
  AM10 P5E_CPU0_PE0_RX_DN<11> @S9S_MB_2U_LIB.S9S_MB_2U(SCH_1):P5E_CPU0_PE0_RX_DN(11)    I37 @S9S_MB_2U_LIB.S9S_MB_2U(SCH_1):PAGE29
  AK10 P5E_CPU0_PE0_RX_DN<10> @S9S_MB_2U_LIB.S9S_MB_2U(SCH_1):P5E_CPU0_PE0_RX_DN(10)    I37 @S9S_MB_2U_LIB.S9S_MB_2U(SCH_1):PAGE29
   AJ9 P5E_CPU0_PE0_RX_DN<9> @S9S_MB_2U_LIB.S9S_MB_2U(SCH_1):P5E_CPU0_PE0_RX_DN(9)    I37 @S9S_MB_2U_LIB.S9S_MB_2U(SCH_1):PAGE29
  AF10 P5E_CPU0_PE0_RX_DN<8> @S9S_MB_2U_LIB.S9S_MB_2U(SCH_1):P5E_CPU0_PE0_RX_DN(8)    I37 @S9S_MB_2U_LIB.S9S_MB_2U(SCH_1):PAGE29
   AE9 P5E_CPU0_PE0_RX_DN<7> @S9S_MB_2U_LIB.S9S_MB_2U(SCH_1):P5E_CPU0_PE0_RX_DN(7)    I37 @S9S_MB_2U_LIB.S9S_MB_2U(SCH_1):PAGE29
  AB10 P5E_CPU0_PE0_RX_DN<6> @S9S_MB_2U_LIB.S9S_MB_2U(SCH_1):P5E_CPU0_PE0_RX_DN(6)    I37 @S9S_MB_2U_LIB.S9S_MB_2U(SCH_1):PAGE29
   AA9 P5E_CPU0_PE0_RX_DN<5> @S9S_MB_2U_LIB.S9S_MB_2U(SCH_1):P5E_CPU0_PE0_RX_DN(5)    I37 @S9S_MB_2U_LIB.S9S_MB_2U(SCH_1):PAGE29
   V10 P5E_CPU0_PE0_RX_DN<4> @S9S_MB_2U_LIB.S9S_MB_2U(SCH_1):P5E_CPU0_PE0_RX_DN(4)    I37 @S9S_MB_2U_LIB.S9S_MB_2U(SCH_1):PAGE29
   T10 P5E_CPU0_PE0_RX_DN<3> @S9S_MB_2U_LIB.S9S_MB_2U(SCH_1):P5E_CPU0_PE0_RX_DN(3)    I37 @S9S_MB_2U_LIB.S9S_MB_2U(SCH_1):PAGE29
   P10 P5E_CPU0_PE0_RX_DN<2> @S9S_MB_2U_LIB.S9S_MB_2U(SCH_1):P5E_CPU0_PE0_RX_DN(2)    I37 @S9S_MB_2U_LIB.S9S_MB_2U(SCH_1):PAGE29
   M10 P5E_CPU0_PE0_RX_DN<1> @S9S_MB_2U_LIB.S9S_MB_2U(SCH_1):P5E_CPU0_PE0_RX_DN(1)    I37 @S9S_MB_2U_LIB.S9S_MB_2U(SCH_1):PAGE29
   K10 P5E_CPU0_PE0_RX_DN<0> @S9S_MB_2U_LIB.S9S_MB_2U(SCH_1):P5E_CPU0_PE0_RX_DN(0)    I37 @S9S_MB_2U_LIB.S9S_MB_2U(SCH_1):PAGE29
  AY10 P5E_CPU0_PE0_RX_DP<15> @S9S_MB_2U_LIB.S9S_MB_2U(SCH_1):P5E_CPU0_PE0_RX_DP(15)    I37 @S9S_MB_2U_LIB.S9S_MB_2U(SCH_1):PAGE29
  AW11 P5E_CPU0_PE0_RX_DP<14> @S9S_MB_2U_LIB.S9S_MB_2U(SCH_1):P5E_CPU0_PE0_RX_DP(14)    I37 @S9S_MB_2U_LIB.S9S_MB_2U(SCH_1):PAGE29
  AT10 P5E_CPU0_PE0_RX_DP<13> @S9S_MB_2U_LIB.S9S_MB_2U(SCH_1):P5E_CPU0_PE0_RX_DP(13)    I37 @S9S_MB_2U_LIB.S9S_MB_2U(SCH_1):PAGE29
  AR11 P5E_CPU0_PE0_RX_DP<12> @S9S_MB_2U_LIB.S9S_MB_2U(SCH_1):P5E_CPU0_PE0_RX_DP(12)    I37 @S9S_MB_2U_LIB.S9S_MB_2U(SCH_1):PAGE29
   AN9 P5E_CPU0_PE0_RX_DP<11> @S9S_MB_2U_LIB.S9S_MB_2U(SCH_1):P5E_CPU0_PE0_RX_DP(11)    I37 @S9S_MB_2U_LIB.S9S_MB_2U(SCH_1):PAGE29
  AL11 P5E_CPU0_PE0_RX_DP<10> @S9S_MB_2U_LIB.S9S_MB_2U(SCH_1):P5E_CPU0_PE0_RX_DP(10)    I37 @S9S_MB_2U_LIB.S9S_MB_2U(SCH_1):PAGE29
  AH10 P5E_CPU0_PE0_RX_DP<9> @S9S_MB_2U_LIB.S9S_MB_2U(SCH_1):P5E_CPU0_PE0_RX_DP(9)    I37 @S9S_MB_2U_LIB.S9S_MB_2U(SCH_1):PAGE29
  AG11 P5E_CPU0_PE0_RX_DP<8> @S9S_MB_2U_LIB.S9S_MB_2U(SCH_1):P5E_CPU0_PE0_RX_DP(8)    I37 @S9S_MB_2U_LIB.S9S_MB_2U(SCH_1):PAGE29
  AD10 P5E_CPU0_PE0_RX_DP<7> @S9S_MB_2U_LIB.S9S_MB_2U(SCH_1):P5E_CPU0_PE0_RX_DP(7)    I37 @S9S_MB_2U_LIB.S9S_MB_2U(SCH_1):PAGE29
  AC11 P5E_CPU0_PE0_RX_DP<6> @S9S_MB_2U_LIB.S9S_MB_2U(SCH_1):P5E_CPU0_PE0_RX_DP(6)    I37 @S9S_MB_2U_LIB.S9S_MB_2U(SCH_1):PAGE29
   Y10 P5E_CPU0_PE0_RX_DP<5> @S9S_MB_2U_LIB.S9S_MB_2U(SCH_1):P5E_CPU0_PE0_RX_DP(5)    I37 @S9S_MB_2U_LIB.S9S_MB_2U(SCH_1):PAGE29
   W11 P5E_CPU0_PE0_RX_DP<4> @S9S_MB_2U_LIB.S9S_MB_2U(SCH_1):P5E_CPU0_PE0_RX_DP(4)    I37 @S9S_MB_2U_LIB.S9S_MB_2U(SCH_1):PAGE29
    U9 P5E_CPU0_PE0_RX_DP<3> @S9S_MB_2U_LIB.S9S_MB_2U(SCH_1):P5E_CPU0_PE0_RX_DP(3)    I37 @S9S_MB_2U_LIB.S9S_MB_2U(SCH_1):PAGE29
   R11 P5E_CPU0_PE0_RX_DP<2> @S9S_MB_2U_LIB.S9S_MB_2U(SCH_1):P5E_CPU0_PE0_RX_DP(2)    I37 @S9S_MB_2U_LIB.S9S_MB_2U(SCH_1):PAGE29
    N9 P5E_CPU0_PE0_RX_DP<1> @S9S_MB_2U_LIB.S9S_MB_2U(SCH_1):P5E_CPU0_PE0_RX_DP(1)    I37 @S9S_MB_2U_LIB.S9S_MB_2U(SCH_1):PAGE29
   L11 P5E_CPU0_PE0_RX_DP<0> @S9S_MB_2U_LIB.S9S_MB_2U(SCH_1):P5E_CPU0_PE0_RX_DP(0)    I37 @S9S_MB_2U_LIB.S9S_MB_2U(SCH_1):PAGE29
  BB14 P5E_CPU0_PE0_TX_DN<15> @S9S_MB_2U_LIB.S9S_MB_2U(SCH_1):P5E_CPU0_PE0_TX_DN(15)    I37 @S9S_MB_2U_LIB.S9S_MB_2U(SCH_1):PAGE29
  BA13 P5E_CPU0_PE0_TX_DN<14> @S9S_MB_2U_LIB.S9S_MB_2U(SCH_1):P5E_CPU0_PE0_TX_DN(14)    I37 @S9S_MB_2U_LIB.S9S_MB_2U(SCH_1):PAGE29
  AV14 P5E_CPU0_PE0_TX_DN<13> @S9S_MB_2U_LIB.S9S_MB_2U(SCH_1):P5E_CPU0_PE0_TX_DN(13)    I37 @S9S_MB_2U_LIB.S9S_MB_2U(SCH_1):PAGE29
  AU13 P5E_CPU0_PE0_TX_DN<12> @S9S_MB_2U_LIB.S9S_MB_2U(SCH_1):P5E_CPU0_PE0_TX_DN(12)    I37 @S9S_MB_2U_LIB.S9S_MB_2U(SCH_1):PAGE29
  AP14 P5E_CPU0_PE0_TX_DN<11> @S9S_MB_2U_LIB.S9S_MB_2U(SCH_1):P5E_CPU0_PE0_TX_DN(11)    I37 @S9S_MB_2U_LIB.S9S_MB_2U(SCH_1):PAGE29
  AN13 P5E_CPU0_PE0_TX_DN<10> @S9S_MB_2U_LIB.S9S_MB_2U(SCH_1):P5E_CPU0_PE0_TX_DN(10)    I37 @S9S_MB_2U_LIB.S9S_MB_2U(SCH_1):PAGE29
  AK14 P5E_CPU0_PE0_TX_DN<9> @S9S_MB_2U_LIB.S9S_MB_2U(SCH_1):P5E_CPU0_PE0_TX_DN(9)    I37 @S9S_MB_2U_LIB.S9S_MB_2U(SCH_1):PAGE29
  AJ13 P5E_CPU0_PE0_TX_DN<8> @S9S_MB_2U_LIB.S9S_MB_2U(SCH_1):P5E_CPU0_PE0_TX_DN(8)    I37 @S9S_MB_2U_LIB.S9S_MB_2U(SCH_1):PAGE29
  AF14 P5E_CPU0_PE0_TX_DN<7> @S9S_MB_2U_LIB.S9S_MB_2U(SCH_1):P5E_CPU0_PE0_TX_DN(7)    I37 @S9S_MB_2U_LIB.S9S_MB_2U(SCH_1):PAGE29
  AE13 P5E_CPU0_PE0_TX_DN<6> @S9S_MB_2U_LIB.S9S_MB_2U(SCH_1):P5E_CPU0_PE0_TX_DN(6)    I37 @S9S_MB_2U_LIB.S9S_MB_2U(SCH_1):PAGE29
  AB14 P5E_CPU0_PE0_TX_DN<5> @S9S_MB_2U_LIB.S9S_MB_2U(SCH_1):P5E_CPU0_PE0_TX_DN(5)    I37 @S9S_MB_2U_LIB.S9S_MB_2U(SCH_1):PAGE29
  AA13 P5E_CPU0_PE0_TX_DN<4> @S9S_MB_2U_LIB.S9S_MB_2U(SCH_1):P5E_CPU0_PE0_TX_DN(4)    I37 @S9S_MB_2U_LIB.S9S_MB_2U(SCH_1):PAGE29
   V14 P5E_CPU0_PE0_TX_DN<3> @S9S_MB_2U_LIB.S9S_MB_2U(SCH_1):P5E_CPU0_PE0_TX_DN(3)    I37 @S9S_MB_2U_LIB.S9S_MB_2U(SCH_1):PAGE29
   U13 P5E_CPU0_PE0_TX_DN<2> @S9S_MB_2U_LIB.S9S_MB_2U(SCH_1):P5E_CPU0_PE0_TX_DN(2)    I37 @S9S_MB_2U_LIB.S9S_MB_2U(SCH_1):PAGE29
   P14 P5E_CPU0_PE0_TX_DN<1> @S9S_MB_2U_LIB.S9S_MB_2U(SCH_1):P5E_CPU0_PE0_TX_DN(1)    I37 @S9S_MB_2U_LIB.S9S_MB_2U(SCH_1):PAGE29
   N13 P5E_CPU0_PE0_TX_DN<0> @S9S_MB_2U_LIB.S9S_MB_2U(SCH_1):P5E_CPU0_PE0_TX_DN(0)    I37 @S9S_MB_2U_LIB.S9S_MB_2U(SCH_1):PAGE29
  BC15 P5E_CPU0_PE0_TX_DP<15> @S9S_MB_2U_LIB.S9S_MB_2U(SCH_1):P5E_CPU0_PE0_TX_DP(15)    I37 @S9S_MB_2U_LIB.S9S_MB_2U(SCH_1):PAGE29
  AY14 P5E_CPU0_PE0_TX_DP<14> @S9S_MB_2U_LIB.S9S_MB_2U(SCH_1):P5E_CPU0_PE0_TX_DP(14)    I37 @S9S_MB_2U_LIB.S9S_MB_2U(SCH_1):PAGE29
  AW15 P5E_CPU0_PE0_TX_DP<13> @S9S_MB_2U_LIB.S9S_MB_2U(SCH_1):P5E_CPU0_PE0_TX_DP(13)    I37 @S9S_MB_2U_LIB.S9S_MB_2U(SCH_1):PAGE29
  AT14 P5E_CPU0_PE0_TX_DP<12> @S9S_MB_2U_LIB.S9S_MB_2U(SCH_1):P5E_CPU0_PE0_TX_DP(12)    I37 @S9S_MB_2U_LIB.S9S_MB_2U(SCH_1):PAGE29
  AR15 P5E_CPU0_PE0_TX_DP<11> @S9S_MB_2U_LIB.S9S_MB_2U(SCH_1):P5E_CPU0_PE0_TX_DP(11)    I37 @S9S_MB_2U_LIB.S9S_MB_2U(SCH_1):PAGE29
  AM14 P5E_CPU0_PE0_TX_DP<10> @S9S_MB_2U_LIB.S9S_MB_2U(SCH_1):P5E_CPU0_PE0_TX_DP(10)    I37 @S9S_MB_2U_LIB.S9S_MB_2U(SCH_1):PAGE29
  AL15 P5E_CPU0_PE0_TX_DP<9> @S9S_MB_2U_LIB.S9S_MB_2U(SCH_1):P5E_CPU0_PE0_TX_DP(9)    I37 @S9S_MB_2U_LIB.S9S_MB_2U(SCH_1):PAGE29
  AH14 P5E_CPU0_PE0_TX_DP<8> @S9S_MB_2U_LIB.S9S_MB_2U(SCH_1):P5E_CPU0_PE0_TX_DP(8)    I37 @S9S_MB_2U_LIB.S9S_MB_2U(SCH_1):PAGE29
  AG15 P5E_CPU0_PE0_TX_DP<7> @S9S_MB_2U_LIB.S9S_MB_2U(SCH_1):P5E_CPU0_PE0_TX_DP(7)    I37 @S9S_MB_2U_LIB.S9S_MB_2U(SCH_1):PAGE29
  AD14 P5E_CPU0_PE0_TX_DP<6> @S9S_MB_2U_LIB.S9S_MB_2U(SCH_1):P5E_CPU0_PE0_TX_DP(6)    I37 @S9S_MB_2U_LIB.S9S_MB_2U(SCH_1):PAGE29
  AC15 P5E_CPU0_PE0_TX_DP<5> @S9S_MB_2U_LIB.S9S_MB_2U(SCH_1):P5E_CPU0_PE0_TX_DP(5)    I37 @S9S_MB_2U_LIB.S9S_MB_2U(SCH_1):PAGE29
   Y14 P5E_CPU0_PE0_TX_DP<4> @S9S_MB_2U_LIB.S9S_MB_2U(SCH_1):P5E_CPU0_PE0_TX_DP(4)    I37 @S9S_MB_2U_LIB.S9S_MB_2U(SCH_1):PAGE29
   W15 P5E_CPU0_PE0_TX_DP<3> @S9S_MB_2U_LIB.S9S_MB_2U(SCH_1):P5E_CPU0_PE0_TX_DP(3)    I37 @S9S_MB_2U_LIB.S9S_MB_2U(SCH_1):PAGE29
   T14 P5E_CPU0_PE0_TX_DP<2> @S9S_MB_2U_LIB.S9S_MB_2U(SCH_1):P5E_CPU0_PE0_TX_DP(2)    I37 @S9S_MB_2U_LIB.S9S_MB_2U(SCH_1):PAGE29
   R15 P5E_CPU0_PE0_TX_DP<1> @S9S_MB_2U_LIB.S9S_MB_2U(SCH_1):P5E_CPU0_PE0_TX_DP(1)    I37 @S9S_MB_2U_LIB.S9S_MB_2U(SCH_1):PAGE29
   M14 P5E_CPU0_PE0_TX_DP<0> @S9S_MB_2U_LIB.S9S_MB_2U(SCH_1):P5E_CPU0_PE0_TX_DP(0)    I37 @S9S_MB_2U_LIB.S9S_MB_2U(SCH_1):PAGE29
  BC11 P5E_CPU0_PE1_RX_DN<15> @S9S_MB_2U_LIB.S9S_MB_2U(SCH_1):P5E_CPU0_PE1_RX_DN(15)   I176 @S9S_MB_2U_LIB.S9S_MB_2U(SCH_1):PAGE29
  BF10 P5E_CPU0_PE1_RX_DN<14> @S9S_MB_2U_LIB.S9S_MB_2U(SCH_1):P5E_CPU0_PE1_RX_DN(14)   I176 @S9S_MB_2U_LIB.S9S_MB_2U(SCH_1):PAGE29
  BG11 P5E_CPU0_PE1_RX_DN<13> @S9S_MB_2U_LIB.S9S_MB_2U(SCH_1):P5E_CPU0_PE1_RX_DN(13)   I176 @S9S_MB_2U_LIB.S9S_MB_2U(SCH_1):PAGE29
  BK10 P5E_CPU0_PE1_RX_DN<12> @S9S_MB_2U_LIB.S9S_MB_2U(SCH_1):P5E_CPU0_PE1_RX_DN(12)   I176 @S9S_MB_2U_LIB.S9S_MB_2U(SCH_1):PAGE29
  BL11 P5E_CPU0_PE1_RX_DN<11> @S9S_MB_2U_LIB.S9S_MB_2U(SCH_1):P5E_CPU0_PE1_RX_DN(11)   I176 @S9S_MB_2U_LIB.S9S_MB_2U(SCH_1):PAGE29
  BP10 P5E_CPU0_PE1_RX_DN<10> @S9S_MB_2U_LIB.S9S_MB_2U(SCH_1):P5E_CPU0_PE1_RX_DN(10)   I176 @S9S_MB_2U_LIB.S9S_MB_2U(SCH_1):PAGE29
  BR11 P5E_CPU0_PE1_RX_DN<9> @S9S_MB_2U_LIB.S9S_MB_2U(SCH_1):P5E_CPU0_PE1_RX_DN(9)   I176 @S9S_MB_2U_LIB.S9S_MB_2U(SCH_1):PAGE29
  BV10 P5E_CPU0_PE1_RX_DN<8> @S9S_MB_2U_LIB.S9S_MB_2U(SCH_1):P5E_CPU0_PE1_RX_DN(8)   I176 @S9S_MB_2U_LIB.S9S_MB_2U(SCH_1):PAGE29
  BW11 P5E_CPU0_PE1_RX_DN<7> @S9S_MB_2U_LIB.S9S_MB_2U(SCH_1):P5E_CPU0_PE1_RX_DN(7)   I176 @S9S_MB_2U_LIB.S9S_MB_2U(SCH_1):PAGE29
  CB10 P5E_CPU0_PE1_RX_DN<6> @S9S_MB_2U_LIB.S9S_MB_2U(SCH_1):P5E_CPU0_PE1_RX_DN(6)   I176 @S9S_MB_2U_LIB.S9S_MB_2U(SCH_1):PAGE29
  CC11 P5E_CPU0_PE1_RX_DN<5> @S9S_MB_2U_LIB.S9S_MB_2U(SCH_1):P5E_CPU0_PE1_RX_DN(5)   I176 @S9S_MB_2U_LIB.S9S_MB_2U(SCH_1):PAGE29
  CF10 P5E_CPU0_PE1_RX_DN<4> @S9S_MB_2U_LIB.S9S_MB_2U(SCH_1):P5E_CPU0_PE1_RX_DN(4)   I176 @S9S_MB_2U_LIB.S9S_MB_2U(SCH_1):PAGE29
  CG11 P5E_CPU0_PE1_RX_DN<3> @S9S_MB_2U_LIB.S9S_MB_2U(SCH_1):P5E_CPU0_PE1_RX_DN(3)   I176 @S9S_MB_2U_LIB.S9S_MB_2U(SCH_1):PAGE29
  CK10 P5E_CPU0_PE1_RX_DN<2> @S9S_MB_2U_LIB.S9S_MB_2U(SCH_1):P5E_CPU0_PE1_RX_DN(2)   I176 @S9S_MB_2U_LIB.S9S_MB_2U(SCH_1):PAGE29
  CL11 P5E_CPU0_PE1_RX_DN<1> @S9S_MB_2U_LIB.S9S_MB_2U(SCH_1):P5E_CPU0_PE1_RX_DN(1)   I176 @S9S_MB_2U_LIB.S9S_MB_2U(SCH_1):PAGE29
  CP10 P5E_CPU0_PE1_RX_DN<0> @S9S_MB_2U_LIB.S9S_MB_2U(SCH_1):P5E_CPU0_PE1_RX_DN(0)   I176 @S9S_MB_2U_LIB.S9S_MB_2U(SCH_1):PAGE29
  BD10 P5E_CPU0_PE1_RX_DP<15> @S9S_MB_2U_LIB.S9S_MB_2U(SCH_1):P5E_CPU0_PE1_RX_DP(15)   I176 @S9S_MB_2U_LIB.S9S_MB_2U(SCH_1):PAGE29
   BE9 P5E_CPU0_PE1_RX_DP<14> @S9S_MB_2U_LIB.S9S_MB_2U(SCH_1):P5E_CPU0_PE1_RX_DP(14)   I176 @S9S_MB_2U_LIB.S9S_MB_2U(SCH_1):PAGE29
  BH10 P5E_CPU0_PE1_RX_DP<13> @S9S_MB_2U_LIB.S9S_MB_2U(SCH_1):P5E_CPU0_PE1_RX_DP(13)   I176 @S9S_MB_2U_LIB.S9S_MB_2U(SCH_1):PAGE29
   BJ9 P5E_CPU0_PE1_RX_DP<12> @S9S_MB_2U_LIB.S9S_MB_2U(SCH_1):P5E_CPU0_PE1_RX_DP(12)   I176 @S9S_MB_2U_LIB.S9S_MB_2U(SCH_1):PAGE29
  BM10 P5E_CPU0_PE1_RX_DP<11> @S9S_MB_2U_LIB.S9S_MB_2U(SCH_1):P5E_CPU0_PE1_RX_DP(11)   I176 @S9S_MB_2U_LIB.S9S_MB_2U(SCH_1):PAGE29
   BN9 P5E_CPU0_PE1_RX_DP<10> @S9S_MB_2U_LIB.S9S_MB_2U(SCH_1):P5E_CPU0_PE1_RX_DP(10)   I176 @S9S_MB_2U_LIB.S9S_MB_2U(SCH_1):PAGE29
  BT10 P5E_CPU0_PE1_RX_DP<9> @S9S_MB_2U_LIB.S9S_MB_2U(SCH_1):P5E_CPU0_PE1_RX_DP(9)   I176 @S9S_MB_2U_LIB.S9S_MB_2U(SCH_1):PAGE29
   BU9 P5E_CPU0_PE1_RX_DP<8> @S9S_MB_2U_LIB.S9S_MB_2U(SCH_1):P5E_CPU0_PE1_RX_DP(8)   I176 @S9S_MB_2U_LIB.S9S_MB_2U(SCH_1):PAGE29
  BY10 P5E_CPU0_PE1_RX_DP<7> @S9S_MB_2U_LIB.S9S_MB_2U(SCH_1):P5E_CPU0_PE1_RX_DP(7)   I176 @S9S_MB_2U_LIB.S9S_MB_2U(SCH_1):PAGE29
   CA9 P5E_CPU0_PE1_RX_DP<6> @S9S_MB_2U_LIB.S9S_MB_2U(SCH_1):P5E_CPU0_PE1_RX_DP(6)   I176 @S9S_MB_2U_LIB.S9S_MB_2U(SCH_1):PAGE29
  CD10 P5E_CPU0_PE1_RX_DP<5> @S9S_MB_2U_LIB.S9S_MB_2U(SCH_1):P5E_CPU0_PE1_RX_DP(5)   I176 @S9S_MB_2U_LIB.S9S_MB_2U(SCH_1):PAGE29
   CE9 P5E_CPU0_PE1_RX_DP<4> @S9S_MB_2U_LIB.S9S_MB_2U(SCH_1):P5E_CPU0_PE1_RX_DP(4)   I176 @S9S_MB_2U_LIB.S9S_MB_2U(SCH_1):PAGE29
  CH10 P5E_CPU0_PE1_RX_DP<3> @S9S_MB_2U_LIB.S9S_MB_2U(SCH_1):P5E_CPU0_PE1_RX_DP(3)   I176 @S9S_MB_2U_LIB.S9S_MB_2U(SCH_1):PAGE29
   CJ9 P5E_CPU0_PE1_RX_DP<2> @S9S_MB_2U_LIB.S9S_MB_2U(SCH_1):P5E_CPU0_PE1_RX_DP(2)   I176 @S9S_MB_2U_LIB.S9S_MB_2U(SCH_1):PAGE29
  CM10 P5E_CPU0_PE1_RX_DP<1> @S9S_MB_2U_LIB.S9S_MB_2U(SCH_1):P5E_CPU0_PE1_RX_DP(1)   I176 @S9S_MB_2U_LIB.S9S_MB_2U(SCH_1):PAGE29
   CN9 P5E_CPU0_PE1_RX_DP<0> @S9S_MB_2U_LIB.S9S_MB_2U(SCH_1):P5E_CPU0_PE1_RX_DP(0)   I176 @S9S_MB_2U_LIB.S9S_MB_2U(SCH_1):PAGE29
  BE13 P5E_CPU0_PE1_TX_DN<15> @S9S_MB_2U_LIB.S9S_MB_2U(SCH_1):P5E_CPU0_PE1_TX_DN(15)   I176 @S9S_MB_2U_LIB.S9S_MB_2U(SCH_1):PAGE29
  BF14 P5E_CPU0_PE1_TX_DN<14> @S9S_MB_2U_LIB.S9S_MB_2U(SCH_1):P5E_CPU0_PE1_TX_DN(14)   I176 @S9S_MB_2U_LIB.S9S_MB_2U(SCH_1):PAGE29
  BJ13 P5E_CPU0_PE1_TX_DN<13> @S9S_MB_2U_LIB.S9S_MB_2U(SCH_1):P5E_CPU0_PE1_TX_DN(13)   I176 @S9S_MB_2U_LIB.S9S_MB_2U(SCH_1):PAGE29
  BK14 P5E_CPU0_PE1_TX_DN<12> @S9S_MB_2U_LIB.S9S_MB_2U(SCH_1):P5E_CPU0_PE1_TX_DN(12)   I176 @S9S_MB_2U_LIB.S9S_MB_2U(SCH_1):PAGE29
  BN13 P5E_CPU0_PE1_TX_DN<11> @S9S_MB_2U_LIB.S9S_MB_2U(SCH_1):P5E_CPU0_PE1_TX_DN(11)   I176 @S9S_MB_2U_LIB.S9S_MB_2U(SCH_1):PAGE29
  BP14 P5E_CPU0_PE1_TX_DN<10> @S9S_MB_2U_LIB.S9S_MB_2U(SCH_1):P5E_CPU0_PE1_TX_DN(10)   I176 @S9S_MB_2U_LIB.S9S_MB_2U(SCH_1):PAGE29
  BU13 P5E_CPU0_PE1_TX_DN<9> @S9S_MB_2U_LIB.S9S_MB_2U(SCH_1):P5E_CPU0_PE1_TX_DN(9)   I176 @S9S_MB_2U_LIB.S9S_MB_2U(SCH_1):PAGE29
  BV14 P5E_CPU0_PE1_TX_DN<8> @S9S_MB_2U_LIB.S9S_MB_2U(SCH_1):P5E_CPU0_PE1_TX_DN(8)   I176 @S9S_MB_2U_LIB.S9S_MB_2U(SCH_1):PAGE29
  CA13 P5E_CPU0_PE1_TX_DN<7> @S9S_MB_2U_LIB.S9S_MB_2U(SCH_1):P5E_CPU0_PE1_TX_DN(7)   I176 @S9S_MB_2U_LIB.S9S_MB_2U(SCH_1):PAGE29
  CB14 P5E_CPU0_PE1_TX_DN<6> @S9S_MB_2U_LIB.S9S_MB_2U(SCH_1):P5E_CPU0_PE1_TX_DN(6)   I176 @S9S_MB_2U_LIB.S9S_MB_2U(SCH_1):PAGE29
  CE13 P5E_CPU0_PE1_TX_DN<5> @S9S_MB_2U_LIB.S9S_MB_2U(SCH_1):P5E_CPU0_PE1_TX_DN(5)   I176 @S9S_MB_2U_LIB.S9S_MB_2U(SCH_1):PAGE29
  CF14 P5E_CPU0_PE1_TX_DN<4> @S9S_MB_2U_LIB.S9S_MB_2U(SCH_1):P5E_CPU0_PE1_TX_DN(4)   I176 @S9S_MB_2U_LIB.S9S_MB_2U(SCH_1):PAGE29
  CJ13 P5E_CPU0_PE1_TX_DN<3> @S9S_MB_2U_LIB.S9S_MB_2U(SCH_1):P5E_CPU0_PE1_TX_DN(3)   I176 @S9S_MB_2U_LIB.S9S_MB_2U(SCH_1):PAGE29
  CK14 P5E_CPU0_PE1_TX_DN<2> @S9S_MB_2U_LIB.S9S_MB_2U(SCH_1):P5E_CPU0_PE1_TX_DN(2)   I176 @S9S_MB_2U_LIB.S9S_MB_2U(SCH_1):PAGE29
  CN13 P5E_CPU0_PE1_TX_DN<1> @S9S_MB_2U_LIB.S9S_MB_2U(SCH_1):P5E_CPU0_PE1_TX_DN(1)   I176 @S9S_MB_2U_LIB.S9S_MB_2U(SCH_1):PAGE29
  CP14 P5E_CPU0_PE1_TX_DN<0> @S9S_MB_2U_LIB.S9S_MB_2U(SCH_1):P5E_CPU0_PE1_TX_DN(0)   I176 @S9S_MB_2U_LIB.S9S_MB_2U(SCH_1):PAGE29
  BD14 P5E_CPU0_PE1_TX_DP<15> @S9S_MB_2U_LIB.S9S_MB_2U(SCH_1):P5E_CPU0_PE1_TX_DP(15)   I176 @S9S_MB_2U_LIB.S9S_MB_2U(SCH_1):PAGE29
  BG15 P5E_CPU0_PE1_TX_DP<14> @S9S_MB_2U_LIB.S9S_MB_2U(SCH_1):P5E_CPU0_PE1_TX_DP(14)   I176 @S9S_MB_2U_LIB.S9S_MB_2U(SCH_1):PAGE29
  BH14 P5E_CPU0_PE1_TX_DP<13> @S9S_MB_2U_LIB.S9S_MB_2U(SCH_1):P5E_CPU0_PE1_TX_DP(13)   I176 @S9S_MB_2U_LIB.S9S_MB_2U(SCH_1):PAGE29
  BL15 P5E_CPU0_PE1_TX_DP<12> @S9S_MB_2U_LIB.S9S_MB_2U(SCH_1):P5E_CPU0_PE1_TX_DP(12)   I176 @S9S_MB_2U_LIB.S9S_MB_2U(SCH_1):PAGE29
  BM14 P5E_CPU0_PE1_TX_DP<11> @S9S_MB_2U_LIB.S9S_MB_2U(SCH_1):P5E_CPU0_PE1_TX_DP(11)   I176 @S9S_MB_2U_LIB.S9S_MB_2U(SCH_1):PAGE29
  BR15 P5E_CPU0_PE1_TX_DP<10> @S9S_MB_2U_LIB.S9S_MB_2U(SCH_1):P5E_CPU0_PE1_TX_DP(10)   I176 @S9S_MB_2U_LIB.S9S_MB_2U(SCH_1):PAGE29
  BT14 P5E_CPU0_PE1_TX_DP<9> @S9S_MB_2U_LIB.S9S_MB_2U(SCH_1):P5E_CPU0_PE1_TX_DP(9)   I176 @S9S_MB_2U_LIB.S9S_MB_2U(SCH_1):PAGE29
  BW15 P5E_CPU0_PE1_TX_DP<8> @S9S_MB_2U_LIB.S9S_MB_2U(SCH_1):P5E_CPU0_PE1_TX_DP(8)   I176 @S9S_MB_2U_LIB.S9S_MB_2U(SCH_1):PAGE29
  BY14 P5E_CPU0_PE1_TX_DP<7> @S9S_MB_2U_LIB.S9S_MB_2U(SCH_1):P5E_CPU0_PE1_TX_DP(7)   I176 @S9S_MB_2U_LIB.S9S_MB_2U(SCH_1):PAGE29
  CC15 P5E_CPU0_PE1_TX_DP<6> @S9S_MB_2U_LIB.S9S_MB_2U(SCH_1):P5E_CPU0_PE1_TX_DP(6)   I176 @S9S_MB_2U_LIB.S9S_MB_2U(SCH_1):PAGE29
  CD14 P5E_CPU0_PE1_TX_DP<5> @S9S_MB_2U_LIB.S9S_MB_2U(SCH_1):P5E_CPU0_PE1_TX_DP(5)   I176 @S9S_MB_2U_LIB.S9S_MB_2U(SCH_1):PAGE29
  CG15 P5E_CPU0_PE1_TX_DP<4> @S9S_MB_2U_LIB.S9S_MB_2U(SCH_1):P5E_CPU0_PE1_TX_DP(4)   I176 @S9S_MB_2U_LIB.S9S_MB_2U(SCH_1):PAGE29
  CH14 P5E_CPU0_PE1_TX_DP<3> @S9S_MB_2U_LIB.S9S_MB_2U(SCH_1):P5E_CPU0_PE1_TX_DP(3)   I176 @S9S_MB_2U_LIB.S9S_MB_2U(SCH_1):PAGE29
  CL15 P5E_CPU0_PE1_TX_DP<2> @S9S_MB_2U_LIB.S9S_MB_2U(SCH_1):P5E_CPU0_PE1_TX_DP(2)   I176 @S9S_MB_2U_LIB.S9S_MB_2U(SCH_1):PAGE29
  CM14 P5E_CPU0_PE1_TX_DP<1> @S9S_MB_2U_LIB.S9S_MB_2U(SCH_1):P5E_CPU0_PE1_TX_DP(1)   I176 @S9S_MB_2U_LIB.S9S_MB_2U(SCH_1):PAGE29
  CR15 P5E_CPU0_PE1_TX_DP<0> @S9S_MB_2U_LIB.S9S_MB_2U(SCH_1):P5E_CPU0_PE1_TX_DP(0)   I176 @S9S_MB_2U_LIB.S9S_MB_2U(SCH_1):PAGE29
  EH10 P5E_CPU0_PE2_RX_DN<15> @S9S_MB_2U_LIB.S9S_MB_2U(SCH_1):P5E_CPU0_PE2_RX_DN(15)   I139 @S9S_MB_2U_LIB.S9S_MB_2U(SCH_1):PAGE30
   EE9 P5E_CPU0_PE2_RX_DN<14> @S9S_MB_2U_LIB.S9S_MB_2U(SCH_1):P5E_CPU0_PE2_RX_DN(14)   I139 @S9S_MB_2U_LIB.S9S_MB_2U(SCH_1):PAGE30
  ED10 P5E_CPU0_PE2_RX_DN<13> @S9S_MB_2U_LIB.S9S_MB_2U(SCH_1):P5E_CPU0_PE2_RX_DN(13)   I139 @S9S_MB_2U_LIB.S9S_MB_2U(SCH_1):PAGE30
   EA9 P5E_CPU0_PE2_RX_DN<12> @S9S_MB_2U_LIB.S9S_MB_2U(SCH_1):P5E_CPU0_PE2_RX_DN(12)   I139 @S9S_MB_2U_LIB.S9S_MB_2U(SCH_1):PAGE30
  DY10 P5E_CPU0_PE2_RX_DN<11> @S9S_MB_2U_LIB.S9S_MB_2U(SCH_1):P5E_CPU0_PE2_RX_DN(11)   I139 @S9S_MB_2U_LIB.S9S_MB_2U(SCH_1):PAGE30
   DU9 P5E_CPU0_PE2_RX_DN<10> @S9S_MB_2U_LIB.S9S_MB_2U(SCH_1):P5E_CPU0_PE2_RX_DN(10)   I139 @S9S_MB_2U_LIB.S9S_MB_2U(SCH_1):PAGE30
  DT10 P5E_CPU0_PE2_RX_DN<9> @S9S_MB_2U_LIB.S9S_MB_2U(SCH_1):P5E_CPU0_PE2_RX_DN(9)   I139 @S9S_MB_2U_LIB.S9S_MB_2U(SCH_1):PAGE30
   DN9 P5E_CPU0_PE2_RX_DN<8> @S9S_MB_2U_LIB.S9S_MB_2U(SCH_1):P5E_CPU0_PE2_RX_DN(8)   I139 @S9S_MB_2U_LIB.S9S_MB_2U(SCH_1):PAGE30
  DM10 P5E_CPU0_PE2_RX_DN<7> @S9S_MB_2U_LIB.S9S_MB_2U(SCH_1):P5E_CPU0_PE2_RX_DN(7)   I139 @S9S_MB_2U_LIB.S9S_MB_2U(SCH_1):PAGE30
   DJ9 P5E_CPU0_PE2_RX_DN<6> @S9S_MB_2U_LIB.S9S_MB_2U(SCH_1):P5E_CPU0_PE2_RX_DN(6)   I139 @S9S_MB_2U_LIB.S9S_MB_2U(SCH_1):PAGE30
  DH10 P5E_CPU0_PE2_RX_DN<5> @S9S_MB_2U_LIB.S9S_MB_2U(SCH_1):P5E_CPU0_PE2_RX_DN(5)   I139 @S9S_MB_2U_LIB.S9S_MB_2U(SCH_1):PAGE30
   DE9 P5E_CPU0_PE2_RX_DN<4> @S9S_MB_2U_LIB.S9S_MB_2U(SCH_1):P5E_CPU0_PE2_RX_DN(4)   I139 @S9S_MB_2U_LIB.S9S_MB_2U(SCH_1):PAGE30
  DD10 P5E_CPU0_PE2_RX_DN<3> @S9S_MB_2U_LIB.S9S_MB_2U(SCH_1):P5E_CPU0_PE2_RX_DN(3)   I139 @S9S_MB_2U_LIB.S9S_MB_2U(SCH_1):PAGE30
   DA9 P5E_CPU0_PE2_RX_DN<2> @S9S_MB_2U_LIB.S9S_MB_2U(SCH_1):P5E_CPU0_PE2_RX_DN(2)   I139 @S9S_MB_2U_LIB.S9S_MB_2U(SCH_1):PAGE30
  CY10 P5E_CPU0_PE2_RX_DN<1> @S9S_MB_2U_LIB.S9S_MB_2U(SCH_1):P5E_CPU0_PE2_RX_DN(1)   I139 @S9S_MB_2U_LIB.S9S_MB_2U(SCH_1):PAGE30
   CU9 P5E_CPU0_PE2_RX_DN<0> @S9S_MB_2U_LIB.S9S_MB_2U(SCH_1):P5E_CPU0_PE2_RX_DN(0)   I139 @S9S_MB_2U_LIB.S9S_MB_2U(SCH_1):PAGE30
  EG11 P5E_CPU0_PE2_RX_DP<15> @S9S_MB_2U_LIB.S9S_MB_2U(SCH_1):P5E_CPU0_PE2_RX_DP(15)   I139 @S9S_MB_2U_LIB.S9S_MB_2U(SCH_1):PAGE30
  EF10 P5E_CPU0_PE2_RX_DP<14> @S9S_MB_2U_LIB.S9S_MB_2U(SCH_1):P5E_CPU0_PE2_RX_DP(14)   I139 @S9S_MB_2U_LIB.S9S_MB_2U(SCH_1):PAGE30
  EC11 P5E_CPU0_PE2_RX_DP<13> @S9S_MB_2U_LIB.S9S_MB_2U(SCH_1):P5E_CPU0_PE2_RX_DP(13)   I139 @S9S_MB_2U_LIB.S9S_MB_2U(SCH_1):PAGE30
  EB10 P5E_CPU0_PE2_RX_DP<12> @S9S_MB_2U_LIB.S9S_MB_2U(SCH_1):P5E_CPU0_PE2_RX_DP(12)   I139 @S9S_MB_2U_LIB.S9S_MB_2U(SCH_1):PAGE30
  DW11 P5E_CPU0_PE2_RX_DP<11> @S9S_MB_2U_LIB.S9S_MB_2U(SCH_1):P5E_CPU0_PE2_RX_DP(11)   I139 @S9S_MB_2U_LIB.S9S_MB_2U(SCH_1):PAGE30
  DV10 P5E_CPU0_PE2_RX_DP<10> @S9S_MB_2U_LIB.S9S_MB_2U(SCH_1):P5E_CPU0_PE2_RX_DP(10)   I139 @S9S_MB_2U_LIB.S9S_MB_2U(SCH_1):PAGE30
  DR11 P5E_CPU0_PE2_RX_DP<9> @S9S_MB_2U_LIB.S9S_MB_2U(SCH_1):P5E_CPU0_PE2_RX_DP(9)   I139 @S9S_MB_2U_LIB.S9S_MB_2U(SCH_1):PAGE30
  DP10 P5E_CPU0_PE2_RX_DP<8> @S9S_MB_2U_LIB.S9S_MB_2U(SCH_1):P5E_CPU0_PE2_RX_DP(8)   I139 @S9S_MB_2U_LIB.S9S_MB_2U(SCH_1):PAGE30
  DL11 P5E_CPU0_PE2_RX_DP<7> @S9S_MB_2U_LIB.S9S_MB_2U(SCH_1):P5E_CPU0_PE2_RX_DP(7)   I139 @S9S_MB_2U_LIB.S9S_MB_2U(SCH_1):PAGE30
  DK10 P5E_CPU0_PE2_RX_DP<6> @S9S_MB_2U_LIB.S9S_MB_2U(SCH_1):P5E_CPU0_PE2_RX_DP(6)   I139 @S9S_MB_2U_LIB.S9S_MB_2U(SCH_1):PAGE30
  DG11 P5E_CPU0_PE2_RX_DP<5> @S9S_MB_2U_LIB.S9S_MB_2U(SCH_1):P5E_CPU0_PE2_RX_DP(5)   I139 @S9S_MB_2U_LIB.S9S_MB_2U(SCH_1):PAGE30
  DF10 P5E_CPU0_PE2_RX_DP<4> @S9S_MB_2U_LIB.S9S_MB_2U(SCH_1):P5E_CPU0_PE2_RX_DP(4)   I139 @S9S_MB_2U_LIB.S9S_MB_2U(SCH_1):PAGE30
  DC11 P5E_CPU0_PE2_RX_DP<3> @S9S_MB_2U_LIB.S9S_MB_2U(SCH_1):P5E_CPU0_PE2_RX_DP(3)   I139 @S9S_MB_2U_LIB.S9S_MB_2U(SCH_1):PAGE30
  DB10 P5E_CPU0_PE2_RX_DP<2> @S9S_MB_2U_LIB.S9S_MB_2U(SCH_1):P5E_CPU0_PE2_RX_DP(2)   I139 @S9S_MB_2U_LIB.S9S_MB_2U(SCH_1):PAGE30
  CW11 P5E_CPU0_PE2_RX_DP<1> @S9S_MB_2U_LIB.S9S_MB_2U(SCH_1):P5E_CPU0_PE2_RX_DP(1)   I139 @S9S_MB_2U_LIB.S9S_MB_2U(SCH_1):PAGE30
  CV10 P5E_CPU0_PE2_RX_DP<0> @S9S_MB_2U_LIB.S9S_MB_2U(SCH_1):P5E_CPU0_PE2_RX_DP(0)   I139 @S9S_MB_2U_LIB.S9S_MB_2U(SCH_1):PAGE30
  EF14 P5E_CPU0_PE2_TX_DN<15> @S9S_MB_2U_LIB.S9S_MB_2U(SCH_1):P5E_CPU0_PE2_TX_DN(15)   I139 @S9S_MB_2U_LIB.S9S_MB_2U(SCH_1):PAGE30
  EE13 P5E_CPU0_PE2_TX_DN<14> @S9S_MB_2U_LIB.S9S_MB_2U(SCH_1):P5E_CPU0_PE2_TX_DN(14)   I139 @S9S_MB_2U_LIB.S9S_MB_2U(SCH_1):PAGE30
  EB14 P5E_CPU0_PE2_TX_DN<13> @S9S_MB_2U_LIB.S9S_MB_2U(SCH_1):P5E_CPU0_PE2_TX_DN(13)   I139 @S9S_MB_2U_LIB.S9S_MB_2U(SCH_1):PAGE30
  EA13 P5E_CPU0_PE2_TX_DN<12> @S9S_MB_2U_LIB.S9S_MB_2U(SCH_1):P5E_CPU0_PE2_TX_DN(12)   I139 @S9S_MB_2U_LIB.S9S_MB_2U(SCH_1):PAGE30
  DV14 P5E_CPU0_PE2_TX_DN<11> @S9S_MB_2U_LIB.S9S_MB_2U(SCH_1):P5E_CPU0_PE2_TX_DN(11)   I139 @S9S_MB_2U_LIB.S9S_MB_2U(SCH_1):PAGE30
  DU13 P5E_CPU0_PE2_TX_DN<10> @S9S_MB_2U_LIB.S9S_MB_2U(SCH_1):P5E_CPU0_PE2_TX_DN(10)   I139 @S9S_MB_2U_LIB.S9S_MB_2U(SCH_1):PAGE30
  DP14 P5E_CPU0_PE2_TX_DN<9> @S9S_MB_2U_LIB.S9S_MB_2U(SCH_1):P5E_CPU0_PE2_TX_DN(9)   I139 @S9S_MB_2U_LIB.S9S_MB_2U(SCH_1):PAGE30
  DN13 P5E_CPU0_PE2_TX_DN<8> @S9S_MB_2U_LIB.S9S_MB_2U(SCH_1):P5E_CPU0_PE2_TX_DN(8)   I139 @S9S_MB_2U_LIB.S9S_MB_2U(SCH_1):PAGE30
  DK14 P5E_CPU0_PE2_TX_DN<7> @S9S_MB_2U_LIB.S9S_MB_2U(SCH_1):P5E_CPU0_PE2_TX_DN(7)   I139 @S9S_MB_2U_LIB.S9S_MB_2U(SCH_1):PAGE30
  DJ13 P5E_CPU0_PE2_TX_DN<6> @S9S_MB_2U_LIB.S9S_MB_2U(SCH_1):P5E_CPU0_PE2_TX_DN(6)   I139 @S9S_MB_2U_LIB.S9S_MB_2U(SCH_1):PAGE30
  DF14 P5E_CPU0_PE2_TX_DN<5> @S9S_MB_2U_LIB.S9S_MB_2U(SCH_1):P5E_CPU0_PE2_TX_DN(5)   I139 @S9S_MB_2U_LIB.S9S_MB_2U(SCH_1):PAGE30
  DE13 P5E_CPU0_PE2_TX_DN<4> @S9S_MB_2U_LIB.S9S_MB_2U(SCH_1):P5E_CPU0_PE2_TX_DN(4)   I139 @S9S_MB_2U_LIB.S9S_MB_2U(SCH_1):PAGE30
  DB14 P5E_CPU0_PE2_TX_DN<3> @S9S_MB_2U_LIB.S9S_MB_2U(SCH_1):P5E_CPU0_PE2_TX_DN(3)   I139 @S9S_MB_2U_LIB.S9S_MB_2U(SCH_1):PAGE30
  DA13 P5E_CPU0_PE2_TX_DN<2> @S9S_MB_2U_LIB.S9S_MB_2U(SCH_1):P5E_CPU0_PE2_TX_DN(2)   I139 @S9S_MB_2U_LIB.S9S_MB_2U(SCH_1):PAGE30
  CV14 P5E_CPU0_PE2_TX_DN<1> @S9S_MB_2U_LIB.S9S_MB_2U(SCH_1):P5E_CPU0_PE2_TX_DN(1)   I139 @S9S_MB_2U_LIB.S9S_MB_2U(SCH_1):PAGE30
  CU13 P5E_CPU0_PE2_TX_DN<0> @S9S_MB_2U_LIB.S9S_MB_2U(SCH_1):P5E_CPU0_PE2_TX_DN(0)   I139 @S9S_MB_2U_LIB.S9S_MB_2U(SCH_1):PAGE30
  EG15 P5E_CPU0_PE2_TX_DP<15> @S9S_MB_2U_LIB.S9S_MB_2U(SCH_1):P5E_CPU0_PE2_TX_DP(15)   I139 @S9S_MB_2U_LIB.S9S_MB_2U(SCH_1):PAGE30
  ED14 P5E_CPU0_PE2_TX_DP<14> @S9S_MB_2U_LIB.S9S_MB_2U(SCH_1):P5E_CPU0_PE2_TX_DP(14)   I139 @S9S_MB_2U_LIB.S9S_MB_2U(SCH_1):PAGE30
  EC15 P5E_CPU0_PE2_TX_DP<13> @S9S_MB_2U_LIB.S9S_MB_2U(SCH_1):P5E_CPU0_PE2_TX_DP(13)   I139 @S9S_MB_2U_LIB.S9S_MB_2U(SCH_1):PAGE30
  DY14 P5E_CPU0_PE2_TX_DP<12> @S9S_MB_2U_LIB.S9S_MB_2U(SCH_1):P5E_CPU0_PE2_TX_DP(12)   I139 @S9S_MB_2U_LIB.S9S_MB_2U(SCH_1):PAGE30
  DW15 P5E_CPU0_PE2_TX_DP<11> @S9S_MB_2U_LIB.S9S_MB_2U(SCH_1):P5E_CPU0_PE2_TX_DP(11)   I139 @S9S_MB_2U_LIB.S9S_MB_2U(SCH_1):PAGE30
  DT14 P5E_CPU0_PE2_TX_DP<10> @S9S_MB_2U_LIB.S9S_MB_2U(SCH_1):P5E_CPU0_PE2_TX_DP(10)   I139 @S9S_MB_2U_LIB.S9S_MB_2U(SCH_1):PAGE30
  DR15 P5E_CPU0_PE2_TX_DP<9> @S9S_MB_2U_LIB.S9S_MB_2U(SCH_1):P5E_CPU0_PE2_TX_DP(9)   I139 @S9S_MB_2U_LIB.S9S_MB_2U(SCH_1):PAGE30
  DM14 P5E_CPU0_PE2_TX_DP<8> @S9S_MB_2U_LIB.S9S_MB_2U(SCH_1):P5E_CPU0_PE2_TX_DP(8)   I139 @S9S_MB_2U_LIB.S9S_MB_2U(SCH_1):PAGE30
  DL15 P5E_CPU0_PE2_TX_DP<7> @S9S_MB_2U_LIB.S9S_MB_2U(SCH_1):P5E_CPU0_PE2_TX_DP(7)   I139 @S9S_MB_2U_LIB.S9S_MB_2U(SCH_1):PAGE30
  DH14 P5E_CPU0_PE2_TX_DP<6> @S9S_MB_2U_LIB.S9S_MB_2U(SCH_1):P5E_CPU0_PE2_TX_DP(6)   I139 @S9S_MB_2U_LIB.S9S_MB_2U(SCH_1):PAGE30
  DG15 P5E_CPU0_PE2_TX_DP<5> @S9S_MB_2U_LIB.S9S_MB_2U(SCH_1):P5E_CPU0_PE2_TX_DP(5)   I139 @S9S_MB_2U_LIB.S9S_MB_2U(SCH_1):PAGE30
  DD14 P5E_CPU0_PE2_TX_DP<4> @S9S_MB_2U_LIB.S9S_MB_2U(SCH_1):P5E_CPU0_PE2_TX_DP(4)   I139 @S9S_MB_2U_LIB.S9S_MB_2U(SCH_1):PAGE30
  DC15 P5E_CPU0_PE2_TX_DP<3> @S9S_MB_2U_LIB.S9S_MB_2U(SCH_1):P5E_CPU0_PE2_TX_DP(3)   I139 @S9S_MB_2U_LIB.S9S_MB_2U(SCH_1):PAGE30
  CY14 P5E_CPU0_PE2_TX_DP<2> @S9S_MB_2U_LIB.S9S_MB_2U(SCH_1):P5E_CPU0_PE2_TX_DP(2)   I139 @S9S_MB_2U_LIB.S9S_MB_2U(SCH_1):PAGE30
  CW15 P5E_CPU0_PE2_TX_DP<1> @S9S_MB_2U_LIB.S9S_MB_2U(SCH_1):P5E_CPU0_PE2_TX_DP(1)   I139 @S9S_MB_2U_LIB.S9S_MB_2U(SCH_1):PAGE30
  CT14 P5E_CPU0_PE2_TX_DP<0> @S9S_MB_2U_LIB.S9S_MB_2U(SCH_1):P5E_CPU0_PE2_TX_DP(0)   I139 @S9S_MB_2U_LIB.S9S_MB_2U(SCH_1):PAGE30
  CU90 P5E_CPU0_PE3_RX_DN<15> @S9S_MB_2U_LIB.S9S_MB_2U(SCH_1):P5E_CPU0_PE3_RX_DN(15)   I140 @S9S_MB_2U_LIB.S9S_MB_2U(SCH_1):PAGE30
  CV89 P5E_CPU0_PE3_RX_DN<14> @S9S_MB_2U_LIB.S9S_MB_2U(SCH_1):P5E_CPU0_PE3_RX_DN(14)   I140 @S9S_MB_2U_LIB.S9S_MB_2U(SCH_1):PAGE30
  DA90 P5E_CPU0_PE3_RX_DN<13> @S9S_MB_2U_LIB.S9S_MB_2U(SCH_1):P5E_CPU0_PE3_RX_DN(13)   I140 @S9S_MB_2U_LIB.S9S_MB_2U(SCH_1):PAGE30
  DB89 P5E_CPU0_PE3_RX_DN<12> @S9S_MB_2U_LIB.S9S_MB_2U(SCH_1):P5E_CPU0_PE3_RX_DN(12)   I140 @S9S_MB_2U_LIB.S9S_MB_2U(SCH_1):PAGE30
  DD91 P5E_CPU0_PE3_RX_DN<11> @S9S_MB_2U_LIB.S9S_MB_2U(SCH_1):P5E_CPU0_PE3_RX_DN(11)   I140 @S9S_MB_2U_LIB.S9S_MB_2U(SCH_1):PAGE30
  DG90 P5E_CPU0_PE3_RX_DN<10> @S9S_MB_2U_LIB.S9S_MB_2U(SCH_1):P5E_CPU0_PE3_RX_DN(10)   I140 @S9S_MB_2U_LIB.S9S_MB_2U(SCH_1):PAGE30
  DH91 P5E_CPU0_PE3_RX_DN<9> @S9S_MB_2U_LIB.S9S_MB_2U(SCH_1):P5E_CPU0_PE3_RX_DN(9)   I140 @S9S_MB_2U_LIB.S9S_MB_2U(SCH_1):PAGE30
  DL90 P5E_CPU0_PE3_RX_DN<8> @S9S_MB_2U_LIB.S9S_MB_2U(SCH_1):P5E_CPU0_PE3_RX_DN(8)   I140 @S9S_MB_2U_LIB.S9S_MB_2U(SCH_1):PAGE30
  DN90 P5E_CPU0_PE3_RX_DN<7> @S9S_MB_2U_LIB.S9S_MB_2U(SCH_1):P5E_CPU0_PE3_RX_DN(7)   I140 @S9S_MB_2U_LIB.S9S_MB_2U(SCH_1):PAGE30
  DP89 P5E_CPU0_PE3_RX_DN<6> @S9S_MB_2U_LIB.S9S_MB_2U(SCH_1):P5E_CPU0_PE3_RX_DN(6)   I140 @S9S_MB_2U_LIB.S9S_MB_2U(SCH_1):PAGE30
  DU90 P5E_CPU0_PE3_RX_DN<5> @S9S_MB_2U_LIB.S9S_MB_2U(SCH_1):P5E_CPU0_PE3_RX_DN(5)   I140 @S9S_MB_2U_LIB.S9S_MB_2U(SCH_1):PAGE30
  DV89 P5E_CPU0_PE3_RX_DN<4> @S9S_MB_2U_LIB.S9S_MB_2U(SCH_1):P5E_CPU0_PE3_RX_DN(4)   I140 @S9S_MB_2U_LIB.S9S_MB_2U(SCH_1):PAGE30
  DY91 P5E_CPU0_PE3_RX_DN<3> @S9S_MB_2U_LIB.S9S_MB_2U(SCH_1):P5E_CPU0_PE3_RX_DN(3)   I140 @S9S_MB_2U_LIB.S9S_MB_2U(SCH_1):PAGE30
  EC90 P5E_CPU0_PE3_RX_DN<2> @S9S_MB_2U_LIB.S9S_MB_2U(SCH_1):P5E_CPU0_PE3_RX_DN(2)   I140 @S9S_MB_2U_LIB.S9S_MB_2U(SCH_1):PAGE30
  ED91 P5E_CPU0_PE3_RX_DN<1> @S9S_MB_2U_LIB.S9S_MB_2U(SCH_1):P5E_CPU0_PE3_RX_DN(1)   I140 @S9S_MB_2U_LIB.S9S_MB_2U(SCH_1):PAGE30
  EH89 P5E_CPU0_PE3_RX_DN<0> @S9S_MB_2U_LIB.S9S_MB_2U(SCH_1):P5E_CPU0_PE3_RX_DN(0)   I140 @S9S_MB_2U_LIB.S9S_MB_2U(SCH_1):PAGE30
  CT91 P5E_CPU0_PE3_RX_DP<15> @S9S_MB_2U_LIB.S9S_MB_2U(SCH_1):P5E_CPU0_PE3_RX_DP(15)   I140 @S9S_MB_2U_LIB.S9S_MB_2U(SCH_1):PAGE30
  CW90 P5E_CPU0_PE3_RX_DP<14> @S9S_MB_2U_LIB.S9S_MB_2U(SCH_1):P5E_CPU0_PE3_RX_DP(14)   I140 @S9S_MB_2U_LIB.S9S_MB_2U(SCH_1):PAGE30
  CY91 P5E_CPU0_PE3_RX_DP<13> @S9S_MB_2U_LIB.S9S_MB_2U(SCH_1):P5E_CPU0_PE3_RX_DP(13)   I140 @S9S_MB_2U_LIB.S9S_MB_2U(SCH_1):PAGE30
  DC90 P5E_CPU0_PE3_RX_DP<12> @S9S_MB_2U_LIB.S9S_MB_2U(SCH_1):P5E_CPU0_PE3_RX_DP(12)   I140 @S9S_MB_2U_LIB.S9S_MB_2U(SCH_1):PAGE30
  DE90 P5E_CPU0_PE3_RX_DP<11> @S9S_MB_2U_LIB.S9S_MB_2U(SCH_1):P5E_CPU0_PE3_RX_DP(11)   I140 @S9S_MB_2U_LIB.S9S_MB_2U(SCH_1):PAGE30
  DF89 P5E_CPU0_PE3_RX_DP<10> @S9S_MB_2U_LIB.S9S_MB_2U(SCH_1):P5E_CPU0_PE3_RX_DP(10)   I140 @S9S_MB_2U_LIB.S9S_MB_2U(SCH_1):PAGE30
  DJ90 P5E_CPU0_PE3_RX_DP<9> @S9S_MB_2U_LIB.S9S_MB_2U(SCH_1):P5E_CPU0_PE3_RX_DP(9)   I140 @S9S_MB_2U_LIB.S9S_MB_2U(SCH_1):PAGE30
  DK89 P5E_CPU0_PE3_RX_DP<8> @S9S_MB_2U_LIB.S9S_MB_2U(SCH_1):P5E_CPU0_PE3_RX_DP(8)   I140 @S9S_MB_2U_LIB.S9S_MB_2U(SCH_1):PAGE30
  DM91 P5E_CPU0_PE3_RX_DP<7> @S9S_MB_2U_LIB.S9S_MB_2U(SCH_1):P5E_CPU0_PE3_RX_DP(7)   I140 @S9S_MB_2U_LIB.S9S_MB_2U(SCH_1):PAGE30
  DR90 P5E_CPU0_PE3_RX_DP<6> @S9S_MB_2U_LIB.S9S_MB_2U(SCH_1):P5E_CPU0_PE3_RX_DP(6)   I140 @S9S_MB_2U_LIB.S9S_MB_2U(SCH_1):PAGE30
  DT91 P5E_CPU0_PE3_RX_DP<5> @S9S_MB_2U_LIB.S9S_MB_2U(SCH_1):P5E_CPU0_PE3_RX_DP(5)   I140 @S9S_MB_2U_LIB.S9S_MB_2U(SCH_1):PAGE30
  DW90 P5E_CPU0_PE3_RX_DP<4> @S9S_MB_2U_LIB.S9S_MB_2U(SCH_1):P5E_CPU0_PE3_RX_DP(4)   I140 @S9S_MB_2U_LIB.S9S_MB_2U(SCH_1):PAGE30
  EA90 P5E_CPU0_PE3_RX_DP<3> @S9S_MB_2U_LIB.S9S_MB_2U(SCH_1):P5E_CPU0_PE3_RX_DP(3)   I140 @S9S_MB_2U_LIB.S9S_MB_2U(SCH_1):PAGE30
  EB89 P5E_CPU0_PE3_RX_DP<2> @S9S_MB_2U_LIB.S9S_MB_2U(SCH_1):P5E_CPU0_PE3_RX_DP(2)   I140 @S9S_MB_2U_LIB.S9S_MB_2U(SCH_1):PAGE30
  EE90 P5E_CPU0_PE3_RX_DP<1> @S9S_MB_2U_LIB.S9S_MB_2U(SCH_1):P5E_CPU0_PE3_RX_DP(1)   I140 @S9S_MB_2U_LIB.S9S_MB_2U(SCH_1):PAGE30
  EJ90 P5E_CPU0_PE3_RX_DP<0> @S9S_MB_2U_LIB.S9S_MB_2U(SCH_1):P5E_CPU0_PE3_RX_DP(0)   I140 @S9S_MB_2U_LIB.S9S_MB_2U(SCH_1):PAGE30
  CP85 P5E_CPU0_PE3_TX_DN<15> @S9S_MB_2U_LIB.S9S_MB_2U(SCH_1):P5E_CPU0_PE3_TX_DN(15)   I140 @S9S_MB_2U_LIB.S9S_MB_2U(SCH_1):PAGE30
  CT87 P5E_CPU0_PE3_TX_DN<14> @S9S_MB_2U_LIB.S9S_MB_2U(SCH_1):P5E_CPU0_PE3_TX_DN(14)   I140 @S9S_MB_2U_LIB.S9S_MB_2U(SCH_1):PAGE30
  CV85 P5E_CPU0_PE3_TX_DN<13> @S9S_MB_2U_LIB.S9S_MB_2U(SCH_1):P5E_CPU0_PE3_TX_DN(13)   I140 @S9S_MB_2U_LIB.S9S_MB_2U(SCH_1):PAGE30
  CY87 P5E_CPU0_PE3_TX_DN<12> @S9S_MB_2U_LIB.S9S_MB_2U(SCH_1):P5E_CPU0_PE3_TX_DN(12)   I140 @S9S_MB_2U_LIB.S9S_MB_2U(SCH_1):PAGE30
  DB85 P5E_CPU0_PE3_TX_DN<11> @S9S_MB_2U_LIB.S9S_MB_2U(SCH_1):P5E_CPU0_PE3_TX_DN(11)   I140 @S9S_MB_2U_LIB.S9S_MB_2U(SCH_1):PAGE30
  DD87 P5E_CPU0_PE3_TX_DN<10> @S9S_MB_2U_LIB.S9S_MB_2U(SCH_1):P5E_CPU0_PE3_TX_DN(10)   I140 @S9S_MB_2U_LIB.S9S_MB_2U(SCH_1):PAGE30
  DF85 P5E_CPU0_PE3_TX_DN<9> @S9S_MB_2U_LIB.S9S_MB_2U(SCH_1):P5E_CPU0_PE3_TX_DN(9)   I140 @S9S_MB_2U_LIB.S9S_MB_2U(SCH_1):PAGE30
  DH87 P5E_CPU0_PE3_TX_DN<8> @S9S_MB_2U_LIB.S9S_MB_2U(SCH_1):P5E_CPU0_PE3_TX_DN(8)   I140 @S9S_MB_2U_LIB.S9S_MB_2U(SCH_1):PAGE30
  DK85 P5E_CPU0_PE3_TX_DN<7> @S9S_MB_2U_LIB.S9S_MB_2U(SCH_1):P5E_CPU0_PE3_TX_DN(7)   I140 @S9S_MB_2U_LIB.S9S_MB_2U(SCH_1):PAGE30
  DM87 P5E_CPU0_PE3_TX_DN<6> @S9S_MB_2U_LIB.S9S_MB_2U(SCH_1):P5E_CPU0_PE3_TX_DN(6)   I140 @S9S_MB_2U_LIB.S9S_MB_2U(SCH_1):PAGE30
  DP85 P5E_CPU0_PE3_TX_DN<5> @S9S_MB_2U_LIB.S9S_MB_2U(SCH_1):P5E_CPU0_PE3_TX_DN(5)   I140 @S9S_MB_2U_LIB.S9S_MB_2U(SCH_1):PAGE30
  DT87 P5E_CPU0_PE3_TX_DN<4> @S9S_MB_2U_LIB.S9S_MB_2U(SCH_1):P5E_CPU0_PE3_TX_DN(4)   I140 @S9S_MB_2U_LIB.S9S_MB_2U(SCH_1):PAGE30
  DV85 P5E_CPU0_PE3_TX_DN<3> @S9S_MB_2U_LIB.S9S_MB_2U(SCH_1):P5E_CPU0_PE3_TX_DN(3)   I140 @S9S_MB_2U_LIB.S9S_MB_2U(SCH_1):PAGE30
  DY87 P5E_CPU0_PE3_TX_DN<2> @S9S_MB_2U_LIB.S9S_MB_2U(SCH_1):P5E_CPU0_PE3_TX_DN(2)   I140 @S9S_MB_2U_LIB.S9S_MB_2U(SCH_1):PAGE30
  EB85 P5E_CPU0_PE3_TX_DN<1> @S9S_MB_2U_LIB.S9S_MB_2U(SCH_1):P5E_CPU0_PE3_TX_DN(1)   I140 @S9S_MB_2U_LIB.S9S_MB_2U(SCH_1):PAGE30
  EE86 P5E_CPU0_PE3_TX_DN<0> @S9S_MB_2U_LIB.S9S_MB_2U(SCH_1):P5E_CPU0_PE3_TX_DN(0)   I140 @S9S_MB_2U_LIB.S9S_MB_2U(SCH_1):PAGE30
  CR86 P5E_CPU0_PE3_TX_DP<15> @S9S_MB_2U_LIB.S9S_MB_2U(SCH_1):P5E_CPU0_PE3_TX_DP(15)   I140 @S9S_MB_2U_LIB.S9S_MB_2U(SCH_1):PAGE30
  CU86 P5E_CPU0_PE3_TX_DP<14> @S9S_MB_2U_LIB.S9S_MB_2U(SCH_1):P5E_CPU0_PE3_TX_DP(14)   I140 @S9S_MB_2U_LIB.S9S_MB_2U(SCH_1):PAGE30
  CW86 P5E_CPU0_PE3_TX_DP<13> @S9S_MB_2U_LIB.S9S_MB_2U(SCH_1):P5E_CPU0_PE3_TX_DP(13)   I140 @S9S_MB_2U_LIB.S9S_MB_2U(SCH_1):PAGE30
  DA86 P5E_CPU0_PE3_TX_DP<12> @S9S_MB_2U_LIB.S9S_MB_2U(SCH_1):P5E_CPU0_PE3_TX_DP(12)   I140 @S9S_MB_2U_LIB.S9S_MB_2U(SCH_1):PAGE30
  DC86 P5E_CPU0_PE3_TX_DP<11> @S9S_MB_2U_LIB.S9S_MB_2U(SCH_1):P5E_CPU0_PE3_TX_DP(11)   I140 @S9S_MB_2U_LIB.S9S_MB_2U(SCH_1):PAGE30
  DE86 P5E_CPU0_PE3_TX_DP<10> @S9S_MB_2U_LIB.S9S_MB_2U(SCH_1):P5E_CPU0_PE3_TX_DP(10)   I140 @S9S_MB_2U_LIB.S9S_MB_2U(SCH_1):PAGE30
  DG86 P5E_CPU0_PE3_TX_DP<9> @S9S_MB_2U_LIB.S9S_MB_2U(SCH_1):P5E_CPU0_PE3_TX_DP(9)   I140 @S9S_MB_2U_LIB.S9S_MB_2U(SCH_1):PAGE30
  DJ86 P5E_CPU0_PE3_TX_DP<8> @S9S_MB_2U_LIB.S9S_MB_2U(SCH_1):P5E_CPU0_PE3_TX_DP(8)   I140 @S9S_MB_2U_LIB.S9S_MB_2U(SCH_1):PAGE30
  DL86 P5E_CPU0_PE3_TX_DP<7> @S9S_MB_2U_LIB.S9S_MB_2U(SCH_1):P5E_CPU0_PE3_TX_DP(7)   I140 @S9S_MB_2U_LIB.S9S_MB_2U(SCH_1):PAGE30
  DN86 P5E_CPU0_PE3_TX_DP<6> @S9S_MB_2U_LIB.S9S_MB_2U(SCH_1):P5E_CPU0_PE3_TX_DP(6)   I140 @S9S_MB_2U_LIB.S9S_MB_2U(SCH_1):PAGE30
  DR86 P5E_CPU0_PE3_TX_DP<5> @S9S_MB_2U_LIB.S9S_MB_2U(SCH_1):P5E_CPU0_PE3_TX_DP(5)   I140 @S9S_MB_2U_LIB.S9S_MB_2U(SCH_1):PAGE30
  DU86 P5E_CPU0_PE3_TX_DP<4> @S9S_MB_2U_LIB.S9S_MB_2U(SCH_1):P5E_CPU0_PE3_TX_DP(4)   I140 @S9S_MB_2U_LIB.S9S_MB_2U(SCH_1):PAGE30
  DW86 P5E_CPU0_PE3_TX_DP<3> @S9S_MB_2U_LIB.S9S_MB_2U(SCH_1):P5E_CPU0_PE3_TX_DP(3)   I140 @S9S_MB_2U_LIB.S9S_MB_2U(SCH_1):PAGE30
  EA86 P5E_CPU0_PE3_TX_DP<2> @S9S_MB_2U_LIB.S9S_MB_2U(SCH_1):P5E_CPU0_PE3_TX_DP(2)   I140 @S9S_MB_2U_LIB.S9S_MB_2U(SCH_1):PAGE30
  EC86 P5E_CPU0_PE3_TX_DP<1> @S9S_MB_2U_LIB.S9S_MB_2U(SCH_1):P5E_CPU0_PE3_TX_DP(1)   I140 @S9S_MB_2U_LIB.S9S_MB_2U(SCH_1):PAGE30
  ED87 P5E_CPU0_PE3_TX_DP<0> @S9S_MB_2U_LIB.S9S_MB_2U(SCH_1):P5E_CPU0_PE3_TX_DP(0)   I140 @S9S_MB_2U_LIB.S9S_MB_2U(SCH_1):PAGE30
  BB89 P5E_CPU0_PE4_RX_DN<15> @S9S_MB_2U_LIB.S9S_MB_2U(SCH_1):P5E_CPU0_PE4_RX_DN(15)   I139 @S9S_MB_2U_LIB.S9S_MB_2U(SCH_1):PAGE31
  AY91 P5E_CPU0_PE4_RX_DN<14> @S9S_MB_2U_LIB.S9S_MB_2U(SCH_1):P5E_CPU0_PE4_RX_DN(14)   I139 @S9S_MB_2U_LIB.S9S_MB_2U(SCH_1):PAGE31
  AV89 P5E_CPU0_PE4_RX_DN<13> @S9S_MB_2U_LIB.S9S_MB_2U(SCH_1):P5E_CPU0_PE4_RX_DN(13)   I139 @S9S_MB_2U_LIB.S9S_MB_2U(SCH_1):PAGE31
  AT91 P5E_CPU0_PE4_RX_DN<12> @S9S_MB_2U_LIB.S9S_MB_2U(SCH_1):P5E_CPU0_PE4_RX_DN(12)   I139 @S9S_MB_2U_LIB.S9S_MB_2U(SCH_1):PAGE31
  AP89 P5E_CPU0_PE4_RX_DN<11> @S9S_MB_2U_LIB.S9S_MB_2U(SCH_1):P5E_CPU0_PE4_RX_DN(11)   I139 @S9S_MB_2U_LIB.S9S_MB_2U(SCH_1):PAGE31
  AM91 P5E_CPU0_PE4_RX_DN<10> @S9S_MB_2U_LIB.S9S_MB_2U(SCH_1):P5E_CPU0_PE4_RX_DN(10)   I139 @S9S_MB_2U_LIB.S9S_MB_2U(SCH_1):PAGE31
  AK89 P5E_CPU0_PE4_RX_DN<9> @S9S_MB_2U_LIB.S9S_MB_2U(SCH_1):P5E_CPU0_PE4_RX_DN(9)   I139 @S9S_MB_2U_LIB.S9S_MB_2U(SCH_1):PAGE31
  AH91 P5E_CPU0_PE4_RX_DN<8> @S9S_MB_2U_LIB.S9S_MB_2U(SCH_1):P5E_CPU0_PE4_RX_DN(8)   I139 @S9S_MB_2U_LIB.S9S_MB_2U(SCH_1):PAGE31
  AF89 P5E_CPU0_PE4_RX_DN<7> @S9S_MB_2U_LIB.S9S_MB_2U(SCH_1):P5E_CPU0_PE4_RX_DN(7)   I139 @S9S_MB_2U_LIB.S9S_MB_2U(SCH_1):PAGE31
  AD91 P5E_CPU0_PE4_RX_DN<6> @S9S_MB_2U_LIB.S9S_MB_2U(SCH_1):P5E_CPU0_PE4_RX_DN(6)   I139 @S9S_MB_2U_LIB.S9S_MB_2U(SCH_1):PAGE31
  AB89 P5E_CPU0_PE4_RX_DN<5> @S9S_MB_2U_LIB.S9S_MB_2U(SCH_1):P5E_CPU0_PE4_RX_DN(5)   I139 @S9S_MB_2U_LIB.S9S_MB_2U(SCH_1):PAGE31
   Y91 P5E_CPU0_PE4_RX_DN<4> @S9S_MB_2U_LIB.S9S_MB_2U(SCH_1):P5E_CPU0_PE4_RX_DN(4)   I139 @S9S_MB_2U_LIB.S9S_MB_2U(SCH_1):PAGE31
   V89 P5E_CPU0_PE4_RX_DN<3> @S9S_MB_2U_LIB.S9S_MB_2U(SCH_1):P5E_CPU0_PE4_RX_DN(3)   I139 @S9S_MB_2U_LIB.S9S_MB_2U(SCH_1):PAGE31
   T91 P5E_CPU0_PE4_RX_DN<2> @S9S_MB_2U_LIB.S9S_MB_2U(SCH_1):P5E_CPU0_PE4_RX_DN(2)   I139 @S9S_MB_2U_LIB.S9S_MB_2U(SCH_1):PAGE31
   P89 P5E_CPU0_PE4_RX_DN<1> @S9S_MB_2U_LIB.S9S_MB_2U(SCH_1):P5E_CPU0_PE4_RX_DN(1)   I139 @S9S_MB_2U_LIB.S9S_MB_2U(SCH_1):PAGE31
   J90 P5E_CPU0_PE4_RX_DN<0> @S9S_MB_2U_LIB.S9S_MB_2U(SCH_1):P5E_CPU0_PE4_RX_DN(0)   I139 @S9S_MB_2U_LIB.S9S_MB_2U(SCH_1):PAGE31
  BA90 P5E_CPU0_PE4_RX_DP<15> @S9S_MB_2U_LIB.S9S_MB_2U(SCH_1):P5E_CPU0_PE4_RX_DP(15)   I139 @S9S_MB_2U_LIB.S9S_MB_2U(SCH_1):PAGE31
  AW90 P5E_CPU0_PE4_RX_DP<14> @S9S_MB_2U_LIB.S9S_MB_2U(SCH_1):P5E_CPU0_PE4_RX_DP(14)   I139 @S9S_MB_2U_LIB.S9S_MB_2U(SCH_1):PAGE31
  AU90 P5E_CPU0_PE4_RX_DP<13> @S9S_MB_2U_LIB.S9S_MB_2U(SCH_1):P5E_CPU0_PE4_RX_DP(13)   I139 @S9S_MB_2U_LIB.S9S_MB_2U(SCH_1):PAGE31
  AR90 P5E_CPU0_PE4_RX_DP<12> @S9S_MB_2U_LIB.S9S_MB_2U(SCH_1):P5E_CPU0_PE4_RX_DP(12)   I139 @S9S_MB_2U_LIB.S9S_MB_2U(SCH_1):PAGE31
  AN90 P5E_CPU0_PE4_RX_DP<11> @S9S_MB_2U_LIB.S9S_MB_2U(SCH_1):P5E_CPU0_PE4_RX_DP(11)   I139 @S9S_MB_2U_LIB.S9S_MB_2U(SCH_1):PAGE31
  AL90 P5E_CPU0_PE4_RX_DP<10> @S9S_MB_2U_LIB.S9S_MB_2U(SCH_1):P5E_CPU0_PE4_RX_DP(10)   I139 @S9S_MB_2U_LIB.S9S_MB_2U(SCH_1):PAGE31
  AJ90 P5E_CPU0_PE4_RX_DP<9> @S9S_MB_2U_LIB.S9S_MB_2U(SCH_1):P5E_CPU0_PE4_RX_DP(9)   I139 @S9S_MB_2U_LIB.S9S_MB_2U(SCH_1):PAGE31
  AG90 P5E_CPU0_PE4_RX_DP<8> @S9S_MB_2U_LIB.S9S_MB_2U(SCH_1):P5E_CPU0_PE4_RX_DP(8)   I139 @S9S_MB_2U_LIB.S9S_MB_2U(SCH_1):PAGE31
  AE90 P5E_CPU0_PE4_RX_DP<7> @S9S_MB_2U_LIB.S9S_MB_2U(SCH_1):P5E_CPU0_PE4_RX_DP(7)   I139 @S9S_MB_2U_LIB.S9S_MB_2U(SCH_1):PAGE31
  AC90 P5E_CPU0_PE4_RX_DP<6> @S9S_MB_2U_LIB.S9S_MB_2U(SCH_1):P5E_CPU0_PE4_RX_DP(6)   I139 @S9S_MB_2U_LIB.S9S_MB_2U(SCH_1):PAGE31
  AA90 P5E_CPU0_PE4_RX_DP<5> @S9S_MB_2U_LIB.S9S_MB_2U(SCH_1):P5E_CPU0_PE4_RX_DP(5)   I139 @S9S_MB_2U_LIB.S9S_MB_2U(SCH_1):PAGE31
   W90 P5E_CPU0_PE4_RX_DP<4> @S9S_MB_2U_LIB.S9S_MB_2U(SCH_1):P5E_CPU0_PE4_RX_DP(4)   I139 @S9S_MB_2U_LIB.S9S_MB_2U(SCH_1):PAGE31
   U90 P5E_CPU0_PE4_RX_DP<3> @S9S_MB_2U_LIB.S9S_MB_2U(SCH_1):P5E_CPU0_PE4_RX_DP(3)   I139 @S9S_MB_2U_LIB.S9S_MB_2U(SCH_1):PAGE31
   R90 P5E_CPU0_PE4_RX_DP<2> @S9S_MB_2U_LIB.S9S_MB_2U(SCH_1):P5E_CPU0_PE4_RX_DP(2)   I139 @S9S_MB_2U_LIB.S9S_MB_2U(SCH_1):PAGE31
   N90 P5E_CPU0_PE4_RX_DP<1> @S9S_MB_2U_LIB.S9S_MB_2U(SCH_1):P5E_CPU0_PE4_RX_DP(1)   I139 @S9S_MB_2U_LIB.S9S_MB_2U(SCH_1):PAGE31
   K89 P5E_CPU0_PE4_RX_DP<0> @S9S_MB_2U_LIB.S9S_MB_2U(SCH_1):P5E_CPU0_PE4_RX_DP(0)   I139 @S9S_MB_2U_LIB.S9S_MB_2U(SCH_1):PAGE31
  BA86 P5E_CPU0_PE4_TX_DN<15> @S9S_MB_2U_LIB.S9S_MB_2U(SCH_1):P5E_CPU0_PE4_TX_DN(15)   I139 @S9S_MB_2U_LIB.S9S_MB_2U(SCH_1):PAGE31
  AW86 P5E_CPU0_PE4_TX_DN<14> @S9S_MB_2U_LIB.S9S_MB_2U(SCH_1):P5E_CPU0_PE4_TX_DN(14)   I139 @S9S_MB_2U_LIB.S9S_MB_2U(SCH_1):PAGE31
  AU86 P5E_CPU0_PE4_TX_DN<13> @S9S_MB_2U_LIB.S9S_MB_2U(SCH_1):P5E_CPU0_PE4_TX_DN(13)   I139 @S9S_MB_2U_LIB.S9S_MB_2U(SCH_1):PAGE31
  AR86 P5E_CPU0_PE4_TX_DN<12> @S9S_MB_2U_LIB.S9S_MB_2U(SCH_1):P5E_CPU0_PE4_TX_DN(12)   I139 @S9S_MB_2U_LIB.S9S_MB_2U(SCH_1):PAGE31
  AP85 P5E_CPU0_PE4_TX_DN<11> @S9S_MB_2U_LIB.S9S_MB_2U(SCH_1):P5E_CPU0_PE4_TX_DN(11)   I139 @S9S_MB_2U_LIB.S9S_MB_2U(SCH_1):PAGE31
  AL86 P5E_CPU0_PE4_TX_DN<10> @S9S_MB_2U_LIB.S9S_MB_2U(SCH_1):P5E_CPU0_PE4_TX_DN(10)   I139 @S9S_MB_2U_LIB.S9S_MB_2U(SCH_1):PAGE31
  AJ86 P5E_CPU0_PE4_TX_DN<9> @S9S_MB_2U_LIB.S9S_MB_2U(SCH_1):P5E_CPU0_PE4_TX_DN(9)   I139 @S9S_MB_2U_LIB.S9S_MB_2U(SCH_1):PAGE31
  AG86 P5E_CPU0_PE4_TX_DN<8> @S9S_MB_2U_LIB.S9S_MB_2U(SCH_1):P5E_CPU0_PE4_TX_DN(8)   I139 @S9S_MB_2U_LIB.S9S_MB_2U(SCH_1):PAGE31
  AE86 P5E_CPU0_PE4_TX_DN<7> @S9S_MB_2U_LIB.S9S_MB_2U(SCH_1):P5E_CPU0_PE4_TX_DN(7)   I139 @S9S_MB_2U_LIB.S9S_MB_2U(SCH_1):PAGE31
  AC86 P5E_CPU0_PE4_TX_DN<6> @S9S_MB_2U_LIB.S9S_MB_2U(SCH_1):P5E_CPU0_PE4_TX_DN(6)   I139 @S9S_MB_2U_LIB.S9S_MB_2U(SCH_1):PAGE31
  AA86 P5E_CPU0_PE4_TX_DN<5> @S9S_MB_2U_LIB.S9S_MB_2U(SCH_1):P5E_CPU0_PE4_TX_DN(5)   I139 @S9S_MB_2U_LIB.S9S_MB_2U(SCH_1):PAGE31
   W86 P5E_CPU0_PE4_TX_DN<4> @S9S_MB_2U_LIB.S9S_MB_2U(SCH_1):P5E_CPU0_PE4_TX_DN(4)   I139 @S9S_MB_2U_LIB.S9S_MB_2U(SCH_1):PAGE31
   U86 P5E_CPU0_PE4_TX_DN<3> @S9S_MB_2U_LIB.S9S_MB_2U(SCH_1):P5E_CPU0_PE4_TX_DN(3)   I139 @S9S_MB_2U_LIB.S9S_MB_2U(SCH_1):PAGE31
   R86 P5E_CPU0_PE4_TX_DN<2> @S9S_MB_2U_LIB.S9S_MB_2U(SCH_1):P5E_CPU0_PE4_TX_DN(2)   I139 @S9S_MB_2U_LIB.S9S_MB_2U(SCH_1):PAGE31
   P85 P5E_CPU0_PE4_TX_DN<1> @S9S_MB_2U_LIB.S9S_MB_2U(SCH_1):P5E_CPU0_PE4_TX_DN(1)   I139 @S9S_MB_2U_LIB.S9S_MB_2U(SCH_1):PAGE31
   L86 P5E_CPU0_PE4_TX_DN<0> @S9S_MB_2U_LIB.S9S_MB_2U(SCH_1):P5E_CPU0_PE4_TX_DN(0)   I139 @S9S_MB_2U_LIB.S9S_MB_2U(SCH_1):PAGE31
  BB85 P5E_CPU0_PE4_TX_DP<15> @S9S_MB_2U_LIB.S9S_MB_2U(SCH_1):P5E_CPU0_PE4_TX_DP(15)   I139 @S9S_MB_2U_LIB.S9S_MB_2U(SCH_1):PAGE31
  AY87 P5E_CPU0_PE4_TX_DP<14> @S9S_MB_2U_LIB.S9S_MB_2U(SCH_1):P5E_CPU0_PE4_TX_DP(14)   I139 @S9S_MB_2U_LIB.S9S_MB_2U(SCH_1):PAGE31
  AV85 P5E_CPU0_PE4_TX_DP<13> @S9S_MB_2U_LIB.S9S_MB_2U(SCH_1):P5E_CPU0_PE4_TX_DP(13)   I139 @S9S_MB_2U_LIB.S9S_MB_2U(SCH_1):PAGE31
  AT87 P5E_CPU0_PE4_TX_DP<12> @S9S_MB_2U_LIB.S9S_MB_2U(SCH_1):P5E_CPU0_PE4_TX_DP(12)   I139 @S9S_MB_2U_LIB.S9S_MB_2U(SCH_1):PAGE31
  AN86 P5E_CPU0_PE4_TX_DP<11> @S9S_MB_2U_LIB.S9S_MB_2U(SCH_1):P5E_CPU0_PE4_TX_DP(11)   I139 @S9S_MB_2U_LIB.S9S_MB_2U(SCH_1):PAGE31
  AM87 P5E_CPU0_PE4_TX_DP<10> @S9S_MB_2U_LIB.S9S_MB_2U(SCH_1):P5E_CPU0_PE4_TX_DP(10)   I139 @S9S_MB_2U_LIB.S9S_MB_2U(SCH_1):PAGE31
  AK85 P5E_CPU0_PE4_TX_DP<9> @S9S_MB_2U_LIB.S9S_MB_2U(SCH_1):P5E_CPU0_PE4_TX_DP(9)   I139 @S9S_MB_2U_LIB.S9S_MB_2U(SCH_1):PAGE31
  AH87 P5E_CPU0_PE4_TX_DP<8> @S9S_MB_2U_LIB.S9S_MB_2U(SCH_1):P5E_CPU0_PE4_TX_DP(8)   I139 @S9S_MB_2U_LIB.S9S_MB_2U(SCH_1):PAGE31
  AF85 P5E_CPU0_PE4_TX_DP<7> @S9S_MB_2U_LIB.S9S_MB_2U(SCH_1):P5E_CPU0_PE4_TX_DP(7)   I139 @S9S_MB_2U_LIB.S9S_MB_2U(SCH_1):PAGE31
  AD87 P5E_CPU0_PE4_TX_DP<6> @S9S_MB_2U_LIB.S9S_MB_2U(SCH_1):P5E_CPU0_PE4_TX_DP(6)   I139 @S9S_MB_2U_LIB.S9S_MB_2U(SCH_1):PAGE31
  AB85 P5E_CPU0_PE4_TX_DP<5> @S9S_MB_2U_LIB.S9S_MB_2U(SCH_1):P5E_CPU0_PE4_TX_DP(5)   I139 @S9S_MB_2U_LIB.S9S_MB_2U(SCH_1):PAGE31
   Y87 P5E_CPU0_PE4_TX_DP<4> @S9S_MB_2U_LIB.S9S_MB_2U(SCH_1):P5E_CPU0_PE4_TX_DP(4)   I139 @S9S_MB_2U_LIB.S9S_MB_2U(SCH_1):PAGE31
   V85 P5E_CPU0_PE4_TX_DP<3> @S9S_MB_2U_LIB.S9S_MB_2U(SCH_1):P5E_CPU0_PE4_TX_DP(3)   I139 @S9S_MB_2U_LIB.S9S_MB_2U(SCH_1):PAGE31
   T87 P5E_CPU0_PE4_TX_DP<2> @S9S_MB_2U_LIB.S9S_MB_2U(SCH_1):P5E_CPU0_PE4_TX_DP(2)   I139 @S9S_MB_2U_LIB.S9S_MB_2U(SCH_1):PAGE31
   N86 P5E_CPU0_PE4_TX_DP<1> @S9S_MB_2U_LIB.S9S_MB_2U(SCH_1):P5E_CPU0_PE4_TX_DP(1)   I139 @S9S_MB_2U_LIB.S9S_MB_2U(SCH_1):PAGE31
   M87 P5E_CPU0_PE4_TX_DP<0> @S9S_MB_2U_LIB.S9S_MB_2U(SCH_1):P5E_CPU0_PE4_TX_DP(0)   I139 @S9S_MB_2U_LIB.S9S_MB_2U(SCH_1):PAGE31
   BU5 UPI_CPU1_CPU0_P1P0_DP<23> @S9S_MB_2U_LIB.S9S_MB_2U(SCH_1):UPI_CPU1_CPU0_P1P0_DP(23)    I70 @S9S_MB_2U_LIB.S9S_MB_2U(SCH_1):PAGE32
   BR7 UPI_CPU1_CPU0_P1P0_DN<22> @S9S_MB_2U_LIB.S9S_MB_2U(SCH_1):UPI_CPU1_CPU0_P1P0_DN(22)    I70 @S9S_MB_2U_LIB.S9S_MB_2U(SCH_1):PAGE32
   BN5 UPI_CPU1_CPU0_P1P0_DP<21> @S9S_MB_2U_LIB.S9S_MB_2U(SCH_1):UPI_CPU1_CPU0_P1P0_DP(21)    I70 @S9S_MB_2U_LIB.S9S_MB_2U(SCH_1):PAGE32
   BK6 UPI_CPU1_CPU0_P1P0_DP<20> @S9S_MB_2U_LIB.S9S_MB_2U(SCH_1):UPI_CPU1_CPU0_P1P0_DP(20)    I70 @S9S_MB_2U_LIB.S9S_MB_2U(SCH_1):PAGE32
   BJ5 UPI_CPU1_CPU0_P1P0_DP<19> @S9S_MB_2U_LIB.S9S_MB_2U(SCH_1):UPI_CPU1_CPU0_P1P0_DP(19)    I70 @S9S_MB_2U_LIB.S9S_MB_2U(SCH_1):PAGE32
   BF6 UPI_CPU1_CPU0_P1P0_DP<18> @S9S_MB_2U_LIB.S9S_MB_2U(SCH_1):UPI_CPU1_CPU0_P1P0_DP(18)    I70 @S9S_MB_2U_LIB.S9S_MB_2U(SCH_1):PAGE32
   BE5 UPI_CPU1_CPU0_P1P0_DP<17> @S9S_MB_2U_LIB.S9S_MB_2U(SCH_1):UPI_CPU1_CPU0_P1P0_DP(17)    I70 @S9S_MB_2U_LIB.S9S_MB_2U(SCH_1):PAGE32
   BB6 UPI_CPU1_CPU0_P1P0_DP<16> @S9S_MB_2U_LIB.S9S_MB_2U(SCH_1):UPI_CPU1_CPU0_P1P0_DP(16)    I70 @S9S_MB_2U_LIB.S9S_MB_2U(SCH_1):PAGE32
   BA5 UPI_CPU1_CPU0_P1P0_DP<15> @S9S_MB_2U_LIB.S9S_MB_2U(SCH_1):UPI_CPU1_CPU0_P1P0_DP(15)    I70 @S9S_MB_2U_LIB.S9S_MB_2U(SCH_1):PAGE32
   AV6 UPI_CPU1_CPU0_P1P0_DP<14> @S9S_MB_2U_LIB.S9S_MB_2U(SCH_1):UPI_CPU1_CPU0_P1P0_DP(14)    I70 @S9S_MB_2U_LIB.S9S_MB_2U(SCH_1):PAGE32
   AU5 UPI_CPU1_CPU0_P1P0_DP<13> @S9S_MB_2U_LIB.S9S_MB_2U(SCH_1):UPI_CPU1_CPU0_P1P0_DP(13)    I70 @S9S_MB_2U_LIB.S9S_MB_2U(SCH_1):PAGE32
   AP6 UPI_CPU1_CPU0_P1P0_DP<12> @S9S_MB_2U_LIB.S9S_MB_2U(SCH_1):UPI_CPU1_CPU0_P1P0_DP(12)    I70 @S9S_MB_2U_LIB.S9S_MB_2U(SCH_1):PAGE32
   AN5 UPI_CPU1_CPU0_P1P0_DP<11> @S9S_MB_2U_LIB.S9S_MB_2U(SCH_1):UPI_CPU1_CPU0_P1P0_DP(11)    I70 @S9S_MB_2U_LIB.S9S_MB_2U(SCH_1):PAGE32
   AK6 UPI_CPU1_CPU0_P1P0_DP<10> @S9S_MB_2U_LIB.S9S_MB_2U(SCH_1):UPI_CPU1_CPU0_P1P0_DP(10)    I70 @S9S_MB_2U_LIB.S9S_MB_2U(SCH_1):PAGE32
   AH6 UPI_CPU1_CPU0_P1P0_DN<9> @S9S_MB_2U_LIB.S9S_MB_2U(SCH_1):UPI_CPU1_CPU0_P1P0_DN(9)    I70 @S9S_MB_2U_LIB.S9S_MB_2U(SCH_1):PAGE32
   AF6 UPI_CPU1_CPU0_P1P0_DN<8> @S9S_MB_2U_LIB.S9S_MB_2U(SCH_1):UPI_CPU1_CPU0_P1P0_DN(8)    I70 @S9S_MB_2U_LIB.S9S_MB_2U(SCH_1):PAGE32
   AE5 UPI_CPU1_CPU0_P1P0_DN<7> @S9S_MB_2U_LIB.S9S_MB_2U(SCH_1):UPI_CPU1_CPU0_P1P0_DN(7)    I70 @S9S_MB_2U_LIB.S9S_MB_2U(SCH_1):PAGE32
   AB6 UPI_CPU1_CPU0_P1P0_DN<6> @S9S_MB_2U_LIB.S9S_MB_2U(SCH_1):UPI_CPU1_CPU0_P1P0_DN(6)    I70 @S9S_MB_2U_LIB.S9S_MB_2U(SCH_1):PAGE32
   AA5 UPI_CPU1_CPU0_P1P0_DP<5> @S9S_MB_2U_LIB.S9S_MB_2U(SCH_1):UPI_CPU1_CPU0_P1P0_DP(5)    I70 @S9S_MB_2U_LIB.S9S_MB_2U(SCH_1):PAGE32
    V6 UPI_CPU1_CPU0_P1P0_DN<4> @S9S_MB_2U_LIB.S9S_MB_2U(SCH_1):UPI_CPU1_CPU0_P1P0_DN(4)    I70 @S9S_MB_2U_LIB.S9S_MB_2U(SCH_1):PAGE32
    U5 UPI_CPU1_CPU0_P1P0_DP<3> @S9S_MB_2U_LIB.S9S_MB_2U(SCH_1):UPI_CPU1_CPU0_P1P0_DP(3)    I70 @S9S_MB_2U_LIB.S9S_MB_2U(SCH_1):PAGE32
    P6 UPI_CPU1_CPU0_P1P0_DN<2> @S9S_MB_2U_LIB.S9S_MB_2U(SCH_1):UPI_CPU1_CPU0_P1P0_DN(2)    I70 @S9S_MB_2U_LIB.S9S_MB_2U(SCH_1):PAGE32
    N5 UPI_CPU1_CPU0_P1P0_DN<1> @S9S_MB_2U_LIB.S9S_MB_2U(SCH_1):UPI_CPU1_CPU0_P1P0_DN(1)    I70 @S9S_MB_2U_LIB.S9S_MB_2U(SCH_1):PAGE32
    K6 UPI_CPU1_CPU0_P1P0_DN<0> @S9S_MB_2U_LIB.S9S_MB_2U(SCH_1):UPI_CPU1_CPU0_P1P0_DN(0)    I70 @S9S_MB_2U_LIB.S9S_MB_2U(SCH_1):PAGE32
   BT6 UPI_CPU1_CPU0_P1P0_DN<23> @S9S_MB_2U_LIB.S9S_MB_2U(SCH_1):UPI_CPU1_CPU0_P1P0_DN(23)    I70 @S9S_MB_2U_LIB.S9S_MB_2U(SCH_1):PAGE32
   BP6 UPI_CPU1_CPU0_P1P0_DP<22> @S9S_MB_2U_LIB.S9S_MB_2U(SCH_1):UPI_CPU1_CPU0_P1P0_DP(22)    I70 @S9S_MB_2U_LIB.S9S_MB_2U(SCH_1):PAGE32
   BM6 UPI_CPU1_CPU0_P1P0_DN<21> @S9S_MB_2U_LIB.S9S_MB_2U(SCH_1):UPI_CPU1_CPU0_P1P0_DN(21)    I70 @S9S_MB_2U_LIB.S9S_MB_2U(SCH_1):PAGE32
   BL7 UPI_CPU1_CPU0_P1P0_DN<20> @S9S_MB_2U_LIB.S9S_MB_2U(SCH_1):UPI_CPU1_CPU0_P1P0_DN(20)    I70 @S9S_MB_2U_LIB.S9S_MB_2U(SCH_1):PAGE32
   BH6 UPI_CPU1_CPU0_P1P0_DN<19> @S9S_MB_2U_LIB.S9S_MB_2U(SCH_1):UPI_CPU1_CPU0_P1P0_DN(19)    I70 @S9S_MB_2U_LIB.S9S_MB_2U(SCH_1):PAGE32
   BG7 UPI_CPU1_CPU0_P1P0_DN<18> @S9S_MB_2U_LIB.S9S_MB_2U(SCH_1):UPI_CPU1_CPU0_P1P0_DN(18)    I70 @S9S_MB_2U_LIB.S9S_MB_2U(SCH_1):PAGE32
   BD6 UPI_CPU1_CPU0_P1P0_DN<17> @S9S_MB_2U_LIB.S9S_MB_2U(SCH_1):UPI_CPU1_CPU0_P1P0_DN(17)    I70 @S9S_MB_2U_LIB.S9S_MB_2U(SCH_1):PAGE32
   BC7 UPI_CPU1_CPU0_P1P0_DN<16> @S9S_MB_2U_LIB.S9S_MB_2U(SCH_1):UPI_CPU1_CPU0_P1P0_DN(16)    I70 @S9S_MB_2U_LIB.S9S_MB_2U(SCH_1):PAGE32
   AY6 UPI_CPU1_CPU0_P1P0_DN<15> @S9S_MB_2U_LIB.S9S_MB_2U(SCH_1):UPI_CPU1_CPU0_P1P0_DN(15)    I70 @S9S_MB_2U_LIB.S9S_MB_2U(SCH_1):PAGE32
   AW7 UPI_CPU1_CPU0_P1P0_DN<14> @S9S_MB_2U_LIB.S9S_MB_2U(SCH_1):UPI_CPU1_CPU0_P1P0_DN(14)    I70 @S9S_MB_2U_LIB.S9S_MB_2U(SCH_1):PAGE32
   AT6 UPI_CPU1_CPU0_P1P0_DN<13> @S9S_MB_2U_LIB.S9S_MB_2U(SCH_1):UPI_CPU1_CPU0_P1P0_DN(13)    I70 @S9S_MB_2U_LIB.S9S_MB_2U(SCH_1):PAGE32
   AR7 UPI_CPU1_CPU0_P1P0_DN<12> @S9S_MB_2U_LIB.S9S_MB_2U(SCH_1):UPI_CPU1_CPU0_P1P0_DN(12)    I70 @S9S_MB_2U_LIB.S9S_MB_2U(SCH_1):PAGE32
   AM6 UPI_CPU1_CPU0_P1P0_DN<11> @S9S_MB_2U_LIB.S9S_MB_2U(SCH_1):UPI_CPU1_CPU0_P1P0_DN(11)    I70 @S9S_MB_2U_LIB.S9S_MB_2U(SCH_1):PAGE32
   AL7 UPI_CPU1_CPU0_P1P0_DN<10> @S9S_MB_2U_LIB.S9S_MB_2U(SCH_1):UPI_CPU1_CPU0_P1P0_DN(10)    I70 @S9S_MB_2U_LIB.S9S_MB_2U(SCH_1):PAGE32
   AJ5 UPI_CPU1_CPU0_P1P0_DP<9> @S9S_MB_2U_LIB.S9S_MB_2U(SCH_1):UPI_CPU1_CPU0_P1P0_DP(9)    I70 @S9S_MB_2U_LIB.S9S_MB_2U(SCH_1):PAGE32
   AG7 UPI_CPU1_CPU0_P1P0_DP<8> @S9S_MB_2U_LIB.S9S_MB_2U(SCH_1):UPI_CPU1_CPU0_P1P0_DP(8)    I70 @S9S_MB_2U_LIB.S9S_MB_2U(SCH_1):PAGE32
   AD6 UPI_CPU1_CPU0_P1P0_DP<7> @S9S_MB_2U_LIB.S9S_MB_2U(SCH_1):UPI_CPU1_CPU0_P1P0_DP(7)    I70 @S9S_MB_2U_LIB.S9S_MB_2U(SCH_1):PAGE32
   AC7 UPI_CPU1_CPU0_P1P0_DP<6> @S9S_MB_2U_LIB.S9S_MB_2U(SCH_1):UPI_CPU1_CPU0_P1P0_DP(6)    I70 @S9S_MB_2U_LIB.S9S_MB_2U(SCH_1):PAGE32
    Y6 UPI_CPU1_CPU0_P1P0_DN<5> @S9S_MB_2U_LIB.S9S_MB_2U(SCH_1):UPI_CPU1_CPU0_P1P0_DN(5)    I70 @S9S_MB_2U_LIB.S9S_MB_2U(SCH_1):PAGE32
    W7 UPI_CPU1_CPU0_P1P0_DP<4> @S9S_MB_2U_LIB.S9S_MB_2U(SCH_1):UPI_CPU1_CPU0_P1P0_DP(4)    I70 @S9S_MB_2U_LIB.S9S_MB_2U(SCH_1):PAGE32
    T6 UPI_CPU1_CPU0_P1P0_DN<3> @S9S_MB_2U_LIB.S9S_MB_2U(SCH_1):UPI_CPU1_CPU0_P1P0_DN(3)    I70 @S9S_MB_2U_LIB.S9S_MB_2U(SCH_1):PAGE32
    R7 UPI_CPU1_CPU0_P1P0_DP<2> @S9S_MB_2U_LIB.S9S_MB_2U(SCH_1):UPI_CPU1_CPU0_P1P0_DP(2)    I70 @S9S_MB_2U_LIB.S9S_MB_2U(SCH_1):PAGE32
    M6 UPI_CPU1_CPU0_P1P0_DP<1> @S9S_MB_2U_LIB.S9S_MB_2U(SCH_1):UPI_CPU1_CPU0_P1P0_DP(1)    I70 @S9S_MB_2U_LIB.S9S_MB_2U(SCH_1):PAGE32
    L7 UPI_CPU1_CPU0_P1P0_DP<0> @S9S_MB_2U_LIB.S9S_MB_2U(SCH_1):UPI_CPU1_CPU0_P1P0_DP(0)    I70 @S9S_MB_2U_LIB.S9S_MB_2U(SCH_1):PAGE32
   BT2 UPI_CPU0_CPU1_P0P1_DN<23> @S9S_MB_2U_LIB.S9S_MB_2U(SCH_1):UPI_CPU0_CPU1_P0P1_DN(23)    I70 @S9S_MB_2U_LIB.S9S_MB_2U(SCH_1):PAGE32
   BR3 UPI_CPU0_CPU1_P0P1_DP<22> @S9S_MB_2U_LIB.S9S_MB_2U(SCH_1):UPI_CPU0_CPU1_P0P1_DP(22)    I70 @S9S_MB_2U_LIB.S9S_MB_2U(SCH_1):PAGE32
   BM2 UPI_CPU0_CPU1_P0P1_DP<21> @S9S_MB_2U_LIB.S9S_MB_2U(SCH_1):UPI_CPU0_CPU1_P0P1_DP(21)    I70 @S9S_MB_2U_LIB.S9S_MB_2U(SCH_1):PAGE32
   BK2 UPI_CPU0_CPU1_P0P1_DP<20> @S9S_MB_2U_LIB.S9S_MB_2U(SCH_1):UPI_CPU0_CPU1_P0P1_DP(20)    I70 @S9S_MB_2U_LIB.S9S_MB_2U(SCH_1):PAGE32
   BH2 UPI_CPU0_CPU1_P0P1_DN<19> @S9S_MB_2U_LIB.S9S_MB_2U(SCH_1):UPI_CPU0_CPU1_P0P1_DN(19)    I70 @S9S_MB_2U_LIB.S9S_MB_2U(SCH_1):PAGE32
   BF2 UPI_CPU0_CPU1_P0P1_DN<18> @S9S_MB_2U_LIB.S9S_MB_2U(SCH_1):UPI_CPU0_CPU1_P0P1_DN(18)    I70 @S9S_MB_2U_LIB.S9S_MB_2U(SCH_1):PAGE32
   BD2 UPI_CPU0_CPU1_P0P1_DN<17> @S9S_MB_2U_LIB.S9S_MB_2U(SCH_1):UPI_CPU0_CPU1_P0P1_DN(17)    I70 @S9S_MB_2U_LIB.S9S_MB_2U(SCH_1):PAGE32
   BB2 UPI_CPU0_CPU1_P0P1_DN<16> @S9S_MB_2U_LIB.S9S_MB_2U(SCH_1):UPI_CPU0_CPU1_P0P1_DN(16)    I70 @S9S_MB_2U_LIB.S9S_MB_2U(SCH_1):PAGE32
   AY2 UPI_CPU0_CPU1_P0P1_DP<15> @S9S_MB_2U_LIB.S9S_MB_2U(SCH_1):UPI_CPU0_CPU1_P0P1_DP(15)    I70 @S9S_MB_2U_LIB.S9S_MB_2U(SCH_1):PAGE32
   AU1 UPI_CPU0_CPU1_P0P1_DN<14> @S9S_MB_2U_LIB.S9S_MB_2U(SCH_1):UPI_CPU0_CPU1_P0P1_DN(14)    I70 @S9S_MB_2U_LIB.S9S_MB_2U(SCH_1):PAGE32
   AT2 UPI_CPU0_CPU1_P0P1_DP<13> @S9S_MB_2U_LIB.S9S_MB_2U(SCH_1):UPI_CPU0_CPU1_P0P1_DP(13)    I70 @S9S_MB_2U_LIB.S9S_MB_2U(SCH_1):PAGE32
   AP2 UPI_CPU0_CPU1_P0P1_DP<12> @S9S_MB_2U_LIB.S9S_MB_2U(SCH_1):UPI_CPU0_CPU1_P0P1_DP(12)    I70 @S9S_MB_2U_LIB.S9S_MB_2U(SCH_1):PAGE32
   AM2 UPI_CPU0_CPU1_P0P1_DN<11> @S9S_MB_2U_LIB.S9S_MB_2U(SCH_1):UPI_CPU0_CPU1_P0P1_DN(11)    I70 @S9S_MB_2U_LIB.S9S_MB_2U(SCH_1):PAGE32
   AK2 UPI_CPU0_CPU1_P0P1_DN<10> @S9S_MB_2U_LIB.S9S_MB_2U(SCH_1):UPI_CPU0_CPU1_P0P1_DN(10)    I70 @S9S_MB_2U_LIB.S9S_MB_2U(SCH_1):PAGE32
   AH2 UPI_CPU0_CPU1_P0P1_DN<9> @S9S_MB_2U_LIB.S9S_MB_2U(SCH_1):UPI_CPU0_CPU1_P0P1_DN(9)    I70 @S9S_MB_2U_LIB.S9S_MB_2U(SCH_1):PAGE32
   AF2 UPI_CPU0_CPU1_P0P1_DN<8> @S9S_MB_2U_LIB.S9S_MB_2U(SCH_1):UPI_CPU0_CPU1_P0P1_DN(8)    I70 @S9S_MB_2U_LIB.S9S_MB_2U(SCH_1):PAGE32
   AD2 UPI_CPU0_CPU1_P0P1_DN<7> @S9S_MB_2U_LIB.S9S_MB_2U(SCH_1):UPI_CPU0_CPU1_P0P1_DN(7)    I70 @S9S_MB_2U_LIB.S9S_MB_2U(SCH_1):PAGE32
   AA1 UPI_CPU0_CPU1_P0P1_DN<6> @S9S_MB_2U_LIB.S9S_MB_2U(SCH_1):UPI_CPU0_CPU1_P0P1_DN(6)    I70 @S9S_MB_2U_LIB.S9S_MB_2U(SCH_1):PAGE32
    Y2 UPI_CPU0_CPU1_P0P1_DN<5> @S9S_MB_2U_LIB.S9S_MB_2U(SCH_1):UPI_CPU0_CPU1_P0P1_DN(5)    I70 @S9S_MB_2U_LIB.S9S_MB_2U(SCH_1):PAGE32
    U1 UPI_CPU0_CPU1_P0P1_DN<4> @S9S_MB_2U_LIB.S9S_MB_2U(SCH_1):UPI_CPU0_CPU1_P0P1_DN(4)    I70 @S9S_MB_2U_LIB.S9S_MB_2U(SCH_1):PAGE32
    T2 UPI_CPU0_CPU1_P0P1_DN<3> @S9S_MB_2U_LIB.S9S_MB_2U(SCH_1):UPI_CPU0_CPU1_P0P1_DN(3)    I70 @S9S_MB_2U_LIB.S9S_MB_2U(SCH_1):PAGE32
    N1 UPI_CPU0_CPU1_P0P1_DN<2> @S9S_MB_2U_LIB.S9S_MB_2U(SCH_1):UPI_CPU0_CPU1_P0P1_DN(2)    I70 @S9S_MB_2U_LIB.S9S_MB_2U(SCH_1):PAGE32
    M2 UPI_CPU0_CPU1_P0P1_DN<1> @S9S_MB_2U_LIB.S9S_MB_2U(SCH_1):UPI_CPU0_CPU1_P0P1_DN(1)    I70 @S9S_MB_2U_LIB.S9S_MB_2U(SCH_1):PAGE32
    K4 UPI_CPU0_CPU1_P0P1_DN<0> @S9S_MB_2U_LIB.S9S_MB_2U(SCH_1):UPI_CPU0_CPU1_P0P1_DN(0)    I70 @S9S_MB_2U_LIB.S9S_MB_2U(SCH_1):PAGE32
   BU3 UPI_CPU0_CPU1_P0P1_DP<23> @S9S_MB_2U_LIB.S9S_MB_2U(SCH_1):UPI_CPU0_CPU1_P0P1_DP(23)    I70 @S9S_MB_2U_LIB.S9S_MB_2U(SCH_1):PAGE32
   BN3 UPI_CPU0_CPU1_P0P1_DN<22> @S9S_MB_2U_LIB.S9S_MB_2U(SCH_1):UPI_CPU0_CPU1_P0P1_DN(22)    I70 @S9S_MB_2U_LIB.S9S_MB_2U(SCH_1):PAGE32
   BL3 UPI_CPU0_CPU1_P0P1_DN<21> @S9S_MB_2U_LIB.S9S_MB_2U(SCH_1):UPI_CPU0_CPU1_P0P1_DN(21)    I70 @S9S_MB_2U_LIB.S9S_MB_2U(SCH_1):PAGE32
   BJ1 UPI_CPU0_CPU1_P0P1_DN<20> @S9S_MB_2U_LIB.S9S_MB_2U(SCH_1):UPI_CPU0_CPU1_P0P1_DN(20)    I70 @S9S_MB_2U_LIB.S9S_MB_2U(SCH_1):PAGE32
   BG3 UPI_CPU0_CPU1_P0P1_DP<19> @S9S_MB_2U_LIB.S9S_MB_2U(SCH_1):UPI_CPU0_CPU1_P0P1_DP(19)    I70 @S9S_MB_2U_LIB.S9S_MB_2U(SCH_1):PAGE32
   BE1 UPI_CPU0_CPU1_P0P1_DP<18> @S9S_MB_2U_LIB.S9S_MB_2U(SCH_1):UPI_CPU0_CPU1_P0P1_DP(18)    I70 @S9S_MB_2U_LIB.S9S_MB_2U(SCH_1):PAGE32
   BC3 UPI_CPU0_CPU1_P0P1_DP<17> @S9S_MB_2U_LIB.S9S_MB_2U(SCH_1):UPI_CPU0_CPU1_P0P1_DP(17)    I70 @S9S_MB_2U_LIB.S9S_MB_2U(SCH_1):PAGE32
   BA1 UPI_CPU0_CPU1_P0P1_DP<16> @S9S_MB_2U_LIB.S9S_MB_2U(SCH_1):UPI_CPU0_CPU1_P0P1_DP(16)    I70 @S9S_MB_2U_LIB.S9S_MB_2U(SCH_1):PAGE32
   AW3 UPI_CPU0_CPU1_P0P1_DN<15> @S9S_MB_2U_LIB.S9S_MB_2U(SCH_1):UPI_CPU0_CPU1_P0P1_DN(15)    I70 @S9S_MB_2U_LIB.S9S_MB_2U(SCH_1):PAGE32
   AV2 UPI_CPU0_CPU1_P0P1_DP<14> @S9S_MB_2U_LIB.S9S_MB_2U(SCH_1):UPI_CPU0_CPU1_P0P1_DP(14)    I70 @S9S_MB_2U_LIB.S9S_MB_2U(SCH_1):PAGE32
   AR3 UPI_CPU0_CPU1_P0P1_DN<13> @S9S_MB_2U_LIB.S9S_MB_2U(SCH_1):UPI_CPU0_CPU1_P0P1_DN(13)    I70 @S9S_MB_2U_LIB.S9S_MB_2U(SCH_1):PAGE32
   AN1 UPI_CPU0_CPU1_P0P1_DN<12> @S9S_MB_2U_LIB.S9S_MB_2U(SCH_1):UPI_CPU0_CPU1_P0P1_DN(12)    I70 @S9S_MB_2U_LIB.S9S_MB_2U(SCH_1):PAGE32
   AL3 UPI_CPU0_CPU1_P0P1_DP<11> @S9S_MB_2U_LIB.S9S_MB_2U(SCH_1):UPI_CPU0_CPU1_P0P1_DP(11)    I70 @S9S_MB_2U_LIB.S9S_MB_2U(SCH_1):PAGE32
   AJ1 UPI_CPU0_CPU1_P0P1_DP<10> @S9S_MB_2U_LIB.S9S_MB_2U(SCH_1):UPI_CPU0_CPU1_P0P1_DP(10)    I70 @S9S_MB_2U_LIB.S9S_MB_2U(SCH_1):PAGE32
   AG3 UPI_CPU0_CPU1_P0P1_DP<9> @S9S_MB_2U_LIB.S9S_MB_2U(SCH_1):UPI_CPU0_CPU1_P0P1_DP(9)    I70 @S9S_MB_2U_LIB.S9S_MB_2U(SCH_1):PAGE32
   AE1 UPI_CPU0_CPU1_P0P1_DP<8> @S9S_MB_2U_LIB.S9S_MB_2U(SCH_1):UPI_CPU0_CPU1_P0P1_DP(8)    I70 @S9S_MB_2U_LIB.S9S_MB_2U(SCH_1):PAGE32
   AC3 UPI_CPU0_CPU1_P0P1_DP<7> @S9S_MB_2U_LIB.S9S_MB_2U(SCH_1):UPI_CPU0_CPU1_P0P1_DP(7)    I70 @S9S_MB_2U_LIB.S9S_MB_2U(SCH_1):PAGE32
   AB2 UPI_CPU0_CPU1_P0P1_DP<6> @S9S_MB_2U_LIB.S9S_MB_2U(SCH_1):UPI_CPU0_CPU1_P0P1_DP(6)    I70 @S9S_MB_2U_LIB.S9S_MB_2U(SCH_1):PAGE32
    W3 UPI_CPU0_CPU1_P0P1_DP<5> @S9S_MB_2U_LIB.S9S_MB_2U(SCH_1):UPI_CPU0_CPU1_P0P1_DP(5)    I70 @S9S_MB_2U_LIB.S9S_MB_2U(SCH_1):PAGE32
    V2 UPI_CPU0_CPU1_P0P1_DP<4> @S9S_MB_2U_LIB.S9S_MB_2U(SCH_1):UPI_CPU0_CPU1_P0P1_DP(4)    I70 @S9S_MB_2U_LIB.S9S_MB_2U(SCH_1):PAGE32
    R3 UPI_CPU0_CPU1_P0P1_DP<3> @S9S_MB_2U_LIB.S9S_MB_2U(SCH_1):UPI_CPU0_CPU1_P0P1_DP(3)    I70 @S9S_MB_2U_LIB.S9S_MB_2U(SCH_1):PAGE32
    P2 UPI_CPU0_CPU1_P0P1_DP<2> @S9S_MB_2U_LIB.S9S_MB_2U(SCH_1):UPI_CPU0_CPU1_P0P1_DP(2)    I70 @S9S_MB_2U_LIB.S9S_MB_2U(SCH_1):PAGE32
    L3 UPI_CPU0_CPU1_P0P1_DP<1> @S9S_MB_2U_LIB.S9S_MB_2U(SCH_1):UPI_CPU0_CPU1_P0P1_DP(1)    I70 @S9S_MB_2U_LIB.S9S_MB_2U(SCH_1):PAGE32
    J3 UPI_CPU0_CPU1_P0P1_DP<0> @S9S_MB_2U_LIB.S9S_MB_2U(SCH_1):UPI_CPU0_CPU1_P0P1_DP(0)    I70 @S9S_MB_2U_LIB.S9S_MB_2U(SCH_1):PAGE32
   CB2 UPI_CPU1_CPU0_P0P1_DP<23> @S9S_MB_2U_LIB.S9S_MB_2U(SCH_1):UPI_CPU1_CPU0_P0P1_DP(23)   I102 @S9S_MB_2U_LIB.S9S_MB_2U(SCH_1):PAGE33
   CD2 UPI_CPU1_CPU0_P0P1_DP<22> @S9S_MB_2U_LIB.S9S_MB_2U(SCH_1):UPI_CPU1_CPU0_P0P1_DP(22)   I102 @S9S_MB_2U_LIB.S9S_MB_2U(SCH_1):PAGE33
   CF2 UPI_CPU1_CPU0_P0P1_DN<21> @S9S_MB_2U_LIB.S9S_MB_2U(SCH_1):UPI_CPU1_CPU0_P0P1_DN(21)   I102 @S9S_MB_2U_LIB.S9S_MB_2U(SCH_1):PAGE33
   CH2 UPI_CPU1_CPU0_P0P1_DP<20> @S9S_MB_2U_LIB.S9S_MB_2U(SCH_1):UPI_CPU1_CPU0_P0P1_DP(20)   I102 @S9S_MB_2U_LIB.S9S_MB_2U(SCH_1):PAGE33
   CJ1 UPI_CPU1_CPU0_P0P1_DP<19> @S9S_MB_2U_LIB.S9S_MB_2U(SCH_1):UPI_CPU1_CPU0_P0P1_DP(19)   I102 @S9S_MB_2U_LIB.S9S_MB_2U(SCH_1):PAGE33
   CL3 UPI_CPU1_CPU0_P0P1_DN<18> @S9S_MB_2U_LIB.S9S_MB_2U(SCH_1):UPI_CPU1_CPU0_P0P1_DN(18)   I102 @S9S_MB_2U_LIB.S9S_MB_2U(SCH_1):PAGE33
   CN1 UPI_CPU1_CPU0_P0P1_DP<17> @S9S_MB_2U_LIB.S9S_MB_2U(SCH_1):UPI_CPU1_CPU0_P0P1_DP(17)   I102 @S9S_MB_2U_LIB.S9S_MB_2U(SCH_1):PAGE33
   CR3 UPI_CPU1_CPU0_P0P1_DN<16> @S9S_MB_2U_LIB.S9S_MB_2U(SCH_1):UPI_CPU1_CPU0_P0P1_DN(16)   I102 @S9S_MB_2U_LIB.S9S_MB_2U(SCH_1):PAGE33
   CV2 UPI_CPU1_CPU0_P0P1_DN<15> @S9S_MB_2U_LIB.S9S_MB_2U(SCH_1):UPI_CPU1_CPU0_P0P1_DN(15)   I102 @S9S_MB_2U_LIB.S9S_MB_2U(SCH_1):PAGE33
   CY2 UPI_CPU1_CPU0_P0P1_DN<14> @S9S_MB_2U_LIB.S9S_MB_2U(SCH_1):UPI_CPU1_CPU0_P0P1_DN(14)   I102 @S9S_MB_2U_LIB.S9S_MB_2U(SCH_1):PAGE33
   DB2 UPI_CPU1_CPU0_P0P1_DN<13> @S9S_MB_2U_LIB.S9S_MB_2U(SCH_1):UPI_CPU1_CPU0_P0P1_DN(13)   I102 @S9S_MB_2U_LIB.S9S_MB_2U(SCH_1):PAGE33
   DD2 UPI_CPU1_CPU0_P0P1_DP<12> @S9S_MB_2U_LIB.S9S_MB_2U(SCH_1):UPI_CPU1_CPU0_P0P1_DP(12)   I102 @S9S_MB_2U_LIB.S9S_MB_2U(SCH_1):PAGE33
   DE1 UPI_CPU1_CPU0_P0P1_DN<11> @S9S_MB_2U_LIB.S9S_MB_2U(SCH_1):UPI_CPU1_CPU0_P0P1_DN(11)   I102 @S9S_MB_2U_LIB.S9S_MB_2U(SCH_1):PAGE33
   DG3 UPI_CPU1_CPU0_P0P1_DN<10> @S9S_MB_2U_LIB.S9S_MB_2U(SCH_1):UPI_CPU1_CPU0_P0P1_DN(10)   I102 @S9S_MB_2U_LIB.S9S_MB_2U(SCH_1):PAGE33
   DJ1 UPI_CPU1_CPU0_P0P1_DN<9> @S9S_MB_2U_LIB.S9S_MB_2U(SCH_1):UPI_CPU1_CPU0_P0P1_DN(9)   I102 @S9S_MB_2U_LIB.S9S_MB_2U(SCH_1):PAGE33
   DL3 UPI_CPU1_CPU0_P0P1_DN<8> @S9S_MB_2U_LIB.S9S_MB_2U(SCH_1):UPI_CPU1_CPU0_P0P1_DN(8)   I102 @S9S_MB_2U_LIB.S9S_MB_2U(SCH_1):PAGE33
   DN1 UPI_CPU1_CPU0_P0P1_DN<7> @S9S_MB_2U_LIB.S9S_MB_2U(SCH_1):UPI_CPU1_CPU0_P0P1_DN(7)   I102 @S9S_MB_2U_LIB.S9S_MB_2U(SCH_1):PAGE33
   DT2 UPI_CPU1_CPU0_P0P1_DN<6> @S9S_MB_2U_LIB.S9S_MB_2U(SCH_1):UPI_CPU1_CPU0_P0P1_DN(6)   I102 @S9S_MB_2U_LIB.S9S_MB_2U(SCH_1):PAGE33
   DU1 UPI_CPU1_CPU0_P0P1_DN<5> @S9S_MB_2U_LIB.S9S_MB_2U(SCH_1):UPI_CPU1_CPU0_P0P1_DN(5)   I102 @S9S_MB_2U_LIB.S9S_MB_2U(SCH_1):PAGE33
   DY2 UPI_CPU1_CPU0_P0P1_DN<4> @S9S_MB_2U_LIB.S9S_MB_2U(SCH_1):UPI_CPU1_CPU0_P0P1_DN(4)   I102 @S9S_MB_2U_LIB.S9S_MB_2U(SCH_1):PAGE33
   EA1 UPI_CPU1_CPU0_P0P1_DN<3> @S9S_MB_2U_LIB.S9S_MB_2U(SCH_1):UPI_CPU1_CPU0_P0P1_DN(3)   I102 @S9S_MB_2U_LIB.S9S_MB_2U(SCH_1):PAGE33
   ED2 UPI_CPU1_CPU0_P0P1_DP<2> @S9S_MB_2U_LIB.S9S_MB_2U(SCH_1):UPI_CPU1_CPU0_P0P1_DP(2)   I102 @S9S_MB_2U_LIB.S9S_MB_2U(SCH_1):PAGE33
   EE3 UPI_CPU1_CPU0_P0P1_DN<1> @S9S_MB_2U_LIB.S9S_MB_2U(SCH_1):UPI_CPU1_CPU0_P0P1_DN(1)   I102 @S9S_MB_2U_LIB.S9S_MB_2U(SCH_1):PAGE33
   EH2 UPI_CPU1_CPU0_P0P1_DN<0> @S9S_MB_2U_LIB.S9S_MB_2U(SCH_1):UPI_CPU1_CPU0_P0P1_DN(0)   I102 @S9S_MB_2U_LIB.S9S_MB_2U(SCH_1):PAGE33
   BY2 UPI_CPU1_CPU0_P0P1_DN<23> @S9S_MB_2U_LIB.S9S_MB_2U(SCH_1):UPI_CPU1_CPU0_P0P1_DN(23)   I102 @S9S_MB_2U_LIB.S9S_MB_2U(SCH_1):PAGE33
   CC3 UPI_CPU1_CPU0_P0P1_DN<22> @S9S_MB_2U_LIB.S9S_MB_2U(SCH_1):UPI_CPU1_CPU0_P0P1_DN(22)   I102 @S9S_MB_2U_LIB.S9S_MB_2U(SCH_1):PAGE33
   CE1 UPI_CPU1_CPU0_P0P1_DP<21> @S9S_MB_2U_LIB.S9S_MB_2U(SCH_1):UPI_CPU1_CPU0_P0P1_DP(21)   I102 @S9S_MB_2U_LIB.S9S_MB_2U(SCH_1):PAGE33
   CG3 UPI_CPU1_CPU0_P0P1_DN<20> @S9S_MB_2U_LIB.S9S_MB_2U(SCH_1):UPI_CPU1_CPU0_P0P1_DN(20)   I102 @S9S_MB_2U_LIB.S9S_MB_2U(SCH_1):PAGE33
   CK2 UPI_CPU1_CPU0_P0P1_DN<19> @S9S_MB_2U_LIB.S9S_MB_2U(SCH_1):UPI_CPU1_CPU0_P0P1_DN(19)   I102 @S9S_MB_2U_LIB.S9S_MB_2U(SCH_1):PAGE33
   CM2 UPI_CPU1_CPU0_P0P1_DP<18> @S9S_MB_2U_LIB.S9S_MB_2U(SCH_1):UPI_CPU1_CPU0_P0P1_DP(18)   I102 @S9S_MB_2U_LIB.S9S_MB_2U(SCH_1):PAGE33
   CP2 UPI_CPU1_CPU0_P0P1_DN<17> @S9S_MB_2U_LIB.S9S_MB_2U(SCH_1):UPI_CPU1_CPU0_P0P1_DN(17)   I102 @S9S_MB_2U_LIB.S9S_MB_2U(SCH_1):PAGE33
   CT2 UPI_CPU1_CPU0_P0P1_DP<16> @S9S_MB_2U_LIB.S9S_MB_2U(SCH_1):UPI_CPU1_CPU0_P0P1_DP(16)   I102 @S9S_MB_2U_LIB.S9S_MB_2U(SCH_1):PAGE33
   CU1 UPI_CPU1_CPU0_P0P1_DP<15> @S9S_MB_2U_LIB.S9S_MB_2U(SCH_1):UPI_CPU1_CPU0_P0P1_DP(15)   I102 @S9S_MB_2U_LIB.S9S_MB_2U(SCH_1):PAGE33
   CW3 UPI_CPU1_CPU0_P0P1_DP<14> @S9S_MB_2U_LIB.S9S_MB_2U(SCH_1):UPI_CPU1_CPU0_P0P1_DP(14)   I102 @S9S_MB_2U_LIB.S9S_MB_2U(SCH_1):PAGE33
   DA1 UPI_CPU1_CPU0_P0P1_DP<13> @S9S_MB_2U_LIB.S9S_MB_2U(SCH_1):UPI_CPU1_CPU0_P0P1_DP(13)   I102 @S9S_MB_2U_LIB.S9S_MB_2U(SCH_1):PAGE33
   DC3 UPI_CPU1_CPU0_P0P1_DN<12> @S9S_MB_2U_LIB.S9S_MB_2U(SCH_1):UPI_CPU1_CPU0_P0P1_DN(12)   I102 @S9S_MB_2U_LIB.S9S_MB_2U(SCH_1):PAGE33
   DF2 UPI_CPU1_CPU0_P0P1_DP<11> @S9S_MB_2U_LIB.S9S_MB_2U(SCH_1):UPI_CPU1_CPU0_P0P1_DP(11)   I102 @S9S_MB_2U_LIB.S9S_MB_2U(SCH_1):PAGE33
   DH2 UPI_CPU1_CPU0_P0P1_DP<10> @S9S_MB_2U_LIB.S9S_MB_2U(SCH_1):UPI_CPU1_CPU0_P0P1_DP(10)   I102 @S9S_MB_2U_LIB.S9S_MB_2U(SCH_1):PAGE33
   DK2 UPI_CPU1_CPU0_P0P1_DP<9> @S9S_MB_2U_LIB.S9S_MB_2U(SCH_1):UPI_CPU1_CPU0_P0P1_DP(9)   I102 @S9S_MB_2U_LIB.S9S_MB_2U(SCH_1):PAGE33
   DM2 UPI_CPU1_CPU0_P0P1_DP<8> @S9S_MB_2U_LIB.S9S_MB_2U(SCH_1):UPI_CPU1_CPU0_P0P1_DP(8)   I102 @S9S_MB_2U_LIB.S9S_MB_2U(SCH_1):PAGE33
   DP2 UPI_CPU1_CPU0_P0P1_DP<7> @S9S_MB_2U_LIB.S9S_MB_2U(SCH_1):UPI_CPU1_CPU0_P0P1_DP(7)   I102 @S9S_MB_2U_LIB.S9S_MB_2U(SCH_1):PAGE33
   DR3 UPI_CPU1_CPU0_P0P1_DP<6> @S9S_MB_2U_LIB.S9S_MB_2U(SCH_1):UPI_CPU1_CPU0_P0P1_DP(6)   I102 @S9S_MB_2U_LIB.S9S_MB_2U(SCH_1):PAGE33
   DV2 UPI_CPU1_CPU0_P0P1_DP<5> @S9S_MB_2U_LIB.S9S_MB_2U(SCH_1):UPI_CPU1_CPU0_P0P1_DP(5)   I102 @S9S_MB_2U_LIB.S9S_MB_2U(SCH_1):PAGE33
   DW3 UPI_CPU1_CPU0_P0P1_DP<4> @S9S_MB_2U_LIB.S9S_MB_2U(SCH_1):UPI_CPU1_CPU0_P0P1_DP(4)   I102 @S9S_MB_2U_LIB.S9S_MB_2U(SCH_1):PAGE33
   EB2 UPI_CPU1_CPU0_P0P1_DP<3> @S9S_MB_2U_LIB.S9S_MB_2U(SCH_1):UPI_CPU1_CPU0_P0P1_DP(3)   I102 @S9S_MB_2U_LIB.S9S_MB_2U(SCH_1):PAGE33
   EC3 UPI_CPU1_CPU0_P0P1_DN<2> @S9S_MB_2U_LIB.S9S_MB_2U(SCH_1):UPI_CPU1_CPU0_P0P1_DN(2)   I102 @S9S_MB_2U_LIB.S9S_MB_2U(SCH_1):PAGE33
   EG3 UPI_CPU1_CPU0_P0P1_DP<1> @S9S_MB_2U_LIB.S9S_MB_2U(SCH_1):UPI_CPU1_CPU0_P0P1_DP(1)   I102 @S9S_MB_2U_LIB.S9S_MB_2U(SCH_1):PAGE33
   EJ3 UPI_CPU1_CPU0_P0P1_DP<0> @S9S_MB_2U_LIB.S9S_MB_2U(SCH_1):UPI_CPU1_CPU0_P0P1_DP(0)   I102 @S9S_MB_2U_LIB.S9S_MB_2U(SCH_1):PAGE33
   BY6 UPI_CPU0_CPU1_P1P0_DP<23> @S9S_MB_2U_LIB.S9S_MB_2U(SCH_1):UPI_CPU0_CPU1_P1P0_DP(23)   I102 @S9S_MB_2U_LIB.S9S_MB_2U(SCH_1):PAGE33
   CA5 UPI_CPU0_CPU1_P1P0_DN<22> @S9S_MB_2U_LIB.S9S_MB_2U(SCH_1):UPI_CPU0_CPU1_P1P0_DN(22)   I102 @S9S_MB_2U_LIB.S9S_MB_2U(SCH_1):PAGE33
   CD6 UPI_CPU0_CPU1_P1P0_DP<21> @S9S_MB_2U_LIB.S9S_MB_2U(SCH_1):UPI_CPU0_CPU1_P1P0_DP(21)   I102 @S9S_MB_2U_LIB.S9S_MB_2U(SCH_1):PAGE33
   CE5 UPI_CPU0_CPU1_P1P0_DP<20> @S9S_MB_2U_LIB.S9S_MB_2U(SCH_1):UPI_CPU0_CPU1_P1P0_DP(20)   I102 @S9S_MB_2U_LIB.S9S_MB_2U(SCH_1):PAGE33
   CH6 UPI_CPU0_CPU1_P1P0_DP<19> @S9S_MB_2U_LIB.S9S_MB_2U(SCH_1):UPI_CPU0_CPU1_P1P0_DP(19)   I102 @S9S_MB_2U_LIB.S9S_MB_2U(SCH_1):PAGE33
   CJ5 UPI_CPU0_CPU1_P1P0_DP<18> @S9S_MB_2U_LIB.S9S_MB_2U(SCH_1):UPI_CPU0_CPU1_P1P0_DP(18)   I102 @S9S_MB_2U_LIB.S9S_MB_2U(SCH_1):PAGE33
   CM6 UPI_CPU0_CPU1_P1P0_DP<17> @S9S_MB_2U_LIB.S9S_MB_2U(SCH_1):UPI_CPU0_CPU1_P1P0_DP(17)   I102 @S9S_MB_2U_LIB.S9S_MB_2U(SCH_1):PAGE33
   CN5 UPI_CPU0_CPU1_P1P0_DP<16> @S9S_MB_2U_LIB.S9S_MB_2U(SCH_1):UPI_CPU0_CPU1_P1P0_DP(16)   I102 @S9S_MB_2U_LIB.S9S_MB_2U(SCH_1):PAGE33
   CT6 UPI_CPU0_CPU1_P1P0_DP<15> @S9S_MB_2U_LIB.S9S_MB_2U(SCH_1):UPI_CPU0_CPU1_P1P0_DP(15)   I102 @S9S_MB_2U_LIB.S9S_MB_2U(SCH_1):PAGE33
   CU5 UPI_CPU0_CPU1_P1P0_DP<14> @S9S_MB_2U_LIB.S9S_MB_2U(SCH_1):UPI_CPU0_CPU1_P1P0_DP(14)   I102 @S9S_MB_2U_LIB.S9S_MB_2U(SCH_1):PAGE33
   CY6 UPI_CPU0_CPU1_P1P0_DP<13> @S9S_MB_2U_LIB.S9S_MB_2U(SCH_1):UPI_CPU0_CPU1_P1P0_DP(13)   I102 @S9S_MB_2U_LIB.S9S_MB_2U(SCH_1):PAGE33
   DA5 UPI_CPU0_CPU1_P1P0_DP<12> @S9S_MB_2U_LIB.S9S_MB_2U(SCH_1):UPI_CPU0_CPU1_P1P0_DP(12)   I102 @S9S_MB_2U_LIB.S9S_MB_2U(SCH_1):PAGE33
   DD6 UPI_CPU0_CPU1_P1P0_DP<11> @S9S_MB_2U_LIB.S9S_MB_2U(SCH_1):UPI_CPU0_CPU1_P1P0_DP(11)   I102 @S9S_MB_2U_LIB.S9S_MB_2U(SCH_1):PAGE33
   DE5 UPI_CPU0_CPU1_P1P0_DP<10> @S9S_MB_2U_LIB.S9S_MB_2U(SCH_1):UPI_CPU0_CPU1_P1P0_DP(10)   I102 @S9S_MB_2U_LIB.S9S_MB_2U(SCH_1):PAGE33
   DH6 UPI_CPU0_CPU1_P1P0_DN<9> @S9S_MB_2U_LIB.S9S_MB_2U(SCH_1):UPI_CPU0_CPU1_P1P0_DN(9)   I102 @S9S_MB_2U_LIB.S9S_MB_2U(SCH_1):PAGE33
   DK6 UPI_CPU0_CPU1_P1P0_DN<8> @S9S_MB_2U_LIB.S9S_MB_2U(SCH_1):UPI_CPU0_CPU1_P1P0_DN(8)   I102 @S9S_MB_2U_LIB.S9S_MB_2U(SCH_1):PAGE33
   DL7 UPI_CPU0_CPU1_P1P0_DN<7> @S9S_MB_2U_LIB.S9S_MB_2U(SCH_1):UPI_CPU0_CPU1_P1P0_DN(7)   I102 @S9S_MB_2U_LIB.S9S_MB_2U(SCH_1):PAGE33
   DP6 UPI_CPU0_CPU1_P1P0_DN<6> @S9S_MB_2U_LIB.S9S_MB_2U(SCH_1):UPI_CPU0_CPU1_P1P0_DN(6)   I102 @S9S_MB_2U_LIB.S9S_MB_2U(SCH_1):PAGE33
   DT6 UPI_CPU0_CPU1_P1P0_DP<5> @S9S_MB_2U_LIB.S9S_MB_2U(SCH_1):UPI_CPU0_CPU1_P1P0_DP(5)   I102 @S9S_MB_2U_LIB.S9S_MB_2U(SCH_1):PAGE33
   DV6 UPI_CPU0_CPU1_P1P0_DN<4> @S9S_MB_2U_LIB.S9S_MB_2U(SCH_1):UPI_CPU0_CPU1_P1P0_DN(4)   I102 @S9S_MB_2U_LIB.S9S_MB_2U(SCH_1):PAGE33
   DY6 UPI_CPU0_CPU1_P1P0_DP<3> @S9S_MB_2U_LIB.S9S_MB_2U(SCH_1):UPI_CPU0_CPU1_P1P0_DP(3)   I102 @S9S_MB_2U_LIB.S9S_MB_2U(SCH_1):PAGE33
   EB6 UPI_CPU0_CPU1_P1P0_DN<2> @S9S_MB_2U_LIB.S9S_MB_2U(SCH_1):UPI_CPU0_CPU1_P1P0_DN(2)   I102 @S9S_MB_2U_LIB.S9S_MB_2U(SCH_1):PAGE33
   EC7 UPI_CPU0_CPU1_P1P0_DN<1> @S9S_MB_2U_LIB.S9S_MB_2U(SCH_1):UPI_CPU0_CPU1_P1P0_DN(1)   I102 @S9S_MB_2U_LIB.S9S_MB_2U(SCH_1):PAGE33
   EF6 UPI_CPU0_CPU1_P1P0_DN<0> @S9S_MB_2U_LIB.S9S_MB_2U(SCH_1):UPI_CPU0_CPU1_P1P0_DN(0)   I102 @S9S_MB_2U_LIB.S9S_MB_2U(SCH_1):PAGE33
   BW7 UPI_CPU0_CPU1_P1P0_DN<23> @S9S_MB_2U_LIB.S9S_MB_2U(SCH_1):UPI_CPU0_CPU1_P1P0_DN(23)   I102 @S9S_MB_2U_LIB.S9S_MB_2U(SCH_1):PAGE33
   CB6 UPI_CPU0_CPU1_P1P0_DP<22> @S9S_MB_2U_LIB.S9S_MB_2U(SCH_1):UPI_CPU0_CPU1_P1P0_DP(22)   I102 @S9S_MB_2U_LIB.S9S_MB_2U(SCH_1):PAGE33
   CC7 UPI_CPU0_CPU1_P1P0_DN<21> @S9S_MB_2U_LIB.S9S_MB_2U(SCH_1):UPI_CPU0_CPU1_P1P0_DN(21)   I102 @S9S_MB_2U_LIB.S9S_MB_2U(SCH_1):PAGE33
   CF6 UPI_CPU0_CPU1_P1P0_DN<20> @S9S_MB_2U_LIB.S9S_MB_2U(SCH_1):UPI_CPU0_CPU1_P1P0_DN(20)   I102 @S9S_MB_2U_LIB.S9S_MB_2U(SCH_1):PAGE33
   CG7 UPI_CPU0_CPU1_P1P0_DN<19> @S9S_MB_2U_LIB.S9S_MB_2U(SCH_1):UPI_CPU0_CPU1_P1P0_DN(19)   I102 @S9S_MB_2U_LIB.S9S_MB_2U(SCH_1):PAGE33
   CK6 UPI_CPU0_CPU1_P1P0_DN<18> @S9S_MB_2U_LIB.S9S_MB_2U(SCH_1):UPI_CPU0_CPU1_P1P0_DN(18)   I102 @S9S_MB_2U_LIB.S9S_MB_2U(SCH_1):PAGE33
   CL7 UPI_CPU0_CPU1_P1P0_DN<17> @S9S_MB_2U_LIB.S9S_MB_2U(SCH_1):UPI_CPU0_CPU1_P1P0_DN(17)   I102 @S9S_MB_2U_LIB.S9S_MB_2U(SCH_1):PAGE33
   CP6 UPI_CPU0_CPU1_P1P0_DN<16> @S9S_MB_2U_LIB.S9S_MB_2U(SCH_1):UPI_CPU0_CPU1_P1P0_DN(16)   I102 @S9S_MB_2U_LIB.S9S_MB_2U(SCH_1):PAGE33
   CR7 UPI_CPU0_CPU1_P1P0_DN<15> @S9S_MB_2U_LIB.S9S_MB_2U(SCH_1):UPI_CPU0_CPU1_P1P0_DN(15)   I102 @S9S_MB_2U_LIB.S9S_MB_2U(SCH_1):PAGE33
   CV6 UPI_CPU0_CPU1_P1P0_DN<14> @S9S_MB_2U_LIB.S9S_MB_2U(SCH_1):UPI_CPU0_CPU1_P1P0_DN(14)   I102 @S9S_MB_2U_LIB.S9S_MB_2U(SCH_1):PAGE33
   CW7 UPI_CPU0_CPU1_P1P0_DN<13> @S9S_MB_2U_LIB.S9S_MB_2U(SCH_1):UPI_CPU0_CPU1_P1P0_DN(13)   I102 @S9S_MB_2U_LIB.S9S_MB_2U(SCH_1):PAGE33
   DB6 UPI_CPU0_CPU1_P1P0_DN<12> @S9S_MB_2U_LIB.S9S_MB_2U(SCH_1):UPI_CPU0_CPU1_P1P0_DN(12)   I102 @S9S_MB_2U_LIB.S9S_MB_2U(SCH_1):PAGE33
   DC7 UPI_CPU0_CPU1_P1P0_DN<11> @S9S_MB_2U_LIB.S9S_MB_2U(SCH_1):UPI_CPU0_CPU1_P1P0_DN(11)   I102 @S9S_MB_2U_LIB.S9S_MB_2U(SCH_1):PAGE33
   DF6 UPI_CPU0_CPU1_P1P0_DN<10> @S9S_MB_2U_LIB.S9S_MB_2U(SCH_1):UPI_CPU0_CPU1_P1P0_DN(10)   I102 @S9S_MB_2U_LIB.S9S_MB_2U(SCH_1):PAGE33
   DG7 UPI_CPU0_CPU1_P1P0_DP<9> @S9S_MB_2U_LIB.S9S_MB_2U(SCH_1):UPI_CPU0_CPU1_P1P0_DP(9)   I102 @S9S_MB_2U_LIB.S9S_MB_2U(SCH_1):PAGE33
   DJ5 UPI_CPU0_CPU1_P1P0_DP<8> @S9S_MB_2U_LIB.S9S_MB_2U(SCH_1):UPI_CPU0_CPU1_P1P0_DP(8)   I102 @S9S_MB_2U_LIB.S9S_MB_2U(SCH_1):PAGE33
   DM6 UPI_CPU0_CPU1_P1P0_DP<7> @S9S_MB_2U_LIB.S9S_MB_2U(SCH_1):UPI_CPU0_CPU1_P1P0_DP(7)   I102 @S9S_MB_2U_LIB.S9S_MB_2U(SCH_1):PAGE33
   DN5 UPI_CPU0_CPU1_P1P0_DP<6> @S9S_MB_2U_LIB.S9S_MB_2U(SCH_1):UPI_CPU0_CPU1_P1P0_DP(6)   I102 @S9S_MB_2U_LIB.S9S_MB_2U(SCH_1):PAGE33
   DR7 UPI_CPU0_CPU1_P1P0_DN<5> @S9S_MB_2U_LIB.S9S_MB_2U(SCH_1):UPI_CPU0_CPU1_P1P0_DN(5)   I102 @S9S_MB_2U_LIB.S9S_MB_2U(SCH_1):PAGE33
   DU5 UPI_CPU0_CPU1_P1P0_DP<4> @S9S_MB_2U_LIB.S9S_MB_2U(SCH_1):UPI_CPU0_CPU1_P1P0_DP(4)   I102 @S9S_MB_2U_LIB.S9S_MB_2U(SCH_1):PAGE33
   DW7 UPI_CPU0_CPU1_P1P0_DN<3> @S9S_MB_2U_LIB.S9S_MB_2U(SCH_1):UPI_CPU0_CPU1_P1P0_DN(3)   I102 @S9S_MB_2U_LIB.S9S_MB_2U(SCH_1):PAGE33
   EA5 UPI_CPU0_CPU1_P1P0_DP<2> @S9S_MB_2U_LIB.S9S_MB_2U(SCH_1):UPI_CPU0_CPU1_P1P0_DP(2)   I102 @S9S_MB_2U_LIB.S9S_MB_2U(SCH_1):PAGE33
   ED6 UPI_CPU0_CPU1_P1P0_DP<1> @S9S_MB_2U_LIB.S9S_MB_2U(SCH_1):UPI_CPU0_CPU1_P1P0_DP(1)   I102 @S9S_MB_2U_LIB.S9S_MB_2U(SCH_1):PAGE33
   EE5 UPI_CPU0_CPU1_P1P0_DP<0> @S9S_MB_2U_LIB.S9S_MB_2U(SCH_1):UPI_CPU0_CPU1_P1P0_DP(0)   I102 @S9S_MB_2U_LIB.S9S_MB_2U(SCH_1):PAGE33
  BD73 UPI_CPU1_CPU0_P2P2_DP<0> @S9S_MB_2U_LIB.S9S_MB_2U(SCH_1):UPI_CPU1_CPU0_P2P2_DP(0)   I102 @S9S_MB_2U_LIB.S9S_MB_2U(SCH_1):PAGE34
  BK73 UPI_CPU1_CPU0_P2P2_DN<1> @S9S_MB_2U_LIB.S9S_MB_2U(SCH_1):UPI_CPU1_CPU0_P2P2_DN(1)   I102 @S9S_MB_2U_LIB.S9S_MB_2U(SCH_1):PAGE34
  BN74 UPI_CPU1_CPU0_P2P2_DP<2> @S9S_MB_2U_LIB.S9S_MB_2U(SCH_1):UPI_CPU1_CPU0_P2P2_DP(2)   I102 @S9S_MB_2U_LIB.S9S_MB_2U(SCH_1):PAGE34
  BG74 UPI_CPU1_CPU0_P2P2_DP<3> @S9S_MB_2U_LIB.S9S_MB_2U(SCH_1):UPI_CPU1_CPU0_P2P2_DP(3)   I102 @S9S_MB_2U_LIB.S9S_MB_2U(SCH_1):PAGE34
  BL76 UPI_CPU1_CPU0_P2P2_DP<4> @S9S_MB_2U_LIB.S9S_MB_2U(SCH_1):UPI_CPU1_CPU0_P2P2_DP(4)   I102 @S9S_MB_2U_LIB.S9S_MB_2U(SCH_1):PAGE34
  BJ76 UPI_CPU1_CPU0_P2P2_DN<5> @S9S_MB_2U_LIB.S9S_MB_2U(SCH_1):UPI_CPU1_CPU0_P2P2_DN(5)   I102 @S9S_MB_2U_LIB.S9S_MB_2U(SCH_1):PAGE34
  BH75 UPI_CPU1_CPU0_P2P2_DN<6> @S9S_MB_2U_LIB.S9S_MB_2U(SCH_1):UPI_CPU1_CPU0_P2P2_DN(6)   I102 @S9S_MB_2U_LIB.S9S_MB_2U(SCH_1):PAGE34
  AW74 UPI_CPU1_CPU0_P2P2_DP<7> @S9S_MB_2U_LIB.S9S_MB_2U(SCH_1):UPI_CPU1_CPU0_P2P2_DP(7)   I102 @S9S_MB_2U_LIB.S9S_MB_2U(SCH_1):PAGE34
  BB75 UPI_CPU1_CPU0_P2P2_DP<8> @S9S_MB_2U_LIB.S9S_MB_2U(SCH_1):UPI_CPU1_CPU0_P2P2_DP(8)   I102 @S9S_MB_2U_LIB.S9S_MB_2U(SCH_1):PAGE34
  AY75 UPI_CPU1_CPU0_P2P2_DN<9> @S9S_MB_2U_LIB.S9S_MB_2U(SCH_1):UPI_CPU1_CPU0_P2P2_DN(9)   I102 @S9S_MB_2U_LIB.S9S_MB_2U(SCH_1):PAGE34
  AV73 UPI_CPU1_CPU0_P2P2_DN<10> @S9S_MB_2U_LIB.S9S_MB_2U(SCH_1):UPI_CPU1_CPU0_P2P2_DN(10)   I102 @S9S_MB_2U_LIB.S9S_MB_2U(SCH_1):PAGE34
  BA72 UPI_CPU1_CPU0_P2P2_DP<11> @S9S_MB_2U_LIB.S9S_MB_2U(SCH_1):UPI_CPU1_CPU0_P2P2_DP(11)   I102 @S9S_MB_2U_LIB.S9S_MB_2U(SCH_1):PAGE34
  AG82 UPI_CPU1_CPU0_P2P2_DP<12> @S9S_MB_2U_LIB.S9S_MB_2U(SCH_1):UPI_CPU1_CPU0_P2P2_DP(12)   I102 @S9S_MB_2U_LIB.S9S_MB_2U(SCH_1):PAGE34
  AJ80 UPI_CPU1_CPU0_P2P2_DN<13> @S9S_MB_2U_LIB.S9S_MB_2U(SCH_1):UPI_CPU1_CPU0_P2P2_DN(13)   I102 @S9S_MB_2U_LIB.S9S_MB_2U(SCH_1):PAGE34
  AE82 UPI_CPU1_CPU0_P2P2_DP<14> @S9S_MB_2U_LIB.S9S_MB_2U(SCH_1):UPI_CPU1_CPU0_P2P2_DP(14)   I102 @S9S_MB_2U_LIB.S9S_MB_2U(SCH_1):PAGE34
  AF79 UPI_CPU1_CPU0_P2P2_DP<15> @S9S_MB_2U_LIB.S9S_MB_2U(SCH_1):UPI_CPU1_CPU0_P2P2_DP(15)   I102 @S9S_MB_2U_LIB.S9S_MB_2U(SCH_1):PAGE34
  AD81 UPI_CPU1_CPU0_P2P2_DP<16> @S9S_MB_2U_LIB.S9S_MB_2U(SCH_1):UPI_CPU1_CPU0_P2P2_DP(16)   I102 @S9S_MB_2U_LIB.S9S_MB_2U(SCH_1):PAGE34
  AC80 UPI_CPU1_CPU0_P2P2_DN<17> @S9S_MB_2U_LIB.S9S_MB_2U(SCH_1):UPI_CPU1_CPU0_P2P2_DN(17)   I102 @S9S_MB_2U_LIB.S9S_MB_2U(SCH_1):PAGE34
   L80 UPI_CPU1_CPU0_P2P2_DN<18> @S9S_MB_2U_LIB.S9S_MB_2U(SCH_1):UPI_CPU1_CPU0_P2P2_DN(18)   I102 @S9S_MB_2U_LIB.S9S_MB_2U(SCH_1):PAGE34
   J82 UPI_CPU1_CPU0_P2P2_DN<19> @S9S_MB_2U_LIB.S9S_MB_2U(SCH_1):UPI_CPU1_CPU0_P2P2_DN(19)   I102 @S9S_MB_2U_LIB.S9S_MB_2U(SCH_1):PAGE34
   K79 UPI_CPU1_CPU0_P2P2_DN<20> @S9S_MB_2U_LIB.S9S_MB_2U(SCH_1):UPI_CPU1_CPU0_P2P2_DN(20)   I102 @S9S_MB_2U_LIB.S9S_MB_2U(SCH_1):PAGE34
   G82 UPI_CPU1_CPU0_P2P2_DN<21> @S9S_MB_2U_LIB.S9S_MB_2U(SCH_1):UPI_CPU1_CPU0_P2P2_DN(21)   I102 @S9S_MB_2U_LIB.S9S_MB_2U(SCH_1):PAGE34
   F81 UPI_CPU1_CPU0_P2P2_DP<22> @S9S_MB_2U_LIB.S9S_MB_2U(SCH_1):UPI_CPU1_CPU0_P2P2_DP(22)   I102 @S9S_MB_2U_LIB.S9S_MB_2U(SCH_1):PAGE34
   E80 UPI_CPU1_CPU0_P2P2_DN<23> @S9S_MB_2U_LIB.S9S_MB_2U(SCH_1):UPI_CPU1_CPU0_P2P2_DN(23)   I102 @S9S_MB_2U_LIB.S9S_MB_2U(SCH_1):PAGE34
  BC74 UPI_CPU1_CPU0_P2P2_DN<0> @S9S_MB_2U_LIB.S9S_MB_2U(SCH_1):UPI_CPU1_CPU0_P2P2_DN(0)   I102 @S9S_MB_2U_LIB.S9S_MB_2U(SCH_1):PAGE34
  BL74 UPI_CPU1_CPU0_P2P2_DP<1> @S9S_MB_2U_LIB.S9S_MB_2U(SCH_1):UPI_CPU1_CPU0_P2P2_DP(1)   I102 @S9S_MB_2U_LIB.S9S_MB_2U(SCH_1):PAGE34
  BM75 UPI_CPU1_CPU0_P2P2_DN<2> @S9S_MB_2U_LIB.S9S_MB_2U(SCH_1):UPI_CPU1_CPU0_P2P2_DN(2)   I102 @S9S_MB_2U_LIB.S9S_MB_2U(SCH_1):PAGE34
  BJ74 UPI_CPU1_CPU0_P2P2_DN<3> @S9S_MB_2U_LIB.S9S_MB_2U(SCH_1):UPI_CPU1_CPU0_P2P2_DN(3)   I102 @S9S_MB_2U_LIB.S9S_MB_2U(SCH_1):PAGE34
  BN76 UPI_CPU1_CPU0_P2P2_DN<4> @S9S_MB_2U_LIB.S9S_MB_2U(SCH_1):UPI_CPU1_CPU0_P2P2_DN(4)   I102 @S9S_MB_2U_LIB.S9S_MB_2U(SCH_1):PAGE34
  BK77 UPI_CPU1_CPU0_P2P2_DP<5> @S9S_MB_2U_LIB.S9S_MB_2U(SCH_1):UPI_CPU1_CPU0_P2P2_DP(5)   I102 @S9S_MB_2U_LIB.S9S_MB_2U(SCH_1):PAGE34
  BG76 UPI_CPU1_CPU0_P2P2_DP<6> @S9S_MB_2U_LIB.S9S_MB_2U(SCH_1):UPI_CPU1_CPU0_P2P2_DP(6)   I102 @S9S_MB_2U_LIB.S9S_MB_2U(SCH_1):PAGE34
  AV75 UPI_CPU1_CPU0_P2P2_DN<7> @S9S_MB_2U_LIB.S9S_MB_2U(SCH_1):UPI_CPU1_CPU0_P2P2_DN(7)   I102 @S9S_MB_2U_LIB.S9S_MB_2U(SCH_1):PAGE34
  BD75 UPI_CPU1_CPU0_P2P2_DN<8> @S9S_MB_2U_LIB.S9S_MB_2U(SCH_1):UPI_CPU1_CPU0_P2P2_DN(8)   I102 @S9S_MB_2U_LIB.S9S_MB_2U(SCH_1):PAGE34
  BA76 UPI_CPU1_CPU0_P2P2_DP<9> @S9S_MB_2U_LIB.S9S_MB_2U(SCH_1):UPI_CPU1_CPU0_P2P2_DP(9)   I102 @S9S_MB_2U_LIB.S9S_MB_2U(SCH_1):PAGE34
  AY73 UPI_CPU1_CPU0_P2P2_DP<10> @S9S_MB_2U_LIB.S9S_MB_2U(SCH_1):UPI_CPU1_CPU0_P2P2_DP(10)   I102 @S9S_MB_2U_LIB.S9S_MB_2U(SCH_1):PAGE34
  BB73 UPI_CPU1_CPU0_P2P2_DN<11> @S9S_MB_2U_LIB.S9S_MB_2U(SCH_1):UPI_CPU1_CPU0_P2P2_DN(11)   I102 @S9S_MB_2U_LIB.S9S_MB_2U(SCH_1):PAGE34
  AJ82 UPI_CPU1_CPU0_P2P2_DN<12> @S9S_MB_2U_LIB.S9S_MB_2U(SCH_1):UPI_CPU1_CPU0_P2P2_DN(12)   I102 @S9S_MB_2U_LIB.S9S_MB_2U(SCH_1):PAGE34
  AH81 UPI_CPU1_CPU0_P2P2_DP<13> @S9S_MB_2U_LIB.S9S_MB_2U(SCH_1):UPI_CPU1_CPU0_P2P2_DP(13)   I102 @S9S_MB_2U_LIB.S9S_MB_2U(SCH_1):PAGE34
  AF83 UPI_CPU1_CPU0_P2P2_DN<14> @S9S_MB_2U_LIB.S9S_MB_2U(SCH_1):UPI_CPU1_CPU0_P2P2_DN(14)   I102 @S9S_MB_2U_LIB.S9S_MB_2U(SCH_1):PAGE34
  AG80 UPI_CPU1_CPU0_P2P2_DN<15> @S9S_MB_2U_LIB.S9S_MB_2U(SCH_1):UPI_CPU1_CPU0_P2P2_DN(15)   I102 @S9S_MB_2U_LIB.S9S_MB_2U(SCH_1):PAGE34
  AC82 UPI_CPU1_CPU0_P2P2_DN<16> @S9S_MB_2U_LIB.S9S_MB_2U(SCH_1):UPI_CPU1_CPU0_P2P2_DN(16)   I102 @S9S_MB_2U_LIB.S9S_MB_2U(SCH_1):PAGE34
  AE80 UPI_CPU1_CPU0_P2P2_DP<17> @S9S_MB_2U_LIB.S9S_MB_2U(SCH_1):UPI_CPU1_CPU0_P2P2_DP(17)   I102 @S9S_MB_2U_LIB.S9S_MB_2U(SCH_1):PAGE34
   K81 UPI_CPU1_CPU0_P2P2_DP<18> @S9S_MB_2U_LIB.S9S_MB_2U(SCH_1):UPI_CPU1_CPU0_P2P2_DP(18)   I102 @S9S_MB_2U_LIB.S9S_MB_2U(SCH_1):PAGE34
   L82 UPI_CPU1_CPU0_P2P2_DP<19> @S9S_MB_2U_LIB.S9S_MB_2U(SCH_1):UPI_CPU1_CPU0_P2P2_DP(19)   I102 @S9S_MB_2U_LIB.S9S_MB_2U(SCH_1):PAGE34
   M79 UPI_CPU1_CPU0_P2P2_DP<20> @S9S_MB_2U_LIB.S9S_MB_2U(SCH_1):UPI_CPU1_CPU0_P2P2_DP(20)   I102 @S9S_MB_2U_LIB.S9S_MB_2U(SCH_1):PAGE34
   H83 UPI_CPU1_CPU0_P2P2_DP<21> @S9S_MB_2U_LIB.S9S_MB_2U(SCH_1):UPI_CPU1_CPU0_P2P2_DP(21)   I102 @S9S_MB_2U_LIB.S9S_MB_2U(SCH_1):PAGE34
   E82 UPI_CPU1_CPU0_P2P2_DN<22> @S9S_MB_2U_LIB.S9S_MB_2U(SCH_1):UPI_CPU1_CPU0_P2P2_DN(22)   I102 @S9S_MB_2U_LIB.S9S_MB_2U(SCH_1):PAGE34
   G80 UPI_CPU1_CPU0_P2P2_DP<23> @S9S_MB_2U_LIB.S9S_MB_2U(SCH_1):UPI_CPU1_CPU0_P2P2_DP(23)   I102 @S9S_MB_2U_LIB.S9S_MB_2U(SCH_1):PAGE34
  BM71 UPI_CPU0_CPU1_P2P2_DN<0> @S9S_MB_2U_LIB.S9S_MB_2U(SCH_1):UPI_CPU0_CPU1_P2P2_DN(0)   I102 @S9S_MB_2U_LIB.S9S_MB_2U(SCH_1):PAGE34
  BG80 UPI_CPU0_CPU1_P2P2_DN<1> @S9S_MB_2U_LIB.S9S_MB_2U(SCH_1):UPI_CPU0_CPU1_P2P2_DN(1)   I102 @S9S_MB_2U_LIB.S9S_MB_2U(SCH_1):PAGE34
  BF81 UPI_CPU0_CPU1_P2P2_DN<2> @S9S_MB_2U_LIB.S9S_MB_2U(SCH_1):UPI_CPU0_CPU1_P2P2_DN(2)   I102 @S9S_MB_2U_LIB.S9S_MB_2U(SCH_1):PAGE34
  BD79 UPI_CPU0_CPU1_P2P2_DN<3> @S9S_MB_2U_LIB.S9S_MB_2U(SCH_1):UPI_CPU0_CPU1_P2P2_DN(3)   I102 @S9S_MB_2U_LIB.S9S_MB_2U(SCH_1):PAGE34
  BE82 UPI_CPU0_CPU1_P2P2_DN<4> @S9S_MB_2U_LIB.S9S_MB_2U(SCH_1):UPI_CPU0_CPU1_P2P2_DN(4)   I102 @S9S_MB_2U_LIB.S9S_MB_2U(SCH_1):PAGE34
  BC82 UPI_CPU0_CPU1_P2P2_DN<5> @S9S_MB_2U_LIB.S9S_MB_2U(SCH_1):UPI_CPU0_CPU1_P2P2_DN(5)   I102 @S9S_MB_2U_LIB.S9S_MB_2U(SCH_1):PAGE34
  BA80 UPI_CPU0_CPU1_P2P2_DN<6> @S9S_MB_2U_LIB.S9S_MB_2U(SCH_1):UPI_CPU0_CPU1_P2P2_DN(6)   I102 @S9S_MB_2U_LIB.S9S_MB_2U(SCH_1):PAGE34
  AV81 UPI_CPU0_CPU1_P2P2_DN<7> @S9S_MB_2U_LIB.S9S_MB_2U(SCH_1):UPI_CPU0_CPU1_P2P2_DN(7)   I102 @S9S_MB_2U_LIB.S9S_MB_2U(SCH_1):PAGE34
  AT83 UPI_CPU0_CPU1_P2P2_DN<8> @S9S_MB_2U_LIB.S9S_MB_2U(SCH_1):UPI_CPU0_CPU1_P2P2_DN(8)   I102 @S9S_MB_2U_LIB.S9S_MB_2U(SCH_1):PAGE34
  AR80 UPI_CPU0_CPU1_P2P2_DN<9> @S9S_MB_2U_LIB.S9S_MB_2U(SCH_1):UPI_CPU0_CPU1_P2P2_DN(9)   I102 @S9S_MB_2U_LIB.S9S_MB_2U(SCH_1):PAGE34
  AN82 UPI_CPU0_CPU1_P2P2_DN<10> @S9S_MB_2U_LIB.S9S_MB_2U(SCH_1):UPI_CPU0_CPU1_P2P2_DN(10)   I102 @S9S_MB_2U_LIB.S9S_MB_2U(SCH_1):PAGE34
  AM81 UPI_CPU0_CPU1_P2P2_DN<11> @S9S_MB_2U_LIB.S9S_MB_2U(SCH_1):UPI_CPU0_CPU1_P2P2_DN(11)   I102 @S9S_MB_2U_LIB.S9S_MB_2U(SCH_1):PAGE34
  AU78 UPI_CPU0_CPU1_P2P2_DN<12> @S9S_MB_2U_LIB.S9S_MB_2U(SCH_1):UPI_CPU0_CPU1_P2P2_DN(12)   I102 @S9S_MB_2U_LIB.S9S_MB_2U(SCH_1):PAGE34
  AW78 UPI_CPU0_CPU1_P2P2_DN<13> @S9S_MB_2U_LIB.S9S_MB_2U(SCH_1):UPI_CPU0_CPU1_P2P2_DN(13)   I102 @S9S_MB_2U_LIB.S9S_MB_2U(SCH_1):PAGE34
   Y81 UPI_CPU0_CPU1_P2P2_DN<14> @S9S_MB_2U_LIB.S9S_MB_2U(SCH_1):UPI_CPU0_CPU1_P2P2_DN(14)   I102 @S9S_MB_2U_LIB.S9S_MB_2U(SCH_1):PAGE34
   V83 UPI_CPU0_CPU1_P2P2_DN<15> @S9S_MB_2U_LIB.S9S_MB_2U(SCH_1):UPI_CPU0_CPU1_P2P2_DN(15)   I102 @S9S_MB_2U_LIB.S9S_MB_2U(SCH_1):PAGE34
   U80 UPI_CPU0_CPU1_P2P2_DN<16> @S9S_MB_2U_LIB.S9S_MB_2U(SCH_1):UPI_CPU0_CPU1_P2P2_DN(16)   I102 @S9S_MB_2U_LIB.S9S_MB_2U(SCH_1):PAGE34
   R82 UPI_CPU0_CPU1_P2P2_DN<17> @S9S_MB_2U_LIB.S9S_MB_2U(SCH_1):UPI_CPU0_CPU1_P2P2_DN(17)   I102 @S9S_MB_2U_LIB.S9S_MB_2U(SCH_1):PAGE34
   P81 UPI_CPU0_CPU1_P2P2_DN<18> @S9S_MB_2U_LIB.S9S_MB_2U(SCH_1):UPI_CPU0_CPU1_P2P2_DN(18)   I102 @S9S_MB_2U_LIB.S9S_MB_2U(SCH_1):PAGE34
   H85 UPI_CPU0_CPU1_P2P2_DN<19> @S9S_MB_2U_LIB.S9S_MB_2U(SCH_1):UPI_CPU0_CPU1_P2P2_DN(19)   I102 @S9S_MB_2U_LIB.S9S_MB_2U(SCH_1):PAGE34
   F87 UPI_CPU0_CPU1_P2P2_DN<20> @S9S_MB_2U_LIB.S9S_MB_2U(SCH_1):UPI_CPU0_CPU1_P2P2_DN(20)   I102 @S9S_MB_2U_LIB.S9S_MB_2U(SCH_1):PAGE34
   D87 UPI_CPU0_CPU1_P2P2_DN<21> @S9S_MB_2U_LIB.S9S_MB_2U(SCH_1):UPI_CPU0_CPU1_P2P2_DN(21)   I102 @S9S_MB_2U_LIB.S9S_MB_2U(SCH_1):PAGE34
   E84 UPI_CPU0_CPU1_P2P2_DN<22> @S9S_MB_2U_LIB.S9S_MB_2U(SCH_1):UPI_CPU0_CPU1_P2P2_DN(22)   I102 @S9S_MB_2U_LIB.S9S_MB_2U(SCH_1):PAGE34
   B85 UPI_CPU0_CPU1_P2P2_DN<23> @S9S_MB_2U_LIB.S9S_MB_2U(SCH_1):UPI_CPU0_CPU1_P2P2_DN(23)   I102 @S9S_MB_2U_LIB.S9S_MB_2U(SCH_1):PAGE34
  BN72 UPI_CPU0_CPU1_P2P2_DP<0> @S9S_MB_2U_LIB.S9S_MB_2U(SCH_1):UPI_CPU0_CPU1_P2P2_DP(0)   I102 @S9S_MB_2U_LIB.S9S_MB_2U(SCH_1):PAGE34
  BE80 UPI_CPU0_CPU1_P2P2_DP<1> @S9S_MB_2U_LIB.S9S_MB_2U(SCH_1):UPI_CPU0_CPU1_P2P2_DP(1)   I102 @S9S_MB_2U_LIB.S9S_MB_2U(SCH_1):PAGE34
  BG82 UPI_CPU0_CPU1_P2P2_DP<2> @S9S_MB_2U_LIB.S9S_MB_2U(SCH_1):UPI_CPU0_CPU1_P2P2_DP(2)   I102 @S9S_MB_2U_LIB.S9S_MB_2U(SCH_1):PAGE34
  BC80 UPI_CPU0_CPU1_P2P2_DP<3> @S9S_MB_2U_LIB.S9S_MB_2U(SCH_1):UPI_CPU0_CPU1_P2P2_DP(3)   I102 @S9S_MB_2U_LIB.S9S_MB_2U(SCH_1):PAGE34
  BD83 UPI_CPU0_CPU1_P2P2_DP<4> @S9S_MB_2U_LIB.S9S_MB_2U(SCH_1):UPI_CPU0_CPU1_P2P2_DP(4)   I102 @S9S_MB_2U_LIB.S9S_MB_2U(SCH_1):PAGE34
  BA82 UPI_CPU0_CPU1_P2P2_DP<5> @S9S_MB_2U_LIB.S9S_MB_2U(SCH_1):UPI_CPU0_CPU1_P2P2_DP(5)   I102 @S9S_MB_2U_LIB.S9S_MB_2U(SCH_1):PAGE34
  BB81 UPI_CPU0_CPU1_P2P2_DP<6> @S9S_MB_2U_LIB.S9S_MB_2U(SCH_1):UPI_CPU0_CPU1_P2P2_DP(6)   I102 @S9S_MB_2U_LIB.S9S_MB_2U(SCH_1):PAGE34
  AU82 UPI_CPU0_CPU1_P2P2_DP<7> @S9S_MB_2U_LIB.S9S_MB_2U(SCH_1):UPI_CPU0_CPU1_P2P2_DP(7)   I102 @S9S_MB_2U_LIB.S9S_MB_2U(SCH_1):PAGE34
  AV83 UPI_CPU0_CPU1_P2P2_DP<8> @S9S_MB_2U_LIB.S9S_MB_2U(SCH_1):UPI_CPU0_CPU1_P2P2_DP(8)   I102 @S9S_MB_2U_LIB.S9S_MB_2U(SCH_1):PAGE34
  AT81 UPI_CPU0_CPU1_P2P2_DP<9> @S9S_MB_2U_LIB.S9S_MB_2U(SCH_1):UPI_CPU0_CPU1_P2P2_DP(9)   I102 @S9S_MB_2U_LIB.S9S_MB_2U(SCH_1):PAGE34
  AM83 UPI_CPU0_CPU1_P2P2_DP<10> @S9S_MB_2U_LIB.S9S_MB_2U(SCH_1):UPI_CPU0_CPU1_P2P2_DP(10)   I102 @S9S_MB_2U_LIB.S9S_MB_2U(SCH_1):PAGE34
  AP81 UPI_CPU0_CPU1_P2P2_DP<11> @S9S_MB_2U_LIB.S9S_MB_2U(SCH_1):UPI_CPU0_CPU1_P2P2_DP(11)   I102 @S9S_MB_2U_LIB.S9S_MB_2U(SCH_1):PAGE34
  AV79 UPI_CPU0_CPU1_P2P2_DP<12> @S9S_MB_2U_LIB.S9S_MB_2U(SCH_1):UPI_CPU0_CPU1_P2P2_DP(12)   I102 @S9S_MB_2U_LIB.S9S_MB_2U(SCH_1):PAGE34
  BA78 UPI_CPU0_CPU1_P2P2_DP<13> @S9S_MB_2U_LIB.S9S_MB_2U(SCH_1):UPI_CPU0_CPU1_P2P2_DP(13)   I102 @S9S_MB_2U_LIB.S9S_MB_2U(SCH_1):PAGE34
   W82 UPI_CPU0_CPU1_P2P2_DP<14> @S9S_MB_2U_LIB.S9S_MB_2U(SCH_1):UPI_CPU0_CPU1_P2P2_DP(14)   I102 @S9S_MB_2U_LIB.S9S_MB_2U(SCH_1):PAGE34
   Y83 UPI_CPU0_CPU1_P2P2_DP<15> @S9S_MB_2U_LIB.S9S_MB_2U(SCH_1):UPI_CPU0_CPU1_P2P2_DP(15)   I102 @S9S_MB_2U_LIB.S9S_MB_2U(SCH_1):PAGE34
   V81 UPI_CPU0_CPU1_P2P2_DP<16> @S9S_MB_2U_LIB.S9S_MB_2U(SCH_1):UPI_CPU0_CPU1_P2P2_DP(16)   I102 @S9S_MB_2U_LIB.S9S_MB_2U(SCH_1):PAGE34
   P83 UPI_CPU0_CPU1_P2P2_DP<17> @S9S_MB_2U_LIB.S9S_MB_2U(SCH_1):UPI_CPU0_CPU1_P2P2_DP(17)   I102 @S9S_MB_2U_LIB.S9S_MB_2U(SCH_1):PAGE34
   T81 UPI_CPU0_CPU1_P2P2_DP<18> @S9S_MB_2U_LIB.S9S_MB_2U(SCH_1):UPI_CPU0_CPU1_P2P2_DP(18)   I102 @S9S_MB_2U_LIB.S9S_MB_2U(SCH_1):PAGE34
   G86 UPI_CPU0_CPU1_P2P2_DP<19> @S9S_MB_2U_LIB.S9S_MB_2U(SCH_1):UPI_CPU0_CPU1_P2P2_DP(19)   I102 @S9S_MB_2U_LIB.S9S_MB_2U(SCH_1):PAGE34
   H87 UPI_CPU0_CPU1_P2P2_DP<20> @S9S_MB_2U_LIB.S9S_MB_2U(SCH_1):UPI_CPU0_CPU1_P2P2_DP(20)   I102 @S9S_MB_2U_LIB.S9S_MB_2U(SCH_1):PAGE34
   E88 UPI_CPU0_CPU1_P2P2_DP<21> @S9S_MB_2U_LIB.S9S_MB_2U(SCH_1):UPI_CPU0_CPU1_P2P2_DP(21)   I102 @S9S_MB_2U_LIB.S9S_MB_2U(SCH_1):PAGE34
   F85 UPI_CPU0_CPU1_P2P2_DP<22> @S9S_MB_2U_LIB.S9S_MB_2U(SCH_1):UPI_CPU0_CPU1_P2P2_DP(22)   I102 @S9S_MB_2U_LIB.S9S_MB_2U(SCH_1):PAGE34
   D85 UPI_CPU0_CPU1_P2P2_DP<23> @S9S_MB_2U_LIB.S9S_MB_2U(SCH_1):UPI_CPU0_CPU1_P2P2_DP(23)   I102 @S9S_MB_2U_LIB.S9S_MB_2U(SCH_1):PAGE34
  DA78    GND @S9S_MB_2U_LIB.S9S_MB_2U(SCH_1):GND   I102 @S9S_MB_2U_LIB.S9S_MB_2U(SCH_1):PAGE35
  CT79    GND @S9S_MB_2U_LIB.S9S_MB_2U(SCH_1):GND   I102 @S9S_MB_2U_LIB.S9S_MB_2U(SCH_1):PAGE35
  CN80    GND @S9S_MB_2U_LIB.S9S_MB_2U(SCH_1):GND   I102 @S9S_MB_2U_LIB.S9S_MB_2U(SCH_1):PAGE35
  CP81    GND @S9S_MB_2U_LIB.S9S_MB_2U(SCH_1):GND   I102 @S9S_MB_2U_LIB.S9S_MB_2U(SCH_1):PAGE35
  CW80    GND @S9S_MB_2U_LIB.S9S_MB_2U(SCH_1):GND   I102 @S9S_MB_2U_LIB.S9S_MB_2U(SCH_1):PAGE35
  CR82    GND @S9S_MB_2U_LIB.S9S_MB_2U(SCH_1):GND   I102 @S9S_MB_2U_LIB.S9S_MB_2U(SCH_1):PAGE35
  CU82    GND @S9S_MB_2U_LIB.S9S_MB_2U(SCH_1):GND   I102 @S9S_MB_2U_LIB.S9S_MB_2U(SCH_1):PAGE35
  DF77    GND @S9S_MB_2U_LIB.S9S_MB_2U(SCH_1):GND   I102 @S9S_MB_2U_LIB.S9S_MB_2U(SCH_1):PAGE35
  DB81    GND @S9S_MB_2U_LIB.S9S_MB_2U(SCH_1):GND   I102 @S9S_MB_2U_LIB.S9S_MB_2U(SCH_1):PAGE35
  DC82    GND @S9S_MB_2U_LIB.S9S_MB_2U(SCH_1):GND   I102 @S9S_MB_2U_LIB.S9S_MB_2U(SCH_1):PAGE35
  DE80    GND @S9S_MB_2U_LIB.S9S_MB_2U(SCH_1):GND   I102 @S9S_MB_2U_LIB.S9S_MB_2U(SCH_1):PAGE35
  DF83    GND @S9S_MB_2U_LIB.S9S_MB_2U(SCH_1):GND   I102 @S9S_MB_2U_LIB.S9S_MB_2U(SCH_1):PAGE35
  DH81    GND @S9S_MB_2U_LIB.S9S_MB_2U(SCH_1):GND   I102 @S9S_MB_2U_LIB.S9S_MB_2U(SCH_1):PAGE35
  DG78    GND @S9S_MB_2U_LIB.S9S_MB_2U(SCH_1):GND   I102 @S9S_MB_2U_LIB.S9S_MB_2U(SCH_1):PAGE35
  DJ78    GND @S9S_MB_2U_LIB.S9S_MB_2U(SCH_1):GND   I102 @S9S_MB_2U_LIB.S9S_MB_2U(SCH_1):PAGE35
  DY81    GND @S9S_MB_2U_LIB.S9S_MB_2U(SCH_1):GND   I102 @S9S_MB_2U_LIB.S9S_MB_2U(SCH_1):PAGE35
  EA82    GND @S9S_MB_2U_LIB.S9S_MB_2U(SCH_1):GND   I102 @S9S_MB_2U_LIB.S9S_MB_2U(SCH_1):PAGE35
  EC80    GND @S9S_MB_2U_LIB.S9S_MB_2U(SCH_1):GND   I102 @S9S_MB_2U_LIB.S9S_MB_2U(SCH_1):PAGE35
  ED83    GND @S9S_MB_2U_LIB.S9S_MB_2U(SCH_1):GND   I102 @S9S_MB_2U_LIB.S9S_MB_2U(SCH_1):PAGE35
  EF81    GND @S9S_MB_2U_LIB.S9S_MB_2U(SCH_1):GND   I102 @S9S_MB_2U_LIB.S9S_MB_2U(SCH_1):PAGE35
  EK81    GND @S9S_MB_2U_LIB.S9S_MB_2U(SCH_1):GND   I102 @S9S_MB_2U_LIB.S9S_MB_2U(SCH_1):PAGE35
  EL82    GND @S9S_MB_2U_LIB.S9S_MB_2U(SCH_1):GND   I102 @S9S_MB_2U_LIB.S9S_MB_2U(SCH_1):PAGE35
  EP81    GND @S9S_MB_2U_LIB.S9S_MB_2U(SCH_1):GND   I102 @S9S_MB_2U_LIB.S9S_MB_2U(SCH_1):PAGE35
  EJ80    GND @S9S_MB_2U_LIB.S9S_MB_2U(SCH_1):GND   I102 @S9S_MB_2U_LIB.S9S_MB_2U(SCH_1):PAGE35
  DB79    GND @S9S_MB_2U_LIB.S9S_MB_2U(SCH_1):GND   I102 @S9S_MB_2U_LIB.S9S_MB_2U(SCH_1):PAGE35
  CU80    GND @S9S_MB_2U_LIB.S9S_MB_2U(SCH_1):GND   I102 @S9S_MB_2U_LIB.S9S_MB_2U(SCH_1):PAGE35
  CR80    GND @S9S_MB_2U_LIB.S9S_MB_2U(SCH_1):GND   I102 @S9S_MB_2U_LIB.S9S_MB_2U(SCH_1):PAGE35
  CN82    GND @S9S_MB_2U_LIB.S9S_MB_2U(SCH_1):GND   I102 @S9S_MB_2U_LIB.S9S_MB_2U(SCH_1):PAGE35
  CV81    GND @S9S_MB_2U_LIB.S9S_MB_2U(SCH_1):GND   I102 @S9S_MB_2U_LIB.S9S_MB_2U(SCH_1):PAGE35
  CT83    GND @S9S_MB_2U_LIB.S9S_MB_2U(SCH_1):GND   I102 @S9S_MB_2U_LIB.S9S_MB_2U(SCH_1):PAGE35
  CW82    GND @S9S_MB_2U_LIB.S9S_MB_2U(SCH_1):GND   I102 @S9S_MB_2U_LIB.S9S_MB_2U(SCH_1):PAGE35
  DE78    GND @S9S_MB_2U_LIB.S9S_MB_2U(SCH_1):GND   I102 @S9S_MB_2U_LIB.S9S_MB_2U(SCH_1):PAGE35
  DD81    GND @S9S_MB_2U_LIB.S9S_MB_2U(SCH_1):GND   I102 @S9S_MB_2U_LIB.S9S_MB_2U(SCH_1):PAGE35
  DB83    GND @S9S_MB_2U_LIB.S9S_MB_2U(SCH_1):GND   I102 @S9S_MB_2U_LIB.S9S_MB_2U(SCH_1):PAGE35
  DF81    GND @S9S_MB_2U_LIB.S9S_MB_2U(SCH_1):GND   I102 @S9S_MB_2U_LIB.S9S_MB_2U(SCH_1):PAGE35
  DH83    GND @S9S_MB_2U_LIB.S9S_MB_2U(SCH_1):GND   I102 @S9S_MB_2U_LIB.S9S_MB_2U(SCH_1):PAGE35
  DG82    GND @S9S_MB_2U_LIB.S9S_MB_2U(SCH_1):GND   I102 @S9S_MB_2U_LIB.S9S_MB_2U(SCH_1):PAGE35
  DH79    GND @S9S_MB_2U_LIB.S9S_MB_2U(SCH_1):GND   I102 @S9S_MB_2U_LIB.S9S_MB_2U(SCH_1):PAGE35
  DL78    GND @S9S_MB_2U_LIB.S9S_MB_2U(SCH_1):GND   I102 @S9S_MB_2U_LIB.S9S_MB_2U(SCH_1):PAGE35
  EB81    GND @S9S_MB_2U_LIB.S9S_MB_2U(SCH_1):GND   I102 @S9S_MB_2U_LIB.S9S_MB_2U(SCH_1):PAGE35
  DY83    GND @S9S_MB_2U_LIB.S9S_MB_2U(SCH_1):GND   I102 @S9S_MB_2U_LIB.S9S_MB_2U(SCH_1):PAGE35
  ED81    GND @S9S_MB_2U_LIB.S9S_MB_2U(SCH_1):GND   I102 @S9S_MB_2U_LIB.S9S_MB_2U(SCH_1):PAGE35
  EF83    GND @S9S_MB_2U_LIB.S9S_MB_2U(SCH_1):GND   I102 @S9S_MB_2U_LIB.S9S_MB_2U(SCH_1):PAGE35
  EE82    GND @S9S_MB_2U_LIB.S9S_MB_2U(SCH_1):GND   I102 @S9S_MB_2U_LIB.S9S_MB_2U(SCH_1):PAGE35
  EJ82    GND @S9S_MB_2U_LIB.S9S_MB_2U(SCH_1):GND   I102 @S9S_MB_2U_LIB.S9S_MB_2U(SCH_1):PAGE35
  EN82    GND @S9S_MB_2U_LIB.S9S_MB_2U(SCH_1):GND   I102 @S9S_MB_2U_LIB.S9S_MB_2U(SCH_1):PAGE35
  ER82    GND @S9S_MB_2U_LIB.S9S_MB_2U(SCH_1):GND   I102 @S9S_MB_2U_LIB.S9S_MB_2U(SCH_1):PAGE35
  EL80    GND @S9S_MB_2U_LIB.S9S_MB_2U(SCH_1):GND   I102 @S9S_MB_2U_LIB.S9S_MB_2U(SCH_1):PAGE35
  CF73     NC     NC   I102 @S9S_MB_2U_LIB.S9S_MB_2U(SCH_1):PAGE35
  CV73     NC     NC   I102 @S9S_MB_2U_LIB.S9S_MB_2U(SCH_1):PAGE35
  CJ74     NC     NC   I102 @S9S_MB_2U_LIB.S9S_MB_2U(SCH_1):PAGE35
  CF75     NC     NC   I102 @S9S_MB_2U_LIB.S9S_MB_2U(SCH_1):PAGE35
  CG76     NC     NC   I102 @S9S_MB_2U_LIB.S9S_MB_2U(SCH_1):PAGE35
  CM75     NC     NC   I102 @S9S_MB_2U_LIB.S9S_MB_2U(SCH_1):PAGE35
  CH77     NC     NC   I102 @S9S_MB_2U_LIB.S9S_MB_2U(SCH_1):PAGE35
  CK77     NC     NC   I102 @S9S_MB_2U_LIB.S9S_MB_2U(SCH_1):PAGE35
  CR74     NC     NC   I102 @S9S_MB_2U_LIB.S9S_MB_2U(SCH_1):PAGE35
  CT75     NC     NC   I102 @S9S_MB_2U_LIB.S9S_MB_2U(SCH_1):PAGE35
  CU76     NC     NC   I102 @S9S_MB_2U_LIB.S9S_MB_2U(SCH_1):PAGE35
  CW76     NC     NC   I102 @S9S_MB_2U_LIB.S9S_MB_2U(SCH_1):PAGE35
  DL80     NC     NC   I102 @S9S_MB_2U_LIB.S9S_MB_2U(SCH_1):PAGE35
  DM81     NC     NC   I102 @S9S_MB_2U_LIB.S9S_MB_2U(SCH_1):PAGE35
  DN82     NC     NC   I102 @S9S_MB_2U_LIB.S9S_MB_2U(SCH_1):PAGE35
  DP79     NC     NC   I102 @S9S_MB_2U_LIB.S9S_MB_2U(SCH_1):PAGE35
  DR82     NC     NC   I102 @S9S_MB_2U_LIB.S9S_MB_2U(SCH_1):PAGE35
  DU80     NC     NC   I102 @S9S_MB_2U_LIB.S9S_MB_2U(SCH_1):PAGE35
  EK87     NC     NC   I102 @S9S_MB_2U_LIB.S9S_MB_2U(SCH_1):PAGE35
  EJ86     NC     NC   I102 @S9S_MB_2U_LIB.S9S_MB_2U(SCH_1):PAGE35
  EM87     NC     NC   I102 @S9S_MB_2U_LIB.S9S_MB_2U(SCH_1):PAGE35
  EP85     NC     NC   I102 @S9S_MB_2U_LIB.S9S_MB_2U(SCH_1):PAGE35
  EL84     NC     NC   I102 @S9S_MB_2U_LIB.S9S_MB_2U(SCH_1):PAGE35
  EH85     NC     NC   I102 @S9S_MB_2U_LIB.S9S_MB_2U(SCH_1):PAGE35
  CD73     NC     NC   I102 @S9S_MB_2U_LIB.S9S_MB_2U(SCH_1):PAGE35
  CW74     NC     NC   I102 @S9S_MB_2U_LIB.S9S_MB_2U(SCH_1):PAGE35
  CK75     NC     NC   I102 @S9S_MB_2U_LIB.S9S_MB_2U(SCH_1):PAGE35
  CH75     NC     NC   I102 @S9S_MB_2U_LIB.S9S_MB_2U(SCH_1):PAGE35
  CF77     NC     NC   I102 @S9S_MB_2U_LIB.S9S_MB_2U(SCH_1):PAGE35
  CL76     NC     NC   I102 @S9S_MB_2U_LIB.S9S_MB_2U(SCH_1):PAGE35
  CJ78     NC     NC   I102 @S9S_MB_2U_LIB.S9S_MB_2U(SCH_1):PAGE35
  CM77     NC     NC   I102 @S9S_MB_2U_LIB.S9S_MB_2U(SCH_1):PAGE35
  CU74     NC     NC   I102 @S9S_MB_2U_LIB.S9S_MB_2U(SCH_1):PAGE35
  CR76     NC     NC   I102 @S9S_MB_2U_LIB.S9S_MB_2U(SCH_1):PAGE35
  CV77     NC     NC   I102 @S9S_MB_2U_LIB.S9S_MB_2U(SCH_1):PAGE35
  DA76     NC     NC   I102 @S9S_MB_2U_LIB.S9S_MB_2U(SCH_1):PAGE35
  DN80     NC     NC   I102 @S9S_MB_2U_LIB.S9S_MB_2U(SCH_1):PAGE35
  DL82     NC     NC   I102 @S9S_MB_2U_LIB.S9S_MB_2U(SCH_1):PAGE35
  DP83     NC     NC   I102 @S9S_MB_2U_LIB.S9S_MB_2U(SCH_1):PAGE35
  DR80     NC     NC   I102 @S9S_MB_2U_LIB.S9S_MB_2U(SCH_1):PAGE35
  DU82     NC     NC   I102 @S9S_MB_2U_LIB.S9S_MB_2U(SCH_1):PAGE35
  DT81     NC     NC   I102 @S9S_MB_2U_LIB.S9S_MB_2U(SCH_1):PAGE35
  EL88     NC     NC   I102 @S9S_MB_2U_LIB.S9S_MB_2U(SCH_1):PAGE35
  EH87     NC     NC   I102 @S9S_MB_2U_LIB.S9S_MB_2U(SCH_1):PAGE35
  EP87     NC     NC   I102 @S9S_MB_2U_LIB.S9S_MB_2U(SCH_1):PAGE35
  EN86     NC     NC   I102 @S9S_MB_2U_LIB.S9S_MB_2U(SCH_1):PAGE35
  EM85     NC     NC   I102 @S9S_MB_2U_LIB.S9S_MB_2U(SCH_1):PAGE35
  EK85     NC     NC   I102 @S9S_MB_2U_LIB.S9S_MB_2U(SCH_1):PAGE35
  CM89 PVCCIN_CPU0 @S9S_MB_2U_LIB.S9S_MB_2U(SCH_1):PVCCIN_CPU0     I1 @S9S_MB_2U_LIB.S9S_MB_2U(SCH_1):PAGE36
  CP89 PVCCIN_CPU0 @S9S_MB_2U_LIB.S9S_MB_2U(SCH_1):PVCCIN_CPU0     I1 @S9S_MB_2U_LIB.S9S_MB_2U(SCH_1):PAGE36
  CN90 PVCCIN_CPU0 @S9S_MB_2U_LIB.S9S_MB_2U(SCH_1):PVCCIN_CPU0     I1 @S9S_MB_2U_LIB.S9S_MB_2U(SCH_1):PAGE36
  CN88 PVCCIN_CPU0 @S9S_MB_2U_LIB.S9S_MB_2U(SCH_1):PVCCIN_CPU0     I1 @S9S_MB_2U_LIB.S9S_MB_2U(SCH_1):PAGE36
  CM91 PVCCIN_CPU0 @S9S_MB_2U_LIB.S9S_MB_2U(SCH_1):PVCCIN_CPU0     I1 @S9S_MB_2U_LIB.S9S_MB_2U(SCH_1):PAGE36
  CM87 PVCCIN_CPU0 @S9S_MB_2U_LIB.S9S_MB_2U(SCH_1):PVCCIN_CPU0     I1 @S9S_MB_2U_LIB.S9S_MB_2U(SCH_1):PAGE36
  CL90 PVCCIN_CPU0 @S9S_MB_2U_LIB.S9S_MB_2U(SCH_1):PVCCIN_CPU0     I1 @S9S_MB_2U_LIB.S9S_MB_2U(SCH_1):PAGE36
  CL88 PVCCIN_CPU0 @S9S_MB_2U_LIB.S9S_MB_2U(SCH_1):PVCCIN_CPU0     I1 @S9S_MB_2U_LIB.S9S_MB_2U(SCH_1):PAGE36
  CL86 PVCCIN_CPU0 @S9S_MB_2U_LIB.S9S_MB_2U(SCH_1):PVCCIN_CPU0     I1 @S9S_MB_2U_LIB.S9S_MB_2U(SCH_1):PAGE36
  CL84 PVCCIN_CPU0 @S9S_MB_2U_LIB.S9S_MB_2U(SCH_1):PVCCIN_CPU0     I1 @S9S_MB_2U_LIB.S9S_MB_2U(SCH_1):PAGE36
  CK91 PVCCIN_CPU0 @S9S_MB_2U_LIB.S9S_MB_2U(SCH_1):PVCCIN_CPU0     I1 @S9S_MB_2U_LIB.S9S_MB_2U(SCH_1):PAGE36
  CK89 PVCCIN_CPU0 @S9S_MB_2U_LIB.S9S_MB_2U(SCH_1):PVCCIN_CPU0     I1 @S9S_MB_2U_LIB.S9S_MB_2U(SCH_1):PAGE36
  CK87 PVCCIN_CPU0 @S9S_MB_2U_LIB.S9S_MB_2U(SCH_1):PVCCIN_CPU0     I1 @S9S_MB_2U_LIB.S9S_MB_2U(SCH_1):PAGE36
  CK85 PVCCIN_CPU0 @S9S_MB_2U_LIB.S9S_MB_2U(SCH_1):PVCCIN_CPU0     I1 @S9S_MB_2U_LIB.S9S_MB_2U(SCH_1):PAGE36
  CK83 PVCCIN_CPU0 @S9S_MB_2U_LIB.S9S_MB_2U(SCH_1):PVCCIN_CPU0     I1 @S9S_MB_2U_LIB.S9S_MB_2U(SCH_1):PAGE36
  CJ90 PVCCIN_CPU0 @S9S_MB_2U_LIB.S9S_MB_2U(SCH_1):PVCCIN_CPU0     I1 @S9S_MB_2U_LIB.S9S_MB_2U(SCH_1):PAGE36
  CJ88 PVCCIN_CPU0 @S9S_MB_2U_LIB.S9S_MB_2U(SCH_1):PVCCIN_CPU0     I1 @S9S_MB_2U_LIB.S9S_MB_2U(SCH_1):PAGE36
  CJ86 PVCCIN_CPU0 @S9S_MB_2U_LIB.S9S_MB_2U(SCH_1):PVCCIN_CPU0     I1 @S9S_MB_2U_LIB.S9S_MB_2U(SCH_1):PAGE36
  CJ84 PVCCIN_CPU0 @S9S_MB_2U_LIB.S9S_MB_2U(SCH_1):PVCCIN_CPU0     I1 @S9S_MB_2U_LIB.S9S_MB_2U(SCH_1):PAGE36
  CJ82 PVCCIN_CPU0 @S9S_MB_2U_LIB.S9S_MB_2U(SCH_1):PVCCIN_CPU0     I1 @S9S_MB_2U_LIB.S9S_MB_2U(SCH_1):PAGE36
  CH91 PVCCIN_CPU0 @S9S_MB_2U_LIB.S9S_MB_2U(SCH_1):PVCCIN_CPU0     I1 @S9S_MB_2U_LIB.S9S_MB_2U(SCH_1):PAGE36
  CH81 PVCCIN_CPU0 @S9S_MB_2U_LIB.S9S_MB_2U(SCH_1):PVCCIN_CPU0     I1 @S9S_MB_2U_LIB.S9S_MB_2U(SCH_1):PAGE36
  CG90 PVCCIN_CPU0 @S9S_MB_2U_LIB.S9S_MB_2U(SCH_1):PVCCIN_CPU0     I1 @S9S_MB_2U_LIB.S9S_MB_2U(SCH_1):PAGE36
  CG88 PVCCIN_CPU0 @S9S_MB_2U_LIB.S9S_MB_2U(SCH_1):PVCCIN_CPU0     I1 @S9S_MB_2U_LIB.S9S_MB_2U(SCH_1):PAGE36
  CG86 PVCCIN_CPU0 @S9S_MB_2U_LIB.S9S_MB_2U(SCH_1):PVCCIN_CPU0     I1 @S9S_MB_2U_LIB.S9S_MB_2U(SCH_1):PAGE36
  CG84 PVCCIN_CPU0 @S9S_MB_2U_LIB.S9S_MB_2U(SCH_1):PVCCIN_CPU0     I1 @S9S_MB_2U_LIB.S9S_MB_2U(SCH_1):PAGE36
  CG82 PVCCIN_CPU0 @S9S_MB_2U_LIB.S9S_MB_2U(SCH_1):PVCCIN_CPU0     I1 @S9S_MB_2U_LIB.S9S_MB_2U(SCH_1):PAGE36
  CG80 PVCCIN_CPU0 @S9S_MB_2U_LIB.S9S_MB_2U(SCH_1):PVCCIN_CPU0     I1 @S9S_MB_2U_LIB.S9S_MB_2U(SCH_1):PAGE36
  CF91 PVCCIN_CPU0 @S9S_MB_2U_LIB.S9S_MB_2U(SCH_1):PVCCIN_CPU0     I1 @S9S_MB_2U_LIB.S9S_MB_2U(SCH_1):PAGE36
  CF89 PVCCIN_CPU0 @S9S_MB_2U_LIB.S9S_MB_2U(SCH_1):PVCCIN_CPU0     I1 @S9S_MB_2U_LIB.S9S_MB_2U(SCH_1):PAGE36
  CF87 PVCCIN_CPU0 @S9S_MB_2U_LIB.S9S_MB_2U(SCH_1):PVCCIN_CPU0     I1 @S9S_MB_2U_LIB.S9S_MB_2U(SCH_1):PAGE36
  CF85 PVCCIN_CPU0 @S9S_MB_2U_LIB.S9S_MB_2U(SCH_1):PVCCIN_CPU0     I1 @S9S_MB_2U_LIB.S9S_MB_2U(SCH_1):PAGE36
  CF83 PVCCIN_CPU0 @S9S_MB_2U_LIB.S9S_MB_2U(SCH_1):PVCCIN_CPU0     I1 @S9S_MB_2U_LIB.S9S_MB_2U(SCH_1):PAGE36
  CF81 PVCCIN_CPU0 @S9S_MB_2U_LIB.S9S_MB_2U(SCH_1):PVCCIN_CPU0     I1 @S9S_MB_2U_LIB.S9S_MB_2U(SCH_1):PAGE36
  CF79 PVCCIN_CPU0 @S9S_MB_2U_LIB.S9S_MB_2U(SCH_1):PVCCIN_CPU0     I1 @S9S_MB_2U_LIB.S9S_MB_2U(SCH_1):PAGE36
  CE90 PVCCIN_CPU0 @S9S_MB_2U_LIB.S9S_MB_2U(SCH_1):PVCCIN_CPU0     I1 @S9S_MB_2U_LIB.S9S_MB_2U(SCH_1):PAGE36
  CE88 PVCCIN_CPU0 @S9S_MB_2U_LIB.S9S_MB_2U(SCH_1):PVCCIN_CPU0     I1 @S9S_MB_2U_LIB.S9S_MB_2U(SCH_1):PAGE36
  CE86 PVCCIN_CPU0 @S9S_MB_2U_LIB.S9S_MB_2U(SCH_1):PVCCIN_CPU0     I1 @S9S_MB_2U_LIB.S9S_MB_2U(SCH_1):PAGE36
  CE84 PVCCIN_CPU0 @S9S_MB_2U_LIB.S9S_MB_2U(SCH_1):PVCCIN_CPU0     I1 @S9S_MB_2U_LIB.S9S_MB_2U(SCH_1):PAGE36
  CE82 PVCCIN_CPU0 @S9S_MB_2U_LIB.S9S_MB_2U(SCH_1):PVCCIN_CPU0     I1 @S9S_MB_2U_LIB.S9S_MB_2U(SCH_1):PAGE36
  CE80 PVCCIN_CPU0 @S9S_MB_2U_LIB.S9S_MB_2U(SCH_1):PVCCIN_CPU0     I1 @S9S_MB_2U_LIB.S9S_MB_2U(SCH_1):PAGE36
  CD89 PVCCIN_CPU0 @S9S_MB_2U_LIB.S9S_MB_2U(SCH_1):PVCCIN_CPU0     I1 @S9S_MB_2U_LIB.S9S_MB_2U(SCH_1):PAGE36
  CD87 PVCCIN_CPU0 @S9S_MB_2U_LIB.S9S_MB_2U(SCH_1):PVCCIN_CPU0     I1 @S9S_MB_2U_LIB.S9S_MB_2U(SCH_1):PAGE36
  CD85 PVCCIN_CPU0 @S9S_MB_2U_LIB.S9S_MB_2U(SCH_1):PVCCIN_CPU0     I1 @S9S_MB_2U_LIB.S9S_MB_2U(SCH_1):PAGE36
  CD83 PVCCIN_CPU0 @S9S_MB_2U_LIB.S9S_MB_2U(SCH_1):PVCCIN_CPU0     I1 @S9S_MB_2U_LIB.S9S_MB_2U(SCH_1):PAGE36
  CD81 PVCCIN_CPU0 @S9S_MB_2U_LIB.S9S_MB_2U(SCH_1):PVCCIN_CPU0     I1 @S9S_MB_2U_LIB.S9S_MB_2U(SCH_1):PAGE36
  CD79 PVCCIN_CPU0 @S9S_MB_2U_LIB.S9S_MB_2U(SCH_1):PVCCIN_CPU0     I1 @S9S_MB_2U_LIB.S9S_MB_2U(SCH_1):PAGE36
  CD59 PVCCIN_CPU0 @S9S_MB_2U_LIB.S9S_MB_2U(SCH_1):PVCCIN_CPU0     I1 @S9S_MB_2U_LIB.S9S_MB_2U(SCH_1):PAGE36
  CD57 PVCCIN_CPU0 @S9S_MB_2U_LIB.S9S_MB_2U(SCH_1):PVCCIN_CPU0     I1 @S9S_MB_2U_LIB.S9S_MB_2U(SCH_1):PAGE36
  CD55 PVCCIN_CPU0 @S9S_MB_2U_LIB.S9S_MB_2U(SCH_1):PVCCIN_CPU0     I1 @S9S_MB_2U_LIB.S9S_MB_2U(SCH_1):PAGE36
  CD53 PVCCIN_CPU0 @S9S_MB_2U_LIB.S9S_MB_2U(SCH_1):PVCCIN_CPU0     I1 @S9S_MB_2U_LIB.S9S_MB_2U(SCH_1):PAGE36
  CD51 PVCCIN_CPU0 @S9S_MB_2U_LIB.S9S_MB_2U(SCH_1):PVCCIN_CPU0     I1 @S9S_MB_2U_LIB.S9S_MB_2U(SCH_1):PAGE36
  CD49 PVCCIN_CPU0 @S9S_MB_2U_LIB.S9S_MB_2U(SCH_1):PVCCIN_CPU0     I1 @S9S_MB_2U_LIB.S9S_MB_2U(SCH_1):PAGE36
  CD47 PVCCIN_CPU0 @S9S_MB_2U_LIB.S9S_MB_2U(SCH_1):PVCCIN_CPU0     I1 @S9S_MB_2U_LIB.S9S_MB_2U(SCH_1):PAGE36
  CD44 PVCCIN_CPU0 @S9S_MB_2U_LIB.S9S_MB_2U(SCH_1):PVCCIN_CPU0     I1 @S9S_MB_2U_LIB.S9S_MB_2U(SCH_1):PAGE36
  CD42 PVCCIN_CPU0 @S9S_MB_2U_LIB.S9S_MB_2U(SCH_1):PVCCIN_CPU0     I1 @S9S_MB_2U_LIB.S9S_MB_2U(SCH_1):PAGE36
  CD40 PVCCIN_CPU0 @S9S_MB_2U_LIB.S9S_MB_2U(SCH_1):PVCCIN_CPU0     I1 @S9S_MB_2U_LIB.S9S_MB_2U(SCH_1):PAGE36
  CD38 PVCCIN_CPU0 @S9S_MB_2U_LIB.S9S_MB_2U(SCH_1):PVCCIN_CPU0     I1 @S9S_MB_2U_LIB.S9S_MB_2U(SCH_1):PAGE36
  CD36 PVCCIN_CPU0 @S9S_MB_2U_LIB.S9S_MB_2U(SCH_1):PVCCIN_CPU0     I1 @S9S_MB_2U_LIB.S9S_MB_2U(SCH_1):PAGE36
  CD34 PVCCIN_CPU0 @S9S_MB_2U_LIB.S9S_MB_2U(SCH_1):PVCCIN_CPU0     I1 @S9S_MB_2U_LIB.S9S_MB_2U(SCH_1):PAGE36
  CD32 PVCCIN_CPU0 @S9S_MB_2U_LIB.S9S_MB_2U(SCH_1):PVCCIN_CPU0     I1 @S9S_MB_2U_LIB.S9S_MB_2U(SCH_1):PAGE36
  CC90 PVCCIN_CPU0 @S9S_MB_2U_LIB.S9S_MB_2U(SCH_1):PVCCIN_CPU0     I1 @S9S_MB_2U_LIB.S9S_MB_2U(SCH_1):PAGE36
  CC88 PVCCIN_CPU0 @S9S_MB_2U_LIB.S9S_MB_2U(SCH_1):PVCCIN_CPU0     I1 @S9S_MB_2U_LIB.S9S_MB_2U(SCH_1):PAGE36
  CC86 PVCCIN_CPU0 @S9S_MB_2U_LIB.S9S_MB_2U(SCH_1):PVCCIN_CPU0     I1 @S9S_MB_2U_LIB.S9S_MB_2U(SCH_1):PAGE36
  CC84 PVCCIN_CPU0 @S9S_MB_2U_LIB.S9S_MB_2U(SCH_1):PVCCIN_CPU0     I1 @S9S_MB_2U_LIB.S9S_MB_2U(SCH_1):PAGE36
  CC82 PVCCIN_CPU0 @S9S_MB_2U_LIB.S9S_MB_2U(SCH_1):PVCCIN_CPU0     I1 @S9S_MB_2U_LIB.S9S_MB_2U(SCH_1):PAGE36
  CC80 PVCCIN_CPU0 @S9S_MB_2U_LIB.S9S_MB_2U(SCH_1):PVCCIN_CPU0     I1 @S9S_MB_2U_LIB.S9S_MB_2U(SCH_1):PAGE36
  CC78 PVCCIN_CPU0 @S9S_MB_2U_LIB.S9S_MB_2U(SCH_1):PVCCIN_CPU0     I1 @S9S_MB_2U_LIB.S9S_MB_2U(SCH_1):PAGE36
  CC76 PVCCIN_CPU0 @S9S_MB_2U_LIB.S9S_MB_2U(SCH_1):PVCCIN_CPU0     I1 @S9S_MB_2U_LIB.S9S_MB_2U(SCH_1):PAGE36
  CC60 PVCCIN_CPU0 @S9S_MB_2U_LIB.S9S_MB_2U(SCH_1):PVCCIN_CPU0     I1 @S9S_MB_2U_LIB.S9S_MB_2U(SCH_1):PAGE36
  CC58 PVCCIN_CPU0 @S9S_MB_2U_LIB.S9S_MB_2U(SCH_1):PVCCIN_CPU0     I1 @S9S_MB_2U_LIB.S9S_MB_2U(SCH_1):PAGE36
  CC56 PVCCIN_CPU0 @S9S_MB_2U_LIB.S9S_MB_2U(SCH_1):PVCCIN_CPU0     I1 @S9S_MB_2U_LIB.S9S_MB_2U(SCH_1):PAGE36
  CC54 PVCCIN_CPU0 @S9S_MB_2U_LIB.S9S_MB_2U(SCH_1):PVCCIN_CPU0     I1 @S9S_MB_2U_LIB.S9S_MB_2U(SCH_1):PAGE36
  CC52 PVCCIN_CPU0 @S9S_MB_2U_LIB.S9S_MB_2U(SCH_1):PVCCIN_CPU0     I1 @S9S_MB_2U_LIB.S9S_MB_2U(SCH_1):PAGE36
  CC50 PVCCIN_CPU0 @S9S_MB_2U_LIB.S9S_MB_2U(SCH_1):PVCCIN_CPU0     I1 @S9S_MB_2U_LIB.S9S_MB_2U(SCH_1):PAGE36
  CC48 PVCCIN_CPU0 @S9S_MB_2U_LIB.S9S_MB_2U(SCH_1):PVCCIN_CPU0     I1 @S9S_MB_2U_LIB.S9S_MB_2U(SCH_1):PAGE36
  CC45 PVCCIN_CPU0 @S9S_MB_2U_LIB.S9S_MB_2U(SCH_1):PVCCIN_CPU0     I1 @S9S_MB_2U_LIB.S9S_MB_2U(SCH_1):PAGE36
  CC43 PVCCIN_CPU0 @S9S_MB_2U_LIB.S9S_MB_2U(SCH_1):PVCCIN_CPU0     I1 @S9S_MB_2U_LIB.S9S_MB_2U(SCH_1):PAGE36
  CC41 PVCCIN_CPU0 @S9S_MB_2U_LIB.S9S_MB_2U(SCH_1):PVCCIN_CPU0     I1 @S9S_MB_2U_LIB.S9S_MB_2U(SCH_1):PAGE36
  CC39 PVCCIN_CPU0 @S9S_MB_2U_LIB.S9S_MB_2U(SCH_1):PVCCIN_CPU0     I1 @S9S_MB_2U_LIB.S9S_MB_2U(SCH_1):PAGE36
  CC37 PVCCIN_CPU0 @S9S_MB_2U_LIB.S9S_MB_2U(SCH_1):PVCCIN_CPU0     I1 @S9S_MB_2U_LIB.S9S_MB_2U(SCH_1):PAGE36
  CC35 PVCCIN_CPU0 @S9S_MB_2U_LIB.S9S_MB_2U(SCH_1):PVCCIN_CPU0     I1 @S9S_MB_2U_LIB.S9S_MB_2U(SCH_1):PAGE36
  CC33 PVCCIN_CPU0 @S9S_MB_2U_LIB.S9S_MB_2U(SCH_1):PVCCIN_CPU0     I1 @S9S_MB_2U_LIB.S9S_MB_2U(SCH_1):PAGE36
  CB77 PVCCIN_CPU0 @S9S_MB_2U_LIB.S9S_MB_2U(SCH_1):PVCCIN_CPU0     I1 @S9S_MB_2U_LIB.S9S_MB_2U(SCH_1):PAGE36
  CB75 PVCCIN_CPU0 @S9S_MB_2U_LIB.S9S_MB_2U(SCH_1):PVCCIN_CPU0     I1 @S9S_MB_2U_LIB.S9S_MB_2U(SCH_1):PAGE36
  CB61 PVCCIN_CPU0 @S9S_MB_2U_LIB.S9S_MB_2U(SCH_1):PVCCIN_CPU0     I1 @S9S_MB_2U_LIB.S9S_MB_2U(SCH_1):PAGE36
  CA90 PVCCIN_CPU0 @S9S_MB_2U_LIB.S9S_MB_2U(SCH_1):PVCCIN_CPU0     I1 @S9S_MB_2U_LIB.S9S_MB_2U(SCH_1):PAGE36
  CA88 PVCCIN_CPU0 @S9S_MB_2U_LIB.S9S_MB_2U(SCH_1):PVCCIN_CPU0     I1 @S9S_MB_2U_LIB.S9S_MB_2U(SCH_1):PAGE36
  CA86 PVCCIN_CPU0 @S9S_MB_2U_LIB.S9S_MB_2U(SCH_1):PVCCIN_CPU0     I1 @S9S_MB_2U_LIB.S9S_MB_2U(SCH_1):PAGE36
  CA84 PVCCIN_CPU0 @S9S_MB_2U_LIB.S9S_MB_2U(SCH_1):PVCCIN_CPU0     I1 @S9S_MB_2U_LIB.S9S_MB_2U(SCH_1):PAGE36
  CA82 PVCCIN_CPU0 @S9S_MB_2U_LIB.S9S_MB_2U(SCH_1):PVCCIN_CPU0     I1 @S9S_MB_2U_LIB.S9S_MB_2U(SCH_1):PAGE36
  CA80 PVCCIN_CPU0 @S9S_MB_2U_LIB.S9S_MB_2U(SCH_1):PVCCIN_CPU0     I1 @S9S_MB_2U_LIB.S9S_MB_2U(SCH_1):PAGE36
  CA78 PVCCIN_CPU0 @S9S_MB_2U_LIB.S9S_MB_2U(SCH_1):PVCCIN_CPU0     I1 @S9S_MB_2U_LIB.S9S_MB_2U(SCH_1):PAGE36
  CA76 PVCCIN_CPU0 @S9S_MB_2U_LIB.S9S_MB_2U(SCH_1):PVCCIN_CPU0     I1 @S9S_MB_2U_LIB.S9S_MB_2U(SCH_1):PAGE36
  CA74 PVCCIN_CPU0 @S9S_MB_2U_LIB.S9S_MB_2U(SCH_1):PVCCIN_CPU0     I1 @S9S_MB_2U_LIB.S9S_MB_2U(SCH_1):PAGE36
  CA72 PVCCIN_CPU0 @S9S_MB_2U_LIB.S9S_MB_2U(SCH_1):PVCCIN_CPU0     I1 @S9S_MB_2U_LIB.S9S_MB_2U(SCH_1):PAGE36
  CA70 PVCCIN_CPU0 @S9S_MB_2U_LIB.S9S_MB_2U(SCH_1):PVCCIN_CPU0     I1 @S9S_MB_2U_LIB.S9S_MB_2U(SCH_1):PAGE36
  CA68 PVCCIN_CPU0 @S9S_MB_2U_LIB.S9S_MB_2U(SCH_1):PVCCIN_CPU0     I1 @S9S_MB_2U_LIB.S9S_MB_2U(SCH_1):PAGE36
  CA66 PVCCIN_CPU0 @S9S_MB_2U_LIB.S9S_MB_2U(SCH_1):PVCCIN_CPU0     I1 @S9S_MB_2U_LIB.S9S_MB_2U(SCH_1):PAGE36
  CA64 PVCCIN_CPU0 @S9S_MB_2U_LIB.S9S_MB_2U(SCH_1):PVCCIN_CPU0     I1 @S9S_MB_2U_LIB.S9S_MB_2U(SCH_1):PAGE36
  CA62 PVCCIN_CPU0 @S9S_MB_2U_LIB.S9S_MB_2U(SCH_1):PVCCIN_CPU0     I1 @S9S_MB_2U_LIB.S9S_MB_2U(SCH_1):PAGE36
  CA60 PVCCIN_CPU0 @S9S_MB_2U_LIB.S9S_MB_2U(SCH_1):PVCCIN_CPU0     I1 @S9S_MB_2U_LIB.S9S_MB_2U(SCH_1):PAGE36
  CA58 PVCCIN_CPU0 @S9S_MB_2U_LIB.S9S_MB_2U(SCH_1):PVCCIN_CPU0     I1 @S9S_MB_2U_LIB.S9S_MB_2U(SCH_1):PAGE36
  CA56 PVCCIN_CPU0 @S9S_MB_2U_LIB.S9S_MB_2U(SCH_1):PVCCIN_CPU0     I1 @S9S_MB_2U_LIB.S9S_MB_2U(SCH_1):PAGE36
  CA54 PVCCIN_CPU0 @S9S_MB_2U_LIB.S9S_MB_2U(SCH_1):PVCCIN_CPU0     I1 @S9S_MB_2U_LIB.S9S_MB_2U(SCH_1):PAGE36
  CA52 PVCCIN_CPU0 @S9S_MB_2U_LIB.S9S_MB_2U(SCH_1):PVCCIN_CPU0     I1 @S9S_MB_2U_LIB.S9S_MB_2U(SCH_1):PAGE36
  CA50 PVCCIN_CPU0 @S9S_MB_2U_LIB.S9S_MB_2U(SCH_1):PVCCIN_CPU0     I1 @S9S_MB_2U_LIB.S9S_MB_2U(SCH_1):PAGE36
  CA48 PVCCIN_CPU0 @S9S_MB_2U_LIB.S9S_MB_2U(SCH_1):PVCCIN_CPU0     I1 @S9S_MB_2U_LIB.S9S_MB_2U(SCH_1):PAGE36
  CA45 PVCCIN_CPU0 @S9S_MB_2U_LIB.S9S_MB_2U(SCH_1):PVCCIN_CPU0     I1 @S9S_MB_2U_LIB.S9S_MB_2U(SCH_1):PAGE36
  CA43 PVCCIN_CPU0 @S9S_MB_2U_LIB.S9S_MB_2U(SCH_1):PVCCIN_CPU0     I1 @S9S_MB_2U_LIB.S9S_MB_2U(SCH_1):PAGE36
  CA41 PVCCIN_CPU0 @S9S_MB_2U_LIB.S9S_MB_2U(SCH_1):PVCCIN_CPU0     I1 @S9S_MB_2U_LIB.S9S_MB_2U(SCH_1):PAGE36
  CA39 PVCCIN_CPU0 @S9S_MB_2U_LIB.S9S_MB_2U(SCH_1):PVCCIN_CPU0     I1 @S9S_MB_2U_LIB.S9S_MB_2U(SCH_1):PAGE36
  CA37 PVCCIN_CPU0 @S9S_MB_2U_LIB.S9S_MB_2U(SCH_1):PVCCIN_CPU0     I1 @S9S_MB_2U_LIB.S9S_MB_2U(SCH_1):PAGE36
  CA35 PVCCIN_CPU0 @S9S_MB_2U_LIB.S9S_MB_2U(SCH_1):PVCCIN_CPU0     I1 @S9S_MB_2U_LIB.S9S_MB_2U(SCH_1):PAGE36
  CA33 PVCCIN_CPU0 @S9S_MB_2U_LIB.S9S_MB_2U(SCH_1):PVCCIN_CPU0     I1 @S9S_MB_2U_LIB.S9S_MB_2U(SCH_1):PAGE36
  BY89 PVCCIN_CPU0 @S9S_MB_2U_LIB.S9S_MB_2U(SCH_1):PVCCIN_CPU0     I1 @S9S_MB_2U_LIB.S9S_MB_2U(SCH_1):PAGE36
  BY87 PVCCIN_CPU0 @S9S_MB_2U_LIB.S9S_MB_2U(SCH_1):PVCCIN_CPU0     I1 @S9S_MB_2U_LIB.S9S_MB_2U(SCH_1):PAGE36
  BY85 PVCCIN_CPU0 @S9S_MB_2U_LIB.S9S_MB_2U(SCH_1):PVCCIN_CPU0     I1 @S9S_MB_2U_LIB.S9S_MB_2U(SCH_1):PAGE36
  BY83 PVCCIN_CPU0 @S9S_MB_2U_LIB.S9S_MB_2U(SCH_1):PVCCIN_CPU0     I1 @S9S_MB_2U_LIB.S9S_MB_2U(SCH_1):PAGE36
  BY81 PVCCIN_CPU0 @S9S_MB_2U_LIB.S9S_MB_2U(SCH_1):PVCCIN_CPU0     I1 @S9S_MB_2U_LIB.S9S_MB_2U(SCH_1):PAGE36
  BY79 PVCCIN_CPU0 @S9S_MB_2U_LIB.S9S_MB_2U(SCH_1):PVCCIN_CPU0     I1 @S9S_MB_2U_LIB.S9S_MB_2U(SCH_1):PAGE36
  BY77 PVCCIN_CPU0 @S9S_MB_2U_LIB.S9S_MB_2U(SCH_1):PVCCIN_CPU0     I1 @S9S_MB_2U_LIB.S9S_MB_2U(SCH_1):PAGE36
  BY75 PVCCIN_CPU0 @S9S_MB_2U_LIB.S9S_MB_2U(SCH_1):PVCCIN_CPU0     I1 @S9S_MB_2U_LIB.S9S_MB_2U(SCH_1):PAGE36
  BY73 PVCCIN_CPU0 @S9S_MB_2U_LIB.S9S_MB_2U(SCH_1):PVCCIN_CPU0     I1 @S9S_MB_2U_LIB.S9S_MB_2U(SCH_1):PAGE36
  BY71 PVCCIN_CPU0 @S9S_MB_2U_LIB.S9S_MB_2U(SCH_1):PVCCIN_CPU0     I1 @S9S_MB_2U_LIB.S9S_MB_2U(SCH_1):PAGE36
  BY69 PVCCIN_CPU0 @S9S_MB_2U_LIB.S9S_MB_2U(SCH_1):PVCCIN_CPU0     I1 @S9S_MB_2U_LIB.S9S_MB_2U(SCH_1):PAGE36
  BY67 PVCCIN_CPU0 @S9S_MB_2U_LIB.S9S_MB_2U(SCH_1):PVCCIN_CPU0     I1 @S9S_MB_2U_LIB.S9S_MB_2U(SCH_1):PAGE36
  BY65 PVCCIN_CPU0 @S9S_MB_2U_LIB.S9S_MB_2U(SCH_1):PVCCIN_CPU0     I1 @S9S_MB_2U_LIB.S9S_MB_2U(SCH_1):PAGE36
  BY63 PVCCIN_CPU0 @S9S_MB_2U_LIB.S9S_MB_2U(SCH_1):PVCCIN_CPU0     I1 @S9S_MB_2U_LIB.S9S_MB_2U(SCH_1):PAGE36
  BY61 PVCCIN_CPU0 @S9S_MB_2U_LIB.S9S_MB_2U(SCH_1):PVCCIN_CPU0     I1 @S9S_MB_2U_LIB.S9S_MB_2U(SCH_1):PAGE36
  BY59 PVCCIN_CPU0 @S9S_MB_2U_LIB.S9S_MB_2U(SCH_1):PVCCIN_CPU0     I1 @S9S_MB_2U_LIB.S9S_MB_2U(SCH_1):PAGE36
  BY57 PVCCIN_CPU0 @S9S_MB_2U_LIB.S9S_MB_2U(SCH_1):PVCCIN_CPU0     I1 @S9S_MB_2U_LIB.S9S_MB_2U(SCH_1):PAGE36
  BY55 PVCCIN_CPU0 @S9S_MB_2U_LIB.S9S_MB_2U(SCH_1):PVCCIN_CPU0     I1 @S9S_MB_2U_LIB.S9S_MB_2U(SCH_1):PAGE36
  BY53 PVCCIN_CPU0 @S9S_MB_2U_LIB.S9S_MB_2U(SCH_1):PVCCIN_CPU0     I1 @S9S_MB_2U_LIB.S9S_MB_2U(SCH_1):PAGE36
  BY51 PVCCIN_CPU0 @S9S_MB_2U_LIB.S9S_MB_2U(SCH_1):PVCCIN_CPU0     I1 @S9S_MB_2U_LIB.S9S_MB_2U(SCH_1):PAGE36
  BY49 PVCCIN_CPU0 @S9S_MB_2U_LIB.S9S_MB_2U(SCH_1):PVCCIN_CPU0     I1 @S9S_MB_2U_LIB.S9S_MB_2U(SCH_1):PAGE36
  BY47 PVCCIN_CPU0 @S9S_MB_2U_LIB.S9S_MB_2U(SCH_1):PVCCIN_CPU0     I1 @S9S_MB_2U_LIB.S9S_MB_2U(SCH_1):PAGE36
  BY44 PVCCIN_CPU0 @S9S_MB_2U_LIB.S9S_MB_2U(SCH_1):PVCCIN_CPU0     I1 @S9S_MB_2U_LIB.S9S_MB_2U(SCH_1):PAGE36
  BY42 PVCCIN_CPU0 @S9S_MB_2U_LIB.S9S_MB_2U(SCH_1):PVCCIN_CPU0     I1 @S9S_MB_2U_LIB.S9S_MB_2U(SCH_1):PAGE36
  BY40 PVCCIN_CPU0 @S9S_MB_2U_LIB.S9S_MB_2U(SCH_1):PVCCIN_CPU0     I1 @S9S_MB_2U_LIB.S9S_MB_2U(SCH_1):PAGE36
  BY38 PVCCIN_CPU0 @S9S_MB_2U_LIB.S9S_MB_2U(SCH_1):PVCCIN_CPU0     I1 @S9S_MB_2U_LIB.S9S_MB_2U(SCH_1):PAGE36
  BY36 PVCCIN_CPU0 @S9S_MB_2U_LIB.S9S_MB_2U(SCH_1):PVCCIN_CPU0     I1 @S9S_MB_2U_LIB.S9S_MB_2U(SCH_1):PAGE36
  BY34 PVCCIN_CPU0 @S9S_MB_2U_LIB.S9S_MB_2U(SCH_1):PVCCIN_CPU0     I1 @S9S_MB_2U_LIB.S9S_MB_2U(SCH_1):PAGE36
  BY32 PVCCIN_CPU0 @S9S_MB_2U_LIB.S9S_MB_2U(SCH_1):PVCCIN_CPU0     I1 @S9S_MB_2U_LIB.S9S_MB_2U(SCH_1):PAGE36
  BW90 PVCCIN_CPU0 @S9S_MB_2U_LIB.S9S_MB_2U(SCH_1):PVCCIN_CPU0     I1 @S9S_MB_2U_LIB.S9S_MB_2U(SCH_1):PAGE36
  BW88 PVCCIN_CPU0 @S9S_MB_2U_LIB.S9S_MB_2U(SCH_1):PVCCIN_CPU0     I1 @S9S_MB_2U_LIB.S9S_MB_2U(SCH_1):PAGE36
  BW86 PVCCIN_CPU0 @S9S_MB_2U_LIB.S9S_MB_2U(SCH_1):PVCCIN_CPU0     I1 @S9S_MB_2U_LIB.S9S_MB_2U(SCH_1):PAGE36
  BW84 PVCCIN_CPU0 @S9S_MB_2U_LIB.S9S_MB_2U(SCH_1):PVCCIN_CPU0     I1 @S9S_MB_2U_LIB.S9S_MB_2U(SCH_1):PAGE36
  BW82 PVCCIN_CPU0 @S9S_MB_2U_LIB.S9S_MB_2U(SCH_1):PVCCIN_CPU0     I1 @S9S_MB_2U_LIB.S9S_MB_2U(SCH_1):PAGE36
  BW80 PVCCIN_CPU0 @S9S_MB_2U_LIB.S9S_MB_2U(SCH_1):PVCCIN_CPU0     I1 @S9S_MB_2U_LIB.S9S_MB_2U(SCH_1):PAGE36
  BW78 PVCCIN_CPU0 @S9S_MB_2U_LIB.S9S_MB_2U(SCH_1):PVCCIN_CPU0     I7 @S9S_MB_2U_LIB.S9S_MB_2U(SCH_1):PAGE36
  BW76 PVCCIN_CPU0 @S9S_MB_2U_LIB.S9S_MB_2U(SCH_1):PVCCIN_CPU0     I7 @S9S_MB_2U_LIB.S9S_MB_2U(SCH_1):PAGE36
  BW74 PVCCIN_CPU0 @S9S_MB_2U_LIB.S9S_MB_2U(SCH_1):PVCCIN_CPU0     I7 @S9S_MB_2U_LIB.S9S_MB_2U(SCH_1):PAGE36
  BW72 PVCCIN_CPU0 @S9S_MB_2U_LIB.S9S_MB_2U(SCH_1):PVCCIN_CPU0     I7 @S9S_MB_2U_LIB.S9S_MB_2U(SCH_1):PAGE36
  BW70 PVCCIN_CPU0 @S9S_MB_2U_LIB.S9S_MB_2U(SCH_1):PVCCIN_CPU0     I7 @S9S_MB_2U_LIB.S9S_MB_2U(SCH_1):PAGE36
  BW68 PVCCIN_CPU0 @S9S_MB_2U_LIB.S9S_MB_2U(SCH_1):PVCCIN_CPU0     I7 @S9S_MB_2U_LIB.S9S_MB_2U(SCH_1):PAGE36
  BW66 PVCCIN_CPU0 @S9S_MB_2U_LIB.S9S_MB_2U(SCH_1):PVCCIN_CPU0     I7 @S9S_MB_2U_LIB.S9S_MB_2U(SCH_1):PAGE36
  BW64 PVCCIN_CPU0 @S9S_MB_2U_LIB.S9S_MB_2U(SCH_1):PVCCIN_CPU0     I7 @S9S_MB_2U_LIB.S9S_MB_2U(SCH_1):PAGE36
  BW62 PVCCIN_CPU0 @S9S_MB_2U_LIB.S9S_MB_2U(SCH_1):PVCCIN_CPU0     I7 @S9S_MB_2U_LIB.S9S_MB_2U(SCH_1):PAGE36
  BW60 PVCCIN_CPU0 @S9S_MB_2U_LIB.S9S_MB_2U(SCH_1):PVCCIN_CPU0     I7 @S9S_MB_2U_LIB.S9S_MB_2U(SCH_1):PAGE36
  BW58 PVCCIN_CPU0 @S9S_MB_2U_LIB.S9S_MB_2U(SCH_1):PVCCIN_CPU0     I7 @S9S_MB_2U_LIB.S9S_MB_2U(SCH_1):PAGE36
  BW56 PVCCIN_CPU0 @S9S_MB_2U_LIB.S9S_MB_2U(SCH_1):PVCCIN_CPU0     I7 @S9S_MB_2U_LIB.S9S_MB_2U(SCH_1):PAGE36
  BW54 PVCCIN_CPU0 @S9S_MB_2U_LIB.S9S_MB_2U(SCH_1):PVCCIN_CPU0     I7 @S9S_MB_2U_LIB.S9S_MB_2U(SCH_1):PAGE36
  BW52 PVCCIN_CPU0 @S9S_MB_2U_LIB.S9S_MB_2U(SCH_1):PVCCIN_CPU0     I7 @S9S_MB_2U_LIB.S9S_MB_2U(SCH_1):PAGE36
  BW50 PVCCIN_CPU0 @S9S_MB_2U_LIB.S9S_MB_2U(SCH_1):PVCCIN_CPU0     I7 @S9S_MB_2U_LIB.S9S_MB_2U(SCH_1):PAGE36
  BW48 PVCCIN_CPU0 @S9S_MB_2U_LIB.S9S_MB_2U(SCH_1):PVCCIN_CPU0     I7 @S9S_MB_2U_LIB.S9S_MB_2U(SCH_1):PAGE36
  BW45 PVCCIN_CPU0 @S9S_MB_2U_LIB.S9S_MB_2U(SCH_1):PVCCIN_CPU0     I7 @S9S_MB_2U_LIB.S9S_MB_2U(SCH_1):PAGE36
  BW43 PVCCIN_CPU0 @S9S_MB_2U_LIB.S9S_MB_2U(SCH_1):PVCCIN_CPU0     I7 @S9S_MB_2U_LIB.S9S_MB_2U(SCH_1):PAGE36
  BW41 PVCCIN_CPU0 @S9S_MB_2U_LIB.S9S_MB_2U(SCH_1):PVCCIN_CPU0     I7 @S9S_MB_2U_LIB.S9S_MB_2U(SCH_1):PAGE36
  BW39 PVCCIN_CPU0 @S9S_MB_2U_LIB.S9S_MB_2U(SCH_1):PVCCIN_CPU0     I7 @S9S_MB_2U_LIB.S9S_MB_2U(SCH_1):PAGE36
  BW37 PVCCIN_CPU0 @S9S_MB_2U_LIB.S9S_MB_2U(SCH_1):PVCCIN_CPU0     I7 @S9S_MB_2U_LIB.S9S_MB_2U(SCH_1):PAGE36
  BW35 PVCCIN_CPU0 @S9S_MB_2U_LIB.S9S_MB_2U(SCH_1):PVCCIN_CPU0     I7 @S9S_MB_2U_LIB.S9S_MB_2U(SCH_1):PAGE36
  BW33 PVCCIN_CPU0 @S9S_MB_2U_LIB.S9S_MB_2U(SCH_1):PVCCIN_CPU0     I7 @S9S_MB_2U_LIB.S9S_MB_2U(SCH_1):PAGE36
  BV89 PVCCIN_CPU0 @S9S_MB_2U_LIB.S9S_MB_2U(SCH_1):PVCCIN_CPU0     I7 @S9S_MB_2U_LIB.S9S_MB_2U(SCH_1):PAGE36
  BV87 PVCCIN_CPU0 @S9S_MB_2U_LIB.S9S_MB_2U(SCH_1):PVCCIN_CPU0     I7 @S9S_MB_2U_LIB.S9S_MB_2U(SCH_1):PAGE36
  BV85 PVCCIN_CPU0 @S9S_MB_2U_LIB.S9S_MB_2U(SCH_1):PVCCIN_CPU0     I7 @S9S_MB_2U_LIB.S9S_MB_2U(SCH_1):PAGE36
  BV83 PVCCIN_CPU0 @S9S_MB_2U_LIB.S9S_MB_2U(SCH_1):PVCCIN_CPU0     I7 @S9S_MB_2U_LIB.S9S_MB_2U(SCH_1):PAGE36
  BV81 PVCCIN_CPU0 @S9S_MB_2U_LIB.S9S_MB_2U(SCH_1):PVCCIN_CPU0     I7 @S9S_MB_2U_LIB.S9S_MB_2U(SCH_1):PAGE36
  BV79 PVCCIN_CPU0 @S9S_MB_2U_LIB.S9S_MB_2U(SCH_1):PVCCIN_CPU0     I7 @S9S_MB_2U_LIB.S9S_MB_2U(SCH_1):PAGE36
  BV77 PVCCIN_CPU0 @S9S_MB_2U_LIB.S9S_MB_2U(SCH_1):PVCCIN_CPU0     I7 @S9S_MB_2U_LIB.S9S_MB_2U(SCH_1):PAGE36
  BV75 PVCCIN_CPU0 @S9S_MB_2U_LIB.S9S_MB_2U(SCH_1):PVCCIN_CPU0     I7 @S9S_MB_2U_LIB.S9S_MB_2U(SCH_1):PAGE36
  BV73 PVCCIN_CPU0 @S9S_MB_2U_LIB.S9S_MB_2U(SCH_1):PVCCIN_CPU0     I7 @S9S_MB_2U_LIB.S9S_MB_2U(SCH_1):PAGE36
  BV71 PVCCIN_CPU0 @S9S_MB_2U_LIB.S9S_MB_2U(SCH_1):PVCCIN_CPU0     I7 @S9S_MB_2U_LIB.S9S_MB_2U(SCH_1):PAGE36
  BV69 PVCCIN_CPU0 @S9S_MB_2U_LIB.S9S_MB_2U(SCH_1):PVCCIN_CPU0     I7 @S9S_MB_2U_LIB.S9S_MB_2U(SCH_1):PAGE36
  BV67 PVCCIN_CPU0 @S9S_MB_2U_LIB.S9S_MB_2U(SCH_1):PVCCIN_CPU0     I7 @S9S_MB_2U_LIB.S9S_MB_2U(SCH_1):PAGE36
  BV65 PVCCIN_CPU0 @S9S_MB_2U_LIB.S9S_MB_2U(SCH_1):PVCCIN_CPU0     I7 @S9S_MB_2U_LIB.S9S_MB_2U(SCH_1):PAGE36
  BV63 PVCCIN_CPU0 @S9S_MB_2U_LIB.S9S_MB_2U(SCH_1):PVCCIN_CPU0     I7 @S9S_MB_2U_LIB.S9S_MB_2U(SCH_1):PAGE36
  BV61 PVCCIN_CPU0 @S9S_MB_2U_LIB.S9S_MB_2U(SCH_1):PVCCIN_CPU0     I7 @S9S_MB_2U_LIB.S9S_MB_2U(SCH_1):PAGE36
  BV59 PVCCIN_CPU0 @S9S_MB_2U_LIB.S9S_MB_2U(SCH_1):PVCCIN_CPU0     I7 @S9S_MB_2U_LIB.S9S_MB_2U(SCH_1):PAGE36
  BV57 PVCCIN_CPU0 @S9S_MB_2U_LIB.S9S_MB_2U(SCH_1):PVCCIN_CPU0     I7 @S9S_MB_2U_LIB.S9S_MB_2U(SCH_1):PAGE36
  BV55 PVCCIN_CPU0 @S9S_MB_2U_LIB.S9S_MB_2U(SCH_1):PVCCIN_CPU0     I7 @S9S_MB_2U_LIB.S9S_MB_2U(SCH_1):PAGE36
  BV53 PVCCIN_CPU0 @S9S_MB_2U_LIB.S9S_MB_2U(SCH_1):PVCCIN_CPU0     I7 @S9S_MB_2U_LIB.S9S_MB_2U(SCH_1):PAGE36
  BV51 PVCCIN_CPU0 @S9S_MB_2U_LIB.S9S_MB_2U(SCH_1):PVCCIN_CPU0     I7 @S9S_MB_2U_LIB.S9S_MB_2U(SCH_1):PAGE36
  BV49 PVCCIN_CPU0 @S9S_MB_2U_LIB.S9S_MB_2U(SCH_1):PVCCIN_CPU0     I7 @S9S_MB_2U_LIB.S9S_MB_2U(SCH_1):PAGE36
  BV47 PVCCIN_CPU0 @S9S_MB_2U_LIB.S9S_MB_2U(SCH_1):PVCCIN_CPU0     I7 @S9S_MB_2U_LIB.S9S_MB_2U(SCH_1):PAGE36
  BV44 PVCCIN_CPU0 @S9S_MB_2U_LIB.S9S_MB_2U(SCH_1):PVCCIN_CPU0     I7 @S9S_MB_2U_LIB.S9S_MB_2U(SCH_1):PAGE36
  BV42 PVCCIN_CPU0 @S9S_MB_2U_LIB.S9S_MB_2U(SCH_1):PVCCIN_CPU0     I7 @S9S_MB_2U_LIB.S9S_MB_2U(SCH_1):PAGE36
  BV40 PVCCIN_CPU0 @S9S_MB_2U_LIB.S9S_MB_2U(SCH_1):PVCCIN_CPU0     I7 @S9S_MB_2U_LIB.S9S_MB_2U(SCH_1):PAGE36
  BV38 PVCCIN_CPU0 @S9S_MB_2U_LIB.S9S_MB_2U(SCH_1):PVCCIN_CPU0     I7 @S9S_MB_2U_LIB.S9S_MB_2U(SCH_1):PAGE36
  BV36 PVCCIN_CPU0 @S9S_MB_2U_LIB.S9S_MB_2U(SCH_1):PVCCIN_CPU0     I7 @S9S_MB_2U_LIB.S9S_MB_2U(SCH_1):PAGE36
  BV34 PVCCIN_CPU0 @S9S_MB_2U_LIB.S9S_MB_2U(SCH_1):PVCCIN_CPU0     I7 @S9S_MB_2U_LIB.S9S_MB_2U(SCH_1):PAGE36
  BV32 PVCCIN_CPU0 @S9S_MB_2U_LIB.S9S_MB_2U(SCH_1):PVCCIN_CPU0     I7 @S9S_MB_2U_LIB.S9S_MB_2U(SCH_1):PAGE36
  BU90 PVCCIN_CPU0 @S9S_MB_2U_LIB.S9S_MB_2U(SCH_1):PVCCIN_CPU0     I7 @S9S_MB_2U_LIB.S9S_MB_2U(SCH_1):PAGE36
  BU88 PVCCIN_CPU0 @S9S_MB_2U_LIB.S9S_MB_2U(SCH_1):PVCCIN_CPU0     I7 @S9S_MB_2U_LIB.S9S_MB_2U(SCH_1):PAGE36
  BU86 PVCCIN_CPU0 @S9S_MB_2U_LIB.S9S_MB_2U(SCH_1):PVCCIN_CPU0     I7 @S9S_MB_2U_LIB.S9S_MB_2U(SCH_1):PAGE36
  BU84 PVCCIN_CPU0 @S9S_MB_2U_LIB.S9S_MB_2U(SCH_1):PVCCIN_CPU0     I7 @S9S_MB_2U_LIB.S9S_MB_2U(SCH_1):PAGE36
  BU82 PVCCIN_CPU0 @S9S_MB_2U_LIB.S9S_MB_2U(SCH_1):PVCCIN_CPU0     I7 @S9S_MB_2U_LIB.S9S_MB_2U(SCH_1):PAGE36
  BU80 PVCCIN_CPU0 @S9S_MB_2U_LIB.S9S_MB_2U(SCH_1):PVCCIN_CPU0     I7 @S9S_MB_2U_LIB.S9S_MB_2U(SCH_1):PAGE36
  BU78 PVCCIN_CPU0 @S9S_MB_2U_LIB.S9S_MB_2U(SCH_1):PVCCIN_CPU0     I7 @S9S_MB_2U_LIB.S9S_MB_2U(SCH_1):PAGE36
  BU76 PVCCIN_CPU0 @S9S_MB_2U_LIB.S9S_MB_2U(SCH_1):PVCCIN_CPU0     I7 @S9S_MB_2U_LIB.S9S_MB_2U(SCH_1):PAGE36
  BU74 PVCCIN_CPU0 @S9S_MB_2U_LIB.S9S_MB_2U(SCH_1):PVCCIN_CPU0     I7 @S9S_MB_2U_LIB.S9S_MB_2U(SCH_1):PAGE36
  BU72 PVCCIN_CPU0 @S9S_MB_2U_LIB.S9S_MB_2U(SCH_1):PVCCIN_CPU0     I7 @S9S_MB_2U_LIB.S9S_MB_2U(SCH_1):PAGE36
  BU70 PVCCIN_CPU0 @S9S_MB_2U_LIB.S9S_MB_2U(SCH_1):PVCCIN_CPU0     I7 @S9S_MB_2U_LIB.S9S_MB_2U(SCH_1):PAGE36
  BU68 PVCCIN_CPU0 @S9S_MB_2U_LIB.S9S_MB_2U(SCH_1):PVCCIN_CPU0     I7 @S9S_MB_2U_LIB.S9S_MB_2U(SCH_1):PAGE36
  BU66 PVCCIN_CPU0 @S9S_MB_2U_LIB.S9S_MB_2U(SCH_1):PVCCIN_CPU0     I7 @S9S_MB_2U_LIB.S9S_MB_2U(SCH_1):PAGE36
  BU64 PVCCIN_CPU0 @S9S_MB_2U_LIB.S9S_MB_2U(SCH_1):PVCCIN_CPU0     I7 @S9S_MB_2U_LIB.S9S_MB_2U(SCH_1):PAGE36
  BU62 PVCCIN_CPU0 @S9S_MB_2U_LIB.S9S_MB_2U(SCH_1):PVCCIN_CPU0     I7 @S9S_MB_2U_LIB.S9S_MB_2U(SCH_1):PAGE36
  BU60 PVCCIN_CPU0 @S9S_MB_2U_LIB.S9S_MB_2U(SCH_1):PVCCIN_CPU0     I7 @S9S_MB_2U_LIB.S9S_MB_2U(SCH_1):PAGE36
  BU58 PVCCIN_CPU0 @S9S_MB_2U_LIB.S9S_MB_2U(SCH_1):PVCCIN_CPU0     I7 @S9S_MB_2U_LIB.S9S_MB_2U(SCH_1):PAGE36
  BU56 PVCCIN_CPU0 @S9S_MB_2U_LIB.S9S_MB_2U(SCH_1):PVCCIN_CPU0     I7 @S9S_MB_2U_LIB.S9S_MB_2U(SCH_1):PAGE36
  BU54 PVCCIN_CPU0 @S9S_MB_2U_LIB.S9S_MB_2U(SCH_1):PVCCIN_CPU0     I7 @S9S_MB_2U_LIB.S9S_MB_2U(SCH_1):PAGE36
  BU52 PVCCIN_CPU0 @S9S_MB_2U_LIB.S9S_MB_2U(SCH_1):PVCCIN_CPU0     I7 @S9S_MB_2U_LIB.S9S_MB_2U(SCH_1):PAGE36
  BU50 PVCCIN_CPU0 @S9S_MB_2U_LIB.S9S_MB_2U(SCH_1):PVCCIN_CPU0     I7 @S9S_MB_2U_LIB.S9S_MB_2U(SCH_1):PAGE36
  BU48 PVCCIN_CPU0 @S9S_MB_2U_LIB.S9S_MB_2U(SCH_1):PVCCIN_CPU0     I7 @S9S_MB_2U_LIB.S9S_MB_2U(SCH_1):PAGE36
  BU45 PVCCIN_CPU0 @S9S_MB_2U_LIB.S9S_MB_2U(SCH_1):PVCCIN_CPU0     I7 @S9S_MB_2U_LIB.S9S_MB_2U(SCH_1):PAGE36
  BU43 PVCCIN_CPU0 @S9S_MB_2U_LIB.S9S_MB_2U(SCH_1):PVCCIN_CPU0     I7 @S9S_MB_2U_LIB.S9S_MB_2U(SCH_1):PAGE36
  BU41 PVCCIN_CPU0 @S9S_MB_2U_LIB.S9S_MB_2U(SCH_1):PVCCIN_CPU0     I7 @S9S_MB_2U_LIB.S9S_MB_2U(SCH_1):PAGE36
  BU39 PVCCIN_CPU0 @S9S_MB_2U_LIB.S9S_MB_2U(SCH_1):PVCCIN_CPU0     I7 @S9S_MB_2U_LIB.S9S_MB_2U(SCH_1):PAGE36
  BU37 PVCCIN_CPU0 @S9S_MB_2U_LIB.S9S_MB_2U(SCH_1):PVCCIN_CPU0     I7 @S9S_MB_2U_LIB.S9S_MB_2U(SCH_1):PAGE36
  BU35 PVCCIN_CPU0 @S9S_MB_2U_LIB.S9S_MB_2U(SCH_1):PVCCIN_CPU0     I7 @S9S_MB_2U_LIB.S9S_MB_2U(SCH_1):PAGE36
  BU33 PVCCIN_CPU0 @S9S_MB_2U_LIB.S9S_MB_2U(SCH_1):PVCCIN_CPU0     I7 @S9S_MB_2U_LIB.S9S_MB_2U(SCH_1):PAGE36
  BT89 PVCCIN_CPU0 @S9S_MB_2U_LIB.S9S_MB_2U(SCH_1):PVCCIN_CPU0     I7 @S9S_MB_2U_LIB.S9S_MB_2U(SCH_1):PAGE36
  BT87 PVCCIN_CPU0 @S9S_MB_2U_LIB.S9S_MB_2U(SCH_1):PVCCIN_CPU0     I7 @S9S_MB_2U_LIB.S9S_MB_2U(SCH_1):PAGE36
  BT85 PVCCIN_CPU0 @S9S_MB_2U_LIB.S9S_MB_2U(SCH_1):PVCCIN_CPU0     I7 @S9S_MB_2U_LIB.S9S_MB_2U(SCH_1):PAGE36
  BT83 PVCCIN_CPU0 @S9S_MB_2U_LIB.S9S_MB_2U(SCH_1):PVCCIN_CPU0     I7 @S9S_MB_2U_LIB.S9S_MB_2U(SCH_1):PAGE36
  BT81 PVCCIN_CPU0 @S9S_MB_2U_LIB.S9S_MB_2U(SCH_1):PVCCIN_CPU0     I7 @S9S_MB_2U_LIB.S9S_MB_2U(SCH_1):PAGE36
  BT79 PVCCIN_CPU0 @S9S_MB_2U_LIB.S9S_MB_2U(SCH_1):PVCCIN_CPU0     I7 @S9S_MB_2U_LIB.S9S_MB_2U(SCH_1):PAGE36
  BT77 PVCCIN_CPU0 @S9S_MB_2U_LIB.S9S_MB_2U(SCH_1):PVCCIN_CPU0     I7 @S9S_MB_2U_LIB.S9S_MB_2U(SCH_1):PAGE36
  BT75 PVCCIN_CPU0 @S9S_MB_2U_LIB.S9S_MB_2U(SCH_1):PVCCIN_CPU0     I7 @S9S_MB_2U_LIB.S9S_MB_2U(SCH_1):PAGE36
  BT73 PVCCIN_CPU0 @S9S_MB_2U_LIB.S9S_MB_2U(SCH_1):PVCCIN_CPU0     I7 @S9S_MB_2U_LIB.S9S_MB_2U(SCH_1):PAGE36
  BT71 PVCCIN_CPU0 @S9S_MB_2U_LIB.S9S_MB_2U(SCH_1):PVCCIN_CPU0     I7 @S9S_MB_2U_LIB.S9S_MB_2U(SCH_1):PAGE36
  BT69 PVCCIN_CPU0 @S9S_MB_2U_LIB.S9S_MB_2U(SCH_1):PVCCIN_CPU0     I7 @S9S_MB_2U_LIB.S9S_MB_2U(SCH_1):PAGE36
  BT67 PVCCIN_CPU0 @S9S_MB_2U_LIB.S9S_MB_2U(SCH_1):PVCCIN_CPU0     I7 @S9S_MB_2U_LIB.S9S_MB_2U(SCH_1):PAGE36
  BT65 PVCCIN_CPU0 @S9S_MB_2U_LIB.S9S_MB_2U(SCH_1):PVCCIN_CPU0     I7 @S9S_MB_2U_LIB.S9S_MB_2U(SCH_1):PAGE36
  BT63 PVCCIN_CPU0 @S9S_MB_2U_LIB.S9S_MB_2U(SCH_1):PVCCIN_CPU0     I7 @S9S_MB_2U_LIB.S9S_MB_2U(SCH_1):PAGE36
  BT61 PVCCIN_CPU0 @S9S_MB_2U_LIB.S9S_MB_2U(SCH_1):PVCCIN_CPU0     I7 @S9S_MB_2U_LIB.S9S_MB_2U(SCH_1):PAGE36
  BT59 PVCCIN_CPU0 @S9S_MB_2U_LIB.S9S_MB_2U(SCH_1):PVCCIN_CPU0     I7 @S9S_MB_2U_LIB.S9S_MB_2U(SCH_1):PAGE36
  BT57 PVCCIN_CPU0 @S9S_MB_2U_LIB.S9S_MB_2U(SCH_1):PVCCIN_CPU0     I7 @S9S_MB_2U_LIB.S9S_MB_2U(SCH_1):PAGE36
  BT55 PVCCIN_CPU0 @S9S_MB_2U_LIB.S9S_MB_2U(SCH_1):PVCCIN_CPU0     I7 @S9S_MB_2U_LIB.S9S_MB_2U(SCH_1):PAGE36
  BT53 PVCCIN_CPU0 @S9S_MB_2U_LIB.S9S_MB_2U(SCH_1):PVCCIN_CPU0     I7 @S9S_MB_2U_LIB.S9S_MB_2U(SCH_1):PAGE36
  BT51 PVCCIN_CPU0 @S9S_MB_2U_LIB.S9S_MB_2U(SCH_1):PVCCIN_CPU0     I7 @S9S_MB_2U_LIB.S9S_MB_2U(SCH_1):PAGE36
  BT49 PVCCIN_CPU0 @S9S_MB_2U_LIB.S9S_MB_2U(SCH_1):PVCCIN_CPU0     I7 @S9S_MB_2U_LIB.S9S_MB_2U(SCH_1):PAGE36
  BT47 PVCCIN_CPU0 @S9S_MB_2U_LIB.S9S_MB_2U(SCH_1):PVCCIN_CPU0     I7 @S9S_MB_2U_LIB.S9S_MB_2U(SCH_1):PAGE36
  BT44 PVCCIN_CPU0 @S9S_MB_2U_LIB.S9S_MB_2U(SCH_1):PVCCIN_CPU0     I7 @S9S_MB_2U_LIB.S9S_MB_2U(SCH_1):PAGE36
  BT42 PVCCIN_CPU0 @S9S_MB_2U_LIB.S9S_MB_2U(SCH_1):PVCCIN_CPU0     I7 @S9S_MB_2U_LIB.S9S_MB_2U(SCH_1):PAGE36
  BT40 PVCCIN_CPU0 @S9S_MB_2U_LIB.S9S_MB_2U(SCH_1):PVCCIN_CPU0     I7 @S9S_MB_2U_LIB.S9S_MB_2U(SCH_1):PAGE36
  BT38 PVCCIN_CPU0 @S9S_MB_2U_LIB.S9S_MB_2U(SCH_1):PVCCIN_CPU0     I7 @S9S_MB_2U_LIB.S9S_MB_2U(SCH_1):PAGE36
  BT36 PVCCIN_CPU0 @S9S_MB_2U_LIB.S9S_MB_2U(SCH_1):PVCCIN_CPU0     I7 @S9S_MB_2U_LIB.S9S_MB_2U(SCH_1):PAGE36
  BT34 PVCCIN_CPU0 @S9S_MB_2U_LIB.S9S_MB_2U(SCH_1):PVCCIN_CPU0     I7 @S9S_MB_2U_LIB.S9S_MB_2U(SCH_1):PAGE36
  BT32 PVCCIN_CPU0 @S9S_MB_2U_LIB.S9S_MB_2U(SCH_1):PVCCIN_CPU0     I7 @S9S_MB_2U_LIB.S9S_MB_2U(SCH_1):PAGE36
  BR78 PVCCIN_CPU0 @S9S_MB_2U_LIB.S9S_MB_2U(SCH_1):PVCCIN_CPU0     I7 @S9S_MB_2U_LIB.S9S_MB_2U(SCH_1):PAGE36
  BR62 PVCCIN_CPU0 @S9S_MB_2U_LIB.S9S_MB_2U(SCH_1):PVCCIN_CPU0     I7 @S9S_MB_2U_LIB.S9S_MB_2U(SCH_1):PAGE36
  BR60 PVCCIN_CPU0 @S9S_MB_2U_LIB.S9S_MB_2U(SCH_1):PVCCIN_CPU0     I7 @S9S_MB_2U_LIB.S9S_MB_2U(SCH_1):PAGE36
  BP89 PVCCIN_CPU0 @S9S_MB_2U_LIB.S9S_MB_2U(SCH_1):PVCCIN_CPU0     I7 @S9S_MB_2U_LIB.S9S_MB_2U(SCH_1):PAGE36
  BP87 PVCCIN_CPU0 @S9S_MB_2U_LIB.S9S_MB_2U(SCH_1):PVCCIN_CPU0     I7 @S9S_MB_2U_LIB.S9S_MB_2U(SCH_1):PAGE36
  BP85 PVCCIN_CPU0 @S9S_MB_2U_LIB.S9S_MB_2U(SCH_1):PVCCIN_CPU0     I7 @S9S_MB_2U_LIB.S9S_MB_2U(SCH_1):PAGE36
  BP83 PVCCIN_CPU0 @S9S_MB_2U_LIB.S9S_MB_2U(SCH_1):PVCCIN_CPU0     I7 @S9S_MB_2U_LIB.S9S_MB_2U(SCH_1):PAGE36
  BP81 PVCCIN_CPU0 @S9S_MB_2U_LIB.S9S_MB_2U(SCH_1):PVCCIN_CPU0     I7 @S9S_MB_2U_LIB.S9S_MB_2U(SCH_1):PAGE36
  BP79 PVCCIN_CPU0 @S9S_MB_2U_LIB.S9S_MB_2U(SCH_1):PVCCIN_CPU0     I7 @S9S_MB_2U_LIB.S9S_MB_2U(SCH_1):PAGE36
  BP61 PVCCIN_CPU0 @S9S_MB_2U_LIB.S9S_MB_2U(SCH_1):PVCCIN_CPU0     I7 @S9S_MB_2U_LIB.S9S_MB_2U(SCH_1):PAGE36
  BP59 PVCCIN_CPU0 @S9S_MB_2U_LIB.S9S_MB_2U(SCH_1):PVCCIN_CPU0     I7 @S9S_MB_2U_LIB.S9S_MB_2U(SCH_1):PAGE36
  BP57 PVCCIN_CPU0 @S9S_MB_2U_LIB.S9S_MB_2U(SCH_1):PVCCIN_CPU0     I7 @S9S_MB_2U_LIB.S9S_MB_2U(SCH_1):PAGE36
  BP55 PVCCIN_CPU0 @S9S_MB_2U_LIB.S9S_MB_2U(SCH_1):PVCCIN_CPU0     I7 @S9S_MB_2U_LIB.S9S_MB_2U(SCH_1):PAGE36
  BP53 PVCCIN_CPU0 @S9S_MB_2U_LIB.S9S_MB_2U(SCH_1):PVCCIN_CPU0     I7 @S9S_MB_2U_LIB.S9S_MB_2U(SCH_1):PAGE36
  BP51 PVCCIN_CPU0 @S9S_MB_2U_LIB.S9S_MB_2U(SCH_1):PVCCIN_CPU0     I7 @S9S_MB_2U_LIB.S9S_MB_2U(SCH_1):PAGE36
  BP49 PVCCIN_CPU0 @S9S_MB_2U_LIB.S9S_MB_2U(SCH_1):PVCCIN_CPU0     I7 @S9S_MB_2U_LIB.S9S_MB_2U(SCH_1):PAGE36
  BP47 PVCCIN_CPU0 @S9S_MB_2U_LIB.S9S_MB_2U(SCH_1):PVCCIN_CPU0     I7 @S9S_MB_2U_LIB.S9S_MB_2U(SCH_1):PAGE36
  BP44 PVCCIN_CPU0 @S9S_MB_2U_LIB.S9S_MB_2U(SCH_1):PVCCIN_CPU0     I7 @S9S_MB_2U_LIB.S9S_MB_2U(SCH_1):PAGE36
  BP42 PVCCIN_CPU0 @S9S_MB_2U_LIB.S9S_MB_2U(SCH_1):PVCCIN_CPU0     I7 @S9S_MB_2U_LIB.S9S_MB_2U(SCH_1):PAGE36
  BP40 PVCCIN_CPU0 @S9S_MB_2U_LIB.S9S_MB_2U(SCH_1):PVCCIN_CPU0     I7 @S9S_MB_2U_LIB.S9S_MB_2U(SCH_1):PAGE36
  BP38 PVCCIN_CPU0 @S9S_MB_2U_LIB.S9S_MB_2U(SCH_1):PVCCIN_CPU0     I7 @S9S_MB_2U_LIB.S9S_MB_2U(SCH_1):PAGE36
  BP36 PVCCIN_CPU0 @S9S_MB_2U_LIB.S9S_MB_2U(SCH_1):PVCCIN_CPU0     I7 @S9S_MB_2U_LIB.S9S_MB_2U(SCH_1):PAGE36
  BP34 PVCCIN_CPU0 @S9S_MB_2U_LIB.S9S_MB_2U(SCH_1):PVCCIN_CPU0     I7 @S9S_MB_2U_LIB.S9S_MB_2U(SCH_1):PAGE36
  BP32 PVCCIN_CPU0 @S9S_MB_2U_LIB.S9S_MB_2U(SCH_1):PVCCIN_CPU0     I7 @S9S_MB_2U_LIB.S9S_MB_2U(SCH_1):PAGE36
  BN90 PVCCIN_CPU0 @S9S_MB_2U_LIB.S9S_MB_2U(SCH_1):PVCCIN_CPU0     I7 @S9S_MB_2U_LIB.S9S_MB_2U(SCH_1):PAGE36
  BN88 PVCCIN_CPU0 @S9S_MB_2U_LIB.S9S_MB_2U(SCH_1):PVCCIN_CPU0     I7 @S9S_MB_2U_LIB.S9S_MB_2U(SCH_1):PAGE36
  BN86 PVCCIN_CPU0 @S9S_MB_2U_LIB.S9S_MB_2U(SCH_1):PVCCIN_CPU0     I7 @S9S_MB_2U_LIB.S9S_MB_2U(SCH_1):PAGE36
  BN84 PVCCIN_CPU0 @S9S_MB_2U_LIB.S9S_MB_2U(SCH_1):PVCCIN_CPU0     I7 @S9S_MB_2U_LIB.S9S_MB_2U(SCH_1):PAGE36
  BN82 PVCCIN_CPU0 @S9S_MB_2U_LIB.S9S_MB_2U(SCH_1):PVCCIN_CPU0     I7 @S9S_MB_2U_LIB.S9S_MB_2U(SCH_1):PAGE36
  BN80 PVCCIN_CPU0 @S9S_MB_2U_LIB.S9S_MB_2U(SCH_1):PVCCIN_CPU0     I7 @S9S_MB_2U_LIB.S9S_MB_2U(SCH_1):PAGE36
  BN78 PVCCIN_CPU0 @S9S_MB_2U_LIB.S9S_MB_2U(SCH_1):PVCCIN_CPU0     I7 @S9S_MB_2U_LIB.S9S_MB_2U(SCH_1):PAGE36
  BN60 PVCCIN_CPU0 @S9S_MB_2U_LIB.S9S_MB_2U(SCH_1):PVCCIN_CPU0     I7 @S9S_MB_2U_LIB.S9S_MB_2U(SCH_1):PAGE36
  BN58 PVCCIN_CPU0 @S9S_MB_2U_LIB.S9S_MB_2U(SCH_1):PVCCIN_CPU0     I7 @S9S_MB_2U_LIB.S9S_MB_2U(SCH_1):PAGE36
  BN56 PVCCIN_CPU0 @S9S_MB_2U_LIB.S9S_MB_2U(SCH_1):PVCCIN_CPU0     I7 @S9S_MB_2U_LIB.S9S_MB_2U(SCH_1):PAGE36
  BN54 PVCCIN_CPU0 @S9S_MB_2U_LIB.S9S_MB_2U(SCH_1):PVCCIN_CPU0     I7 @S9S_MB_2U_LIB.S9S_MB_2U(SCH_1):PAGE36
  BN52 PVCCIN_CPU0 @S9S_MB_2U_LIB.S9S_MB_2U(SCH_1):PVCCIN_CPU0     I7 @S9S_MB_2U_LIB.S9S_MB_2U(SCH_1):PAGE36
  BN50 PVCCIN_CPU0 @S9S_MB_2U_LIB.S9S_MB_2U(SCH_1):PVCCIN_CPU0     I7 @S9S_MB_2U_LIB.S9S_MB_2U(SCH_1):PAGE36
  BN48 PVCCIN_CPU0 @S9S_MB_2U_LIB.S9S_MB_2U(SCH_1):PVCCIN_CPU0     I7 @S9S_MB_2U_LIB.S9S_MB_2U(SCH_1):PAGE36
  BN45 PVCCIN_CPU0 @S9S_MB_2U_LIB.S9S_MB_2U(SCH_1):PVCCIN_CPU0     I7 @S9S_MB_2U_LIB.S9S_MB_2U(SCH_1):PAGE36
  BN43 PVCCIN_CPU0 @S9S_MB_2U_LIB.S9S_MB_2U(SCH_1):PVCCIN_CPU0     I7 @S9S_MB_2U_LIB.S9S_MB_2U(SCH_1):PAGE36
  BN41 PVCCIN_CPU0 @S9S_MB_2U_LIB.S9S_MB_2U(SCH_1):PVCCIN_CPU0     I7 @S9S_MB_2U_LIB.S9S_MB_2U(SCH_1):PAGE37
  BN39 PVCCIN_CPU0 @S9S_MB_2U_LIB.S9S_MB_2U(SCH_1):PVCCIN_CPU0     I7 @S9S_MB_2U_LIB.S9S_MB_2U(SCH_1):PAGE37
  BN37 PVCCIN_CPU0 @S9S_MB_2U_LIB.S9S_MB_2U(SCH_1):PVCCIN_CPU0     I7 @S9S_MB_2U_LIB.S9S_MB_2U(SCH_1):PAGE37
  BN35 PVCCIN_CPU0 @S9S_MB_2U_LIB.S9S_MB_2U(SCH_1):PVCCIN_CPU0     I7 @S9S_MB_2U_LIB.S9S_MB_2U(SCH_1):PAGE37
  BN33 PVCCIN_CPU0 @S9S_MB_2U_LIB.S9S_MB_2U(SCH_1):PVCCIN_CPU0     I7 @S9S_MB_2U_LIB.S9S_MB_2U(SCH_1):PAGE37
  BM91 PVCCIN_CPU0 @S9S_MB_2U_LIB.S9S_MB_2U(SCH_1):PVCCIN_CPU0     I7 @S9S_MB_2U_LIB.S9S_MB_2U(SCH_1):PAGE37
  BM89 PVCCIN_CPU0 @S9S_MB_2U_LIB.S9S_MB_2U(SCH_1):PVCCIN_CPU0     I7 @S9S_MB_2U_LIB.S9S_MB_2U(SCH_1):PAGE37
  BM87 PVCCIN_CPU0 @S9S_MB_2U_LIB.S9S_MB_2U(SCH_1):PVCCIN_CPU0     I7 @S9S_MB_2U_LIB.S9S_MB_2U(SCH_1):PAGE37
  BM85 PVCCIN_CPU0 @S9S_MB_2U_LIB.S9S_MB_2U(SCH_1):PVCCIN_CPU0     I7 @S9S_MB_2U_LIB.S9S_MB_2U(SCH_1):PAGE37
  BM83 PVCCIN_CPU0 @S9S_MB_2U_LIB.S9S_MB_2U(SCH_1):PVCCIN_CPU0     I7 @S9S_MB_2U_LIB.S9S_MB_2U(SCH_1):PAGE37
  BM81 PVCCIN_CPU0 @S9S_MB_2U_LIB.S9S_MB_2U(SCH_1):PVCCIN_CPU0     I7 @S9S_MB_2U_LIB.S9S_MB_2U(SCH_1):PAGE37
  BM79 PVCCIN_CPU0 @S9S_MB_2U_LIB.S9S_MB_2U(SCH_1):PVCCIN_CPU0     I7 @S9S_MB_2U_LIB.S9S_MB_2U(SCH_1):PAGE37
  BL90 PVCCIN_CPU0 @S9S_MB_2U_LIB.S9S_MB_2U(SCH_1):PVCCIN_CPU0     I7 @S9S_MB_2U_LIB.S9S_MB_2U(SCH_1):PAGE37
  BL88 PVCCIN_CPU0 @S9S_MB_2U_LIB.S9S_MB_2U(SCH_1):PVCCIN_CPU0     I7 @S9S_MB_2U_LIB.S9S_MB_2U(SCH_1):PAGE37
  BL86 PVCCIN_CPU0 @S9S_MB_2U_LIB.S9S_MB_2U(SCH_1):PVCCIN_CPU0     I7 @S9S_MB_2U_LIB.S9S_MB_2U(SCH_1):PAGE37
  BL84 PVCCIN_CPU0 @S9S_MB_2U_LIB.S9S_MB_2U(SCH_1):PVCCIN_CPU0     I7 @S9S_MB_2U_LIB.S9S_MB_2U(SCH_1):PAGE37
  BL82 PVCCIN_CPU0 @S9S_MB_2U_LIB.S9S_MB_2U(SCH_1):PVCCIN_CPU0     I7 @S9S_MB_2U_LIB.S9S_MB_2U(SCH_1):PAGE37
  BL80 PVCCIN_CPU0 @S9S_MB_2U_LIB.S9S_MB_2U(SCH_1):PVCCIN_CPU0     I7 @S9S_MB_2U_LIB.S9S_MB_2U(SCH_1):PAGE37
  BK91 PVCCIN_CPU0 @S9S_MB_2U_LIB.S9S_MB_2U(SCH_1):PVCCIN_CPU0     I7 @S9S_MB_2U_LIB.S9S_MB_2U(SCH_1):PAGE37
  BK89 PVCCIN_CPU0 @S9S_MB_2U_LIB.S9S_MB_2U(SCH_1):PVCCIN_CPU0     I7 @S9S_MB_2U_LIB.S9S_MB_2U(SCH_1):PAGE37
  BK87 PVCCIN_CPU0 @S9S_MB_2U_LIB.S9S_MB_2U(SCH_1):PVCCIN_CPU0     I7 @S9S_MB_2U_LIB.S9S_MB_2U(SCH_1):PAGE37
  BK85 PVCCIN_CPU0 @S9S_MB_2U_LIB.S9S_MB_2U(SCH_1):PVCCIN_CPU0     I7 @S9S_MB_2U_LIB.S9S_MB_2U(SCH_1):PAGE37
  BK83 PVCCIN_CPU0 @S9S_MB_2U_LIB.S9S_MB_2U(SCH_1):PVCCIN_CPU0     I7 @S9S_MB_2U_LIB.S9S_MB_2U(SCH_1):PAGE37
  BK81 PVCCIN_CPU0 @S9S_MB_2U_LIB.S9S_MB_2U(SCH_1):PVCCIN_CPU0     I7 @S9S_MB_2U_LIB.S9S_MB_2U(SCH_1):PAGE37
  BH91 PVCCIN_CPU0 @S9S_MB_2U_LIB.S9S_MB_2U(SCH_1):PVCCIN_CPU0     I7 @S9S_MB_2U_LIB.S9S_MB_2U(SCH_1):PAGE37
  BH89 PVCCIN_CPU0 @S9S_MB_2U_LIB.S9S_MB_2U(SCH_1):PVCCIN_CPU0     I7 @S9S_MB_2U_LIB.S9S_MB_2U(SCH_1):PAGE37
  BH87 PVCCIN_CPU0 @S9S_MB_2U_LIB.S9S_MB_2U(SCH_1):PVCCIN_CPU0     I7 @S9S_MB_2U_LIB.S9S_MB_2U(SCH_1):PAGE37
  BH85 PVCCIN_CPU0 @S9S_MB_2U_LIB.S9S_MB_2U(SCH_1):PVCCIN_CPU0     I7 @S9S_MB_2U_LIB.S9S_MB_2U(SCH_1):PAGE37
  BG90 PVCCIN_CPU0 @S9S_MB_2U_LIB.S9S_MB_2U(SCH_1):PVCCIN_CPU0     I7 @S9S_MB_2U_LIB.S9S_MB_2U(SCH_1):PAGE37
  BG88 PVCCIN_CPU0 @S9S_MB_2U_LIB.S9S_MB_2U(SCH_1):PVCCIN_CPU0     I7 @S9S_MB_2U_LIB.S9S_MB_2U(SCH_1):PAGE37
  BG86 PVCCIN_CPU0 @S9S_MB_2U_LIB.S9S_MB_2U(SCH_1):PVCCIN_CPU0     I7 @S9S_MB_2U_LIB.S9S_MB_2U(SCH_1):PAGE37
  BG84 PVCCIN_CPU0 @S9S_MB_2U_LIB.S9S_MB_2U(SCH_1):PVCCIN_CPU0     I7 @S9S_MB_2U_LIB.S9S_MB_2U(SCH_1):PAGE37
  BF91 PVCCIN_CPU0 @S9S_MB_2U_LIB.S9S_MB_2U(SCH_1):PVCCIN_CPU0     I7 @S9S_MB_2U_LIB.S9S_MB_2U(SCH_1):PAGE37
  BF89 PVCCIN_CPU0 @S9S_MB_2U_LIB.S9S_MB_2U(SCH_1):PVCCIN_CPU0     I7 @S9S_MB_2U_LIB.S9S_MB_2U(SCH_1):PAGE37
  BF87 PVCCIN_CPU0 @S9S_MB_2U_LIB.S9S_MB_2U(SCH_1):PVCCIN_CPU0     I7 @S9S_MB_2U_LIB.S9S_MB_2U(SCH_1):PAGE37
  BF85 PVCCIN_CPU0 @S9S_MB_2U_LIB.S9S_MB_2U(SCH_1):PVCCIN_CPU0     I7 @S9S_MB_2U_LIB.S9S_MB_2U(SCH_1):PAGE37
  BE90 PVCCIN_CPU0 @S9S_MB_2U_LIB.S9S_MB_2U(SCH_1):PVCCIN_CPU0     I7 @S9S_MB_2U_LIB.S9S_MB_2U(SCH_1):PAGE37
  BE88 PVCCIN_CPU0 @S9S_MB_2U_LIB.S9S_MB_2U(SCH_1):PVCCIN_CPU0     I7 @S9S_MB_2U_LIB.S9S_MB_2U(SCH_1):PAGE37
  BE86 PVCCIN_CPU0 @S9S_MB_2U_LIB.S9S_MB_2U(SCH_1):PVCCIN_CPU0     I7 @S9S_MB_2U_LIB.S9S_MB_2U(SCH_1):PAGE37
  BD91 PVCCIN_CPU0 @S9S_MB_2U_LIB.S9S_MB_2U(SCH_1):PVCCIN_CPU0     I7 @S9S_MB_2U_LIB.S9S_MB_2U(SCH_1):PAGE37
  DA21 PVCCINFAON_CPU0 @S9S_MB_2U_LIB.S9S_MB_2U(SCH_1):PVCCINFAON_CPU0     I7 @S9S_MB_2U_LIB.S9S_MB_2U(SCH_1):PAGE37
  CW62 PVCCINFAON_CPU0 @S9S_MB_2U_LIB.S9S_MB_2U(SCH_1):PVCCINFAON_CPU0     I7 @S9S_MB_2U_LIB.S9S_MB_2U(SCH_1):PAGE37
  CV63 PVCCINFAON_CPU0 @S9S_MB_2U_LIB.S9S_MB_2U(SCH_1):PVCCINFAON_CPU0     I7 @S9S_MB_2U_LIB.S9S_MB_2U(SCH_1):PAGE37
  CV61 PVCCINFAON_CPU0 @S9S_MB_2U_LIB.S9S_MB_2U(SCH_1):PVCCINFAON_CPU0     I7 @S9S_MB_2U_LIB.S9S_MB_2U(SCH_1):PAGE37
  CT63 PVCCINFAON_CPU0 @S9S_MB_2U_LIB.S9S_MB_2U(SCH_1):PVCCINFAON_CPU0     I7 @S9S_MB_2U_LIB.S9S_MB_2U(SCH_1):PAGE37
  CP63 PVCCINFAON_CPU0 @S9S_MB_2U_LIB.S9S_MB_2U(SCH_1):PVCCINFAON_CPU0     I7 @S9S_MB_2U_LIB.S9S_MB_2U(SCH_1):PAGE37
  CN19 PVCCINFAON_CPU0 @S9S_MB_2U_LIB.S9S_MB_2U(SCH_1):PVCCINFAON_CPU0     I7 @S9S_MB_2U_LIB.S9S_MB_2U(SCH_1):PAGE37
  CJ19 PVCCINFAON_CPU0 @S9S_MB_2U_LIB.S9S_MB_2U(SCH_1):PVCCINFAON_CPU0     I7 @S9S_MB_2U_LIB.S9S_MB_2U(SCH_1):PAGE37
  CJ11 PVCCINFAON_CPU0 @S9S_MB_2U_LIB.S9S_MB_2U(SCH_1):PVCCINFAON_CPU0     I7 @S9S_MB_2U_LIB.S9S_MB_2U(SCH_1):PAGE37
  CE19 PVCCINFAON_CPU0 @S9S_MB_2U_LIB.S9S_MB_2U(SCH_1):PVCCINFAON_CPU0     I7 @S9S_MB_2U_LIB.S9S_MB_2U(SCH_1):PAGE37
  CA15 PVCCINFAON_CPU0 @S9S_MB_2U_LIB.S9S_MB_2U(SCH_1):PVCCINFAON_CPU0     I7 @S9S_MB_2U_LIB.S9S_MB_2U(SCH_1):PAGE37
  BN15 PVCCINFAON_CPU0 @S9S_MB_2U_LIB.S9S_MB_2U(SCH_1):PVCCINFAON_CPU0     I7 @S9S_MB_2U_LIB.S9S_MB_2U(SCH_1):PAGE37
  BK61 PVCCINFAON_CPU0 @S9S_MB_2U_LIB.S9S_MB_2U(SCH_1):PVCCINFAON_CPU0     I7 @S9S_MB_2U_LIB.S9S_MB_2U(SCH_1):PAGE37
  BJ60 PVCCINFAON_CPU0 @S9S_MB_2U_LIB.S9S_MB_2U(SCH_1):PVCCINFAON_CPU0     I7 @S9S_MB_2U_LIB.S9S_MB_2U(SCH_1):PAGE37
  BJ15 PVCCINFAON_CPU0 @S9S_MB_2U_LIB.S9S_MB_2U(SCH_1):PVCCINFAON_CPU0     I7 @S9S_MB_2U_LIB.S9S_MB_2U(SCH_1):PAGE37
  BG60 PVCCINFAON_CPU0 @S9S_MB_2U_LIB.S9S_MB_2U(SCH_1):PVCCINFAON_CPU0     I7 @S9S_MB_2U_LIB.S9S_MB_2U(SCH_1):PAGE37
  BE60 PVCCINFAON_CPU0 @S9S_MB_2U_LIB.S9S_MB_2U(SCH_1):PVCCINFAON_CPU0     I7 @S9S_MB_2U_LIB.S9S_MB_2U(SCH_1):PAGE37
  BE15 PVCCINFAON_CPU0 @S9S_MB_2U_LIB.S9S_MB_2U(SCH_1):PVCCINFAON_CPU0     I7 @S9S_MB_2U_LIB.S9S_MB_2U(SCH_1):PAGE37
  BC60 PVCCINFAON_CPU0 @S9S_MB_2U_LIB.S9S_MB_2U(SCH_1):PVCCINFAON_CPU0     I7 @S9S_MB_2U_LIB.S9S_MB_2U(SCH_1):PAGE37
  BA15 PVCCINFAON_CPU0 @S9S_MB_2U_LIB.S9S_MB_2U(SCH_1):PVCCINFAON_CPU0     I7 @S9S_MB_2U_LIB.S9S_MB_2U(SCH_1):PAGE37
  AY18 PVCCINFAON_CPU0 @S9S_MB_2U_LIB.S9S_MB_2U(SCH_1):PVCCINFAON_CPU0     I7 @S9S_MB_2U_LIB.S9S_MB_2U(SCH_1):PAGE37
  BC21 P3V3_AUX @S9S_MB_2U_LIB.S9S_MB_2U(SCH_1):P3V3_AUX     I8 @S9S_MB_2U_LIB.S9S_MB_2U(SCH_1):PAGE37
  BA21 P3V3_AUX @S9S_MB_2U_LIB.S9S_MB_2U(SCH_1):P3V3_AUX     I8 @S9S_MB_2U_LIB.S9S_MB_2U(SCH_1):PAGE37
  CY53 PVCCD_HV_CPU0 @S9S_MB_2U_LIB.S9S_MB_2U(SCH_1):PVCCD_HV_CPU0     I8 @S9S_MB_2U_LIB.S9S_MB_2U(SCH_1):PAGE37
  CY36 PVCCD_HV_CPU0 @S9S_MB_2U_LIB.S9S_MB_2U(SCH_1):PVCCD_HV_CPU0     I8 @S9S_MB_2U_LIB.S9S_MB_2U(SCH_1):PAGE37
  CW54 PVCCD_HV_CPU0 @S9S_MB_2U_LIB.S9S_MB_2U(SCH_1):PVCCD_HV_CPU0     I8 @S9S_MB_2U_LIB.S9S_MB_2U(SCH_1):PAGE37
  CY34 PVCCD_HV_CPU0 @S9S_MB_2U_LIB.S9S_MB_2U(SCH_1):PVCCD_HV_CPU0     I8 @S9S_MB_2U_LIB.S9S_MB_2U(SCH_1):PAGE37
  CW56 PVCCD_HV_CPU0 @S9S_MB_2U_LIB.S9S_MB_2U(SCH_1):PVCCD_HV_CPU0     I8 @S9S_MB_2U_LIB.S9S_MB_2U(SCH_1):PAGE37
  CW52 PVCCD_HV_CPU0 @S9S_MB_2U_LIB.S9S_MB_2U(SCH_1):PVCCD_HV_CPU0     I8 @S9S_MB_2U_LIB.S9S_MB_2U(SCH_1):PAGE37
  CW37 PVCCD_HV_CPU0 @S9S_MB_2U_LIB.S9S_MB_2U(SCH_1):PVCCD_HV_CPU0     I8 @S9S_MB_2U_LIB.S9S_MB_2U(SCH_1):PAGE37
  CW35 PVCCD_HV_CPU0 @S9S_MB_2U_LIB.S9S_MB_2U(SCH_1):PVCCD_HV_CPU0     I8 @S9S_MB_2U_LIB.S9S_MB_2U(SCH_1):PAGE37
   CE7 PVCCD_HV_CPU0 @S9S_MB_2U_LIB.S9S_MB_2U(SCH_1):PVCCD_HV_CPU0     I8 @S9S_MB_2U_LIB.S9S_MB_2U(SCH_1):PAGE37
   CA7 PVCCD_HV_CPU0 @S9S_MB_2U_LIB.S9S_MB_2U(SCH_1):PVCCD_HV_CPU0     I8 @S9S_MB_2U_LIB.S9S_MB_2U(SCH_1):PAGE37
   BN7 PVCCD_HV_CPU0 @S9S_MB_2U_LIB.S9S_MB_2U(SCH_1):PVCCD_HV_CPU0     I8 @S9S_MB_2U_LIB.S9S_MB_2U(SCH_1):PAGE37
   BJ7 PVCCD_HV_CPU0 @S9S_MB_2U_LIB.S9S_MB_2U(SCH_1):PVCCD_HV_CPU0     I8 @S9S_MB_2U_LIB.S9S_MB_2U(SCH_1):PAGE37
   BJ3 PVCCD_HV_CPU0 @S9S_MB_2U_LIB.S9S_MB_2U(SCH_1):PVCCD_HV_CPU0     I8 @S9S_MB_2U_LIB.S9S_MB_2U(SCH_1):PAGE37
  BJ11 PVCCD_HV_CPU0 @S9S_MB_2U_LIB.S9S_MB_2U(SCH_1):PVCCD_HV_CPU0     I8 @S9S_MB_2U_LIB.S9S_MB_2U(SCH_1):PAGE37
   BE7 PVCCD_HV_CPU0 @S9S_MB_2U_LIB.S9S_MB_2U(SCH_1):PVCCD_HV_CPU0     I8 @S9S_MB_2U_LIB.S9S_MB_2U(SCH_1):PAGE37
   BE3 PVCCD_HV_CPU0 @S9S_MB_2U_LIB.S9S_MB_2U(SCH_1):PVCCD_HV_CPU0     I8 @S9S_MB_2U_LIB.S9S_MB_2U(SCH_1):PAGE37
  BE11 PVCCD_HV_CPU0 @S9S_MB_2U_LIB.S9S_MB_2U(SCH_1):PVCCD_HV_CPU0     I8 @S9S_MB_2U_LIB.S9S_MB_2U(SCH_1):PAGE37
   BA7 PVCCD_HV_CPU0 @S9S_MB_2U_LIB.S9S_MB_2U(SCH_1):PVCCD_HV_CPU0     I8 @S9S_MB_2U_LIB.S9S_MB_2U(SCH_1):PAGE37
   BA3 PVCCD_HV_CPU0 @S9S_MB_2U_LIB.S9S_MB_2U(SCH_1):PVCCD_HV_CPU0     I8 @S9S_MB_2U_LIB.S9S_MB_2U(SCH_1):PAGE37
  AV55 PVCCD_HV_CPU0 @S9S_MB_2U_LIB.S9S_MB_2U(SCH_1):PVCCD_HV_CPU0     I8 @S9S_MB_2U_LIB.S9S_MB_2U(SCH_1):PAGE37
  AV53 PVCCD_HV_CPU0 @S9S_MB_2U_LIB.S9S_MB_2U(SCH_1):PVCCD_HV_CPU0     I8 @S9S_MB_2U_LIB.S9S_MB_2U(SCH_1):PAGE37
  AV36 PVCCD_HV_CPU0 @S9S_MB_2U_LIB.S9S_MB_2U(SCH_1):PVCCD_HV_CPU0     I8 @S9S_MB_2U_LIB.S9S_MB_2U(SCH_1):PAGE37
  AV34 PVCCD_HV_CPU0 @S9S_MB_2U_LIB.S9S_MB_2U(SCH_1):PVCCD_HV_CPU0     I8 @S9S_MB_2U_LIB.S9S_MB_2U(SCH_1):PAGE37
   AU7 PVCCD_HV_CPU0 @S9S_MB_2U_LIB.S9S_MB_2U(SCH_1):PVCCD_HV_CPU0     I8 @S9S_MB_2U_LIB.S9S_MB_2U(SCH_1):PAGE37
  AU54 PVCCD_HV_CPU0 @S9S_MB_2U_LIB.S9S_MB_2U(SCH_1):PVCCD_HV_CPU0     I8 @S9S_MB_2U_LIB.S9S_MB_2U(SCH_1):PAGE37
  AU35 PVCCD_HV_CPU0 @S9S_MB_2U_LIB.S9S_MB_2U(SCH_1):PVCCD_HV_CPU0     I8 @S9S_MB_2U_LIB.S9S_MB_2U(SCH_1):PAGE37
   AU3 PVCCD_HV_CPU0 @S9S_MB_2U_LIB.S9S_MB_2U(SCH_1):PVCCD_HV_CPU0     I8 @S9S_MB_2U_LIB.S9S_MB_2U(SCH_1):PAGE37
  AT55 PVCCD_HV_CPU0 @S9S_MB_2U_LIB.S9S_MB_2U(SCH_1):PVCCD_HV_CPU0     I8 @S9S_MB_2U_LIB.S9S_MB_2U(SCH_1):PAGE37
  AT36 PVCCD_HV_CPU0 @S9S_MB_2U_LIB.S9S_MB_2U(SCH_1):PVCCD_HV_CPU0     I8 @S9S_MB_2U_LIB.S9S_MB_2U(SCH_1):PAGE37
    N3 PVCCFA_EHV_CPU0 @S9S_MB_2U_LIB.S9S_MB_2U(SCH_1):PVCCFA_EHV_CPU0     I8 @S9S_MB_2U_LIB.S9S_MB_2U(SCH_1):PAGE37
    U3 PVCCFA_EHV_CPU0 @S9S_MB_2U_LIB.S9S_MB_2U(SCH_1):PVCCFA_EHV_CPU0     I8 @S9S_MB_2U_LIB.S9S_MB_2U(SCH_1):PAGE37
  AW60 PVCCFA_EHV_CPU0 @S9S_MB_2U_LIB.S9S_MB_2U(SCH_1):PVCCFA_EHV_CPU0     I8 @S9S_MB_2U_LIB.S9S_MB_2U(SCH_1):PAGE37
  AV61 PVCCFA_EHV_CPU0 @S9S_MB_2U_LIB.S9S_MB_2U(SCH_1):PVCCFA_EHV_CPU0     I8 @S9S_MB_2U_LIB.S9S_MB_2U(SCH_1):PAGE37
  AU60 PVCCFA_EHV_CPU0 @S9S_MB_2U_LIB.S9S_MB_2U(SCH_1):PVCCFA_EHV_CPU0     I8 @S9S_MB_2U_LIB.S9S_MB_2U(SCH_1):PAGE37
  AT61 PVCCFA_EHV_CPU0 @S9S_MB_2U_LIB.S9S_MB_2U(SCH_1):PVCCFA_EHV_CPU0     I8 @S9S_MB_2U_LIB.S9S_MB_2U(SCH_1):PAGE37
   AN3 PVCCFA_EHV_CPU0 @S9S_MB_2U_LIB.S9S_MB_2U(SCH_1):PVCCFA_EHV_CPU0     I8 @S9S_MB_2U_LIB.S9S_MB_2U(SCH_1):PAGE37
   AJ3 PVCCFA_EHV_CPU0 @S9S_MB_2U_LIB.S9S_MB_2U(SCH_1):PVCCFA_EHV_CPU0     I8 @S9S_MB_2U_LIB.S9S_MB_2U(SCH_1):PAGE37
   AE3 PVCCFA_EHV_CPU0 @S9S_MB_2U_LIB.S9S_MB_2U(SCH_1):PVCCFA_EHV_CPU0     I8 @S9S_MB_2U_LIB.S9S_MB_2U(SCH_1):PAGE37
   AA3 PVCCFA_EHV_CPU0 @S9S_MB_2U_LIB.S9S_MB_2U(SCH_1):PVCCFA_EHV_CPU0     I8 @S9S_MB_2U_LIB.S9S_MB_2U(SCH_1):PAGE37
  DJ11 PVCCINFAON_CPU0 @S9S_MB_2U_LIB.S9S_MB_2U(SCH_1):PVCCINFAON_CPU0     I8 @S9S_MB_2U_LIB.S9S_MB_2U(SCH_1):PAGE37
   DE7 PVCCINFAON_CPU0 @S9S_MB_2U_LIB.S9S_MB_2U(SCH_1):PVCCINFAON_CPU0     I8 @S9S_MB_2U_LIB.S9S_MB_2U(SCH_1):PAGE37
   DA7 PVCCINFAON_CPU0 @S9S_MB_2U_LIB.S9S_MB_2U(SCH_1):PVCCINFAON_CPU0     I8 @S9S_MB_2U_LIB.S9S_MB_2U(SCH_1):PAGE37
   DA3 PVCCINFAON_CPU0 @S9S_MB_2U_LIB.S9S_MB_2U(SCH_1):PVCCINFAON_CPU0     I8 @S9S_MB_2U_LIB.S9S_MB_2U(SCH_1):PAGE37
  CW64 PVCCINFAON_CPU0 @S9S_MB_2U_LIB.S9S_MB_2U(SCH_1):PVCCINFAON_CPU0     I8 @S9S_MB_2U_LIB.S9S_MB_2U(SCH_1):PAGE37
  CR66 PVCCINFAON_CPU0 @S9S_MB_2U_LIB.S9S_MB_2U(SCH_1):PVCCINFAON_CPU0     I8 @S9S_MB_2U_LIB.S9S_MB_2U(SCH_1):PAGE37
   DJ7 PVCCINFAON_CPU0 @S9S_MB_2U_LIB.S9S_MB_2U(SCH_1):PVCCINFAON_CPU0     I8 @S9S_MB_2U_LIB.S9S_MB_2U(SCH_1):PAGE37
   DJ3 PVCCINFAON_CPU0 @S9S_MB_2U_LIB.S9S_MB_2U(SCH_1):PVCCINFAON_CPU0     I8 @S9S_MB_2U_LIB.S9S_MB_2U(SCH_1):PAGE37
  DJ15 PVCCINFAON_CPU0 @S9S_MB_2U_LIB.S9S_MB_2U(SCH_1):PVCCINFAON_CPU0     I8 @S9S_MB_2U_LIB.S9S_MB_2U(SCH_1):PAGE37
   DE3 PVCCINFAON_CPU0 @S9S_MB_2U_LIB.S9S_MB_2U(SCH_1):PVCCINFAON_CPU0     I8 @S9S_MB_2U_LIB.S9S_MB_2U(SCH_1):PAGE37
  DE15 PVCCINFAON_CPU0 @S9S_MB_2U_LIB.S9S_MB_2U(SCH_1):PVCCINFAON_CPU0     I8 @S9S_MB_2U_LIB.S9S_MB_2U(SCH_1):PAGE37
  DE11 PVCCINFAON_CPU0 @S9S_MB_2U_LIB.S9S_MB_2U(SCH_1):PVCCINFAON_CPU0     I8 @S9S_MB_2U_LIB.S9S_MB_2U(SCH_1):PAGE37
  DA64 PVCCINFAON_CPU0 @S9S_MB_2U_LIB.S9S_MB_2U(SCH_1):PVCCINFAON_CPU0     I8 @S9S_MB_2U_LIB.S9S_MB_2U(SCH_1):PAGE37
  DA15 PVCCINFAON_CPU0 @S9S_MB_2U_LIB.S9S_MB_2U(SCH_1):PVCCINFAON_CPU0     I8 @S9S_MB_2U_LIB.S9S_MB_2U(SCH_1):PAGE37
  DA11 PVCCINFAON_CPU0 @S9S_MB_2U_LIB.S9S_MB_2U(SCH_1):PVCCINFAON_CPU0     I8 @S9S_MB_2U_LIB.S9S_MB_2U(SCH_1):PAGE37
  CY67 PVCCINFAON_CPU0 @S9S_MB_2U_LIB.S9S_MB_2U(SCH_1):PVCCINFAON_CPU0     I8 @S9S_MB_2U_LIB.S9S_MB_2U(SCH_1):PAGE37
  CY65 PVCCINFAON_CPU0 @S9S_MB_2U_LIB.S9S_MB_2U(SCH_1):PVCCINFAON_CPU0     I8 @S9S_MB_2U_LIB.S9S_MB_2U(SCH_1):PAGE37
  CW66 PVCCINFAON_CPU0 @S9S_MB_2U_LIB.S9S_MB_2U(SCH_1):PVCCINFAON_CPU0     I8 @S9S_MB_2U_LIB.S9S_MB_2U(SCH_1):PAGE37
  CV67 PVCCINFAON_CPU0 @S9S_MB_2U_LIB.S9S_MB_2U(SCH_1):PVCCINFAON_CPU0     I8 @S9S_MB_2U_LIB.S9S_MB_2U(SCH_1):PAGE37
  CV65 PVCCINFAON_CPU0 @S9S_MB_2U_LIB.S9S_MB_2U(SCH_1):PVCCINFAON_CPU0     I8 @S9S_MB_2U_LIB.S9S_MB_2U(SCH_1):PAGE37
   CU7 PVCCINFAON_CPU0 @S9S_MB_2U_LIB.S9S_MB_2U(SCH_1):PVCCINFAON_CPU0     I8 @S9S_MB_2U_LIB.S9S_MB_2U(SCH_1):PAGE37
  CU64 PVCCINFAON_CPU0 @S9S_MB_2U_LIB.S9S_MB_2U(SCH_1):PVCCINFAON_CPU0     I8 @S9S_MB_2U_LIB.S9S_MB_2U(SCH_1):PAGE37
   CU3 PVCCINFAON_CPU0 @S9S_MB_2U_LIB.S9S_MB_2U(SCH_1):PVCCINFAON_CPU0     I8 @S9S_MB_2U_LIB.S9S_MB_2U(SCH_1):PAGE37
  CU15 PVCCINFAON_CPU0 @S9S_MB_2U_LIB.S9S_MB_2U(SCH_1):PVCCINFAON_CPU0     I8 @S9S_MB_2U_LIB.S9S_MB_2U(SCH_1):PAGE37
  CU11 PVCCINFAON_CPU0 @S9S_MB_2U_LIB.S9S_MB_2U(SCH_1):PVCCINFAON_CPU0     I8 @S9S_MB_2U_LIB.S9S_MB_2U(SCH_1):PAGE37
  CT67 PVCCINFAON_CPU0 @S9S_MB_2U_LIB.S9S_MB_2U(SCH_1):PVCCINFAON_CPU0     I8 @S9S_MB_2U_LIB.S9S_MB_2U(SCH_1):PAGE37
  CT65 PVCCINFAON_CPU0 @S9S_MB_2U_LIB.S9S_MB_2U(SCH_1):PVCCINFAON_CPU0     I8 @S9S_MB_2U_LIB.S9S_MB_2U(SCH_1):PAGE37
  CP67 PVCCINFAON_CPU0 @S9S_MB_2U_LIB.S9S_MB_2U(SCH_1):PVCCINFAON_CPU0     I8 @S9S_MB_2U_LIB.S9S_MB_2U(SCH_1):PAGE37
  CP65 PVCCINFAON_CPU0 @S9S_MB_2U_LIB.S9S_MB_2U(SCH_1):PVCCINFAON_CPU0     I8 @S9S_MB_2U_LIB.S9S_MB_2U(SCH_1):PAGE37
   CN7 PVCCINFAON_CPU0 @S9S_MB_2U_LIB.S9S_MB_2U(SCH_1):PVCCINFAON_CPU0     I8 @S9S_MB_2U_LIB.S9S_MB_2U(SCH_1):PAGE37
  CN66 PVCCINFAON_CPU0 @S9S_MB_2U_LIB.S9S_MB_2U(SCH_1):PVCCINFAON_CPU0     I8 @S9S_MB_2U_LIB.S9S_MB_2U(SCH_1):PAGE37
  CN64 PVCCINFAON_CPU0 @S9S_MB_2U_LIB.S9S_MB_2U(SCH_1):PVCCINFAON_CPU0     I8 @S9S_MB_2U_LIB.S9S_MB_2U(SCH_1):PAGE37
   CN3 PVCCINFAON_CPU0 @S9S_MB_2U_LIB.S9S_MB_2U(SCH_1):PVCCINFAON_CPU0     I8 @S9S_MB_2U_LIB.S9S_MB_2U(SCH_1):PAGE37
  CN15 PVCCINFAON_CPU0 @S9S_MB_2U_LIB.S9S_MB_2U(SCH_1):PVCCINFAON_CPU0     I8 @S9S_MB_2U_LIB.S9S_MB_2U(SCH_1):PAGE37
  CN11 PVCCINFAON_CPU0 @S9S_MB_2U_LIB.S9S_MB_2U(SCH_1):PVCCINFAON_CPU0     I8 @S9S_MB_2U_LIB.S9S_MB_2U(SCH_1):PAGE37
   CJ7 PVCCINFAON_CPU0 @S9S_MB_2U_LIB.S9S_MB_2U(SCH_1):PVCCINFAON_CPU0     I8 @S9S_MB_2U_LIB.S9S_MB_2U(SCH_1):PAGE37
   CJ3 PVCCINFAON_CPU0 @S9S_MB_2U_LIB.S9S_MB_2U(SCH_1):PVCCINFAON_CPU0     I8 @S9S_MB_2U_LIB.S9S_MB_2U(SCH_1):PAGE37
  CJ15 PVCCINFAON_CPU0 @S9S_MB_2U_LIB.S9S_MB_2U(SCH_1):PVCCINFAON_CPU0     I8 @S9S_MB_2U_LIB.S9S_MB_2U(SCH_1):PAGE37
  CE15 PVCCINFAON_CPU0 @S9S_MB_2U_LIB.S9S_MB_2U(SCH_1):PVCCINFAON_CPU0     I8 @S9S_MB_2U_LIB.S9S_MB_2U(SCH_1):PAGE37
  BN19 PVNN_MAIN_CPU0 @S9S_MB_2U_LIB.S9S_MB_2U(SCH_1):PVNN_MAIN_CPU0     I8 @S9S_MB_2U_LIB.S9S_MB_2U(SCH_1):PAGE37
  BJ19 PVNN_MAIN_CPU0 @S9S_MB_2U_LIB.S9S_MB_2U(SCH_1):PVNN_MAIN_CPU0     I8 @S9S_MB_2U_LIB.S9S_MB_2U(SCH_1):PAGE37
  BE19 PVNN_MAIN_CPU0 @S9S_MB_2U_LIB.S9S_MB_2U(SCH_1):PVNN_MAIN_CPU0     I8 @S9S_MB_2U_LIB.S9S_MB_2U(SCH_1):PAGE37
  BA19 PVNN_MAIN_CPU0 @S9S_MB_2U_LIB.S9S_MB_2U(SCH_1):PVNN_MAIN_CPU0     I8 @S9S_MB_2U_LIB.S9S_MB_2U(SCH_1):PAGE37
  CG68 PVPP_HBM_CPU0 @S9S_MB_2U_LIB.S9S_MB_2U(SCH_1):PVPP_HBM_CPU0     I8 @S9S_MB_2U_LIB.S9S_MB_2U(SCH_1):PAGE37
  CF67 PVPP_HBM_CPU0 @S9S_MB_2U_LIB.S9S_MB_2U(SCH_1):PVPP_HBM_CPU0     I8 @S9S_MB_2U_LIB.S9S_MB_2U(SCH_1):PAGE37
  CE68 PVPP_HBM_CPU0 @S9S_MB_2U_LIB.S9S_MB_2U(SCH_1):PVPP_HBM_CPU0     I8 @S9S_MB_2U_LIB.S9S_MB_2U(SCH_1):PAGE37
  CD67 PVPP_HBM_CPU0 @S9S_MB_2U_LIB.S9S_MB_2U(SCH_1):PVPP_HBM_CPU0     I8 @S9S_MB_2U_LIB.S9S_MB_2U(SCH_1):PAGE37
  CC68 PVPP_HBM_CPU0 @S9S_MB_2U_LIB.S9S_MB_2U(SCH_1):PVPP_HBM_CPU0     I8 @S9S_MB_2U_LIB.S9S_MB_2U(SCH_1):PAGE37
   Y89 PVCCFA_EHV_FIVRA_CPU0 @S9S_MB_2U_LIB.S9S_MB_2U(SCH_1):PVCCFA_EHV_FIVRA_CPU0     I4 @S9S_MB_2U_LIB.S9S_MB_2U(SCH_1):PAGE38
   Y85 PVCCFA_EHV_FIVRA_CPU0 @S9S_MB_2U_LIB.S9S_MB_2U(SCH_1):PVCCFA_EHV_FIVRA_CPU0     I4 @S9S_MB_2U_LIB.S9S_MB_2U(SCH_1):PAGE38
   Y79 PVCCFA_EHV_FIVRA_CPU0 @S9S_MB_2U_LIB.S9S_MB_2U(SCH_1):PVCCFA_EHV_FIVRA_CPU0     I4 @S9S_MB_2U_LIB.S9S_MB_2U(SCH_1):PAGE38
   W80 PVCCFA_EHV_FIVRA_CPU0 @S9S_MB_2U_LIB.S9S_MB_2U(SCH_1):PVCCFA_EHV_FIVRA_CPU0     I4 @S9S_MB_2U_LIB.S9S_MB_2U(SCH_1):PAGE38
    U7 PVCCFA_EHV_FIVRA_CPU0 @S9S_MB_2U_LIB.S9S_MB_2U(SCH_1):PVCCFA_EHV_FIVRA_CPU0     I4 @S9S_MB_2U_LIB.S9S_MB_2U(SCH_1):PAGE38
   U15 PVCCFA_EHV_FIVRA_CPU0 @S9S_MB_2U_LIB.S9S_MB_2U(SCH_1):PVCCFA_EHV_FIVRA_CPU0     I4 @S9S_MB_2U_LIB.S9S_MB_2U(SCH_1):PAGE38
   U11 PVCCFA_EHV_FIVRA_CPU0 @S9S_MB_2U_LIB.S9S_MB_2U(SCH_1):PVCCFA_EHV_FIVRA_CPU0     I4 @S9S_MB_2U_LIB.S9S_MB_2U(SCH_1):PAGE38
   T89 PVCCFA_EHV_FIVRA_CPU0 @S9S_MB_2U_LIB.S9S_MB_2U(SCH_1):PVCCFA_EHV_FIVRA_CPU0     I4 @S9S_MB_2U_LIB.S9S_MB_2U(SCH_1):PAGE38
   T85 PVCCFA_EHV_FIVRA_CPU0 @S9S_MB_2U_LIB.S9S_MB_2U(SCH_1):PVCCFA_EHV_FIVRA_CPU0     I4 @S9S_MB_2U_LIB.S9S_MB_2U(SCH_1):PAGE38
   R80 PVCCFA_EHV_FIVRA_CPU0 @S9S_MB_2U_LIB.S9S_MB_2U(SCH_1):PVCCFA_EHV_FIVRA_CPU0     I4 @S9S_MB_2U_LIB.S9S_MB_2U(SCH_1):PAGE38
   P79 PVCCFA_EHV_FIVRA_CPU0 @S9S_MB_2U_LIB.S9S_MB_2U(SCH_1):PVCCFA_EHV_FIVRA_CPU0     I4 @S9S_MB_2U_LIB.S9S_MB_2U(SCH_1):PAGE38
    N7 PVCCFA_EHV_FIVRA_CPU0 @S9S_MB_2U_LIB.S9S_MB_2U(SCH_1):PVCCFA_EHV_FIVRA_CPU0     I4 @S9S_MB_2U_LIB.S9S_MB_2U(SCH_1):PAGE38
   N11 PVCCFA_EHV_FIVRA_CPU0 @S9S_MB_2U_LIB.S9S_MB_2U(SCH_1):PVCCFA_EHV_FIVRA_CPU0     I4 @S9S_MB_2U_LIB.S9S_MB_2U(SCH_1):PAGE38
   M89 PVCCFA_EHV_FIVRA_CPU0 @S9S_MB_2U_LIB.S9S_MB_2U(SCH_1):PVCCFA_EHV_FIVRA_CPU0     I4 @S9S_MB_2U_LIB.S9S_MB_2U(SCH_1):PAGE38
   M85 PVCCFA_EHV_FIVRA_CPU0 @S9S_MB_2U_LIB.S9S_MB_2U(SCH_1):PVCCFA_EHV_FIVRA_CPU0     I4 @S9S_MB_2U_LIB.S9S_MB_2U(SCH_1):PAGE38
   L84 PVCCFA_EHV_FIVRA_CPU0 @S9S_MB_2U_LIB.S9S_MB_2U(SCH_1):PVCCFA_EHV_FIVRA_CPU0     I4 @S9S_MB_2U_LIB.S9S_MB_2U(SCH_1):PAGE38
   K87 PVCCFA_EHV_FIVRA_CPU0 @S9S_MB_2U_LIB.S9S_MB_2U(SCH_1):PVCCFA_EHV_FIVRA_CPU0     I4 @S9S_MB_2U_LIB.S9S_MB_2U(SCH_1):PAGE38
   J80 PVCCFA_EHV_FIVRA_CPU0 @S9S_MB_2U_LIB.S9S_MB_2U(SCH_1):PVCCFA_EHV_FIVRA_CPU0     I4 @S9S_MB_2U_LIB.S9S_MB_2U(SCH_1):PAGE38
    J7 PVCCFA_EHV_FIVRA_CPU0 @S9S_MB_2U_LIB.S9S_MB_2U(SCH_1):PVCCFA_EHV_FIVRA_CPU0     I4 @S9S_MB_2U_LIB.S9S_MB_2U(SCH_1):PAGE38
   J11 PVCCFA_EHV_FIVRA_CPU0 @S9S_MB_2U_LIB.S9S_MB_2U(SCH_1):PVCCFA_EHV_FIVRA_CPU0     I4 @S9S_MB_2U_LIB.S9S_MB_2U(SCH_1):PAGE38
   H89 PVCCFA_EHV_FIVRA_CPU0 @S9S_MB_2U_LIB.S9S_MB_2U(SCH_1):PVCCFA_EHV_FIVRA_CPU0     I4 @S9S_MB_2U_LIB.S9S_MB_2U(SCH_1):PAGE38
  EN84 PVCCFA_EHV_FIVRA_CPU0 @S9S_MB_2U_LIB.S9S_MB_2U(SCH_1):PVCCFA_EHV_FIVRA_CPU0     I4 @S9S_MB_2U_LIB.S9S_MB_2U(SCH_1):PAGE38
  EJ84 PVCCFA_EHV_FIVRA_CPU0 @S9S_MB_2U_LIB.S9S_MB_2U(SCH_1):PVCCFA_EHV_FIVRA_CPU0     I4 @S9S_MB_2U_LIB.S9S_MB_2U(SCH_1):PAGE38
  EJ15 PVCCFA_EHV_FIVRA_CPU0 @S9S_MB_2U_LIB.S9S_MB_2U(SCH_1):PVCCFA_EHV_FIVRA_CPU0     I4 @S9S_MB_2U_LIB.S9S_MB_2U(SCH_1):PAGE38
  EG80 PVCCFA_EHV_FIVRA_CPU0 @S9S_MB_2U_LIB.S9S_MB_2U(SCH_1):PVCCFA_EHV_FIVRA_CPU0     I4 @S9S_MB_2U_LIB.S9S_MB_2U(SCH_1):PAGE38
  EF79 PVCCFA_EHV_FIVRA_CPU0 @S9S_MB_2U_LIB.S9S_MB_2U(SCH_1):PVCCFA_EHV_FIVRA_CPU0     I4 @S9S_MB_2U_LIB.S9S_MB_2U(SCH_1):PAGE38
  EE84 PVCCFA_EHV_FIVRA_CPU0 @S9S_MB_2U_LIB.S9S_MB_2U(SCH_1):PVCCFA_EHV_FIVRA_CPU0     I4 @S9S_MB_2U_LIB.S9S_MB_2U(SCH_1):PAGE38
   EE7 PVCCFA_EHV_FIVRA_CPU0 @S9S_MB_2U_LIB.S9S_MB_2U(SCH_1):PVCCFA_EHV_FIVRA_CPU0     I4 @S9S_MB_2U_LIB.S9S_MB_2U(SCH_1):PAGE38
  EE15 PVCCFA_EHV_FIVRA_CPU0 @S9S_MB_2U_LIB.S9S_MB_2U(SCH_1):PVCCFA_EHV_FIVRA_CPU0     I4 @S9S_MB_2U_LIB.S9S_MB_2U(SCH_1):PAGE38
  EE11 PVCCFA_EHV_FIVRA_CPU0 @S9S_MB_2U_LIB.S9S_MB_2U(SCH_1):PVCCFA_EHV_FIVRA_CPU0     I4 @S9S_MB_2U_LIB.S9S_MB_2U(SCH_1):PAGE38
  ED89 PVCCFA_EHV_FIVRA_CPU0 @S9S_MB_2U_LIB.S9S_MB_2U(SCH_1):PVCCFA_EHV_FIVRA_CPU0     I4 @S9S_MB_2U_LIB.S9S_MB_2U(SCH_1):PAGE38
  ED85 PVCCFA_EHV_FIVRA_CPU0 @S9S_MB_2U_LIB.S9S_MB_2U(SCH_1):PVCCFA_EHV_FIVRA_CPU0     I4 @S9S_MB_2U_LIB.S9S_MB_2U(SCH_1):PAGE38
  ED79 PVCCFA_EHV_FIVRA_CPU0 @S9S_MB_2U_LIB.S9S_MB_2U(SCH_1):PVCCFA_EHV_FIVRA_CPU0     I4 @S9S_MB_2U_LIB.S9S_MB_2U(SCH_1):PAGE38
  EC78 PVCCFA_EHV_FIVRA_CPU0 @S9S_MB_2U_LIB.S9S_MB_2U(SCH_1):PVCCFA_EHV_FIVRA_CPU0     I4 @S9S_MB_2U_LIB.S9S_MB_2U(SCH_1):PAGE38
   EA7 PVCCFA_EHV_FIVRA_CPU0 @S9S_MB_2U_LIB.S9S_MB_2U(SCH_1):PVCCFA_EHV_FIVRA_CPU0     I4 @S9S_MB_2U_LIB.S9S_MB_2U(SCH_1):PAGE38
   EA3 PVCCFA_EHV_FIVRA_CPU0 @S9S_MB_2U_LIB.S9S_MB_2U(SCH_1):PVCCFA_EHV_FIVRA_CPU0     I4 @S9S_MB_2U_LIB.S9S_MB_2U(SCH_1):PAGE38
  EA15 PVCCFA_EHV_FIVRA_CPU0 @S9S_MB_2U_LIB.S9S_MB_2U(SCH_1):PVCCFA_EHV_FIVRA_CPU0     I4 @S9S_MB_2U_LIB.S9S_MB_2U(SCH_1):PAGE38
  EA11 PVCCFA_EHV_FIVRA_CPU0 @S9S_MB_2U_LIB.S9S_MB_2U(SCH_1):PVCCFA_EHV_FIVRA_CPU0     I4 @S9S_MB_2U_LIB.S9S_MB_2U(SCH_1):PAGE38
  DY89 PVCCFA_EHV_FIVRA_CPU0 @S9S_MB_2U_LIB.S9S_MB_2U(SCH_1):PVCCFA_EHV_FIVRA_CPU0     I4 @S9S_MB_2U_LIB.S9S_MB_2U(SCH_1):PAGE38
  DY85 PVCCFA_EHV_FIVRA_CPU0 @S9S_MB_2U_LIB.S9S_MB_2U(SCH_1):PVCCFA_EHV_FIVRA_CPU0     I4 @S9S_MB_2U_LIB.S9S_MB_2U(SCH_1):PAGE38
   DU7 PVCCFA_EHV_FIVRA_CPU0 @S9S_MB_2U_LIB.S9S_MB_2U(SCH_1):PVCCFA_EHV_FIVRA_CPU0     I4 @S9S_MB_2U_LIB.S9S_MB_2U(SCH_1):PAGE38
   DU3 PVCCFA_EHV_FIVRA_CPU0 @S9S_MB_2U_LIB.S9S_MB_2U(SCH_1):PVCCFA_EHV_FIVRA_CPU0     I4 @S9S_MB_2U_LIB.S9S_MB_2U(SCH_1):PAGE38
  DU15 PVCCFA_EHV_FIVRA_CPU0 @S9S_MB_2U_LIB.S9S_MB_2U(SCH_1):PVCCFA_EHV_FIVRA_CPU0     I4 @S9S_MB_2U_LIB.S9S_MB_2U(SCH_1):PAGE38
  DU11 PVCCFA_EHV_FIVRA_CPU0 @S9S_MB_2U_LIB.S9S_MB_2U(SCH_1):PVCCFA_EHV_FIVRA_CPU0     I4 @S9S_MB_2U_LIB.S9S_MB_2U(SCH_1):PAGE38
  DT89 PVCCFA_EHV_FIVRA_CPU0 @S9S_MB_2U_LIB.S9S_MB_2U(SCH_1):PVCCFA_EHV_FIVRA_CPU0     I4 @S9S_MB_2U_LIB.S9S_MB_2U(SCH_1):PAGE38
  DT85 PVCCFA_EHV_FIVRA_CPU0 @S9S_MB_2U_LIB.S9S_MB_2U(SCH_1):PVCCFA_EHV_FIVRA_CPU0     I4 @S9S_MB_2U_LIB.S9S_MB_2U(SCH_1):PAGE38
  DT79 PVCCFA_EHV_FIVRA_CPU0 @S9S_MB_2U_LIB.S9S_MB_2U(SCH_1):PVCCFA_EHV_FIVRA_CPU0     I4 @S9S_MB_2U_LIB.S9S_MB_2U(SCH_1):PAGE38
   DN7 PVCCFA_EHV_FIVRA_CPU0 @S9S_MB_2U_LIB.S9S_MB_2U(SCH_1):PVCCFA_EHV_FIVRA_CPU0     I4 @S9S_MB_2U_LIB.S9S_MB_2U(SCH_1):PAGE38
   DN3 PVCCFA_EHV_FIVRA_CPU0 @S9S_MB_2U_LIB.S9S_MB_2U(SCH_1):PVCCFA_EHV_FIVRA_CPU0     I4 @S9S_MB_2U_LIB.S9S_MB_2U(SCH_1):PAGE38
  DN15 PVCCFA_EHV_FIVRA_CPU0 @S9S_MB_2U_LIB.S9S_MB_2U(SCH_1):PVCCFA_EHV_FIVRA_CPU0     I4 @S9S_MB_2U_LIB.S9S_MB_2U(SCH_1):PAGE38
  DN11 PVCCFA_EHV_FIVRA_CPU0 @S9S_MB_2U_LIB.S9S_MB_2U(SCH_1):PVCCFA_EHV_FIVRA_CPU0     I4 @S9S_MB_2U_LIB.S9S_MB_2U(SCH_1):PAGE38
  DM89 PVCCFA_EHV_FIVRA_CPU0 @S9S_MB_2U_LIB.S9S_MB_2U(SCH_1):PVCCFA_EHV_FIVRA_CPU0     I4 @S9S_MB_2U_LIB.S9S_MB_2U(SCH_1):PAGE38
  DM85 PVCCFA_EHV_FIVRA_CPU0 @S9S_MB_2U_LIB.S9S_MB_2U(SCH_1):PVCCFA_EHV_FIVRA_CPU0     I4 @S9S_MB_2U_LIB.S9S_MB_2U(SCH_1):PAGE38
  DM83 PVCCFA_EHV_FIVRA_CPU0 @S9S_MB_2U_LIB.S9S_MB_2U(SCH_1):PVCCFA_EHV_FIVRA_CPU0     I4 @S9S_MB_2U_LIB.S9S_MB_2U(SCH_1):PAGE38
  DH89 PVCCFA_EHV_FIVRA_CPU0 @S9S_MB_2U_LIB.S9S_MB_2U(SCH_1):PVCCFA_EHV_FIVRA_CPU0     I4 @S9S_MB_2U_LIB.S9S_MB_2U(SCH_1):PAGE38
  DD89 PVCCFA_EHV_FIVRA_CPU0 @S9S_MB_2U_LIB.S9S_MB_2U(SCH_1):PVCCFA_EHV_FIVRA_CPU0     I4 @S9S_MB_2U_LIB.S9S_MB_2U(SCH_1):PAGE38
  DD85 PVCCFA_EHV_FIVRA_CPU0 @S9S_MB_2U_LIB.S9S_MB_2U(SCH_1):PVCCFA_EHV_FIVRA_CPU0     I4 @S9S_MB_2U_LIB.S9S_MB_2U(SCH_1):PAGE38
  DD83 PVCCFA_EHV_FIVRA_CPU0 @S9S_MB_2U_LIB.S9S_MB_2U(SCH_1):PVCCFA_EHV_FIVRA_CPU0     I4 @S9S_MB_2U_LIB.S9S_MB_2U(SCH_1):PAGE38
  DD77 PVCCFA_EHV_FIVRA_CPU0 @S9S_MB_2U_LIB.S9S_MB_2U(SCH_1):PVCCFA_EHV_FIVRA_CPU0     I4 @S9S_MB_2U_LIB.S9S_MB_2U(SCH_1):PAGE38
  CY89 PVCCFA_EHV_FIVRA_CPU0 @S9S_MB_2U_LIB.S9S_MB_2U(SCH_1):PVCCFA_EHV_FIVRA_CPU0     I4 @S9S_MB_2U_LIB.S9S_MB_2U(SCH_1):PAGE38
  CY85 PVCCFA_EHV_FIVRA_CPU0 @S9S_MB_2U_LIB.S9S_MB_2U(SCH_1):PVCCFA_EHV_FIVRA_CPU0     I4 @S9S_MB_2U_LIB.S9S_MB_2U(SCH_1):PAGE38
  CY79 PVCCFA_EHV_FIVRA_CPU0 @S9S_MB_2U_LIB.S9S_MB_2U(SCH_1):PVCCFA_EHV_FIVRA_CPU0     I4 @S9S_MB_2U_LIB.S9S_MB_2U(SCH_1):PAGE38
  CY75 PVCCFA_EHV_FIVRA_CPU0 @S9S_MB_2U_LIB.S9S_MB_2U(SCH_1):PVCCFA_EHV_FIVRA_CPU0     I4 @S9S_MB_2U_LIB.S9S_MB_2U(SCH_1):PAGE38
  CT85 PVCCFA_EHV_FIVRA_CPU0 @S9S_MB_2U_LIB.S9S_MB_2U(SCH_1):PVCCFA_EHV_FIVRA_CPU0     I4 @S9S_MB_2U_LIB.S9S_MB_2U(SCH_1):PAGE38
  CT77 PVCCFA_EHV_FIVRA_CPU0 @S9S_MB_2U_LIB.S9S_MB_2U(SCH_1):PVCCFA_EHV_FIVRA_CPU0     I4 @S9S_MB_2U_LIB.S9S_MB_2U(SCH_1):PAGE38
  CP73 PVCCFA_EHV_FIVRA_CPU0 @S9S_MB_2U_LIB.S9S_MB_2U(SCH_1):PVCCFA_EHV_FIVRA_CPU0     I4 @S9S_MB_2U_LIB.S9S_MB_2U(SCH_1):PAGE38
  CN78 PVCCFA_EHV_FIVRA_CPU0 @S9S_MB_2U_LIB.S9S_MB_2U(SCH_1):PVCCFA_EHV_FIVRA_CPU0     I4 @S9S_MB_2U_LIB.S9S_MB_2U(SCH_1):PAGE38
  CM73 PVCCFA_EHV_FIVRA_CPU0 @S9S_MB_2U_LIB.S9S_MB_2U(SCH_1):PVCCFA_EHV_FIVRA_CPU0     I4 @S9S_MB_2U_LIB.S9S_MB_2U(SCH_1):PAGE38
  CK79 PVCCFA_EHV_FIVRA_CPU0 @S9S_MB_2U_LIB.S9S_MB_2U(SCH_1):PVCCFA_EHV_FIVRA_CPU0     I4 @S9S_MB_2U_LIB.S9S_MB_2U(SCH_1):PAGE38
  CK73 PVCCFA_EHV_FIVRA_CPU0 @S9S_MB_2U_LIB.S9S_MB_2U(SCH_1):PVCCFA_EHV_FIVRA_CPU0     I4 @S9S_MB_2U_LIB.S9S_MB_2U(SCH_1):PAGE38
  CE74 PVCCFA_EHV_FIVRA_CPU0 @S9S_MB_2U_LIB.S9S_MB_2U(SCH_1):PVCCFA_EHV_FIVRA_CPU0     I4 @S9S_MB_2U_LIB.S9S_MB_2U(SCH_1):PAGE38
   C88 PVCCFA_EHV_FIVRA_CPU0 @S9S_MB_2U_LIB.S9S_MB_2U(SCH_1):PVCCFA_EHV_FIVRA_CPU0     I4 @S9S_MB_2U_LIB.S9S_MB_2U(SCH_1):PAGE38
   C84 PVCCFA_EHV_FIVRA_CPU0 @S9S_MB_2U_LIB.S9S_MB_2U(SCH_1):PVCCFA_EHV_FIVRA_CPU0     I4 @S9S_MB_2U_LIB.S9S_MB_2U(SCH_1):PAGE38
  BJ78 PVCCFA_EHV_FIVRA_CPU0 @S9S_MB_2U_LIB.S9S_MB_2U(SCH_1):PVCCFA_EHV_FIVRA_CPU0     I4 @S9S_MB_2U_LIB.S9S_MB_2U(SCH_1):PAGE38
  BJ72 PVCCFA_EHV_FIVRA_CPU0 @S9S_MB_2U_LIB.S9S_MB_2U(SCH_1):PVCCFA_EHV_FIVRA_CPU0     I4 @S9S_MB_2U_LIB.S9S_MB_2U(SCH_1):PAGE38
  BH79 PVCCFA_EHV_FIVRA_CPU0 @S9S_MB_2U_LIB.S9S_MB_2U(SCH_1):PVCCFA_EHV_FIVRA_CPU0     I4 @S9S_MB_2U_LIB.S9S_MB_2U(SCH_1):PAGE38
  BF77 PVCCFA_EHV_FIVRA_CPU0 @S9S_MB_2U_LIB.S9S_MB_2U(SCH_1):PVCCFA_EHV_FIVRA_CPU0     I4 @S9S_MB_2U_LIB.S9S_MB_2U(SCH_1):PAGE38
  BE72 PVCCFA_EHV_FIVRA_CPU0 @S9S_MB_2U_LIB.S9S_MB_2U(SCH_1):PVCCFA_EHV_FIVRA_CPU0     I4 @S9S_MB_2U_LIB.S9S_MB_2U(SCH_1):PAGE38
  AY89 PVCCFA_EHV_FIVRA_CPU0 @S9S_MB_2U_LIB.S9S_MB_2U(SCH_1):PVCCFA_EHV_FIVRA_CPU0     I4 @S9S_MB_2U_LIB.S9S_MB_2U(SCH_1):PAGE38
  AW76 PVCCFA_EHV_FIVRA_CPU0 @S9S_MB_2U_LIB.S9S_MB_2U(SCH_1):PVCCFA_EHV_FIVRA_CPU0     I4 @S9S_MB_2U_LIB.S9S_MB_2U(SCH_1):PAGE38
  AU15 PVCCFA_EHV_FIVRA_CPU0 @S9S_MB_2U_LIB.S9S_MB_2U(SCH_1):PVCCFA_EHV_FIVRA_CPU0     I4 @S9S_MB_2U_LIB.S9S_MB_2U(SCH_1):PAGE38
  AT89 PVCCFA_EHV_FIVRA_CPU0 @S9S_MB_2U_LIB.S9S_MB_2U(SCH_1):PVCCFA_EHV_FIVRA_CPU0     I4 @S9S_MB_2U_LIB.S9S_MB_2U(SCH_1):PAGE38
  AT73 PVCCFA_EHV_FIVRA_CPU0 @S9S_MB_2U_LIB.S9S_MB_2U(SCH_1):PVCCFA_EHV_FIVRA_CPU0     I4 @S9S_MB_2U_LIB.S9S_MB_2U(SCH_1):PAGE38
  AN80 PVCCFA_EHV_FIVRA_CPU0 @S9S_MB_2U_LIB.S9S_MB_2U(SCH_1):PVCCFA_EHV_FIVRA_CPU0     I4 @S9S_MB_2U_LIB.S9S_MB_2U(SCH_1):PAGE38
   AN7 PVCCFA_EHV_FIVRA_CPU0 @S9S_MB_2U_LIB.S9S_MB_2U(SCH_1):PVCCFA_EHV_FIVRA_CPU0     I4 @S9S_MB_2U_LIB.S9S_MB_2U(SCH_1):PAGE38
  AN15 PVCCFA_EHV_FIVRA_CPU0 @S9S_MB_2U_LIB.S9S_MB_2U(SCH_1):PVCCFA_EHV_FIVRA_CPU0     I4 @S9S_MB_2U_LIB.S9S_MB_2U(SCH_1):PAGE38
  AN11 PVCCFA_EHV_FIVRA_CPU0 @S9S_MB_2U_LIB.S9S_MB_2U(SCH_1):PVCCFA_EHV_FIVRA_CPU0     I4 @S9S_MB_2U_LIB.S9S_MB_2U(SCH_1):PAGE38
  AM89 PVCCFA_EHV_FIVRA_CPU0 @S9S_MB_2U_LIB.S9S_MB_2U(SCH_1):PVCCFA_EHV_FIVRA_CPU0     I4 @S9S_MB_2U_LIB.S9S_MB_2U(SCH_1):PAGE38
  AM85 PVCCFA_EHV_FIVRA_CPU0 @S9S_MB_2U_LIB.S9S_MB_2U(SCH_1):PVCCFA_EHV_FIVRA_CPU0     I4 @S9S_MB_2U_LIB.S9S_MB_2U(SCH_1):PAGE38
  AM79 PVCCFA_EHV_FIVRA_CPU0 @S9S_MB_2U_LIB.S9S_MB_2U(SCH_1):PVCCFA_EHV_FIVRA_CPU0     I4 @S9S_MB_2U_LIB.S9S_MB_2U(SCH_1):PAGE38
   AJ7 PVCCFA_EHV_FIVRA_CPU0 @S9S_MB_2U_LIB.S9S_MB_2U(SCH_1):PVCCFA_EHV_FIVRA_CPU0     I4 @S9S_MB_2U_LIB.S9S_MB_2U(SCH_1):PAGE38
  AJ15 PVCCFA_EHV_FIVRA_CPU0 @S9S_MB_2U_LIB.S9S_MB_2U(SCH_1):PVCCFA_EHV_FIVRA_CPU0     I4 @S9S_MB_2U_LIB.S9S_MB_2U(SCH_1):PAGE38
  AJ11 PVCCFA_EHV_FIVRA_CPU0 @S9S_MB_2U_LIB.S9S_MB_2U(SCH_1):PVCCFA_EHV_FIVRA_CPU0     I4 @S9S_MB_2U_LIB.S9S_MB_2U(SCH_1):PAGE38
  AH89 PVCCFA_EHV_FIVRA_CPU0 @S9S_MB_2U_LIB.S9S_MB_2U(SCH_1):PVCCFA_EHV_FIVRA_CPU0     I4 @S9S_MB_2U_LIB.S9S_MB_2U(SCH_1):PAGE38
  AH85 PVCCFA_EHV_FIVRA_CPU0 @S9S_MB_2U_LIB.S9S_MB_2U(SCH_1):PVCCFA_EHV_FIVRA_CPU0     I4 @S9S_MB_2U_LIB.S9S_MB_2U(SCH_1):PAGE38
  AG78 PVCCFA_EHV_FIVRA_CPU0 @S9S_MB_2U_LIB.S9S_MB_2U(SCH_1):PVCCFA_EHV_FIVRA_CPU0     I4 @S9S_MB_2U_LIB.S9S_MB_2U(SCH_1):PAGE38
  AF77 PVCCFA_EHV_FIVRA_CPU0 @S9S_MB_2U_LIB.S9S_MB_2U(SCH_1):PVCCFA_EHV_FIVRA_CPU0     I4 @S9S_MB_2U_LIB.S9S_MB_2U(SCH_1):PAGE38
   AE7 PVCCFA_EHV_FIVRA_CPU0 @S9S_MB_2U_LIB.S9S_MB_2U(SCH_1):PVCCFA_EHV_FIVRA_CPU0     I4 @S9S_MB_2U_LIB.S9S_MB_2U(SCH_1):PAGE38
  AE15 PVCCFA_EHV_FIVRA_CPU0 @S9S_MB_2U_LIB.S9S_MB_2U(SCH_1):PVCCFA_EHV_FIVRA_CPU0     I4 @S9S_MB_2U_LIB.S9S_MB_2U(SCH_1):PAGE38
  AE11 PVCCFA_EHV_FIVRA_CPU0 @S9S_MB_2U_LIB.S9S_MB_2U(SCH_1):PVCCFA_EHV_FIVRA_CPU0     I4 @S9S_MB_2U_LIB.S9S_MB_2U(SCH_1):PAGE38
  AD89 PVCCFA_EHV_FIVRA_CPU0 @S9S_MB_2U_LIB.S9S_MB_2U(SCH_1):PVCCFA_EHV_FIVRA_CPU0     I4 @S9S_MB_2U_LIB.S9S_MB_2U(SCH_1):PAGE38
  AD85 PVCCFA_EHV_FIVRA_CPU0 @S9S_MB_2U_LIB.S9S_MB_2U(SCH_1):PVCCFA_EHV_FIVRA_CPU0     I4 @S9S_MB_2U_LIB.S9S_MB_2U(SCH_1):PAGE38
   AA7 PVCCFA_EHV_FIVRA_CPU0 @S9S_MB_2U_LIB.S9S_MB_2U(SCH_1):PVCCFA_EHV_FIVRA_CPU0     I4 @S9S_MB_2U_LIB.S9S_MB_2U(SCH_1):PAGE38
  AA15 PVCCFA_EHV_FIVRA_CPU0 @S9S_MB_2U_LIB.S9S_MB_2U(SCH_1):PVCCFA_EHV_FIVRA_CPU0     I4 @S9S_MB_2U_LIB.S9S_MB_2U(SCH_1):PAGE38
  AA11 PVCCFA_EHV_FIVRA_CPU0 @S9S_MB_2U_LIB.S9S_MB_2U(SCH_1):PVCCFA_EHV_FIVRA_CPU0     I4 @S9S_MB_2U_LIB.S9S_MB_2U(SCH_1):PAGE38
  ER41    GND @S9S_MB_2U_LIB.S9S_MB_2U(SCH_1):GND     I1 @S9S_MB_2U_LIB.S9S_MB_2U(SCH_1):PAGE39
  ER43    GND @S9S_MB_2U_LIB.S9S_MB_2U(SCH_1):GND     I1 @S9S_MB_2U_LIB.S9S_MB_2U(SCH_1):PAGE39
  ER48    GND @S9S_MB_2U_LIB.S9S_MB_2U(SCH_1):GND     I1 @S9S_MB_2U_LIB.S9S_MB_2U(SCH_1):PAGE39
  ER50    GND @S9S_MB_2U_LIB.S9S_MB_2U(SCH_1):GND     I1 @S9S_MB_2U_LIB.S9S_MB_2U(SCH_1):PAGE39
  ET57    GND @S9S_MB_2U_LIB.S9S_MB_2U(SCH_1):GND     I1 @S9S_MB_2U_LIB.S9S_MB_2U(SCH_1):PAGE39
  ET38    GND @S9S_MB_2U_LIB.S9S_MB_2U(SCH_1):GND     I1 @S9S_MB_2U_LIB.S9S_MB_2U(SCH_1):PAGE39
  ET34    GND @S9S_MB_2U_LIB.S9S_MB_2U(SCH_1):GND     I1 @S9S_MB_2U_LIB.S9S_MB_2U(SCH_1):PAGE39
  ET28    GND @S9S_MB_2U_LIB.S9S_MB_2U(SCH_1):GND     I1 @S9S_MB_2U_LIB.S9S_MB_2U(SCH_1):PAGE39
  ET22    GND @S9S_MB_2U_LIB.S9S_MB_2U(SCH_1):GND     I1 @S9S_MB_2U_LIB.S9S_MB_2U(SCH_1):PAGE39
  ET16    GND @S9S_MB_2U_LIB.S9S_MB_2U(SCH_1):GND     I1 @S9S_MB_2U_LIB.S9S_MB_2U(SCH_1):PAGE39
  ET10    GND @S9S_MB_2U_LIB.S9S_MB_2U(SCH_1):GND     I1 @S9S_MB_2U_LIB.S9S_MB_2U(SCH_1):PAGE39
  ER86    GND @S9S_MB_2U_LIB.S9S_MB_2U(SCH_1):GND     I1 @S9S_MB_2U_LIB.S9S_MB_2U(SCH_1):PAGE39
  ER84    GND @S9S_MB_2U_LIB.S9S_MB_2U(SCH_1):GND     I1 @S9S_MB_2U_LIB.S9S_MB_2U(SCH_1):PAGE39
  ER80    GND @S9S_MB_2U_LIB.S9S_MB_2U(SCH_1):GND     I1 @S9S_MB_2U_LIB.S9S_MB_2U(SCH_1):PAGE39
  ER78    GND @S9S_MB_2U_LIB.S9S_MB_2U(SCH_1):GND     I1 @S9S_MB_2U_LIB.S9S_MB_2U(SCH_1):PAGE39
  ER74    GND @S9S_MB_2U_LIB.S9S_MB_2U(SCH_1):GND     I1 @S9S_MB_2U_LIB.S9S_MB_2U(SCH_1):PAGE39
  ER70    GND @S9S_MB_2U_LIB.S9S_MB_2U(SCH_1):GND     I1 @S9S_MB_2U_LIB.S9S_MB_2U(SCH_1):PAGE39
   ER7    GND @S9S_MB_2U_LIB.S9S_MB_2U(SCH_1):GND     I1 @S9S_MB_2U_LIB.S9S_MB_2U(SCH_1):PAGE39
   ER5    GND @S9S_MB_2U_LIB.S9S_MB_2U(SCH_1):GND     I1 @S9S_MB_2U_LIB.S9S_MB_2U(SCH_1):PAGE39
  ER33    GND @S9S_MB_2U_LIB.S9S_MB_2U(SCH_1):GND     I1 @S9S_MB_2U_LIB.S9S_MB_2U(SCH_1):PAGE39
  ER27    GND @S9S_MB_2U_LIB.S9S_MB_2U(SCH_1):GND     I1 @S9S_MB_2U_LIB.S9S_MB_2U(SCH_1):PAGE39
  EP83    GND @S9S_MB_2U_LIB.S9S_MB_2U(SCH_1):GND     I1 @S9S_MB_2U_LIB.S9S_MB_2U(SCH_1):PAGE39
  EP67    GND @S9S_MB_2U_LIB.S9S_MB_2U(SCH_1):GND     I1 @S9S_MB_2U_LIB.S9S_MB_2U(SCH_1):PAGE39
  EN80    GND @S9S_MB_2U_LIB.S9S_MB_2U(SCH_1):GND     I1 @S9S_MB_2U_LIB.S9S_MB_2U(SCH_1):PAGE39
  EN78    GND @S9S_MB_2U_LIB.S9S_MB_2U(SCH_1):GND     I1 @S9S_MB_2U_LIB.S9S_MB_2U(SCH_1):PAGE39
  EN64    GND @S9S_MB_2U_LIB.S9S_MB_2U(SCH_1):GND     I1 @S9S_MB_2U_LIB.S9S_MB_2U(SCH_1):PAGE39
  EN56    GND @S9S_MB_2U_LIB.S9S_MB_2U(SCH_1):GND     I1 @S9S_MB_2U_LIB.S9S_MB_2U(SCH_1):PAGE39
  EN54    GND @S9S_MB_2U_LIB.S9S_MB_2U(SCH_1):GND     I1 @S9S_MB_2U_LIB.S9S_MB_2U(SCH_1):PAGE39
  EN52    GND @S9S_MB_2U_LIB.S9S_MB_2U(SCH_1):GND     I1 @S9S_MB_2U_LIB.S9S_MB_2U(SCH_1):PAGE39
  EN50    GND @S9S_MB_2U_LIB.S9S_MB_2U(SCH_1):GND     I1 @S9S_MB_2U_LIB.S9S_MB_2U(SCH_1):PAGE39
  EN48    GND @S9S_MB_2U_LIB.S9S_MB_2U(SCH_1):GND     I1 @S9S_MB_2U_LIB.S9S_MB_2U(SCH_1):PAGE39
  EN45    GND @S9S_MB_2U_LIB.S9S_MB_2U(SCH_1):GND     I1 @S9S_MB_2U_LIB.S9S_MB_2U(SCH_1):PAGE39
  EN43    GND @S9S_MB_2U_LIB.S9S_MB_2U(SCH_1):GND     I1 @S9S_MB_2U_LIB.S9S_MB_2U(SCH_1):PAGE39
  EN41    GND @S9S_MB_2U_LIB.S9S_MB_2U(SCH_1):GND     I1 @S9S_MB_2U_LIB.S9S_MB_2U(SCH_1):PAGE39
  EN37    GND @S9S_MB_2U_LIB.S9S_MB_2U(SCH_1):GND     I1 @S9S_MB_2U_LIB.S9S_MB_2U(SCH_1):PAGE39
  EN35    GND @S9S_MB_2U_LIB.S9S_MB_2U(SCH_1):GND     I1 @S9S_MB_2U_LIB.S9S_MB_2U(SCH_1):PAGE39
  EN33    GND @S9S_MB_2U_LIB.S9S_MB_2U(SCH_1):GND     I1 @S9S_MB_2U_LIB.S9S_MB_2U(SCH_1):PAGE39
  EN31    GND @S9S_MB_2U_LIB.S9S_MB_2U(SCH_1):GND     I1 @S9S_MB_2U_LIB.S9S_MB_2U(SCH_1):PAGE39
  EN29    GND @S9S_MB_2U_LIB.S9S_MB_2U(SCH_1):GND     I1 @S9S_MB_2U_LIB.S9S_MB_2U(SCH_1):PAGE39
  EN27    GND @S9S_MB_2U_LIB.S9S_MB_2U(SCH_1):GND     I1 @S9S_MB_2U_LIB.S9S_MB_2U(SCH_1):PAGE39
  EN25    GND @S9S_MB_2U_LIB.S9S_MB_2U(SCH_1):GND     I1 @S9S_MB_2U_LIB.S9S_MB_2U(SCH_1):PAGE39
  EN23    GND @S9S_MB_2U_LIB.S9S_MB_2U(SCH_1):GND     I1 @S9S_MB_2U_LIB.S9S_MB_2U(SCH_1):PAGE39
  EN21    GND @S9S_MB_2U_LIB.S9S_MB_2U(SCH_1):GND     I1 @S9S_MB_2U_LIB.S9S_MB_2U(SCH_1):PAGE39
  EN19    GND @S9S_MB_2U_LIB.S9S_MB_2U(SCH_1):GND     I1 @S9S_MB_2U_LIB.S9S_MB_2U(SCH_1):PAGE39
  EN17    GND @S9S_MB_2U_LIB.S9S_MB_2U(SCH_1):GND     I1 @S9S_MB_2U_LIB.S9S_MB_2U(SCH_1):PAGE39
  EN15    GND @S9S_MB_2U_LIB.S9S_MB_2U(SCH_1):GND     I1 @S9S_MB_2U_LIB.S9S_MB_2U(SCH_1):PAGE39
  EN13    GND @S9S_MB_2U_LIB.S9S_MB_2U(SCH_1):GND     I1 @S9S_MB_2U_LIB.S9S_MB_2U(SCH_1):PAGE39
  EN11    GND @S9S_MB_2U_LIB.S9S_MB_2U(SCH_1):GND     I1 @S9S_MB_2U_LIB.S9S_MB_2U(SCH_1):PAGE39
  EM83    GND @S9S_MB_2U_LIB.S9S_MB_2U(SCH_1):GND     I1 @S9S_MB_2U_LIB.S9S_MB_2U(SCH_1):PAGE39
  EM81    GND @S9S_MB_2U_LIB.S9S_MB_2U(SCH_1):GND     I1 @S9S_MB_2U_LIB.S9S_MB_2U(SCH_1):PAGE39
   EM8    GND @S9S_MB_2U_LIB.S9S_MB_2U(SCH_1):GND     I1 @S9S_MB_2U_LIB.S9S_MB_2U(SCH_1):PAGE39
  EM73    GND @S9S_MB_2U_LIB.S9S_MB_2U(SCH_1):GND     I1 @S9S_MB_2U_LIB.S9S_MB_2U(SCH_1):PAGE39
  ET59    GND @S9S_MB_2U_LIB.S9S_MB_2U(SCH_1):GND     I1 @S9S_MB_2U_LIB.S9S_MB_2U(SCH_1):PAGE39
  EM42    GND @S9S_MB_2U_LIB.S9S_MB_2U(SCH_1):GND     I1 @S9S_MB_2U_LIB.S9S_MB_2U(SCH_1):PAGE39
  ET53    GND @S9S_MB_2U_LIB.S9S_MB_2U(SCH_1):GND     I1 @S9S_MB_2U_LIB.S9S_MB_2U(SCH_1):PAGE39
  EL76    GND @S9S_MB_2U_LIB.S9S_MB_2U(SCH_1):GND     I1 @S9S_MB_2U_LIB.S9S_MB_2U(SCH_1):PAGE39
  EL64    GND @S9S_MB_2U_LIB.S9S_MB_2U(SCH_1):GND     I1 @S9S_MB_2U_LIB.S9S_MB_2U(SCH_1):PAGE39
   EL5    GND @S9S_MB_2U_LIB.S9S_MB_2U(SCH_1):GND     I1 @S9S_MB_2U_LIB.S9S_MB_2U(SCH_1):PAGE39
  EL45    GND @S9S_MB_2U_LIB.S9S_MB_2U(SCH_1):GND     I1 @S9S_MB_2U_LIB.S9S_MB_2U(SCH_1):PAGE39
  ET32    GND @S9S_MB_2U_LIB.S9S_MB_2U(SCH_1):GND     I1 @S9S_MB_2U_LIB.S9S_MB_2U(SCH_1):PAGE39
  EL39    GND @S9S_MB_2U_LIB.S9S_MB_2U(SCH_1):GND     I1 @S9S_MB_2U_LIB.S9S_MB_2U(SCH_1):PAGE39
  ET26    GND @S9S_MB_2U_LIB.S9S_MB_2U(SCH_1):GND     I1 @S9S_MB_2U_LIB.S9S_MB_2U(SCH_1):PAGE39
  EL33    GND @S9S_MB_2U_LIB.S9S_MB_2U(SCH_1):GND     I1 @S9S_MB_2U_LIB.S9S_MB_2U(SCH_1):PAGE39
  ET20    GND @S9S_MB_2U_LIB.S9S_MB_2U(SCH_1):GND     I1 @S9S_MB_2U_LIB.S9S_MB_2U(SCH_1):PAGE39
   EL3    GND @S9S_MB_2U_LIB.S9S_MB_2U(SCH_1):GND     I1 @S9S_MB_2U_LIB.S9S_MB_2U(SCH_1):PAGE39
  ET14    GND @S9S_MB_2U_LIB.S9S_MB_2U(SCH_1):GND     I1 @S9S_MB_2U_LIB.S9S_MB_2U(SCH_1):PAGE39
  EL27    GND @S9S_MB_2U_LIB.S9S_MB_2U(SCH_1):GND     I1 @S9S_MB_2U_LIB.S9S_MB_2U(SCH_1):PAGE39
   ER9    GND @S9S_MB_2U_LIB.S9S_MB_2U(SCH_1):GND     I1 @S9S_MB_2U_LIB.S9S_MB_2U(SCH_1):PAGE39
  EL21    GND @S9S_MB_2U_LIB.S9S_MB_2U(SCH_1):GND     I1 @S9S_MB_2U_LIB.S9S_MB_2U(SCH_1):PAGE39
  EK75    GND @S9S_MB_2U_LIB.S9S_MB_2U(SCH_1):GND     I1 @S9S_MB_2U_LIB.S9S_MB_2U(SCH_1):PAGE39
  EK69    GND @S9S_MB_2U_LIB.S9S_MB_2U(SCH_1):GND     I1 @S9S_MB_2U_LIB.S9S_MB_2U(SCH_1):PAGE39
  EK65    GND @S9S_MB_2U_LIB.S9S_MB_2U(SCH_1):GND     I1 @S9S_MB_2U_LIB.S9S_MB_2U(SCH_1):PAGE39
  EK57    GND @S9S_MB_2U_LIB.S9S_MB_2U(SCH_1):GND     I1 @S9S_MB_2U_LIB.S9S_MB_2U(SCH_1):PAGE39
  EK47    GND @S9S_MB_2U_LIB.S9S_MB_2U(SCH_1):GND     I1 @S9S_MB_2U_LIB.S9S_MB_2U(SCH_1):PAGE39
  EK40    GND @S9S_MB_2U_LIB.S9S_MB_2U(SCH_1):GND     I1 @S9S_MB_2U_LIB.S9S_MB_2U(SCH_1):PAGE39
  ER64    GND @S9S_MB_2U_LIB.S9S_MB_2U(SCH_1):GND     I1 @S9S_MB_2U_LIB.S9S_MB_2U(SCH_1):PAGE39
  ER58    GND @S9S_MB_2U_LIB.S9S_MB_2U(SCH_1):GND     I1 @S9S_MB_2U_LIB.S9S_MB_2U(SCH_1):PAGE39
   EK4    GND @S9S_MB_2U_LIB.S9S_MB_2U(SCH_1):GND     I1 @S9S_MB_2U_LIB.S9S_MB_2U(SCH_1):PAGE39
  EK38    GND @S9S_MB_2U_LIB.S9S_MB_2U(SCH_1):GND     I1 @S9S_MB_2U_LIB.S9S_MB_2U(SCH_1):PAGE39
  ER52    GND @S9S_MB_2U_LIB.S9S_MB_2U(SCH_1):GND     I1 @S9S_MB_2U_LIB.S9S_MB_2U(SCH_1):PAGE39
  EK34    GND @S9S_MB_2U_LIB.S9S_MB_2U(SCH_1):GND     I1 @S9S_MB_2U_LIB.S9S_MB_2U(SCH_1):PAGE39
  ER39    GND @S9S_MB_2U_LIB.S9S_MB_2U(SCH_1):GND     I1 @S9S_MB_2U_LIB.S9S_MB_2U(SCH_1):PAGE39
  EK32    GND @S9S_MB_2U_LIB.S9S_MB_2U(SCH_1):GND     I1 @S9S_MB_2U_LIB.S9S_MB_2U(SCH_1):PAGE39
  EK28    GND @S9S_MB_2U_LIB.S9S_MB_2U(SCH_1):GND     I1 @S9S_MB_2U_LIB.S9S_MB_2U(SCH_1):PAGE39
  EK22    GND @S9S_MB_2U_LIB.S9S_MB_2U(SCH_1):GND     I1 @S9S_MB_2U_LIB.S9S_MB_2U(SCH_1):PAGE39
   EK2    GND @S9S_MB_2U_LIB.S9S_MB_2U(SCH_1):GND     I1 @S9S_MB_2U_LIB.S9S_MB_2U(SCH_1):PAGE39
  ER21    GND @S9S_MB_2U_LIB.S9S_MB_2U(SCH_1):GND     I1 @S9S_MB_2U_LIB.S9S_MB_2U(SCH_1):PAGE39
  ER15    GND @S9S_MB_2U_LIB.S9S_MB_2U(SCH_1):GND     I1 @S9S_MB_2U_LIB.S9S_MB_2U(SCH_1):PAGE39
  EK14    GND @S9S_MB_2U_LIB.S9S_MB_2U(SCH_1):GND     I1 @S9S_MB_2U_LIB.S9S_MB_2U(SCH_1):PAGE39
  EP77    GND @S9S_MB_2U_LIB.S9S_MB_2U(SCH_1):GND     I1 @S9S_MB_2U_LIB.S9S_MB_2U(SCH_1):PAGE39
  EP71    GND @S9S_MB_2U_LIB.S9S_MB_2U(SCH_1):GND     I1 @S9S_MB_2U_LIB.S9S_MB_2U(SCH_1):PAGE39
  EP69    GND @S9S_MB_2U_LIB.S9S_MB_2U(SCH_1):GND     I1 @S9S_MB_2U_LIB.S9S_MB_2U(SCH_1):PAGE39
  EK10    GND @S9S_MB_2U_LIB.S9S_MB_2U(SCH_1):GND     I1 @S9S_MB_2U_LIB.S9S_MB_2U(SCH_1):PAGE39
   EJ9    GND @S9S_MB_2U_LIB.S9S_MB_2U(SCH_1):GND     I1 @S9S_MB_2U_LIB.S9S_MB_2U(SCH_1):PAGE39
  EJ88    GND @S9S_MB_2U_LIB.S9S_MB_2U(SCH_1):GND     I1 @S9S_MB_2U_LIB.S9S_MB_2U(SCH_1):PAGE39
  EJ78    GND @S9S_MB_2U_LIB.S9S_MB_2U(SCH_1):GND     I1 @S9S_MB_2U_LIB.S9S_MB_2U(SCH_1):PAGE39
  EJ74    GND @S9S_MB_2U_LIB.S9S_MB_2U(SCH_1):GND     I1 @S9S_MB_2U_LIB.S9S_MB_2U(SCH_1):PAGE39
   EN9    GND @S9S_MB_2U_LIB.S9S_MB_2U(SCH_1):GND     I1 @S9S_MB_2U_LIB.S9S_MB_2U(SCH_1):PAGE39
  EN88    GND @S9S_MB_2U_LIB.S9S_MB_2U(SCH_1):GND     I1 @S9S_MB_2U_LIB.S9S_MB_2U(SCH_1):PAGE39
   EJ7    GND @S9S_MB_2U_LIB.S9S_MB_2U(SCH_1):GND     I1 @S9S_MB_2U_LIB.S9S_MB_2U(SCH_1):PAGE39
  EJ66    GND @S9S_MB_2U_LIB.S9S_MB_2U(SCH_1):GND     I1 @S9S_MB_2U_LIB.S9S_MB_2U(SCH_1):PAGE39
  EJ60    GND @S9S_MB_2U_LIB.S9S_MB_2U(SCH_1):GND     I1 @S9S_MB_2U_LIB.S9S_MB_2U(SCH_1):PAGE39
  EN72    GND @S9S_MB_2U_LIB.S9S_MB_2U(SCH_1):GND     I1 @S9S_MB_2U_LIB.S9S_MB_2U(SCH_1):PAGE39
  EN66    GND @S9S_MB_2U_LIB.S9S_MB_2U(SCH_1):GND     I1 @S9S_MB_2U_LIB.S9S_MB_2U(SCH_1):PAGE39
  EJ56    GND @S9S_MB_2U_LIB.S9S_MB_2U(SCH_1):GND     I1 @S9S_MB_2U_LIB.S9S_MB_2U(SCH_1):PAGE39
  EN62    GND @S9S_MB_2U_LIB.S9S_MB_2U(SCH_1):GND     I1 @S9S_MB_2U_LIB.S9S_MB_2U(SCH_1):PAGE39
  EN60    GND @S9S_MB_2U_LIB.S9S_MB_2U(SCH_1):GND     I1 @S9S_MB_2U_LIB.S9S_MB_2U(SCH_1):PAGE39
  EN58    GND @S9S_MB_2U_LIB.S9S_MB_2U(SCH_1):GND     I1 @S9S_MB_2U_LIB.S9S_MB_2U(SCH_1):PAGE39
  EJ50    GND @S9S_MB_2U_LIB.S9S_MB_2U(SCH_1):GND     I1 @S9S_MB_2U_LIB.S9S_MB_2U(SCH_1):PAGE39
  EJ48    GND @S9S_MB_2U_LIB.S9S_MB_2U(SCH_1):GND     I1 @S9S_MB_2U_LIB.S9S_MB_2U(SCH_1):PAGE39
  EJ43    GND @S9S_MB_2U_LIB.S9S_MB_2U(SCH_1):GND     I1 @S9S_MB_2U_LIB.S9S_MB_2U(SCH_1):PAGE39
  EJ41    GND @S9S_MB_2U_LIB.S9S_MB_2U(SCH_1):GND     I1 @S9S_MB_2U_LIB.S9S_MB_2U(SCH_1):PAGE39
  EJ37    GND @S9S_MB_2U_LIB.S9S_MB_2U(SCH_1):GND     I1 @S9S_MB_2U_LIB.S9S_MB_2U(SCH_1):PAGE39
  EJ31    GND @S9S_MB_2U_LIB.S9S_MB_2U(SCH_1):GND     I1 @S9S_MB_2U_LIB.S9S_MB_2U(SCH_1):PAGE39
  EJ29    GND @S9S_MB_2U_LIB.S9S_MB_2U(SCH_1):GND     I1 @S9S_MB_2U_LIB.S9S_MB_2U(SCH_1):PAGE39
  EJ23    GND @S9S_MB_2U_LIB.S9S_MB_2U(SCH_1):GND     I1 @S9S_MB_2U_LIB.S9S_MB_2U(SCH_1):PAGE39
  EN39    GND @S9S_MB_2U_LIB.S9S_MB_2U(SCH_1):GND     I1 @S9S_MB_2U_LIB.S9S_MB_2U(SCH_1):PAGE39
  EJ19    GND @S9S_MB_2U_LIB.S9S_MB_2U(SCH_1):GND     I1 @S9S_MB_2U_LIB.S9S_MB_2U(SCH_1):PAGE39
  EJ13    GND @S9S_MB_2U_LIB.S9S_MB_2U(SCH_1):GND     I1 @S9S_MB_2U_LIB.S9S_MB_2U(SCH_1):PAGE39
  EH83    GND @S9S_MB_2U_LIB.S9S_MB_2U(SCH_1):GND     I1 @S9S_MB_2U_LIB.S9S_MB_2U(SCH_1):PAGE39
  EH81    GND @S9S_MB_2U_LIB.S9S_MB_2U(SCH_1):GND     I1 @S9S_MB_2U_LIB.S9S_MB_2U(SCH_1):PAGE39
  EH73    GND @S9S_MB_2U_LIB.S9S_MB_2U(SCH_1):GND     I1 @S9S_MB_2U_LIB.S9S_MB_2U(SCH_1):PAGE39
  EH49    GND @S9S_MB_2U_LIB.S9S_MB_2U(SCH_1):GND     I1 @S9S_MB_2U_LIB.S9S_MB_2U(SCH_1):PAGE39
  EH36    GND @S9S_MB_2U_LIB.S9S_MB_2U(SCH_1):GND     I1 @S9S_MB_2U_LIB.S9S_MB_2U(SCH_1):PAGE39
  EM79    GND @S9S_MB_2U_LIB.S9S_MB_2U(SCH_1):GND     I1 @S9S_MB_2U_LIB.S9S_MB_2U(SCH_1):PAGE39
  EM49    GND @S9S_MB_2U_LIB.S9S_MB_2U(SCH_1):GND     I1 @S9S_MB_2U_LIB.S9S_MB_2U(SCH_1):PAGE39
   EL9    GND @S9S_MB_2U_LIB.S9S_MB_2U(SCH_1):GND     I1 @S9S_MB_2U_LIB.S9S_MB_2U(SCH_1):PAGE39
  EL86    GND @S9S_MB_2U_LIB.S9S_MB_2U(SCH_1):GND     I1 @S9S_MB_2U_LIB.S9S_MB_2U(SCH_1):PAGE39
  EL72    GND @S9S_MB_2U_LIB.S9S_MB_2U(SCH_1):GND     I1 @S9S_MB_2U_LIB.S9S_MB_2U(SCH_1):PAGE39
  EL70    GND @S9S_MB_2U_LIB.S9S_MB_2U(SCH_1):GND     I1 @S9S_MB_2U_LIB.S9S_MB_2U(SCH_1):PAGE39
   EL7    GND @S9S_MB_2U_LIB.S9S_MB_2U(SCH_1):GND     I1 @S9S_MB_2U_LIB.S9S_MB_2U(SCH_1):PAGE39
  EL58    GND @S9S_MB_2U_LIB.S9S_MB_2U(SCH_1):GND     I1 @S9S_MB_2U_LIB.S9S_MB_2U(SCH_1):PAGE39
  EL52    GND @S9S_MB_2U_LIB.S9S_MB_2U(SCH_1):GND     I1 @S9S_MB_2U_LIB.S9S_MB_2U(SCH_1):PAGE39
  EL15    GND @S9S_MB_2U_LIB.S9S_MB_2U(SCH_1):GND     I1 @S9S_MB_2U_LIB.S9S_MB_2U(SCH_1):PAGE39
  EK89    GND @S9S_MB_2U_LIB.S9S_MB_2U(SCH_1):GND     I1 @S9S_MB_2U_LIB.S9S_MB_2U(SCH_1):PAGE39
  EK83    GND @S9S_MB_2U_LIB.S9S_MB_2U(SCH_1):GND     I1 @S9S_MB_2U_LIB.S9S_MB_2U(SCH_1):PAGE39
  EK79    GND @S9S_MB_2U_LIB.S9S_MB_2U(SCH_1):GND     I1 @S9S_MB_2U_LIB.S9S_MB_2U(SCH_1):PAGE39
  EK77    GND @S9S_MB_2U_LIB.S9S_MB_2U(SCH_1):GND     I1 @S9S_MB_2U_LIB.S9S_MB_2U(SCH_1):PAGE39
  EK71    GND @S9S_MB_2U_LIB.S9S_MB_2U(SCH_1):GND     I1 @S9S_MB_2U_LIB.S9S_MB_2U(SCH_1):PAGE39
  EK63    GND @S9S_MB_2U_LIB.S9S_MB_2U(SCH_1):GND     I1 @S9S_MB_2U_LIB.S9S_MB_2U(SCH_1):PAGE39
  EK59    GND @S9S_MB_2U_LIB.S9S_MB_2U(SCH_1):GND     I1 @S9S_MB_2U_LIB.S9S_MB_2U(SCH_1):PAGE39
  EK53    GND @S9S_MB_2U_LIB.S9S_MB_2U(SCH_1):GND     I1 @S9S_MB_2U_LIB.S9S_MB_2U(SCH_1):PAGE39
  EK51    GND @S9S_MB_2U_LIB.S9S_MB_2U(SCH_1):GND     I1 @S9S_MB_2U_LIB.S9S_MB_2U(SCH_1):PAGE39
  EK44    GND @S9S_MB_2U_LIB.S9S_MB_2U(SCH_1):GND     I1 @S9S_MB_2U_LIB.S9S_MB_2U(SCH_1):PAGE39
  EK26    GND @S9S_MB_2U_LIB.S9S_MB_2U(SCH_1):GND     I1 @S9S_MB_2U_LIB.S9S_MB_2U(SCH_1):PAGE39
  EK20    GND @S9S_MB_2U_LIB.S9S_MB_2U(SCH_1):GND     I1 @S9S_MB_2U_LIB.S9S_MB_2U(SCH_1):PAGE39
  EK16    GND @S9S_MB_2U_LIB.S9S_MB_2U(SCH_1):GND     I1 @S9S_MB_2U_LIB.S9S_MB_2U(SCH_1):PAGE39
  EJ72    GND @S9S_MB_2U_LIB.S9S_MB_2U(SCH_1):GND     I1 @S9S_MB_2U_LIB.S9S_MB_2U(SCH_1):PAGE39
  EJ68    GND @S9S_MB_2U_LIB.S9S_MB_2U(SCH_1):GND     I1 @S9S_MB_2U_LIB.S9S_MB_2U(SCH_1):PAGE39
  EJ62    GND @S9S_MB_2U_LIB.S9S_MB_2U(SCH_1):GND     I1 @S9S_MB_2U_LIB.S9S_MB_2U(SCH_1):PAGE39
  EJ54    GND @S9S_MB_2U_LIB.S9S_MB_2U(SCH_1):GND     I1 @S9S_MB_2U_LIB.S9S_MB_2U(SCH_1):PAGE39
  EJ35    GND @S9S_MB_2U_LIB.S9S_MB_2U(SCH_1):GND     I1 @S9S_MB_2U_LIB.S9S_MB_2U(SCH_1):PAGE39
  EJ25    GND @S9S_MB_2U_LIB.S9S_MB_2U(SCH_1):GND     I1 @S9S_MB_2U_LIB.S9S_MB_2U(SCH_1):PAGE39
  EJ17    GND @S9S_MB_2U_LIB.S9S_MB_2U(SCH_1):GND     I1 @S9S_MB_2U_LIB.S9S_MB_2U(SCH_1):PAGE39
  EJ11    GND @S9S_MB_2U_LIB.S9S_MB_2U(SCH_1):GND     I1 @S9S_MB_2U_LIB.S9S_MB_2U(SCH_1):PAGE39
  EH79    GND @S9S_MB_2U_LIB.S9S_MB_2U(SCH_1):GND     I1 @S9S_MB_2U_LIB.S9S_MB_2U(SCH_1):PAGE39
  EH67    GND @S9S_MB_2U_LIB.S9S_MB_2U(SCH_1):GND     I1 @S9S_MB_2U_LIB.S9S_MB_2U(SCH_1):PAGE39
  EH61    GND @S9S_MB_2U_LIB.S9S_MB_2U(SCH_1):GND     I1 @S9S_MB_2U_LIB.S9S_MB_2U(SCH_1):PAGE39
  EH55    GND @S9S_MB_2U_LIB.S9S_MB_2U(SCH_1):GND     I1 @S9S_MB_2U_LIB.S9S_MB_2U(SCH_1):PAGE39
  EH42    GND @S9S_MB_2U_LIB.S9S_MB_2U(SCH_1):GND     I1 @S9S_MB_2U_LIB.S9S_MB_2U(SCH_1):PAGE39
   EH4    GND @S9S_MB_2U_LIB.S9S_MB_2U(SCH_1):GND     I9 @S9S_MB_2U_LIB.S9S_MB_2U(SCH_1):PAGE39
  EH30    GND @S9S_MB_2U_LIB.S9S_MB_2U(SCH_1):GND     I9 @S9S_MB_2U_LIB.S9S_MB_2U(SCH_1):PAGE39
  EH24    GND @S9S_MB_2U_LIB.S9S_MB_2U(SCH_1):GND     I9 @S9S_MB_2U_LIB.S9S_MB_2U(SCH_1):PAGE39
  EH16    GND @S9S_MB_2U_LIB.S9S_MB_2U(SCH_1):GND     I9 @S9S_MB_2U_LIB.S9S_MB_2U(SCH_1):PAGE39
  EG90    GND @S9S_MB_2U_LIB.S9S_MB_2U(SCH_1):GND     I9 @S9S_MB_2U_LIB.S9S_MB_2U(SCH_1):PAGE39
   EG9    GND @S9S_MB_2U_LIB.S9S_MB_2U(SCH_1):GND     I9 @S9S_MB_2U_LIB.S9S_MB_2U(SCH_1):PAGE39
  EG88    GND @S9S_MB_2U_LIB.S9S_MB_2U(SCH_1):GND     I9 @S9S_MB_2U_LIB.S9S_MB_2U(SCH_1):PAGE39
  EG86    GND @S9S_MB_2U_LIB.S9S_MB_2U(SCH_1):GND     I9 @S9S_MB_2U_LIB.S9S_MB_2U(SCH_1):PAGE39
  EG84    GND @S9S_MB_2U_LIB.S9S_MB_2U(SCH_1):GND     I9 @S9S_MB_2U_LIB.S9S_MB_2U(SCH_1):PAGE39
  EG82    GND @S9S_MB_2U_LIB.S9S_MB_2U(SCH_1):GND     I9 @S9S_MB_2U_LIB.S9S_MB_2U(SCH_1):PAGE39
  EG39    GND @S9S_MB_2U_LIB.S9S_MB_2U(SCH_1):GND     I9 @S9S_MB_2U_LIB.S9S_MB_2U(SCH_1):PAGE39
  EF87    GND @S9S_MB_2U_LIB.S9S_MB_2U(SCH_1):GND     I9 @S9S_MB_2U_LIB.S9S_MB_2U(SCH_1):PAGE39
  EF85    GND @S9S_MB_2U_LIB.S9S_MB_2U(SCH_1):GND     I9 @S9S_MB_2U_LIB.S9S_MB_2U(SCH_1):PAGE39
   EF8    GND @S9S_MB_2U_LIB.S9S_MB_2U(SCH_1):GND     I9 @S9S_MB_2U_LIB.S9S_MB_2U(SCH_1):PAGE39
  EF77    GND @S9S_MB_2U_LIB.S9S_MB_2U(SCH_1):GND     I9 @S9S_MB_2U_LIB.S9S_MB_2U(SCH_1):PAGE39
  EF71    GND @S9S_MB_2U_LIB.S9S_MB_2U(SCH_1):GND     I9 @S9S_MB_2U_LIB.S9S_MB_2U(SCH_1):PAGE39
  EF69    GND @S9S_MB_2U_LIB.S9S_MB_2U(SCH_1):GND     I9 @S9S_MB_2U_LIB.S9S_MB_2U(SCH_1):PAGE39
  EF67    GND @S9S_MB_2U_LIB.S9S_MB_2U(SCH_1):GND     I9 @S9S_MB_2U_LIB.S9S_MB_2U(SCH_1):PAGE39
  EF65    GND @S9S_MB_2U_LIB.S9S_MB_2U(SCH_1):GND     I9 @S9S_MB_2U_LIB.S9S_MB_2U(SCH_1):PAGE39
  EF63    GND @S9S_MB_2U_LIB.S9S_MB_2U(SCH_1):GND     I9 @S9S_MB_2U_LIB.S9S_MB_2U(SCH_1):PAGE39
  EF61    GND @S9S_MB_2U_LIB.S9S_MB_2U(SCH_1):GND     I9 @S9S_MB_2U_LIB.S9S_MB_2U(SCH_1):PAGE39
  EF59    GND @S9S_MB_2U_LIB.S9S_MB_2U(SCH_1):GND     I9 @S9S_MB_2U_LIB.S9S_MB_2U(SCH_1):PAGE39
  EF57    GND @S9S_MB_2U_LIB.S9S_MB_2U(SCH_1):GND     I9 @S9S_MB_2U_LIB.S9S_MB_2U(SCH_1):PAGE39
  EF55    GND @S9S_MB_2U_LIB.S9S_MB_2U(SCH_1):GND     I9 @S9S_MB_2U_LIB.S9S_MB_2U(SCH_1):PAGE39
  EF53    GND @S9S_MB_2U_LIB.S9S_MB_2U(SCH_1):GND     I9 @S9S_MB_2U_LIB.S9S_MB_2U(SCH_1):PAGE39
  EF49    GND @S9S_MB_2U_LIB.S9S_MB_2U(SCH_1):GND     I9 @S9S_MB_2U_LIB.S9S_MB_2U(SCH_1):PAGE39
  EF47    GND @S9S_MB_2U_LIB.S9S_MB_2U(SCH_1):GND     I9 @S9S_MB_2U_LIB.S9S_MB_2U(SCH_1):PAGE39
  EF44    GND @S9S_MB_2U_LIB.S9S_MB_2U(SCH_1):GND     I9 @S9S_MB_2U_LIB.S9S_MB_2U(SCH_1):PAGE39
  EF42    GND @S9S_MB_2U_LIB.S9S_MB_2U(SCH_1):GND     I9 @S9S_MB_2U_LIB.S9S_MB_2U(SCH_1):PAGE39
  EF40    GND @S9S_MB_2U_LIB.S9S_MB_2U(SCH_1):GND     I9 @S9S_MB_2U_LIB.S9S_MB_2U(SCH_1):PAGE39
   EF4    GND @S9S_MB_2U_LIB.S9S_MB_2U(SCH_1):GND     I9 @S9S_MB_2U_LIB.S9S_MB_2U(SCH_1):PAGE39
  EF38    GND @S9S_MB_2U_LIB.S9S_MB_2U(SCH_1):GND     I9 @S9S_MB_2U_LIB.S9S_MB_2U(SCH_1):PAGE39
  EF36    GND @S9S_MB_2U_LIB.S9S_MB_2U(SCH_1):GND     I9 @S9S_MB_2U_LIB.S9S_MB_2U(SCH_1):PAGE39
  EF34    GND @S9S_MB_2U_LIB.S9S_MB_2U(SCH_1):GND     I9 @S9S_MB_2U_LIB.S9S_MB_2U(SCH_1):PAGE39
  EF32    GND @S9S_MB_2U_LIB.S9S_MB_2U(SCH_1):GND     I9 @S9S_MB_2U_LIB.S9S_MB_2U(SCH_1):PAGE39
  EF30    GND @S9S_MB_2U_LIB.S9S_MB_2U(SCH_1):GND     I9 @S9S_MB_2U_LIB.S9S_MB_2U(SCH_1):PAGE39
  EF28    GND @S9S_MB_2U_LIB.S9S_MB_2U(SCH_1):GND     I9 @S9S_MB_2U_LIB.S9S_MB_2U(SCH_1):PAGE39
  EF26    GND @S9S_MB_2U_LIB.S9S_MB_2U(SCH_1):GND     I9 @S9S_MB_2U_LIB.S9S_MB_2U(SCH_1):PAGE39
  EF24    GND @S9S_MB_2U_LIB.S9S_MB_2U(SCH_1):GND     I9 @S9S_MB_2U_LIB.S9S_MB_2U(SCH_1):PAGE39
  EF22    GND @S9S_MB_2U_LIB.S9S_MB_2U(SCH_1):GND     I9 @S9S_MB_2U_LIB.S9S_MB_2U(SCH_1):PAGE39
  EF20    GND @S9S_MB_2U_LIB.S9S_MB_2U(SCH_1):GND     I9 @S9S_MB_2U_LIB.S9S_MB_2U(SCH_1):PAGE39
   EF2    GND @S9S_MB_2U_LIB.S9S_MB_2U(SCH_1):GND     I9 @S9S_MB_2U_LIB.S9S_MB_2U(SCH_1):PAGE39
  EF18    GND @S9S_MB_2U_LIB.S9S_MB_2U(SCH_1):GND     I9 @S9S_MB_2U_LIB.S9S_MB_2U(SCH_1):PAGE39
  EF16    GND @S9S_MB_2U_LIB.S9S_MB_2U(SCH_1):GND     I9 @S9S_MB_2U_LIB.S9S_MB_2U(SCH_1):PAGE39
  EF12    GND @S9S_MB_2U_LIB.S9S_MB_2U(SCH_1):GND     I9 @S9S_MB_2U_LIB.S9S_MB_2U(SCH_1):PAGE39
  EE88    GND @S9S_MB_2U_LIB.S9S_MB_2U(SCH_1):GND     I9 @S9S_MB_2U_LIB.S9S_MB_2U(SCH_1):PAGE39
  EE80    GND @S9S_MB_2U_LIB.S9S_MB_2U(SCH_1):GND     I9 @S9S_MB_2U_LIB.S9S_MB_2U(SCH_1):PAGE39
  EE78    GND @S9S_MB_2U_LIB.S9S_MB_2U(SCH_1):GND     I9 @S9S_MB_2U_LIB.S9S_MB_2U(SCH_1):PAGE39
   ED8    GND @S9S_MB_2U_LIB.S9S_MB_2U(SCH_1):GND     I9 @S9S_MB_2U_LIB.S9S_MB_2U(SCH_1):PAGE39
  ED49    GND @S9S_MB_2U_LIB.S9S_MB_2U(SCH_1):GND     I9 @S9S_MB_2U_LIB.S9S_MB_2U(SCH_1):PAGE39
   ED4    GND @S9S_MB_2U_LIB.S9S_MB_2U(SCH_1):GND     I9 @S9S_MB_2U_LIB.S9S_MB_2U(SCH_1):PAGE39
  ED36    GND @S9S_MB_2U_LIB.S9S_MB_2U(SCH_1):GND     I9 @S9S_MB_2U_LIB.S9S_MB_2U(SCH_1):PAGE39
  ED30    GND @S9S_MB_2U_LIB.S9S_MB_2U(SCH_1):GND     I9 @S9S_MB_2U_LIB.S9S_MB_2U(SCH_1):PAGE39
  ED24    GND @S9S_MB_2U_LIB.S9S_MB_2U(SCH_1):GND     I9 @S9S_MB_2U_LIB.S9S_MB_2U(SCH_1):PAGE39
  ED16    GND @S9S_MB_2U_LIB.S9S_MB_2U(SCH_1):GND     I9 @S9S_MB_2U_LIB.S9S_MB_2U(SCH_1):PAGE39
   EC9    GND @S9S_MB_2U_LIB.S9S_MB_2U(SCH_1):GND     I9 @S9S_MB_2U_LIB.S9S_MB_2U(SCH_1):PAGE39
  EC88    GND @S9S_MB_2U_LIB.S9S_MB_2U(SCH_1):GND     I9 @S9S_MB_2U_LIB.S9S_MB_2U(SCH_1):PAGE39
  EC84    GND @S9S_MB_2U_LIB.S9S_MB_2U(SCH_1):GND     I9 @S9S_MB_2U_LIB.S9S_MB_2U(SCH_1):PAGE39
  EC82    GND @S9S_MB_2U_LIB.S9S_MB_2U(SCH_1):GND     I9 @S9S_MB_2U_LIB.S9S_MB_2U(SCH_1):PAGE39
  EC74    GND @S9S_MB_2U_LIB.S9S_MB_2U(SCH_1):GND     I9 @S9S_MB_2U_LIB.S9S_MB_2U(SCH_1):PAGE39
  EC72    GND @S9S_MB_2U_LIB.S9S_MB_2U(SCH_1):GND     I9 @S9S_MB_2U_LIB.S9S_MB_2U(SCH_1):PAGE39
  EC66    GND @S9S_MB_2U_LIB.S9S_MB_2U(SCH_1):GND     I9 @S9S_MB_2U_LIB.S9S_MB_2U(SCH_1):PAGE39
  EC56    GND @S9S_MB_2U_LIB.S9S_MB_2U(SCH_1):GND     I9 @S9S_MB_2U_LIB.S9S_MB_2U(SCH_1):PAGE39
  EC50    GND @S9S_MB_2U_LIB.S9S_MB_2U(SCH_1):GND     I9 @S9S_MB_2U_LIB.S9S_MB_2U(SCH_1):PAGE39
  EC48    GND @S9S_MB_2U_LIB.S9S_MB_2U(SCH_1):GND     I9 @S9S_MB_2U_LIB.S9S_MB_2U(SCH_1):PAGE39
  EC43    GND @S9S_MB_2U_LIB.S9S_MB_2U(SCH_1):GND     I9 @S9S_MB_2U_LIB.S9S_MB_2U(SCH_1):PAGE39
  EC41    GND @S9S_MB_2U_LIB.S9S_MB_2U(SCH_1):GND     I9 @S9S_MB_2U_LIB.S9S_MB_2U(SCH_1):PAGE39
   EH6    GND @S9S_MB_2U_LIB.S9S_MB_2U(SCH_1):GND     I9 @S9S_MB_2U_LIB.S9S_MB_2U(SCH_1):PAGE39
  EC37    GND @S9S_MB_2U_LIB.S9S_MB_2U(SCH_1):GND     I9 @S9S_MB_2U_LIB.S9S_MB_2U(SCH_1):PAGE39
  EC31    GND @S9S_MB_2U_LIB.S9S_MB_2U(SCH_1):GND     I9 @S9S_MB_2U_LIB.S9S_MB_2U(SCH_1):PAGE39
  EC29    GND @S9S_MB_2U_LIB.S9S_MB_2U(SCH_1):GND     I9 @S9S_MB_2U_LIB.S9S_MB_2U(SCH_1):PAGE39
  EC23    GND @S9S_MB_2U_LIB.S9S_MB_2U(SCH_1):GND     I9 @S9S_MB_2U_LIB.S9S_MB_2U(SCH_1):PAGE39
  EC19    GND @S9S_MB_2U_LIB.S9S_MB_2U(SCH_1):GND     I9 @S9S_MB_2U_LIB.S9S_MB_2U(SCH_1):PAGE39
  EC13    GND @S9S_MB_2U_LIB.S9S_MB_2U(SCH_1):GND     I9 @S9S_MB_2U_LIB.S9S_MB_2U(SCH_1):PAGE39
   EC1    GND @S9S_MB_2U_LIB.S9S_MB_2U(SCH_1):GND     I9 @S9S_MB_2U_LIB.S9S_MB_2U(SCH_1):PAGE39
  EB87    GND @S9S_MB_2U_LIB.S9S_MB_2U(SCH_1):GND     I9 @S9S_MB_2U_LIB.S9S_MB_2U(SCH_1):PAGE39
  EB83    GND @S9S_MB_2U_LIB.S9S_MB_2U(SCH_1):GND     I9 @S9S_MB_2U_LIB.S9S_MB_2U(SCH_1):PAGE39
   EB8    GND @S9S_MB_2U_LIB.S9S_MB_2U(SCH_1):GND     I9 @S9S_MB_2U_LIB.S9S_MB_2U(SCH_1):PAGE39
  EH18    GND @S9S_MB_2U_LIB.S9S_MB_2U(SCH_1):GND     I9 @S9S_MB_2U_LIB.S9S_MB_2U(SCH_1):PAGE39
  EB79    GND @S9S_MB_2U_LIB.S9S_MB_2U(SCH_1):GND     I9 @S9S_MB_2U_LIB.S9S_MB_2U(SCH_1):PAGE39
  EH14    GND @S9S_MB_2U_LIB.S9S_MB_2U(SCH_1):GND     I9 @S9S_MB_2U_LIB.S9S_MB_2U(SCH_1):PAGE39
  EH12    GND @S9S_MB_2U_LIB.S9S_MB_2U(SCH_1):GND     I9 @S9S_MB_2U_LIB.S9S_MB_2U(SCH_1):PAGE39
  EB75    GND @S9S_MB_2U_LIB.S9S_MB_2U(SCH_1):GND     I9 @S9S_MB_2U_LIB.S9S_MB_2U(SCH_1):PAGE39
  EB71    GND @S9S_MB_2U_LIB.S9S_MB_2U(SCH_1):GND     I9 @S9S_MB_2U_LIB.S9S_MB_2U(SCH_1):PAGE39
  EB69    GND @S9S_MB_2U_LIB.S9S_MB_2U(SCH_1):GND     I9 @S9S_MB_2U_LIB.S9S_MB_2U(SCH_1):PAGE39
  EB65    GND @S9S_MB_2U_LIB.S9S_MB_2U(SCH_1):GND     I9 @S9S_MB_2U_LIB.S9S_MB_2U(SCH_1):PAGE39
  EB57    GND @S9S_MB_2U_LIB.S9S_MB_2U(SCH_1):GND     I9 @S9S_MB_2U_LIB.S9S_MB_2U(SCH_1):PAGE39
  EB47    GND @S9S_MB_2U_LIB.S9S_MB_2U(SCH_1):GND     I9 @S9S_MB_2U_LIB.S9S_MB_2U(SCH_1):PAGE39
  EB40    GND @S9S_MB_2U_LIB.S9S_MB_2U(SCH_1):GND     I9 @S9S_MB_2U_LIB.S9S_MB_2U(SCH_1):PAGE39
   EG7    GND @S9S_MB_2U_LIB.S9S_MB_2U(SCH_1):GND     I9 @S9S_MB_2U_LIB.S9S_MB_2U(SCH_1):PAGE39
  EB38    GND @S9S_MB_2U_LIB.S9S_MB_2U(SCH_1):GND     I9 @S9S_MB_2U_LIB.S9S_MB_2U(SCH_1):PAGE39
  EB32    GND @S9S_MB_2U_LIB.S9S_MB_2U(SCH_1):GND     I9 @S9S_MB_2U_LIB.S9S_MB_2U(SCH_1):PAGE39
  EG52    GND @S9S_MB_2U_LIB.S9S_MB_2U(SCH_1):GND     I9 @S9S_MB_2U_LIB.S9S_MB_2U(SCH_1):PAGE39
   EG5    GND @S9S_MB_2U_LIB.S9S_MB_2U(SCH_1):GND     I9 @S9S_MB_2U_LIB.S9S_MB_2U(SCH_1):PAGE39
  EB28    GND @S9S_MB_2U_LIB.S9S_MB_2U(SCH_1):GND     I9 @S9S_MB_2U_LIB.S9S_MB_2U(SCH_1):PAGE39
  EB22    GND @S9S_MB_2U_LIB.S9S_MB_2U(SCH_1):GND     I9 @S9S_MB_2U_LIB.S9S_MB_2U(SCH_1):PAGE39
  EB12    GND @S9S_MB_2U_LIB.S9S_MB_2U(SCH_1):GND     I9 @S9S_MB_2U_LIB.S9S_MB_2U(SCH_1):PAGE39
  EA88    GND @S9S_MB_2U_LIB.S9S_MB_2U(SCH_1):GND     I9 @S9S_MB_2U_LIB.S9S_MB_2U(SCH_1):PAGE39
  EA84    GND @S9S_MB_2U_LIB.S9S_MB_2U(SCH_1):GND     I9 @S9S_MB_2U_LIB.S9S_MB_2U(SCH_1):PAGE39
  EG13    GND @S9S_MB_2U_LIB.S9S_MB_2U(SCH_1):GND     I9 @S9S_MB_2U_LIB.S9S_MB_2U(SCH_1):PAGE39
  EF89    GND @S9S_MB_2U_LIB.S9S_MB_2U(SCH_1):GND     I9 @S9S_MB_2U_LIB.S9S_MB_2U(SCH_1):PAGE39
  EA80    GND @S9S_MB_2U_LIB.S9S_MB_2U(SCH_1):GND     I9 @S9S_MB_2U_LIB.S9S_MB_2U(SCH_1):PAGE39
  EA78    GND @S9S_MB_2U_LIB.S9S_MB_2U(SCH_1):GND     I9 @S9S_MB_2U_LIB.S9S_MB_2U(SCH_1):PAGE39
  EA76    GND @S9S_MB_2U_LIB.S9S_MB_2U(SCH_1):GND     I9 @S9S_MB_2U_LIB.S9S_MB_2U(SCH_1):PAGE39
  EA70    GND @S9S_MB_2U_LIB.S9S_MB_2U(SCH_1):GND     I9 @S9S_MB_2U_LIB.S9S_MB_2U(SCH_1):PAGE39
  EA33    GND @S9S_MB_2U_LIB.S9S_MB_2U(SCH_1):GND     I9 @S9S_MB_2U_LIB.S9S_MB_2U(SCH_1):PAGE39
  EF75    GND @S9S_MB_2U_LIB.S9S_MB_2U(SCH_1):GND     I9 @S9S_MB_2U_LIB.S9S_MB_2U(SCH_1):PAGE39
  EF73    GND @S9S_MB_2U_LIB.S9S_MB_2U(SCH_1):GND     I9 @S9S_MB_2U_LIB.S9S_MB_2U(SCH_1):PAGE39
  EA27    GND @S9S_MB_2U_LIB.S9S_MB_2U(SCH_1):GND     I9 @S9S_MB_2U_LIB.S9S_MB_2U(SCH_1):PAGE39
  EA21    GND @S9S_MB_2U_LIB.S9S_MB_2U(SCH_1):GND     I9 @S9S_MB_2U_LIB.S9S_MB_2U(SCH_1):PAGE39
   DY8    GND @S9S_MB_2U_LIB.S9S_MB_2U(SCH_1):GND     I9 @S9S_MB_2U_LIB.S9S_MB_2U(SCH_1):PAGE39
  DY77    GND @S9S_MB_2U_LIB.S9S_MB_2U(SCH_1):GND     I9 @S9S_MB_2U_LIB.S9S_MB_2U(SCH_1):PAGE39
  DW88    GND @S9S_MB_2U_LIB.S9S_MB_2U(SCH_1):GND     I9 @S9S_MB_2U_LIB.S9S_MB_2U(SCH_1):PAGE39
  DW84    GND @S9S_MB_2U_LIB.S9S_MB_2U(SCH_1):GND     I9 @S9S_MB_2U_LIB.S9S_MB_2U(SCH_1):PAGE39
  EF51    GND @S9S_MB_2U_LIB.S9S_MB_2U(SCH_1):GND     I9 @S9S_MB_2U_LIB.S9S_MB_2U(SCH_1):PAGE39
  DW82    GND @S9S_MB_2U_LIB.S9S_MB_2U(SCH_1):GND     I9 @S9S_MB_2U_LIB.S9S_MB_2U(SCH_1):PAGE39
  DW80    GND @S9S_MB_2U_LIB.S9S_MB_2U(SCH_1):GND     I9 @S9S_MB_2U_LIB.S9S_MB_2U(SCH_1):PAGE39
  DW76    GND @S9S_MB_2U_LIB.S9S_MB_2U(SCH_1):GND     I9 @S9S_MB_2U_LIB.S9S_MB_2U(SCH_1):PAGE39
  DW74    GND @S9S_MB_2U_LIB.S9S_MB_2U(SCH_1):GND     I9 @S9S_MB_2U_LIB.S9S_MB_2U(SCH_1):PAGE39
  DW72    GND @S9S_MB_2U_LIB.S9S_MB_2U(SCH_1):GND     I9 @S9S_MB_2U_LIB.S9S_MB_2U(SCH_1):PAGE39
  DW70    GND @S9S_MB_2U_LIB.S9S_MB_2U(SCH_1):GND     I9 @S9S_MB_2U_LIB.S9S_MB_2U(SCH_1):PAGE39
  DW68    GND @S9S_MB_2U_LIB.S9S_MB_2U(SCH_1):GND     I9 @S9S_MB_2U_LIB.S9S_MB_2U(SCH_1):PAGE39
  DW66    GND @S9S_MB_2U_LIB.S9S_MB_2U(SCH_1):GND     I9 @S9S_MB_2U_LIB.S9S_MB_2U(SCH_1):PAGE39
  EE52    GND @S9S_MB_2U_LIB.S9S_MB_2U(SCH_1):GND     I9 @S9S_MB_2U_LIB.S9S_MB_2U(SCH_1):PAGE39
  EE39    GND @S9S_MB_2U_LIB.S9S_MB_2U(SCH_1):GND     I9 @S9S_MB_2U_LIB.S9S_MB_2U(SCH_1):PAGE39
  EE17    GND @S9S_MB_2U_LIB.S9S_MB_2U(SCH_1):GND     I9 @S9S_MB_2U_LIB.S9S_MB_2U(SCH_1):PAGE39
  ED73    GND @S9S_MB_2U_LIB.S9S_MB_2U(SCH_1):GND     I9 @S9S_MB_2U_LIB.S9S_MB_2U(SCH_1):PAGE39
  ED67    GND @S9S_MB_2U_LIB.S9S_MB_2U(SCH_1):GND     I9 @S9S_MB_2U_LIB.S9S_MB_2U(SCH_1):PAGE39
  ED61    GND @S9S_MB_2U_LIB.S9S_MB_2U(SCH_1):GND     I9 @S9S_MB_2U_LIB.S9S_MB_2U(SCH_1):PAGE39
  ED55    GND @S9S_MB_2U_LIB.S9S_MB_2U(SCH_1):GND     I9 @S9S_MB_2U_LIB.S9S_MB_2U(SCH_1):PAGE39
  ED42    GND @S9S_MB_2U_LIB.S9S_MB_2U(SCH_1):GND     I9 @S9S_MB_2U_LIB.S9S_MB_2U(SCH_1):PAGE39
  ED18    GND @S9S_MB_2U_LIB.S9S_MB_2U(SCH_1):GND     I9 @S9S_MB_2U_LIB.S9S_MB_2U(SCH_1):PAGE39
  ED12    GND @S9S_MB_2U_LIB.S9S_MB_2U(SCH_1):GND     I9 @S9S_MB_2U_LIB.S9S_MB_2U(SCH_1):PAGE39
  EC68    GND @S9S_MB_2U_LIB.S9S_MB_2U(SCH_1):GND     I9 @S9S_MB_2U_LIB.S9S_MB_2U(SCH_1):PAGE39
  EC62    GND @S9S_MB_2U_LIB.S9S_MB_2U(SCH_1):GND     I9 @S9S_MB_2U_LIB.S9S_MB_2U(SCH_1):PAGE39
  EC60    GND @S9S_MB_2U_LIB.S9S_MB_2U(SCH_1):GND     I9 @S9S_MB_2U_LIB.S9S_MB_2U(SCH_1):PAGE39
  EC54    GND @S9S_MB_2U_LIB.S9S_MB_2U(SCH_1):GND     I9 @S9S_MB_2U_LIB.S9S_MB_2U(SCH_1):PAGE39
   EC5    GND @S9S_MB_2U_LIB.S9S_MB_2U(SCH_1):GND     I9 @S9S_MB_2U_LIB.S9S_MB_2U(SCH_1):PAGE39
  EC35    GND @S9S_MB_2U_LIB.S9S_MB_2U(SCH_1):GND     I9 @S9S_MB_2U_LIB.S9S_MB_2U(SCH_1):PAGE39
  EC25    GND @S9S_MB_2U_LIB.S9S_MB_2U(SCH_1):GND     I9 @S9S_MB_2U_LIB.S9S_MB_2U(SCH_1):PAGE39
  EB91    GND @S9S_MB_2U_LIB.S9S_MB_2U(SCH_1):GND     I9 @S9S_MB_2U_LIB.S9S_MB_2U(SCH_1):PAGE39
  EB63    GND @S9S_MB_2U_LIB.S9S_MB_2U(SCH_1):GND     I9 @S9S_MB_2U_LIB.S9S_MB_2U(SCH_1):PAGE39
  EB59    GND @S9S_MB_2U_LIB.S9S_MB_2U(SCH_1):GND     I9 @S9S_MB_2U_LIB.S9S_MB_2U(SCH_1):PAGE39
  EB53    GND @S9S_MB_2U_LIB.S9S_MB_2U(SCH_1):GND     I9 @S9S_MB_2U_LIB.S9S_MB_2U(SCH_1):PAGE39
  EB51    GND @S9S_MB_2U_LIB.S9S_MB_2U(SCH_1):GND     I9 @S9S_MB_2U_LIB.S9S_MB_2U(SCH_1):PAGE39
  EB44    GND @S9S_MB_2U_LIB.S9S_MB_2U(SCH_1):GND     I9 @S9S_MB_2U_LIB.S9S_MB_2U(SCH_1):PAGE39
   EB4    GND @S9S_MB_2U_LIB.S9S_MB_2U(SCH_1):GND     I9 @S9S_MB_2U_LIB.S9S_MB_2U(SCH_1):PAGE39
  EB34    GND @S9S_MB_2U_LIB.S9S_MB_2U(SCH_1):GND     I9 @S9S_MB_2U_LIB.S9S_MB_2U(SCH_1):PAGE39
  EB26    GND @S9S_MB_2U_LIB.S9S_MB_2U(SCH_1):GND     I9 @S9S_MB_2U_LIB.S9S_MB_2U(SCH_1):PAGE39
  EB20    GND @S9S_MB_2U_LIB.S9S_MB_2U(SCH_1):GND     I9 @S9S_MB_2U_LIB.S9S_MB_2U(SCH_1):PAGE39
  EB16    GND @S9S_MB_2U_LIB.S9S_MB_2U(SCH_1):GND     I9 @S9S_MB_2U_LIB.S9S_MB_2U(SCH_1):PAGE39
  EA64    GND @S9S_MB_2U_LIB.S9S_MB_2U(SCH_1):GND     I9 @S9S_MB_2U_LIB.S9S_MB_2U(SCH_1):PAGE39
  EA58    GND @S9S_MB_2U_LIB.S9S_MB_2U(SCH_1):GND     I9 @S9S_MB_2U_LIB.S9S_MB_2U(SCH_1):PAGE39
  EA52    GND @S9S_MB_2U_LIB.S9S_MB_2U(SCH_1):GND     I9 @S9S_MB_2U_LIB.S9S_MB_2U(SCH_1):PAGE39
  EA45    GND @S9S_MB_2U_LIB.S9S_MB_2U(SCH_1):GND     I9 @S9S_MB_2U_LIB.S9S_MB_2U(SCH_1):PAGE39
  EA39    GND @S9S_MB_2U_LIB.S9S_MB_2U(SCH_1):GND     I9 @S9S_MB_2U_LIB.S9S_MB_2U(SCH_1):PAGE39
  DY42    GND @S9S_MB_2U_LIB.S9S_MB_2U(SCH_1):GND     I9 @S9S_MB_2U_LIB.S9S_MB_2U(SCH_1):PAGE39
   DY4    GND @S9S_MB_2U_LIB.S9S_MB_2U(SCH_1):GND     I9 @S9S_MB_2U_LIB.S9S_MB_2U(SCH_1):PAGE39
  DY16    GND @S9S_MB_2U_LIB.S9S_MB_2U(SCH_1):GND     I9 @S9S_MB_2U_LIB.S9S_MB_2U(SCH_1):PAGE39
  DY12    GND @S9S_MB_2U_LIB.S9S_MB_2U(SCH_1):GND     I9 @S9S_MB_2U_LIB.S9S_MB_2U(SCH_1):PAGE39
   DW9    GND @S9S_MB_2U_LIB.S9S_MB_2U(SCH_1):GND    I10 @S9S_MB_2U_LIB.S9S_MB_2U(SCH_1):PAGE39
  DW64    GND @S9S_MB_2U_LIB.S9S_MB_2U(SCH_1):GND    I10 @S9S_MB_2U_LIB.S9S_MB_2U(SCH_1):PAGE39
  DW62    GND @S9S_MB_2U_LIB.S9S_MB_2U(SCH_1):GND    I10 @S9S_MB_2U_LIB.S9S_MB_2U(SCH_1):PAGE39
  DW58    GND @S9S_MB_2U_LIB.S9S_MB_2U(SCH_1):GND    I10 @S9S_MB_2U_LIB.S9S_MB_2U(SCH_1):PAGE39
  DW56    GND @S9S_MB_2U_LIB.S9S_MB_2U(SCH_1):GND    I10 @S9S_MB_2U_LIB.S9S_MB_2U(SCH_1):PAGE39
  DW54    GND @S9S_MB_2U_LIB.S9S_MB_2U(SCH_1):GND    I10 @S9S_MB_2U_LIB.S9S_MB_2U(SCH_1):PAGE39
  DW52    GND @S9S_MB_2U_LIB.S9S_MB_2U(SCH_1):GND    I10 @S9S_MB_2U_LIB.S9S_MB_2U(SCH_1):PAGE39
  DW50    GND @S9S_MB_2U_LIB.S9S_MB_2U(SCH_1):GND    I10 @S9S_MB_2U_LIB.S9S_MB_2U(SCH_1):PAGE39
   DW5    GND @S9S_MB_2U_LIB.S9S_MB_2U(SCH_1):GND    I10 @S9S_MB_2U_LIB.S9S_MB_2U(SCH_1):PAGE39
  DW48    GND @S9S_MB_2U_LIB.S9S_MB_2U(SCH_1):GND    I10 @S9S_MB_2U_LIB.S9S_MB_2U(SCH_1):PAGE39
  DW45    GND @S9S_MB_2U_LIB.S9S_MB_2U(SCH_1):GND    I10 @S9S_MB_2U_LIB.S9S_MB_2U(SCH_1):PAGE39
  DW43    GND @S9S_MB_2U_LIB.S9S_MB_2U(SCH_1):GND    I10 @S9S_MB_2U_LIB.S9S_MB_2U(SCH_1):PAGE39
  DW41    GND @S9S_MB_2U_LIB.S9S_MB_2U(SCH_1):GND    I10 @S9S_MB_2U_LIB.S9S_MB_2U(SCH_1):PAGE39
  DW39    GND @S9S_MB_2U_LIB.S9S_MB_2U(SCH_1):GND    I10 @S9S_MB_2U_LIB.S9S_MB_2U(SCH_1):PAGE39
  DW37    GND @S9S_MB_2U_LIB.S9S_MB_2U(SCH_1):GND    I10 @S9S_MB_2U_LIB.S9S_MB_2U(SCH_1):PAGE39
  DW35    GND @S9S_MB_2U_LIB.S9S_MB_2U(SCH_1):GND    I10 @S9S_MB_2U_LIB.S9S_MB_2U(SCH_1):PAGE39
  DW33    GND @S9S_MB_2U_LIB.S9S_MB_2U(SCH_1):GND    I10 @S9S_MB_2U_LIB.S9S_MB_2U(SCH_1):PAGE39
  DW31    GND @S9S_MB_2U_LIB.S9S_MB_2U(SCH_1):GND    I10 @S9S_MB_2U_LIB.S9S_MB_2U(SCH_1):PAGE39
  DW29    GND @S9S_MB_2U_LIB.S9S_MB_2U(SCH_1):GND    I10 @S9S_MB_2U_LIB.S9S_MB_2U(SCH_1):PAGE39
  DW27    GND @S9S_MB_2U_LIB.S9S_MB_2U(SCH_1):GND    I10 @S9S_MB_2U_LIB.S9S_MB_2U(SCH_1):PAGE39
  DW25    GND @S9S_MB_2U_LIB.S9S_MB_2U(SCH_1):GND    I10 @S9S_MB_2U_LIB.S9S_MB_2U(SCH_1):PAGE39
  DW23    GND @S9S_MB_2U_LIB.S9S_MB_2U(SCH_1):GND    I10 @S9S_MB_2U_LIB.S9S_MB_2U(SCH_1):PAGE39
  DW19    GND @S9S_MB_2U_LIB.S9S_MB_2U(SCH_1):GND    I10 @S9S_MB_2U_LIB.S9S_MB_2U(SCH_1):PAGE39
  DW17    GND @S9S_MB_2U_LIB.S9S_MB_2U(SCH_1):GND    I10 @S9S_MB_2U_LIB.S9S_MB_2U(SCH_1):PAGE39
  DW13    GND @S9S_MB_2U_LIB.S9S_MB_2U(SCH_1):GND    I10 @S9S_MB_2U_LIB.S9S_MB_2U(SCH_1):PAGE39
   DW1    GND @S9S_MB_2U_LIB.S9S_MB_2U(SCH_1):GND    I10 @S9S_MB_2U_LIB.S9S_MB_2U(SCH_1):PAGE39
  DV91    GND @S9S_MB_2U_LIB.S9S_MB_2U(SCH_1):GND    I10 @S9S_MB_2U_LIB.S9S_MB_2U(SCH_1):PAGE39
  DV87    GND @S9S_MB_2U_LIB.S9S_MB_2U(SCH_1):GND    I10 @S9S_MB_2U_LIB.S9S_MB_2U(SCH_1):PAGE39
  DV83    GND @S9S_MB_2U_LIB.S9S_MB_2U(SCH_1):GND    I10 @S9S_MB_2U_LIB.S9S_MB_2U(SCH_1):PAGE39
  DV81    GND @S9S_MB_2U_LIB.S9S_MB_2U(SCH_1):GND    I10 @S9S_MB_2U_LIB.S9S_MB_2U(SCH_1):PAGE39
   DV8    GND @S9S_MB_2U_LIB.S9S_MB_2U(SCH_1):GND    I10 @S9S_MB_2U_LIB.S9S_MB_2U(SCH_1):PAGE39
  DV79    GND @S9S_MB_2U_LIB.S9S_MB_2U(SCH_1):GND    I10 @S9S_MB_2U_LIB.S9S_MB_2U(SCH_1):PAGE39
  DV77    GND @S9S_MB_2U_LIB.S9S_MB_2U(SCH_1):GND    I10 @S9S_MB_2U_LIB.S9S_MB_2U(SCH_1):PAGE39
  DU88    GND @S9S_MB_2U_LIB.S9S_MB_2U(SCH_1):GND    I10 @S9S_MB_2U_LIB.S9S_MB_2U(SCH_1):PAGE39
  DU84    GND @S9S_MB_2U_LIB.S9S_MB_2U(SCH_1):GND    I10 @S9S_MB_2U_LIB.S9S_MB_2U(SCH_1):PAGE39
  DU78    GND @S9S_MB_2U_LIB.S9S_MB_2U(SCH_1):GND    I10 @S9S_MB_2U_LIB.S9S_MB_2U(SCH_1):PAGE39
  DU76    GND @S9S_MB_2U_LIB.S9S_MB_2U(SCH_1):GND    I10 @S9S_MB_2U_LIB.S9S_MB_2U(SCH_1):PAGE39
  DU33    GND @S9S_MB_2U_LIB.S9S_MB_2U(SCH_1):GND    I10 @S9S_MB_2U_LIB.S9S_MB_2U(SCH_1):PAGE39
  DU27    GND @S9S_MB_2U_LIB.S9S_MB_2U(SCH_1):GND    I10 @S9S_MB_2U_LIB.S9S_MB_2U(SCH_1):PAGE39
  DU21    GND @S9S_MB_2U_LIB.S9S_MB_2U(SCH_1):GND    I10 @S9S_MB_2U_LIB.S9S_MB_2U(SCH_1):PAGE39
   DT8    GND @S9S_MB_2U_LIB.S9S_MB_2U(SCH_1):GND    I10 @S9S_MB_2U_LIB.S9S_MB_2U(SCH_1):PAGE39
  DT75    GND @S9S_MB_2U_LIB.S9S_MB_2U(SCH_1):GND    I10 @S9S_MB_2U_LIB.S9S_MB_2U(SCH_1):PAGE39
  DT71    GND @S9S_MB_2U_LIB.S9S_MB_2U(SCH_1):GND    I10 @S9S_MB_2U_LIB.S9S_MB_2U(SCH_1):PAGE39
  DT69    GND @S9S_MB_2U_LIB.S9S_MB_2U(SCH_1):GND    I10 @S9S_MB_2U_LIB.S9S_MB_2U(SCH_1):PAGE39
  DT65    GND @S9S_MB_2U_LIB.S9S_MB_2U(SCH_1):GND    I10 @S9S_MB_2U_LIB.S9S_MB_2U(SCH_1):PAGE39
  DT57    GND @S9S_MB_2U_LIB.S9S_MB_2U(SCH_1):GND    I10 @S9S_MB_2U_LIB.S9S_MB_2U(SCH_1):PAGE39
  DT47    GND @S9S_MB_2U_LIB.S9S_MB_2U(SCH_1):GND    I10 @S9S_MB_2U_LIB.S9S_MB_2U(SCH_1):PAGE39
  DT40    GND @S9S_MB_2U_LIB.S9S_MB_2U(SCH_1):GND    I10 @S9S_MB_2U_LIB.S9S_MB_2U(SCH_1):PAGE39
  DT38    GND @S9S_MB_2U_LIB.S9S_MB_2U(SCH_1):GND    I10 @S9S_MB_2U_LIB.S9S_MB_2U(SCH_1):PAGE39
  DT34    GND @S9S_MB_2U_LIB.S9S_MB_2U(SCH_1):GND    I10 @S9S_MB_2U_LIB.S9S_MB_2U(SCH_1):PAGE39
  DT32    GND @S9S_MB_2U_LIB.S9S_MB_2U(SCH_1):GND    I10 @S9S_MB_2U_LIB.S9S_MB_2U(SCH_1):PAGE39
  DT28    GND @S9S_MB_2U_LIB.S9S_MB_2U(SCH_1):GND    I10 @S9S_MB_2U_LIB.S9S_MB_2U(SCH_1):PAGE39
  DT22    GND @S9S_MB_2U_LIB.S9S_MB_2U(SCH_1):GND    I10 @S9S_MB_2U_LIB.S9S_MB_2U(SCH_1):PAGE39
  DT12    GND @S9S_MB_2U_LIB.S9S_MB_2U(SCH_1):GND    I10 @S9S_MB_2U_LIB.S9S_MB_2U(SCH_1):PAGE39
   DR9    GND @S9S_MB_2U_LIB.S9S_MB_2U(SCH_1):GND    I10 @S9S_MB_2U_LIB.S9S_MB_2U(SCH_1):PAGE39
  DR88    GND @S9S_MB_2U_LIB.S9S_MB_2U(SCH_1):GND    I10 @S9S_MB_2U_LIB.S9S_MB_2U(SCH_1):PAGE39
  DR84    GND @S9S_MB_2U_LIB.S9S_MB_2U(SCH_1):GND    I10 @S9S_MB_2U_LIB.S9S_MB_2U(SCH_1):PAGE39
  DR78    GND @S9S_MB_2U_LIB.S9S_MB_2U(SCH_1):GND    I10 @S9S_MB_2U_LIB.S9S_MB_2U(SCH_1):PAGE39
  DR74    GND @S9S_MB_2U_LIB.S9S_MB_2U(SCH_1):GND    I10 @S9S_MB_2U_LIB.S9S_MB_2U(SCH_1):PAGE39
  DR66    GND @S9S_MB_2U_LIB.S9S_MB_2U(SCH_1):GND    I10 @S9S_MB_2U_LIB.S9S_MB_2U(SCH_1):PAGE39
  DR56    GND @S9S_MB_2U_LIB.S9S_MB_2U(SCH_1):GND    I10 @S9S_MB_2U_LIB.S9S_MB_2U(SCH_1):PAGE39
  DR50    GND @S9S_MB_2U_LIB.S9S_MB_2U(SCH_1):GND    I10 @S9S_MB_2U_LIB.S9S_MB_2U(SCH_1):PAGE39
  DR48    GND @S9S_MB_2U_LIB.S9S_MB_2U(SCH_1):GND    I10 @S9S_MB_2U_LIB.S9S_MB_2U(SCH_1):PAGE39
  DR43    GND @S9S_MB_2U_LIB.S9S_MB_2U(SCH_1):GND    I10 @S9S_MB_2U_LIB.S9S_MB_2U(SCH_1):PAGE39
  DR41    GND @S9S_MB_2U_LIB.S9S_MB_2U(SCH_1):GND    I10 @S9S_MB_2U_LIB.S9S_MB_2U(SCH_1):PAGE39
  DR37    GND @S9S_MB_2U_LIB.S9S_MB_2U(SCH_1):GND    I10 @S9S_MB_2U_LIB.S9S_MB_2U(SCH_1):PAGE39
  DR31    GND @S9S_MB_2U_LIB.S9S_MB_2U(SCH_1):GND    I10 @S9S_MB_2U_LIB.S9S_MB_2U(SCH_1):PAGE39
  DR29    GND @S9S_MB_2U_LIB.S9S_MB_2U(SCH_1):GND    I10 @S9S_MB_2U_LIB.S9S_MB_2U(SCH_1):PAGE39
  DR23    GND @S9S_MB_2U_LIB.S9S_MB_2U(SCH_1):GND    I10 @S9S_MB_2U_LIB.S9S_MB_2U(SCH_1):PAGE39
  DR19    GND @S9S_MB_2U_LIB.S9S_MB_2U(SCH_1):GND    I10 @S9S_MB_2U_LIB.S9S_MB_2U(SCH_1):PAGE39
  DR13    GND @S9S_MB_2U_LIB.S9S_MB_2U(SCH_1):GND    I10 @S9S_MB_2U_LIB.S9S_MB_2U(SCH_1):PAGE39
   DR1    GND @S9S_MB_2U_LIB.S9S_MB_2U(SCH_1):GND    I10 @S9S_MB_2U_LIB.S9S_MB_2U(SCH_1):PAGE39
  DP87    GND @S9S_MB_2U_LIB.S9S_MB_2U(SCH_1):GND    I10 @S9S_MB_2U_LIB.S9S_MB_2U(SCH_1):PAGE39
  DP81    GND @S9S_MB_2U_LIB.S9S_MB_2U(SCH_1):GND    I10 @S9S_MB_2U_LIB.S9S_MB_2U(SCH_1):PAGE39
   DP8    GND @S9S_MB_2U_LIB.S9S_MB_2U(SCH_1):GND    I10 @S9S_MB_2U_LIB.S9S_MB_2U(SCH_1):PAGE39
  DP73    GND @S9S_MB_2U_LIB.S9S_MB_2U(SCH_1):GND    I10 @S9S_MB_2U_LIB.S9S_MB_2U(SCH_1):PAGE39
  DP49    GND @S9S_MB_2U_LIB.S9S_MB_2U(SCH_1):GND    I10 @S9S_MB_2U_LIB.S9S_MB_2U(SCH_1):PAGE39
   DP4    GND @S9S_MB_2U_LIB.S9S_MB_2U(SCH_1):GND    I10 @S9S_MB_2U_LIB.S9S_MB_2U(SCH_1):PAGE39
  DP36    GND @S9S_MB_2U_LIB.S9S_MB_2U(SCH_1):GND    I10 @S9S_MB_2U_LIB.S9S_MB_2U(SCH_1):PAGE39
  DP30    GND @S9S_MB_2U_LIB.S9S_MB_2U(SCH_1):GND    I10 @S9S_MB_2U_LIB.S9S_MB_2U(SCH_1):PAGE39
  DP16    GND @S9S_MB_2U_LIB.S9S_MB_2U(SCH_1):GND    I10 @S9S_MB_2U_LIB.S9S_MB_2U(SCH_1):PAGE39
  DN88    GND @S9S_MB_2U_LIB.S9S_MB_2U(SCH_1):GND    I10 @S9S_MB_2U_LIB.S9S_MB_2U(SCH_1):PAGE39
  DN84    GND @S9S_MB_2U_LIB.S9S_MB_2U(SCH_1):GND    I10 @S9S_MB_2U_LIB.S9S_MB_2U(SCH_1):PAGE39
  DN78    GND @S9S_MB_2U_LIB.S9S_MB_2U(SCH_1):GND    I10 @S9S_MB_2U_LIB.S9S_MB_2U(SCH_1):PAGE39
   DM8    GND @S9S_MB_2U_LIB.S9S_MB_2U(SCH_1):GND    I10 @S9S_MB_2U_LIB.S9S_MB_2U(SCH_1):PAGE39
  DM79    GND @S9S_MB_2U_LIB.S9S_MB_2U(SCH_1):GND    I10 @S9S_MB_2U_LIB.S9S_MB_2U(SCH_1):PAGE39
  DM77    GND @S9S_MB_2U_LIB.S9S_MB_2U(SCH_1):GND    I10 @S9S_MB_2U_LIB.S9S_MB_2U(SCH_1):PAGE39
  DM75    GND @S9S_MB_2U_LIB.S9S_MB_2U(SCH_1):GND    I10 @S9S_MB_2U_LIB.S9S_MB_2U(SCH_1):PAGE39
  DM71    GND @S9S_MB_2U_LIB.S9S_MB_2U(SCH_1):GND    I10 @S9S_MB_2U_LIB.S9S_MB_2U(SCH_1):PAGE39
  DM69    GND @S9S_MB_2U_LIB.S9S_MB_2U(SCH_1):GND    I10 @S9S_MB_2U_LIB.S9S_MB_2U(SCH_1):PAGE39
  DM67    GND @S9S_MB_2U_LIB.S9S_MB_2U(SCH_1):GND    I10 @S9S_MB_2U_LIB.S9S_MB_2U(SCH_1):PAGE39
  DM65    GND @S9S_MB_2U_LIB.S9S_MB_2U(SCH_1):GND    I10 @S9S_MB_2U_LIB.S9S_MB_2U(SCH_1):PAGE39
  DM63    GND @S9S_MB_2U_LIB.S9S_MB_2U(SCH_1):GND    I10 @S9S_MB_2U_LIB.S9S_MB_2U(SCH_1):PAGE39
  DM61    GND @S9S_MB_2U_LIB.S9S_MB_2U(SCH_1):GND    I10 @S9S_MB_2U_LIB.S9S_MB_2U(SCH_1):PAGE39
  DM59    GND @S9S_MB_2U_LIB.S9S_MB_2U(SCH_1):GND    I10 @S9S_MB_2U_LIB.S9S_MB_2U(SCH_1):PAGE39
  DM57    GND @S9S_MB_2U_LIB.S9S_MB_2U(SCH_1):GND    I10 @S9S_MB_2U_LIB.S9S_MB_2U(SCH_1):PAGE39
  DM55    GND @S9S_MB_2U_LIB.S9S_MB_2U(SCH_1):GND    I10 @S9S_MB_2U_LIB.S9S_MB_2U(SCH_1):PAGE39
  DM53    GND @S9S_MB_2U_LIB.S9S_MB_2U(SCH_1):GND    I10 @S9S_MB_2U_LIB.S9S_MB_2U(SCH_1):PAGE39
  DM49    GND @S9S_MB_2U_LIB.S9S_MB_2U(SCH_1):GND    I10 @S9S_MB_2U_LIB.S9S_MB_2U(SCH_1):PAGE39
  DM47    GND @S9S_MB_2U_LIB.S9S_MB_2U(SCH_1):GND    I10 @S9S_MB_2U_LIB.S9S_MB_2U(SCH_1):PAGE39
  DM44    GND @S9S_MB_2U_LIB.S9S_MB_2U(SCH_1):GND    I10 @S9S_MB_2U_LIB.S9S_MB_2U(SCH_1):PAGE39
  DM42    GND @S9S_MB_2U_LIB.S9S_MB_2U(SCH_1):GND    I10 @S9S_MB_2U_LIB.S9S_MB_2U(SCH_1):PAGE39
  DM40    GND @S9S_MB_2U_LIB.S9S_MB_2U(SCH_1):GND    I10 @S9S_MB_2U_LIB.S9S_MB_2U(SCH_1):PAGE39
   DM4    GND @S9S_MB_2U_LIB.S9S_MB_2U(SCH_1):GND    I10 @S9S_MB_2U_LIB.S9S_MB_2U(SCH_1):PAGE39
  DM38    GND @S9S_MB_2U_LIB.S9S_MB_2U(SCH_1):GND    I10 @S9S_MB_2U_LIB.S9S_MB_2U(SCH_1):PAGE39
  DM36    GND @S9S_MB_2U_LIB.S9S_MB_2U(SCH_1):GND    I10 @S9S_MB_2U_LIB.S9S_MB_2U(SCH_1):PAGE39
  DM34    GND @S9S_MB_2U_LIB.S9S_MB_2U(SCH_1):GND    I10 @S9S_MB_2U_LIB.S9S_MB_2U(SCH_1):PAGE39
  DM32    GND @S9S_MB_2U_LIB.S9S_MB_2U(SCH_1):GND    I10 @S9S_MB_2U_LIB.S9S_MB_2U(SCH_1):PAGE39
  DM30    GND @S9S_MB_2U_LIB.S9S_MB_2U(SCH_1):GND    I10 @S9S_MB_2U_LIB.S9S_MB_2U(SCH_1):PAGE39
  DM28    GND @S9S_MB_2U_LIB.S9S_MB_2U(SCH_1):GND    I10 @S9S_MB_2U_LIB.S9S_MB_2U(SCH_1):PAGE39
  DM26    GND @S9S_MB_2U_LIB.S9S_MB_2U(SCH_1):GND    I10 @S9S_MB_2U_LIB.S9S_MB_2U(SCH_1):PAGE39
  DM24    GND @S9S_MB_2U_LIB.S9S_MB_2U(SCH_1):GND    I10 @S9S_MB_2U_LIB.S9S_MB_2U(SCH_1):PAGE39
  DM22    GND @S9S_MB_2U_LIB.S9S_MB_2U(SCH_1):GND    I10 @S9S_MB_2U_LIB.S9S_MB_2U(SCH_1):PAGE39
  DM20    GND @S9S_MB_2U_LIB.S9S_MB_2U(SCH_1):GND    I10 @S9S_MB_2U_LIB.S9S_MB_2U(SCH_1):PAGE39
  DM18    GND @S9S_MB_2U_LIB.S9S_MB_2U(SCH_1):GND    I10 @S9S_MB_2U_LIB.S9S_MB_2U(SCH_1):PAGE39
  DM16    GND @S9S_MB_2U_LIB.S9S_MB_2U(SCH_1):GND    I10 @S9S_MB_2U_LIB.S9S_MB_2U(SCH_1):PAGE39
  DM12    GND @S9S_MB_2U_LIB.S9S_MB_2U(SCH_1):GND    I10 @S9S_MB_2U_LIB.S9S_MB_2U(SCH_1):PAGE39
  DW60    GND @S9S_MB_2U_LIB.S9S_MB_2U(SCH_1):GND    I10 @S9S_MB_2U_LIB.S9S_MB_2U(SCH_1):PAGE39
  DW21    GND @S9S_MB_2U_LIB.S9S_MB_2U(SCH_1):GND    I10 @S9S_MB_2U_LIB.S9S_MB_2U(SCH_1):PAGE39
  DV42    GND @S9S_MB_2U_LIB.S9S_MB_2U(SCH_1):GND    I10 @S9S_MB_2U_LIB.S9S_MB_2U(SCH_1):PAGE39
   DV4    GND @S9S_MB_2U_LIB.S9S_MB_2U(SCH_1):GND    I10 @S9S_MB_2U_LIB.S9S_MB_2U(SCH_1):PAGE39
  DV16    GND @S9S_MB_2U_LIB.S9S_MB_2U(SCH_1):GND    I10 @S9S_MB_2U_LIB.S9S_MB_2U(SCH_1):PAGE39
  DV12    GND @S9S_MB_2U_LIB.S9S_MB_2U(SCH_1):GND    I10 @S9S_MB_2U_LIB.S9S_MB_2U(SCH_1):PAGE39
  DU70    GND @S9S_MB_2U_LIB.S9S_MB_2U(SCH_1):GND    I10 @S9S_MB_2U_LIB.S9S_MB_2U(SCH_1):PAGE39
  DU64    GND @S9S_MB_2U_LIB.S9S_MB_2U(SCH_1):GND    I10 @S9S_MB_2U_LIB.S9S_MB_2U(SCH_1):PAGE39
  DU58    GND @S9S_MB_2U_LIB.S9S_MB_2U(SCH_1):GND    I10 @S9S_MB_2U_LIB.S9S_MB_2U(SCH_1):PAGE39
  DU52    GND @S9S_MB_2U_LIB.S9S_MB_2U(SCH_1):GND    I10 @S9S_MB_2U_LIB.S9S_MB_2U(SCH_1):PAGE39
  DU45    GND @S9S_MB_2U_LIB.S9S_MB_2U(SCH_1):GND    I10 @S9S_MB_2U_LIB.S9S_MB_2U(SCH_1):PAGE39
  DU39    GND @S9S_MB_2U_LIB.S9S_MB_2U(SCH_1):GND    I10 @S9S_MB_2U_LIB.S9S_MB_2U(SCH_1):PAGE39
  DT83    GND @S9S_MB_2U_LIB.S9S_MB_2U(SCH_1):GND    I10 @S9S_MB_2U_LIB.S9S_MB_2U(SCH_1):PAGE39
  DT63    GND @S9S_MB_2U_LIB.S9S_MB_2U(SCH_1):GND    I10 @S9S_MB_2U_LIB.S9S_MB_2U(SCH_1):PAGE39
  DT59    GND @S9S_MB_2U_LIB.S9S_MB_2U(SCH_1):GND    I10 @S9S_MB_2U_LIB.S9S_MB_2U(SCH_1):PAGE39
  DT53    GND @S9S_MB_2U_LIB.S9S_MB_2U(SCH_1):GND    I10 @S9S_MB_2U_LIB.S9S_MB_2U(SCH_1):PAGE39
  DT51    GND @S9S_MB_2U_LIB.S9S_MB_2U(SCH_1):GND    I10 @S9S_MB_2U_LIB.S9S_MB_2U(SCH_1):PAGE39
  DT44    GND @S9S_MB_2U_LIB.S9S_MB_2U(SCH_1):GND    I10 @S9S_MB_2U_LIB.S9S_MB_2U(SCH_1):PAGE39
   DT4    GND @S9S_MB_2U_LIB.S9S_MB_2U(SCH_1):GND    I10 @S9S_MB_2U_LIB.S9S_MB_2U(SCH_1):PAGE39
  DT26    GND @S9S_MB_2U_LIB.S9S_MB_2U(SCH_1):GND    I10 @S9S_MB_2U_LIB.S9S_MB_2U(SCH_1):PAGE39
  DT20    GND @S9S_MB_2U_LIB.S9S_MB_2U(SCH_1):GND    I10 @S9S_MB_2U_LIB.S9S_MB_2U(SCH_1):PAGE39
  DT16    GND @S9S_MB_2U_LIB.S9S_MB_2U(SCH_1):GND    I10 @S9S_MB_2U_LIB.S9S_MB_2U(SCH_1):PAGE39
  DR72    GND @S9S_MB_2U_LIB.S9S_MB_2U(SCH_1):GND    I10 @S9S_MB_2U_LIB.S9S_MB_2U(SCH_1):PAGE39
  DR68    GND @S9S_MB_2U_LIB.S9S_MB_2U(SCH_1):GND    I10 @S9S_MB_2U_LIB.S9S_MB_2U(SCH_1):PAGE39
  DR62    GND @S9S_MB_2U_LIB.S9S_MB_2U(SCH_1):GND    I10 @S9S_MB_2U_LIB.S9S_MB_2U(SCH_1):PAGE39
  DR60    GND @S9S_MB_2U_LIB.S9S_MB_2U(SCH_1):GND    I10 @S9S_MB_2U_LIB.S9S_MB_2U(SCH_1):PAGE39
  DR54    GND @S9S_MB_2U_LIB.S9S_MB_2U(SCH_1):GND    I10 @S9S_MB_2U_LIB.S9S_MB_2U(SCH_1):PAGE39
   DR5    GND @S9S_MB_2U_LIB.S9S_MB_2U(SCH_1):GND    I10 @S9S_MB_2U_LIB.S9S_MB_2U(SCH_1):PAGE39
  DR35    GND @S9S_MB_2U_LIB.S9S_MB_2U(SCH_1):GND    I10 @S9S_MB_2U_LIB.S9S_MB_2U(SCH_1):PAGE39
  DR25    GND @S9S_MB_2U_LIB.S9S_MB_2U(SCH_1):GND    I10 @S9S_MB_2U_LIB.S9S_MB_2U(SCH_1):PAGE39
  DP91    GND @S9S_MB_2U_LIB.S9S_MB_2U(SCH_1):GND    I10 @S9S_MB_2U_LIB.S9S_MB_2U(SCH_1):PAGE39
  DP67    GND @S9S_MB_2U_LIB.S9S_MB_2U(SCH_1):GND    I10 @S9S_MB_2U_LIB.S9S_MB_2U(SCH_1):PAGE39
  DP61    GND @S9S_MB_2U_LIB.S9S_MB_2U(SCH_1):GND    I10 @S9S_MB_2U_LIB.S9S_MB_2U(SCH_1):PAGE39
  DP55    GND @S9S_MB_2U_LIB.S9S_MB_2U(SCH_1):GND    I10 @S9S_MB_2U_LIB.S9S_MB_2U(SCH_1):PAGE39
  DP42    GND @S9S_MB_2U_LIB.S9S_MB_2U(SCH_1):GND    I10 @S9S_MB_2U_LIB.S9S_MB_2U(SCH_1):PAGE39
  DP24    GND @S9S_MB_2U_LIB.S9S_MB_2U(SCH_1):GND    I10 @S9S_MB_2U_LIB.S9S_MB_2U(SCH_1):PAGE39
  DP18    GND @S9S_MB_2U_LIB.S9S_MB_2U(SCH_1):GND    I10 @S9S_MB_2U_LIB.S9S_MB_2U(SCH_1):PAGE39
  DP12    GND @S9S_MB_2U_LIB.S9S_MB_2U(SCH_1):GND    I10 @S9S_MB_2U_LIB.S9S_MB_2U(SCH_1):PAGE39
  DN52    GND @S9S_MB_2U_LIB.S9S_MB_2U(SCH_1):GND    I10 @S9S_MB_2U_LIB.S9S_MB_2U(SCH_1):PAGE39
  DN39    GND @S9S_MB_2U_LIB.S9S_MB_2U(SCH_1):GND    I10 @S9S_MB_2U_LIB.S9S_MB_2U(SCH_1):PAGE39
  DN17    GND @S9S_MB_2U_LIB.S9S_MB_2U(SCH_1):GND    I10 @S9S_MB_2U_LIB.S9S_MB_2U(SCH_1):PAGE39
  DM73    GND @S9S_MB_2U_LIB.S9S_MB_2U(SCH_1):GND    I10 @S9S_MB_2U_LIB.S9S_MB_2U(SCH_1):PAGE39
  DM51    GND @S9S_MB_2U_LIB.S9S_MB_2U(SCH_1):GND    I10 @S9S_MB_2U_LIB.S9S_MB_2U(SCH_1):PAGE39
   DL9    GND @S9S_MB_2U_LIB.S9S_MB_2U(SCH_1):GND    I10 @S9S_MB_2U_LIB.S9S_MB_2U(SCH_1):PAGE40
  DL88    GND @S9S_MB_2U_LIB.S9S_MB_2U(SCH_1):GND    I10 @S9S_MB_2U_LIB.S9S_MB_2U(SCH_1):PAGE40
  DL84    GND @S9S_MB_2U_LIB.S9S_MB_2U(SCH_1):GND    I10 @S9S_MB_2U_LIB.S9S_MB_2U(SCH_1):PAGE40
  DL39    GND @S9S_MB_2U_LIB.S9S_MB_2U(SCH_1):GND    I10 @S9S_MB_2U_LIB.S9S_MB_2U(SCH_1):PAGE40
  DK91    GND @S9S_MB_2U_LIB.S9S_MB_2U(SCH_1):GND    I10 @S9S_MB_2U_LIB.S9S_MB_2U(SCH_1):PAGE40
  DK87    GND @S9S_MB_2U_LIB.S9S_MB_2U(SCH_1):GND    I10 @S9S_MB_2U_LIB.S9S_MB_2U(SCH_1):PAGE40
  DK83    GND @S9S_MB_2U_LIB.S9S_MB_2U(SCH_1):GND    I10 @S9S_MB_2U_LIB.S9S_MB_2U(SCH_1):PAGE40
  DK81    GND @S9S_MB_2U_LIB.S9S_MB_2U(SCH_1):GND    I10 @S9S_MB_2U_LIB.S9S_MB_2U(SCH_1):PAGE40
   DK8    GND @S9S_MB_2U_LIB.S9S_MB_2U(SCH_1):GND    I10 @S9S_MB_2U_LIB.S9S_MB_2U(SCH_1):PAGE40
  DK79    GND @S9S_MB_2U_LIB.S9S_MB_2U(SCH_1):GND    I10 @S9S_MB_2U_LIB.S9S_MB_2U(SCH_1):PAGE40
  DK77    GND @S9S_MB_2U_LIB.S9S_MB_2U(SCH_1):GND    I10 @S9S_MB_2U_LIB.S9S_MB_2U(SCH_1):PAGE40
  DK73    GND @S9S_MB_2U_LIB.S9S_MB_2U(SCH_1):GND    I10 @S9S_MB_2U_LIB.S9S_MB_2U(SCH_1):PAGE40
  DK49    GND @S9S_MB_2U_LIB.S9S_MB_2U(SCH_1):GND    I10 @S9S_MB_2U_LIB.S9S_MB_2U(SCH_1):PAGE40
   DK4    GND @S9S_MB_2U_LIB.S9S_MB_2U(SCH_1):GND    I10 @S9S_MB_2U_LIB.S9S_MB_2U(SCH_1):PAGE40
  DK36    GND @S9S_MB_2U_LIB.S9S_MB_2U(SCH_1):GND    I10 @S9S_MB_2U_LIB.S9S_MB_2U(SCH_1):PAGE40
  DK30    GND @S9S_MB_2U_LIB.S9S_MB_2U(SCH_1):GND    I10 @S9S_MB_2U_LIB.S9S_MB_2U(SCH_1):PAGE40
  DK16    GND @S9S_MB_2U_LIB.S9S_MB_2U(SCH_1):GND    I10 @S9S_MB_2U_LIB.S9S_MB_2U(SCH_1):PAGE40
  DJ88    GND @S9S_MB_2U_LIB.S9S_MB_2U(SCH_1):GND    I10 @S9S_MB_2U_LIB.S9S_MB_2U(SCH_1):PAGE40
  DJ84    GND @S9S_MB_2U_LIB.S9S_MB_2U(SCH_1):GND    I10 @S9S_MB_2U_LIB.S9S_MB_2U(SCH_1):PAGE40
  DJ82    GND @S9S_MB_2U_LIB.S9S_MB_2U(SCH_1):GND    I10 @S9S_MB_2U_LIB.S9S_MB_2U(SCH_1):PAGE40
  DJ80    GND @S9S_MB_2U_LIB.S9S_MB_2U(SCH_1):GND    I10 @S9S_MB_2U_LIB.S9S_MB_2U(SCH_1):PAGE40
  DJ74    GND @S9S_MB_2U_LIB.S9S_MB_2U(SCH_1):GND    I10 @S9S_MB_2U_LIB.S9S_MB_2U(SCH_1):PAGE40
  DJ72    GND @S9S_MB_2U_LIB.S9S_MB_2U(SCH_1):GND    I10 @S9S_MB_2U_LIB.S9S_MB_2U(SCH_1):PAGE40
  DJ66    GND @S9S_MB_2U_LIB.S9S_MB_2U(SCH_1):GND    I10 @S9S_MB_2U_LIB.S9S_MB_2U(SCH_1):PAGE40
  DJ60    GND @S9S_MB_2U_LIB.S9S_MB_2U(SCH_1):GND    I10 @S9S_MB_2U_LIB.S9S_MB_2U(SCH_1):PAGE40
  DJ56    GND @S9S_MB_2U_LIB.S9S_MB_2U(SCH_1):GND    I10 @S9S_MB_2U_LIB.S9S_MB_2U(SCH_1):PAGE40
  DJ50    GND @S9S_MB_2U_LIB.S9S_MB_2U(SCH_1):GND    I10 @S9S_MB_2U_LIB.S9S_MB_2U(SCH_1):PAGE40
  DJ48    GND @S9S_MB_2U_LIB.S9S_MB_2U(SCH_1):GND    I10 @S9S_MB_2U_LIB.S9S_MB_2U(SCH_1):PAGE40
  DJ43    GND @S9S_MB_2U_LIB.S9S_MB_2U(SCH_1):GND    I10 @S9S_MB_2U_LIB.S9S_MB_2U(SCH_1):PAGE40
  DJ41    GND @S9S_MB_2U_LIB.S9S_MB_2U(SCH_1):GND    I10 @S9S_MB_2U_LIB.S9S_MB_2U(SCH_1):PAGE40
  DJ37    GND @S9S_MB_2U_LIB.S9S_MB_2U(SCH_1):GND    I10 @S9S_MB_2U_LIB.S9S_MB_2U(SCH_1):PAGE40
  DJ31    GND @S9S_MB_2U_LIB.S9S_MB_2U(SCH_1):GND    I10 @S9S_MB_2U_LIB.S9S_MB_2U(SCH_1):PAGE40
  DJ29    GND @S9S_MB_2U_LIB.S9S_MB_2U(SCH_1):GND    I10 @S9S_MB_2U_LIB.S9S_MB_2U(SCH_1):PAGE40
  DJ23    GND @S9S_MB_2U_LIB.S9S_MB_2U(SCH_1):GND    I10 @S9S_MB_2U_LIB.S9S_MB_2U(SCH_1):PAGE40
  DJ19    GND @S9S_MB_2U_LIB.S9S_MB_2U(SCH_1):GND    I10 @S9S_MB_2U_LIB.S9S_MB_2U(SCH_1):PAGE40
  DH85    GND @S9S_MB_2U_LIB.S9S_MB_2U(SCH_1):GND    I10 @S9S_MB_2U_LIB.S9S_MB_2U(SCH_1):PAGE40
   DH8    GND @S9S_MB_2U_LIB.S9S_MB_2U(SCH_1):GND    I10 @S9S_MB_2U_LIB.S9S_MB_2U(SCH_1):PAGE40
  DH77    GND @S9S_MB_2U_LIB.S9S_MB_2U(SCH_1):GND    I10 @S9S_MB_2U_LIB.S9S_MB_2U(SCH_1):PAGE40
  DH71    GND @S9S_MB_2U_LIB.S9S_MB_2U(SCH_1):GND    I10 @S9S_MB_2U_LIB.S9S_MB_2U(SCH_1):PAGE40
  DH65    GND @S9S_MB_2U_LIB.S9S_MB_2U(SCH_1):GND    I10 @S9S_MB_2U_LIB.S9S_MB_2U(SCH_1):PAGE40
  DH57    GND @S9S_MB_2U_LIB.S9S_MB_2U(SCH_1):GND    I10 @S9S_MB_2U_LIB.S9S_MB_2U(SCH_1):PAGE40
  DH47    GND @S9S_MB_2U_LIB.S9S_MB_2U(SCH_1):GND    I10 @S9S_MB_2U_LIB.S9S_MB_2U(SCH_1):PAGE40
  DH40    GND @S9S_MB_2U_LIB.S9S_MB_2U(SCH_1):GND    I10 @S9S_MB_2U_LIB.S9S_MB_2U(SCH_1):PAGE40
   DH4    GND @S9S_MB_2U_LIB.S9S_MB_2U(SCH_1):GND    I10 @S9S_MB_2U_LIB.S9S_MB_2U(SCH_1):PAGE40
  DH38    GND @S9S_MB_2U_LIB.S9S_MB_2U(SCH_1):GND    I10 @S9S_MB_2U_LIB.S9S_MB_2U(SCH_1):PAGE40
  DH32    GND @S9S_MB_2U_LIB.S9S_MB_2U(SCH_1):GND    I10 @S9S_MB_2U_LIB.S9S_MB_2U(SCH_1):PAGE40
  DH28    GND @S9S_MB_2U_LIB.S9S_MB_2U(SCH_1):GND    I10 @S9S_MB_2U_LIB.S9S_MB_2U(SCH_1):PAGE40
  DH22    GND @S9S_MB_2U_LIB.S9S_MB_2U(SCH_1):GND    I10 @S9S_MB_2U_LIB.S9S_MB_2U(SCH_1):PAGE40
  DH12    GND @S9S_MB_2U_LIB.S9S_MB_2U(SCH_1):GND    I10 @S9S_MB_2U_LIB.S9S_MB_2U(SCH_1):PAGE40
   DG9    GND @S9S_MB_2U_LIB.S9S_MB_2U(SCH_1):GND    I10 @S9S_MB_2U_LIB.S9S_MB_2U(SCH_1):PAGE40
  DG88    GND @S9S_MB_2U_LIB.S9S_MB_2U(SCH_1):GND    I10 @S9S_MB_2U_LIB.S9S_MB_2U(SCH_1):PAGE40
  DG84    GND @S9S_MB_2U_LIB.S9S_MB_2U(SCH_1):GND    I10 @S9S_MB_2U_LIB.S9S_MB_2U(SCH_1):PAGE40
  DG80    GND @S9S_MB_2U_LIB.S9S_MB_2U(SCH_1):GND    I10 @S9S_MB_2U_LIB.S9S_MB_2U(SCH_1):PAGE40
  DG76    GND @S9S_MB_2U_LIB.S9S_MB_2U(SCH_1):GND    I10 @S9S_MB_2U_LIB.S9S_MB_2U(SCH_1):PAGE40
  DG70    GND @S9S_MB_2U_LIB.S9S_MB_2U(SCH_1):GND    I10 @S9S_MB_2U_LIB.S9S_MB_2U(SCH_1):PAGE40
   DG5    GND @S9S_MB_2U_LIB.S9S_MB_2U(SCH_1):GND    I10 @S9S_MB_2U_LIB.S9S_MB_2U(SCH_1):PAGE40
  DG45    GND @S9S_MB_2U_LIB.S9S_MB_2U(SCH_1):GND    I10 @S9S_MB_2U_LIB.S9S_MB_2U(SCH_1):PAGE40
  DG39    GND @S9S_MB_2U_LIB.S9S_MB_2U(SCH_1):GND    I10 @S9S_MB_2U_LIB.S9S_MB_2U(SCH_1):PAGE40
  DG33    GND @S9S_MB_2U_LIB.S9S_MB_2U(SCH_1):GND    I10 @S9S_MB_2U_LIB.S9S_MB_2U(SCH_1):PAGE40
  DG27    GND @S9S_MB_2U_LIB.S9S_MB_2U(SCH_1):GND    I10 @S9S_MB_2U_LIB.S9S_MB_2U(SCH_1):PAGE40
  DF87    GND @S9S_MB_2U_LIB.S9S_MB_2U(SCH_1):GND    I10 @S9S_MB_2U_LIB.S9S_MB_2U(SCH_1):PAGE40
   DF8    GND @S9S_MB_2U_LIB.S9S_MB_2U(SCH_1):GND    I10 @S9S_MB_2U_LIB.S9S_MB_2U(SCH_1):PAGE40
  DF79    GND @S9S_MB_2U_LIB.S9S_MB_2U(SCH_1):GND    I10 @S9S_MB_2U_LIB.S9S_MB_2U(SCH_1):PAGE40
   DF4    GND @S9S_MB_2U_LIB.S9S_MB_2U(SCH_1):GND    I10 @S9S_MB_2U_LIB.S9S_MB_2U(SCH_1):PAGE40
  DE88    GND @S9S_MB_2U_LIB.S9S_MB_2U(SCH_1):GND    I10 @S9S_MB_2U_LIB.S9S_MB_2U(SCH_1):PAGE40
  DE84    GND @S9S_MB_2U_LIB.S9S_MB_2U(SCH_1):GND    I10 @S9S_MB_2U_LIB.S9S_MB_2U(SCH_1):PAGE40
  DE82    GND @S9S_MB_2U_LIB.S9S_MB_2U(SCH_1):GND    I10 @S9S_MB_2U_LIB.S9S_MB_2U(SCH_1):PAGE40
  DE76    GND @S9S_MB_2U_LIB.S9S_MB_2U(SCH_1):GND    I10 @S9S_MB_2U_LIB.S9S_MB_2U(SCH_1):PAGE40
  DE74    GND @S9S_MB_2U_LIB.S9S_MB_2U(SCH_1):GND    I10 @S9S_MB_2U_LIB.S9S_MB_2U(SCH_1):PAGE40
  DE72    GND @S9S_MB_2U_LIB.S9S_MB_2U(SCH_1):GND    I10 @S9S_MB_2U_LIB.S9S_MB_2U(SCH_1):PAGE40
  DE68    GND @S9S_MB_2U_LIB.S9S_MB_2U(SCH_1):GND    I10 @S9S_MB_2U_LIB.S9S_MB_2U(SCH_1):PAGE40
  DE66    GND @S9S_MB_2U_LIB.S9S_MB_2U(SCH_1):GND    I10 @S9S_MB_2U_LIB.S9S_MB_2U(SCH_1):PAGE40
  DE64    GND @S9S_MB_2U_LIB.S9S_MB_2U(SCH_1):GND    I10 @S9S_MB_2U_LIB.S9S_MB_2U(SCH_1):PAGE40
  DE62    GND @S9S_MB_2U_LIB.S9S_MB_2U(SCH_1):GND    I10 @S9S_MB_2U_LIB.S9S_MB_2U(SCH_1):PAGE40
  DE60    GND @S9S_MB_2U_LIB.S9S_MB_2U(SCH_1):GND    I10 @S9S_MB_2U_LIB.S9S_MB_2U(SCH_1):PAGE40
  DE58    GND @S9S_MB_2U_LIB.S9S_MB_2U(SCH_1):GND    I10 @S9S_MB_2U_LIB.S9S_MB_2U(SCH_1):PAGE40
  DE56    GND @S9S_MB_2U_LIB.S9S_MB_2U(SCH_1):GND    I10 @S9S_MB_2U_LIB.S9S_MB_2U(SCH_1):PAGE40
  DE54    GND @S9S_MB_2U_LIB.S9S_MB_2U(SCH_1):GND    I10 @S9S_MB_2U_LIB.S9S_MB_2U(SCH_1):PAGE40
  DE52    GND @S9S_MB_2U_LIB.S9S_MB_2U(SCH_1):GND    I10 @S9S_MB_2U_LIB.S9S_MB_2U(SCH_1):PAGE40
  DE50    GND @S9S_MB_2U_LIB.S9S_MB_2U(SCH_1):GND    I10 @S9S_MB_2U_LIB.S9S_MB_2U(SCH_1):PAGE40
  DE48    GND @S9S_MB_2U_LIB.S9S_MB_2U(SCH_1):GND    I10 @S9S_MB_2U_LIB.S9S_MB_2U(SCH_1):PAGE40
  DE45    GND @S9S_MB_2U_LIB.S9S_MB_2U(SCH_1):GND    I10 @S9S_MB_2U_LIB.S9S_MB_2U(SCH_1):PAGE40
  DE43    GND @S9S_MB_2U_LIB.S9S_MB_2U(SCH_1):GND    I10 @S9S_MB_2U_LIB.S9S_MB_2U(SCH_1):PAGE40
  DE41    GND @S9S_MB_2U_LIB.S9S_MB_2U(SCH_1):GND    I10 @S9S_MB_2U_LIB.S9S_MB_2U(SCH_1):PAGE40
  DE37    GND @S9S_MB_2U_LIB.S9S_MB_2U(SCH_1):GND    I10 @S9S_MB_2U_LIB.S9S_MB_2U(SCH_1):PAGE40
  DE35    GND @S9S_MB_2U_LIB.S9S_MB_2U(SCH_1):GND    I10 @S9S_MB_2U_LIB.S9S_MB_2U(SCH_1):PAGE40
  DE33    GND @S9S_MB_2U_LIB.S9S_MB_2U(SCH_1):GND    I10 @S9S_MB_2U_LIB.S9S_MB_2U(SCH_1):PAGE40
  DE31    GND @S9S_MB_2U_LIB.S9S_MB_2U(SCH_1):GND    I10 @S9S_MB_2U_LIB.S9S_MB_2U(SCH_1):PAGE40
  DE29    GND @S9S_MB_2U_LIB.S9S_MB_2U(SCH_1):GND    I10 @S9S_MB_2U_LIB.S9S_MB_2U(SCH_1):PAGE40
  DE27    GND @S9S_MB_2U_LIB.S9S_MB_2U(SCH_1):GND    I10 @S9S_MB_2U_LIB.S9S_MB_2U(SCH_1):PAGE40
  DE25    GND @S9S_MB_2U_LIB.S9S_MB_2U(SCH_1):GND    I10 @S9S_MB_2U_LIB.S9S_MB_2U(SCH_1):PAGE40
  DE23    GND @S9S_MB_2U_LIB.S9S_MB_2U(SCH_1):GND    I10 @S9S_MB_2U_LIB.S9S_MB_2U(SCH_1):PAGE40
  DE21    GND @S9S_MB_2U_LIB.S9S_MB_2U(SCH_1):GND    I10 @S9S_MB_2U_LIB.S9S_MB_2U(SCH_1):PAGE40
  DE19    GND @S9S_MB_2U_LIB.S9S_MB_2U(SCH_1):GND    I10 @S9S_MB_2U_LIB.S9S_MB_2U(SCH_1):PAGE40
  DE17    GND @S9S_MB_2U_LIB.S9S_MB_2U(SCH_1):GND    I10 @S9S_MB_2U_LIB.S9S_MB_2U(SCH_1):PAGE40
   DD8    GND @S9S_MB_2U_LIB.S9S_MB_2U(SCH_1):GND    I10 @S9S_MB_2U_LIB.S9S_MB_2U(SCH_1):PAGE40
  DD79    GND @S9S_MB_2U_LIB.S9S_MB_2U(SCH_1):GND    I10 @S9S_MB_2U_LIB.S9S_MB_2U(SCH_1):PAGE40
   DD4    GND @S9S_MB_2U_LIB.S9S_MB_2U(SCH_1):GND    I10 @S9S_MB_2U_LIB.S9S_MB_2U(SCH_1):PAGE40
   DC9    GND @S9S_MB_2U_LIB.S9S_MB_2U(SCH_1):GND    I10 @S9S_MB_2U_LIB.S9S_MB_2U(SCH_1):PAGE40
  DC88    GND @S9S_MB_2U_LIB.S9S_MB_2U(SCH_1):GND    I10 @S9S_MB_2U_LIB.S9S_MB_2U(SCH_1):PAGE40
  DC84    GND @S9S_MB_2U_LIB.S9S_MB_2U(SCH_1):GND    I10 @S9S_MB_2U_LIB.S9S_MB_2U(SCH_1):PAGE40
  DC80    GND @S9S_MB_2U_LIB.S9S_MB_2U(SCH_1):GND    I10 @S9S_MB_2U_LIB.S9S_MB_2U(SCH_1):PAGE40
  DC78    GND @S9S_MB_2U_LIB.S9S_MB_2U(SCH_1):GND    I10 @S9S_MB_2U_LIB.S9S_MB_2U(SCH_1):PAGE40
  DC76    GND @S9S_MB_2U_LIB.S9S_MB_2U(SCH_1):GND    I10 @S9S_MB_2U_LIB.S9S_MB_2U(SCH_1):PAGE40
  DC70    GND @S9S_MB_2U_LIB.S9S_MB_2U(SCH_1):GND    I10 @S9S_MB_2U_LIB.S9S_MB_2U(SCH_1):PAGE40
   DC5    GND @S9S_MB_2U_LIB.S9S_MB_2U(SCH_1):GND    I10 @S9S_MB_2U_LIB.S9S_MB_2U(SCH_1):PAGE40
  DC45    GND @S9S_MB_2U_LIB.S9S_MB_2U(SCH_1):GND    I10 @S9S_MB_2U_LIB.S9S_MB_2U(SCH_1):PAGE40
  DC39    GND @S9S_MB_2U_LIB.S9S_MB_2U(SCH_1):GND    I10 @S9S_MB_2U_LIB.S9S_MB_2U(SCH_1):PAGE40
  DC33    GND @S9S_MB_2U_LIB.S9S_MB_2U(SCH_1):GND    I10 @S9S_MB_2U_LIB.S9S_MB_2U(SCH_1):PAGE40
  DC27    GND @S9S_MB_2U_LIB.S9S_MB_2U(SCH_1):GND    I10 @S9S_MB_2U_LIB.S9S_MB_2U(SCH_1):PAGE40
  DL52    GND @S9S_MB_2U_LIB.S9S_MB_2U(SCH_1):GND    I10 @S9S_MB_2U_LIB.S9S_MB_2U(SCH_1):PAGE40
   DL5    GND @S9S_MB_2U_LIB.S9S_MB_2U(SCH_1):GND    I10 @S9S_MB_2U_LIB.S9S_MB_2U(SCH_1):PAGE40
  DL17    GND @S9S_MB_2U_LIB.S9S_MB_2U(SCH_1):GND    I10 @S9S_MB_2U_LIB.S9S_MB_2U(SCH_1):PAGE40
  DL13    GND @S9S_MB_2U_LIB.S9S_MB_2U(SCH_1):GND    I10 @S9S_MB_2U_LIB.S9S_MB_2U(SCH_1):PAGE40
   DL1    GND @S9S_MB_2U_LIB.S9S_MB_2U(SCH_1):GND    I10 @S9S_MB_2U_LIB.S9S_MB_2U(SCH_1):PAGE40
  DK67    GND @S9S_MB_2U_LIB.S9S_MB_2U(SCH_1):GND    I10 @S9S_MB_2U_LIB.S9S_MB_2U(SCH_1):PAGE40
  DK61    GND @S9S_MB_2U_LIB.S9S_MB_2U(SCH_1):GND    I10 @S9S_MB_2U_LIB.S9S_MB_2U(SCH_1):PAGE40
  DK55    GND @S9S_MB_2U_LIB.S9S_MB_2U(SCH_1):GND    I10 @S9S_MB_2U_LIB.S9S_MB_2U(SCH_1):PAGE40
  DK42    GND @S9S_MB_2U_LIB.S9S_MB_2U(SCH_1):GND    I10 @S9S_MB_2U_LIB.S9S_MB_2U(SCH_1):PAGE40
  DK24    GND @S9S_MB_2U_LIB.S9S_MB_2U(SCH_1):GND    I10 @S9S_MB_2U_LIB.S9S_MB_2U(SCH_1):PAGE40
  DK18    GND @S9S_MB_2U_LIB.S9S_MB_2U(SCH_1):GND    I10 @S9S_MB_2U_LIB.S9S_MB_2U(SCH_1):PAGE40
  DK12    GND @S9S_MB_2U_LIB.S9S_MB_2U(SCH_1):GND    I10 @S9S_MB_2U_LIB.S9S_MB_2U(SCH_1):PAGE40
  DJ68    GND @S9S_MB_2U_LIB.S9S_MB_2U(SCH_1):GND    I10 @S9S_MB_2U_LIB.S9S_MB_2U(SCH_1):PAGE40
  DJ62    GND @S9S_MB_2U_LIB.S9S_MB_2U(SCH_1):GND    I10 @S9S_MB_2U_LIB.S9S_MB_2U(SCH_1):PAGE40
  DJ54    GND @S9S_MB_2U_LIB.S9S_MB_2U(SCH_1):GND    I10 @S9S_MB_2U_LIB.S9S_MB_2U(SCH_1):PAGE40
  DJ35    GND @S9S_MB_2U_LIB.S9S_MB_2U(SCH_1):GND    I10 @S9S_MB_2U_LIB.S9S_MB_2U(SCH_1):PAGE40
  DJ25    GND @S9S_MB_2U_LIB.S9S_MB_2U(SCH_1):GND    I10 @S9S_MB_2U_LIB.S9S_MB_2U(SCH_1):PAGE40
  DH75    GND @S9S_MB_2U_LIB.S9S_MB_2U(SCH_1):GND    I10 @S9S_MB_2U_LIB.S9S_MB_2U(SCH_1):PAGE40
  DH69    GND @S9S_MB_2U_LIB.S9S_MB_2U(SCH_1):GND    I10 @S9S_MB_2U_LIB.S9S_MB_2U(SCH_1):PAGE40
  DH63    GND @S9S_MB_2U_LIB.S9S_MB_2U(SCH_1):GND    I10 @S9S_MB_2U_LIB.S9S_MB_2U(SCH_1):PAGE40
  DH59    GND @S9S_MB_2U_LIB.S9S_MB_2U(SCH_1):GND    I10 @S9S_MB_2U_LIB.S9S_MB_2U(SCH_1):PAGE40
  DH53    GND @S9S_MB_2U_LIB.S9S_MB_2U(SCH_1):GND    I10 @S9S_MB_2U_LIB.S9S_MB_2U(SCH_1):PAGE40
  DH51    GND @S9S_MB_2U_LIB.S9S_MB_2U(SCH_1):GND    I10 @S9S_MB_2U_LIB.S9S_MB_2U(SCH_1):PAGE40
  DH44    GND @S9S_MB_2U_LIB.S9S_MB_2U(SCH_1):GND    I10 @S9S_MB_2U_LIB.S9S_MB_2U(SCH_1):PAGE40
  DH34    GND @S9S_MB_2U_LIB.S9S_MB_2U(SCH_1):GND    I10 @S9S_MB_2U_LIB.S9S_MB_2U(SCH_1):PAGE40
  DH26    GND @S9S_MB_2U_LIB.S9S_MB_2U(SCH_1):GND    I10 @S9S_MB_2U_LIB.S9S_MB_2U(SCH_1):PAGE40
  DH20    GND @S9S_MB_2U_LIB.S9S_MB_2U(SCH_1):GND    I10 @S9S_MB_2U_LIB.S9S_MB_2U(SCH_1):PAGE40
  DH16    GND @S9S_MB_2U_LIB.S9S_MB_2U(SCH_1):GND    I10 @S9S_MB_2U_LIB.S9S_MB_2U(SCH_1):PAGE40
  DG64    GND @S9S_MB_2U_LIB.S9S_MB_2U(SCH_1):GND    I10 @S9S_MB_2U_LIB.S9S_MB_2U(SCH_1):PAGE40
  DG58    GND @S9S_MB_2U_LIB.S9S_MB_2U(SCH_1):GND    I10 @S9S_MB_2U_LIB.S9S_MB_2U(SCH_1):PAGE40
  DG52    GND @S9S_MB_2U_LIB.S9S_MB_2U(SCH_1):GND    I10 @S9S_MB_2U_LIB.S9S_MB_2U(SCH_1):PAGE40
  DG21    GND @S9S_MB_2U_LIB.S9S_MB_2U(SCH_1):GND    I10 @S9S_MB_2U_LIB.S9S_MB_2U(SCH_1):PAGE40
  DG13    GND @S9S_MB_2U_LIB.S9S_MB_2U(SCH_1):GND    I10 @S9S_MB_2U_LIB.S9S_MB_2U(SCH_1):PAGE40
   DG1    GND @S9S_MB_2U_LIB.S9S_MB_2U(SCH_1):GND    I10 @S9S_MB_2U_LIB.S9S_MB_2U(SCH_1):PAGE40
  DF91    GND @S9S_MB_2U_LIB.S9S_MB_2U(SCH_1):GND    I10 @S9S_MB_2U_LIB.S9S_MB_2U(SCH_1):PAGE40
  DF49    GND @S9S_MB_2U_LIB.S9S_MB_2U(SCH_1):GND    I10 @S9S_MB_2U_LIB.S9S_MB_2U(SCH_1):PAGE40
  DF16    GND @S9S_MB_2U_LIB.S9S_MB_2U(SCH_1):GND    I10 @S9S_MB_2U_LIB.S9S_MB_2U(SCH_1):PAGE40
  DF12    GND @S9S_MB_2U_LIB.S9S_MB_2U(SCH_1):GND    I10 @S9S_MB_2U_LIB.S9S_MB_2U(SCH_1):PAGE40
  DE70    GND @S9S_MB_2U_LIB.S9S_MB_2U(SCH_1):GND    I10 @S9S_MB_2U_LIB.S9S_MB_2U(SCH_1):PAGE40
  DE39    GND @S9S_MB_2U_LIB.S9S_MB_2U(SCH_1):GND    I10 @S9S_MB_2U_LIB.S9S_MB_2U(SCH_1):PAGE40
  DD49    GND @S9S_MB_2U_LIB.S9S_MB_2U(SCH_1):GND    I10 @S9S_MB_2U_LIB.S9S_MB_2U(SCH_1):PAGE40
  DD16    GND @S9S_MB_2U_LIB.S9S_MB_2U(SCH_1):GND    I10 @S9S_MB_2U_LIB.S9S_MB_2U(SCH_1):PAGE40
  DD12    GND @S9S_MB_2U_LIB.S9S_MB_2U(SCH_1):GND    I10 @S9S_MB_2U_LIB.S9S_MB_2U(SCH_1):PAGE40
  DC64    GND @S9S_MB_2U_LIB.S9S_MB_2U(SCH_1):GND    I10 @S9S_MB_2U_LIB.S9S_MB_2U(SCH_1):PAGE40
  DC58    GND @S9S_MB_2U_LIB.S9S_MB_2U(SCH_1):GND    I10 @S9S_MB_2U_LIB.S9S_MB_2U(SCH_1):PAGE40
  DC52    GND @S9S_MB_2U_LIB.S9S_MB_2U(SCH_1):GND    I10 @S9S_MB_2U_LIB.S9S_MB_2U(SCH_1):PAGE40
  DC21    GND @S9S_MB_2U_LIB.S9S_MB_2U(SCH_1):GND    I10 @S9S_MB_2U_LIB.S9S_MB_2U(SCH_1):PAGE40
  DC13    GND @S9S_MB_2U_LIB.S9S_MB_2U(SCH_1):GND    I10 @S9S_MB_2U_LIB.S9S_MB_2U(SCH_1):PAGE40
   DC1    GND @S9S_MB_2U_LIB.S9S_MB_2U(SCH_1):GND    I10 @S9S_MB_2U_LIB.S9S_MB_2U(SCH_1):PAGE40
  DB91    GND @S9S_MB_2U_LIB.S9S_MB_2U(SCH_1):GND    I10 @S9S_MB_2U_LIB.S9S_MB_2U(SCH_1):PAGE40
  DB87    GND @S9S_MB_2U_LIB.S9S_MB_2U(SCH_1):GND    I11 @S9S_MB_2U_LIB.S9S_MB_2U(SCH_1):PAGE40
   DB8    GND @S9S_MB_2U_LIB.S9S_MB_2U(SCH_1):GND    I11 @S9S_MB_2U_LIB.S9S_MB_2U(SCH_1):PAGE40
  DB77    GND @S9S_MB_2U_LIB.S9S_MB_2U(SCH_1):GND    I11 @S9S_MB_2U_LIB.S9S_MB_2U(SCH_1):PAGE40
  DB71    GND @S9S_MB_2U_LIB.S9S_MB_2U(SCH_1):GND    I11 @S9S_MB_2U_LIB.S9S_MB_2U(SCH_1):PAGE40
  DB65    GND @S9S_MB_2U_LIB.S9S_MB_2U(SCH_1):GND    I11 @S9S_MB_2U_LIB.S9S_MB_2U(SCH_1):PAGE40
  DB57    GND @S9S_MB_2U_LIB.S9S_MB_2U(SCH_1):GND    I11 @S9S_MB_2U_LIB.S9S_MB_2U(SCH_1):PAGE40
  DB47    GND @S9S_MB_2U_LIB.S9S_MB_2U(SCH_1):GND    I11 @S9S_MB_2U_LIB.S9S_MB_2U(SCH_1):PAGE40
  DB40    GND @S9S_MB_2U_LIB.S9S_MB_2U(SCH_1):GND    I11 @S9S_MB_2U_LIB.S9S_MB_2U(SCH_1):PAGE40
   DB4    GND @S9S_MB_2U_LIB.S9S_MB_2U(SCH_1):GND    I11 @S9S_MB_2U_LIB.S9S_MB_2U(SCH_1):PAGE40
  DB38    GND @S9S_MB_2U_LIB.S9S_MB_2U(SCH_1):GND    I11 @S9S_MB_2U_LIB.S9S_MB_2U(SCH_1):PAGE40
  DB32    GND @S9S_MB_2U_LIB.S9S_MB_2U(SCH_1):GND    I11 @S9S_MB_2U_LIB.S9S_MB_2U(SCH_1):PAGE40
  DB28    GND @S9S_MB_2U_LIB.S9S_MB_2U(SCH_1):GND    I11 @S9S_MB_2U_LIB.S9S_MB_2U(SCH_1):PAGE40
  DB22    GND @S9S_MB_2U_LIB.S9S_MB_2U(SCH_1):GND    I11 @S9S_MB_2U_LIB.S9S_MB_2U(SCH_1):PAGE40
  DB12    GND @S9S_MB_2U_LIB.S9S_MB_2U(SCH_1):GND    I11 @S9S_MB_2U_LIB.S9S_MB_2U(SCH_1):PAGE40
  DA88    GND @S9S_MB_2U_LIB.S9S_MB_2U(SCH_1):GND    I11 @S9S_MB_2U_LIB.S9S_MB_2U(SCH_1):PAGE40
  DA84    GND @S9S_MB_2U_LIB.S9S_MB_2U(SCH_1):GND    I11 @S9S_MB_2U_LIB.S9S_MB_2U(SCH_1):PAGE40
  DA82    GND @S9S_MB_2U_LIB.S9S_MB_2U(SCH_1):GND    I11 @S9S_MB_2U_LIB.S9S_MB_2U(SCH_1):PAGE40
  DA80    GND @S9S_MB_2U_LIB.S9S_MB_2U(SCH_1):GND    I11 @S9S_MB_2U_LIB.S9S_MB_2U(SCH_1):PAGE40
  DA74    GND @S9S_MB_2U_LIB.S9S_MB_2U(SCH_1):GND    I11 @S9S_MB_2U_LIB.S9S_MB_2U(SCH_1):PAGE40
  DA72    GND @S9S_MB_2U_LIB.S9S_MB_2U(SCH_1):GND    I11 @S9S_MB_2U_LIB.S9S_MB_2U(SCH_1):PAGE40
  DA66    GND @S9S_MB_2U_LIB.S9S_MB_2U(SCH_1):GND    I11 @S9S_MB_2U_LIB.S9S_MB_2U(SCH_1):PAGE40
  DA62    GND @S9S_MB_2U_LIB.S9S_MB_2U(SCH_1):GND    I11 @S9S_MB_2U_LIB.S9S_MB_2U(SCH_1):PAGE40
  DA60    GND @S9S_MB_2U_LIB.S9S_MB_2U(SCH_1):GND    I11 @S9S_MB_2U_LIB.S9S_MB_2U(SCH_1):PAGE40
  DA58    GND @S9S_MB_2U_LIB.S9S_MB_2U(SCH_1):GND    I11 @S9S_MB_2U_LIB.S9S_MB_2U(SCH_1):PAGE40
  DA56    GND @S9S_MB_2U_LIB.S9S_MB_2U(SCH_1):GND    I11 @S9S_MB_2U_LIB.S9S_MB_2U(SCH_1):PAGE40
  DA54    GND @S9S_MB_2U_LIB.S9S_MB_2U(SCH_1):GND    I11 @S9S_MB_2U_LIB.S9S_MB_2U(SCH_1):PAGE40
  DA50    GND @S9S_MB_2U_LIB.S9S_MB_2U(SCH_1):GND    I11 @S9S_MB_2U_LIB.S9S_MB_2U(SCH_1):PAGE40
  DA48    GND @S9S_MB_2U_LIB.S9S_MB_2U(SCH_1):GND    I11 @S9S_MB_2U_LIB.S9S_MB_2U(SCH_1):PAGE40
  DA41    GND @S9S_MB_2U_LIB.S9S_MB_2U(SCH_1):GND    I11 @S9S_MB_2U_LIB.S9S_MB_2U(SCH_1):PAGE40
  DA37    GND @S9S_MB_2U_LIB.S9S_MB_2U(SCH_1):GND    I11 @S9S_MB_2U_LIB.S9S_MB_2U(SCH_1):PAGE40
  DA35    GND @S9S_MB_2U_LIB.S9S_MB_2U(SCH_1):GND    I11 @S9S_MB_2U_LIB.S9S_MB_2U(SCH_1):PAGE40
  DA33    GND @S9S_MB_2U_LIB.S9S_MB_2U(SCH_1):GND    I11 @S9S_MB_2U_LIB.S9S_MB_2U(SCH_1):PAGE40
  DA31    GND @S9S_MB_2U_LIB.S9S_MB_2U(SCH_1):GND    I11 @S9S_MB_2U_LIB.S9S_MB_2U(SCH_1):PAGE40
  DA29    GND @S9S_MB_2U_LIB.S9S_MB_2U(SCH_1):GND    I11 @S9S_MB_2U_LIB.S9S_MB_2U(SCH_1):PAGE40
  DA25    GND @S9S_MB_2U_LIB.S9S_MB_2U(SCH_1):GND    I11 @S9S_MB_2U_LIB.S9S_MB_2U(SCH_1):PAGE40
  DA23    GND @S9S_MB_2U_LIB.S9S_MB_2U(SCH_1):GND    I11 @S9S_MB_2U_LIB.S9S_MB_2U(SCH_1):PAGE40
  DA19    GND @S9S_MB_2U_LIB.S9S_MB_2U(SCH_1):GND    I11 @S9S_MB_2U_LIB.S9S_MB_2U(SCH_1):PAGE40
  CY83    GND @S9S_MB_2U_LIB.S9S_MB_2U(SCH_1):GND    I11 @S9S_MB_2U_LIB.S9S_MB_2U(SCH_1):PAGE40
  CY81    GND @S9S_MB_2U_LIB.S9S_MB_2U(SCH_1):GND    I11 @S9S_MB_2U_LIB.S9S_MB_2U(SCH_1):PAGE40
   CY8    GND @S9S_MB_2U_LIB.S9S_MB_2U(SCH_1):GND    I11 @S9S_MB_2U_LIB.S9S_MB_2U(SCH_1):PAGE40
  CY77    GND @S9S_MB_2U_LIB.S9S_MB_2U(SCH_1):GND    I11 @S9S_MB_2U_LIB.S9S_MB_2U(SCH_1):PAGE40
  CY73    GND @S9S_MB_2U_LIB.S9S_MB_2U(SCH_1):GND    I11 @S9S_MB_2U_LIB.S9S_MB_2U(SCH_1):PAGE40
  CY63    GND @S9S_MB_2U_LIB.S9S_MB_2U(SCH_1):GND    I11 @S9S_MB_2U_LIB.S9S_MB_2U(SCH_1):PAGE40
  CY30    GND @S9S_MB_2U_LIB.S9S_MB_2U(SCH_1):GND    I11 @S9S_MB_2U_LIB.S9S_MB_2U(SCH_1):PAGE40
  CY26    GND @S9S_MB_2U_LIB.S9S_MB_2U(SCH_1):GND    I11 @S9S_MB_2U_LIB.S9S_MB_2U(SCH_1):PAGE40
  CY18    GND @S9S_MB_2U_LIB.S9S_MB_2U(SCH_1):GND    I11 @S9S_MB_2U_LIB.S9S_MB_2U(SCH_1):PAGE40
  CY16    GND @S9S_MB_2U_LIB.S9S_MB_2U(SCH_1):GND    I11 @S9S_MB_2U_LIB.S9S_MB_2U(SCH_1):PAGE40
  CY12    GND @S9S_MB_2U_LIB.S9S_MB_2U(SCH_1):GND    I11 @S9S_MB_2U_LIB.S9S_MB_2U(SCH_1):PAGE40
   CW9    GND @S9S_MB_2U_LIB.S9S_MB_2U(SCH_1):GND    I11 @S9S_MB_2U_LIB.S9S_MB_2U(SCH_1):PAGE40
  CW88    GND @S9S_MB_2U_LIB.S9S_MB_2U(SCH_1):GND    I11 @S9S_MB_2U_LIB.S9S_MB_2U(SCH_1):PAGE40
  CW84    GND @S9S_MB_2U_LIB.S9S_MB_2U(SCH_1):GND    I11 @S9S_MB_2U_LIB.S9S_MB_2U(SCH_1):PAGE40
  CW78    GND @S9S_MB_2U_LIB.S9S_MB_2U(SCH_1):GND    I11 @S9S_MB_2U_LIB.S9S_MB_2U(SCH_1):PAGE40
  CW72    GND @S9S_MB_2U_LIB.S9S_MB_2U(SCH_1):GND    I11 @S9S_MB_2U_LIB.S9S_MB_2U(SCH_1):PAGE40
   CW5    GND @S9S_MB_2U_LIB.S9S_MB_2U(SCH_1):GND    I11 @S9S_MB_2U_LIB.S9S_MB_2U(SCH_1):PAGE40
  CW17    GND @S9S_MB_2U_LIB.S9S_MB_2U(SCH_1):GND    I11 @S9S_MB_2U_LIB.S9S_MB_2U(SCH_1):PAGE40
  CW13    GND @S9S_MB_2U_LIB.S9S_MB_2U(SCH_1):GND    I11 @S9S_MB_2U_LIB.S9S_MB_2U(SCH_1):PAGE40
   CW1    GND @S9S_MB_2U_LIB.S9S_MB_2U(SCH_1):GND    I11 @S9S_MB_2U_LIB.S9S_MB_2U(SCH_1):PAGE40
  CV91    GND @S9S_MB_2U_LIB.S9S_MB_2U(SCH_1):GND    I11 @S9S_MB_2U_LIB.S9S_MB_2U(SCH_1):PAGE40
  CV87    GND @S9S_MB_2U_LIB.S9S_MB_2U(SCH_1):GND    I11 @S9S_MB_2U_LIB.S9S_MB_2U(SCH_1):PAGE40
  CV83    GND @S9S_MB_2U_LIB.S9S_MB_2U(SCH_1):GND    I11 @S9S_MB_2U_LIB.S9S_MB_2U(SCH_1):PAGE40
   CV8    GND @S9S_MB_2U_LIB.S9S_MB_2U(SCH_1):GND    I11 @S9S_MB_2U_LIB.S9S_MB_2U(SCH_1):PAGE40
  CV75    GND @S9S_MB_2U_LIB.S9S_MB_2U(SCH_1):GND    I11 @S9S_MB_2U_LIB.S9S_MB_2U(SCH_1):PAGE40
   CV4    GND @S9S_MB_2U_LIB.S9S_MB_2U(SCH_1):GND    I11 @S9S_MB_2U_LIB.S9S_MB_2U(SCH_1):PAGE40
  CV12    GND @S9S_MB_2U_LIB.S9S_MB_2U(SCH_1):GND    I11 @S9S_MB_2U_LIB.S9S_MB_2U(SCH_1):PAGE40
  CU88    GND @S9S_MB_2U_LIB.S9S_MB_2U(SCH_1):GND    I11 @S9S_MB_2U_LIB.S9S_MB_2U(SCH_1):PAGE40
  CU84    GND @S9S_MB_2U_LIB.S9S_MB_2U(SCH_1):GND    I11 @S9S_MB_2U_LIB.S9S_MB_2U(SCH_1):PAGE40
  CU68    GND @S9S_MB_2U_LIB.S9S_MB_2U(SCH_1):GND    I11 @S9S_MB_2U_LIB.S9S_MB_2U(SCH_1):PAGE40
  CU66    GND @S9S_MB_2U_LIB.S9S_MB_2U(SCH_1):GND    I11 @S9S_MB_2U_LIB.S9S_MB_2U(SCH_1):PAGE40
  CU60    GND @S9S_MB_2U_LIB.S9S_MB_2U(SCH_1):GND    I11 @S9S_MB_2U_LIB.S9S_MB_2U(SCH_1):PAGE40
  CU23    GND @S9S_MB_2U_LIB.S9S_MB_2U(SCH_1):GND    I11 @S9S_MB_2U_LIB.S9S_MB_2U(SCH_1):PAGE40
  CU21    GND @S9S_MB_2U_LIB.S9S_MB_2U(SCH_1):GND    I11 @S9S_MB_2U_LIB.S9S_MB_2U(SCH_1):PAGE40
  CU19    GND @S9S_MB_2U_LIB.S9S_MB_2U(SCH_1):GND    I11 @S9S_MB_2U_LIB.S9S_MB_2U(SCH_1):PAGE40
  CT81    GND @S9S_MB_2U_LIB.S9S_MB_2U(SCH_1):GND    I11 @S9S_MB_2U_LIB.S9S_MB_2U(SCH_1):PAGE40
  CT73    GND @S9S_MB_2U_LIB.S9S_MB_2U(SCH_1):GND    I11 @S9S_MB_2U_LIB.S9S_MB_2U(SCH_1):PAGE40
  CT69    GND @S9S_MB_2U_LIB.S9S_MB_2U(SCH_1):GND    I11 @S9S_MB_2U_LIB.S9S_MB_2U(SCH_1):PAGE40
  CT12    GND @S9S_MB_2U_LIB.S9S_MB_2U(SCH_1):GND    I11 @S9S_MB_2U_LIB.S9S_MB_2U(SCH_1):PAGE40
  CT10    GND @S9S_MB_2U_LIB.S9S_MB_2U(SCH_1):GND    I11 @S9S_MB_2U_LIB.S9S_MB_2U(SCH_1):PAGE40
  CR90    GND @S9S_MB_2U_LIB.S9S_MB_2U(SCH_1):GND    I11 @S9S_MB_2U_LIB.S9S_MB_2U(SCH_1):PAGE40
   CR9    GND @S9S_MB_2U_LIB.S9S_MB_2U(SCH_1):GND    I11 @S9S_MB_2U_LIB.S9S_MB_2U(SCH_1):PAGE40
  CR88    GND @S9S_MB_2U_LIB.S9S_MB_2U(SCH_1):GND    I11 @S9S_MB_2U_LIB.S9S_MB_2U(SCH_1):PAGE40
  CR84    GND @S9S_MB_2U_LIB.S9S_MB_2U(SCH_1):GND    I11 @S9S_MB_2U_LIB.S9S_MB_2U(SCH_1):PAGE40
  CR64    GND @S9S_MB_2U_LIB.S9S_MB_2U(SCH_1):GND    I11 @S9S_MB_2U_LIB.S9S_MB_2U(SCH_1):PAGE40
  CR62    GND @S9S_MB_2U_LIB.S9S_MB_2U(SCH_1):GND    I11 @S9S_MB_2U_LIB.S9S_MB_2U(SCH_1):PAGE40
   CR5    GND @S9S_MB_2U_LIB.S9S_MB_2U(SCH_1):GND    I11 @S9S_MB_2U_LIB.S9S_MB_2U(SCH_1):PAGE40
  CR17    GND @S9S_MB_2U_LIB.S9S_MB_2U(SCH_1):GND    I11 @S9S_MB_2U_LIB.S9S_MB_2U(SCH_1):PAGE40
  CR13    GND @S9S_MB_2U_LIB.S9S_MB_2U(SCH_1):GND    I11 @S9S_MB_2U_LIB.S9S_MB_2U(SCH_1):PAGE40
  CR11    GND @S9S_MB_2U_LIB.S9S_MB_2U(SCH_1):GND    I11 @S9S_MB_2U_LIB.S9S_MB_2U(SCH_1):PAGE40
   CR1    GND @S9S_MB_2U_LIB.S9S_MB_2U(SCH_1):GND    I11 @S9S_MB_2U_LIB.S9S_MB_2U(SCH_1):PAGE40
  CP91    GND @S9S_MB_2U_LIB.S9S_MB_2U(SCH_1):GND    I11 @S9S_MB_2U_LIB.S9S_MB_2U(SCH_1):PAGE40
  CP87    GND @S9S_MB_2U_LIB.S9S_MB_2U(SCH_1):GND    I11 @S9S_MB_2U_LIB.S9S_MB_2U(SCH_1):PAGE40
  CP83    GND @S9S_MB_2U_LIB.S9S_MB_2U(SCH_1):GND    I11 @S9S_MB_2U_LIB.S9S_MB_2U(SCH_1):PAGE40
   CP8    GND @S9S_MB_2U_LIB.S9S_MB_2U(SCH_1):GND    I11 @S9S_MB_2U_LIB.S9S_MB_2U(SCH_1):PAGE40
  CP77    GND @S9S_MB_2U_LIB.S9S_MB_2U(SCH_1):GND    I11 @S9S_MB_2U_LIB.S9S_MB_2U(SCH_1):PAGE40
  CP75    GND @S9S_MB_2U_LIB.S9S_MB_2U(SCH_1):GND    I11 @S9S_MB_2U_LIB.S9S_MB_2U(SCH_1):PAGE40
   CP4    GND @S9S_MB_2U_LIB.S9S_MB_2U(SCH_1):GND    I11 @S9S_MB_2U_LIB.S9S_MB_2U(SCH_1):PAGE40
  CP18    GND @S9S_MB_2U_LIB.S9S_MB_2U(SCH_1):GND    I11 @S9S_MB_2U_LIB.S9S_MB_2U(SCH_1):PAGE40
  CP12    GND @S9S_MB_2U_LIB.S9S_MB_2U(SCH_1):GND    I11 @S9S_MB_2U_LIB.S9S_MB_2U(SCH_1):PAGE40
  CN86    GND @S9S_MB_2U_LIB.S9S_MB_2U(SCH_1):GND    I11 @S9S_MB_2U_LIB.S9S_MB_2U(SCH_1):PAGE40
  CN84    GND @S9S_MB_2U_LIB.S9S_MB_2U(SCH_1):GND    I11 @S9S_MB_2U_LIB.S9S_MB_2U(SCH_1):PAGE40
  CN74    GND @S9S_MB_2U_LIB.S9S_MB_2U(SCH_1):GND    I11 @S9S_MB_2U_LIB.S9S_MB_2U(SCH_1):PAGE40
  CN72    GND @S9S_MB_2U_LIB.S9S_MB_2U(SCH_1):GND    I11 @S9S_MB_2U_LIB.S9S_MB_2U(SCH_1):PAGE40
  CN70    GND @S9S_MB_2U_LIB.S9S_MB_2U(SCH_1):GND    I11 @S9S_MB_2U_LIB.S9S_MB_2U(SCH_1):PAGE40
  CN68    GND @S9S_MB_2U_LIB.S9S_MB_2U(SCH_1):GND    I11 @S9S_MB_2U_LIB.S9S_MB_2U(SCH_1):PAGE40
  CM85    GND @S9S_MB_2U_LIB.S9S_MB_2U(SCH_1):GND    I11 @S9S_MB_2U_LIB.S9S_MB_2U(SCH_1):PAGE40
  CM83    GND @S9S_MB_2U_LIB.S9S_MB_2U(SCH_1):GND    I11 @S9S_MB_2U_LIB.S9S_MB_2U(SCH_1):PAGE40
  CM81    GND @S9S_MB_2U_LIB.S9S_MB_2U(SCH_1):GND    I11 @S9S_MB_2U_LIB.S9S_MB_2U(SCH_1):PAGE40
   CM8    GND @S9S_MB_2U_LIB.S9S_MB_2U(SCH_1):GND    I11 @S9S_MB_2U_LIB.S9S_MB_2U(SCH_1):PAGE40
  CM79    GND @S9S_MB_2U_LIB.S9S_MB_2U(SCH_1):GND    I11 @S9S_MB_2U_LIB.S9S_MB_2U(SCH_1):PAGE40
  CM67    GND @S9S_MB_2U_LIB.S9S_MB_2U(SCH_1):GND    I11 @S9S_MB_2U_LIB.S9S_MB_2U(SCH_1):PAGE40
  CM65    GND @S9S_MB_2U_LIB.S9S_MB_2U(SCH_1):GND    I11 @S9S_MB_2U_LIB.S9S_MB_2U(SCH_1):PAGE40
  CM61    GND @S9S_MB_2U_LIB.S9S_MB_2U(SCH_1):GND    I11 @S9S_MB_2U_LIB.S9S_MB_2U(SCH_1):PAGE40
   CM4    GND @S9S_MB_2U_LIB.S9S_MB_2U(SCH_1):GND    I11 @S9S_MB_2U_LIB.S9S_MB_2U(SCH_1):PAGE40
  CM24    GND @S9S_MB_2U_LIB.S9S_MB_2U(SCH_1):GND    I11 @S9S_MB_2U_LIB.S9S_MB_2U(SCH_1):PAGE40
  CM20    GND @S9S_MB_2U_LIB.S9S_MB_2U(SCH_1):GND    I11 @S9S_MB_2U_LIB.S9S_MB_2U(SCH_1):PAGE40
  CM12    GND @S9S_MB_2U_LIB.S9S_MB_2U(SCH_1):GND    I11 @S9S_MB_2U_LIB.S9S_MB_2U(SCH_1):PAGE40
   CL9    GND @S9S_MB_2U_LIB.S9S_MB_2U(SCH_1):GND    I11 @S9S_MB_2U_LIB.S9S_MB_2U(SCH_1):PAGE40
  CL82    GND @S9S_MB_2U_LIB.S9S_MB_2U(SCH_1):GND    I11 @S9S_MB_2U_LIB.S9S_MB_2U(SCH_1):PAGE40
  CL80    GND @S9S_MB_2U_LIB.S9S_MB_2U(SCH_1):GND    I11 @S9S_MB_2U_LIB.S9S_MB_2U(SCH_1):PAGE40
  CL78    GND @S9S_MB_2U_LIB.S9S_MB_2U(SCH_1):GND    I11 @S9S_MB_2U_LIB.S9S_MB_2U(SCH_1):PAGE40
  CL74    GND @S9S_MB_2U_LIB.S9S_MB_2U(SCH_1):GND    I11 @S9S_MB_2U_LIB.S9S_MB_2U(SCH_1):PAGE40
  CL62    GND @S9S_MB_2U_LIB.S9S_MB_2U(SCH_1):GND    I11 @S9S_MB_2U_LIB.S9S_MB_2U(SCH_1):PAGE40
   CL5    GND @S9S_MB_2U_LIB.S9S_MB_2U(SCH_1):GND    I11 @S9S_MB_2U_LIB.S9S_MB_2U(SCH_1):PAGE40
  CL17    GND @S9S_MB_2U_LIB.S9S_MB_2U(SCH_1):GND    I11 @S9S_MB_2U_LIB.S9S_MB_2U(SCH_1):PAGE40
  CL13    GND @S9S_MB_2U_LIB.S9S_MB_2U(SCH_1):GND    I11 @S9S_MB_2U_LIB.S9S_MB_2U(SCH_1):PAGE40
   CL1    GND @S9S_MB_2U_LIB.S9S_MB_2U(SCH_1):GND    I11 @S9S_MB_2U_LIB.S9S_MB_2U(SCH_1):PAGE40
  CK81    GND @S9S_MB_2U_LIB.S9S_MB_2U(SCH_1):GND    I11 @S9S_MB_2U_LIB.S9S_MB_2U(SCH_1):PAGE40
  CK69    GND @S9S_MB_2U_LIB.S9S_MB_2U(SCH_1):GND    I11 @S9S_MB_2U_LIB.S9S_MB_2U(SCH_1):PAGE40
  CK63    GND @S9S_MB_2U_LIB.S9S_MB_2U(SCH_1):GND    I11 @S9S_MB_2U_LIB.S9S_MB_2U(SCH_1):PAGE40
  DB75    GND @S9S_MB_2U_LIB.S9S_MB_2U(SCH_1):GND    I11 @S9S_MB_2U_LIB.S9S_MB_2U(SCH_1):PAGE40
  DB69    GND @S9S_MB_2U_LIB.S9S_MB_2U(SCH_1):GND    I11 @S9S_MB_2U_LIB.S9S_MB_2U(SCH_1):PAGE40
  DB63    GND @S9S_MB_2U_LIB.S9S_MB_2U(SCH_1):GND    I11 @S9S_MB_2U_LIB.S9S_MB_2U(SCH_1):PAGE40
  DB59    GND @S9S_MB_2U_LIB.S9S_MB_2U(SCH_1):GND    I11 @S9S_MB_2U_LIB.S9S_MB_2U(SCH_1):PAGE40
  DB53    GND @S9S_MB_2U_LIB.S9S_MB_2U(SCH_1):GND    I11 @S9S_MB_2U_LIB.S9S_MB_2U(SCH_1):PAGE40
  DB51    GND @S9S_MB_2U_LIB.S9S_MB_2U(SCH_1):GND    I11 @S9S_MB_2U_LIB.S9S_MB_2U(SCH_1):PAGE40
  DB44    GND @S9S_MB_2U_LIB.S9S_MB_2U(SCH_1):GND    I11 @S9S_MB_2U_LIB.S9S_MB_2U(SCH_1):PAGE40
  DB34    GND @S9S_MB_2U_LIB.S9S_MB_2U(SCH_1):GND    I11 @S9S_MB_2U_LIB.S9S_MB_2U(SCH_1):PAGE40
  DB26    GND @S9S_MB_2U_LIB.S9S_MB_2U(SCH_1):GND    I11 @S9S_MB_2U_LIB.S9S_MB_2U(SCH_1):PAGE40
  DB20    GND @S9S_MB_2U_LIB.S9S_MB_2U(SCH_1):GND    I11 @S9S_MB_2U_LIB.S9S_MB_2U(SCH_1):PAGE40
  DB16    GND @S9S_MB_2U_LIB.S9S_MB_2U(SCH_1):GND    I11 @S9S_MB_2U_LIB.S9S_MB_2U(SCH_1):PAGE40
  DA68    GND @S9S_MB_2U_LIB.S9S_MB_2U(SCH_1):GND    I11 @S9S_MB_2U_LIB.S9S_MB_2U(SCH_1):PAGE40
  DA43    GND @S9S_MB_2U_LIB.S9S_MB_2U(SCH_1):GND    I11 @S9S_MB_2U_LIB.S9S_MB_2U(SCH_1):PAGE40
   CY4    GND @S9S_MB_2U_LIB.S9S_MB_2U(SCH_1):GND    I11 @S9S_MB_2U_LIB.S9S_MB_2U(SCH_1):PAGE40
  CW70    GND @S9S_MB_2U_LIB.S9S_MB_2U(SCH_1):GND    I11 @S9S_MB_2U_LIB.S9S_MB_2U(SCH_1):PAGE40
  CW33    GND @S9S_MB_2U_LIB.S9S_MB_2U(SCH_1):GND    I11 @S9S_MB_2U_LIB.S9S_MB_2U(SCH_1):PAGE40
  CV79    GND @S9S_MB_2U_LIB.S9S_MB_2U(SCH_1):GND    I11 @S9S_MB_2U_LIB.S9S_MB_2U(SCH_1):PAGE40
  CV26    GND @S9S_MB_2U_LIB.S9S_MB_2U(SCH_1):GND    I11 @S9S_MB_2U_LIB.S9S_MB_2U(SCH_1):PAGE40
  CV16    GND @S9S_MB_2U_LIB.S9S_MB_2U(SCH_1):GND    I11 @S9S_MB_2U_LIB.S9S_MB_2U(SCH_1):PAGE40
  CU78    GND @S9S_MB_2U_LIB.S9S_MB_2U(SCH_1):GND    I11 @S9S_MB_2U_LIB.S9S_MB_2U(SCH_1):PAGE40
  CU72    GND @S9S_MB_2U_LIB.S9S_MB_2U(SCH_1):GND    I11 @S9S_MB_2U_LIB.S9S_MB_2U(SCH_1):PAGE40
  CU25    GND @S9S_MB_2U_LIB.S9S_MB_2U(SCH_1):GND    I11 @S9S_MB_2U_LIB.S9S_MB_2U(SCH_1):PAGE40
  CT89    GND @S9S_MB_2U_LIB.S9S_MB_2U(SCH_1):GND    I11 @S9S_MB_2U_LIB.S9S_MB_2U(SCH_1):PAGE40
   CT8    GND @S9S_MB_2U_LIB.S9S_MB_2U(SCH_1):GND    I11 @S9S_MB_2U_LIB.S9S_MB_2U(SCH_1):PAGE40
   CT4    GND @S9S_MB_2U_LIB.S9S_MB_2U(SCH_1):GND    I11 @S9S_MB_2U_LIB.S9S_MB_2U(SCH_1):PAGE40
  CT16    GND @S9S_MB_2U_LIB.S9S_MB_2U(SCH_1):GND    I11 @S9S_MB_2U_LIB.S9S_MB_2U(SCH_1):PAGE40
  CR78    GND @S9S_MB_2U_LIB.S9S_MB_2U(SCH_1):GND    I11 @S9S_MB_2U_LIB.S9S_MB_2U(SCH_1):PAGE40
  CP79    GND @S9S_MB_2U_LIB.S9S_MB_2U(SCH_1):GND    I11 @S9S_MB_2U_LIB.S9S_MB_2U(SCH_1):PAGE40
  CP16    GND @S9S_MB_2U_LIB.S9S_MB_2U(SCH_1):GND    I11 @S9S_MB_2U_LIB.S9S_MB_2U(SCH_1):PAGE40
  CN76    GND @S9S_MB_2U_LIB.S9S_MB_2U(SCH_1):GND    I11 @S9S_MB_2U_LIB.S9S_MB_2U(SCH_1):PAGE40
  CM22    GND @S9S_MB_2U_LIB.S9S_MB_2U(SCH_1):GND    I11 @S9S_MB_2U_LIB.S9S_MB_2U(SCH_1):PAGE40
  CM16    GND @S9S_MB_2U_LIB.S9S_MB_2U(SCH_1):GND    I11 @S9S_MB_2U_LIB.S9S_MB_2U(SCH_1):PAGE40
   CK8    GND @S9S_MB_2U_LIB.S9S_MB_2U(SCH_1):GND    I12 @S9S_MB_2U_LIB.S9S_MB_2U(SCH_1):PAGE40
  CK26    GND @S9S_MB_2U_LIB.S9S_MB_2U(SCH_1):GND    I12 @S9S_MB_2U_LIB.S9S_MB_2U(SCH_1):PAGE40
  CK20    GND @S9S_MB_2U_LIB.S9S_MB_2U(SCH_1):GND    I12 @S9S_MB_2U_LIB.S9S_MB_2U(SCH_1):PAGE40
  CK16    GND @S9S_MB_2U_LIB.S9S_MB_2U(SCH_1):GND    I12 @S9S_MB_2U_LIB.S9S_MB_2U(SCH_1):PAGE40
  CK12    GND @S9S_MB_2U_LIB.S9S_MB_2U(SCH_1):GND    I12 @S9S_MB_2U_LIB.S9S_MB_2U(SCH_1):PAGE40
  CJ80    GND @S9S_MB_2U_LIB.S9S_MB_2U(SCH_1):GND    I12 @S9S_MB_2U_LIB.S9S_MB_2U(SCH_1):PAGE40
  CJ60    GND @S9S_MB_2U_LIB.S9S_MB_2U(SCH_1):GND    I12 @S9S_MB_2U_LIB.S9S_MB_2U(SCH_1):PAGE40
  CH89    GND @S9S_MB_2U_LIB.S9S_MB_2U(SCH_1):GND    I12 @S9S_MB_2U_LIB.S9S_MB_2U(SCH_1):PAGE40
  CH87    GND @S9S_MB_2U_LIB.S9S_MB_2U(SCH_1):GND    I12 @S9S_MB_2U_LIB.S9S_MB_2U(SCH_1):PAGE40
  CH85    GND @S9S_MB_2U_LIB.S9S_MB_2U(SCH_1):GND    I12 @S9S_MB_2U_LIB.S9S_MB_2U(SCH_1):PAGE40
  CH83    GND @S9S_MB_2U_LIB.S9S_MB_2U(SCH_1):GND    I12 @S9S_MB_2U_LIB.S9S_MB_2U(SCH_1):PAGE40
   CH8    GND @S9S_MB_2U_LIB.S9S_MB_2U(SCH_1):GND    I12 @S9S_MB_2U_LIB.S9S_MB_2U(SCH_1):PAGE40
  CH79    GND @S9S_MB_2U_LIB.S9S_MB_2U(SCH_1):GND    I12 @S9S_MB_2U_LIB.S9S_MB_2U(SCH_1):PAGE40
  CH73    GND @S9S_MB_2U_LIB.S9S_MB_2U(SCH_1):GND    I12 @S9S_MB_2U_LIB.S9S_MB_2U(SCH_1):PAGE40
  CH67    GND @S9S_MB_2U_LIB.S9S_MB_2U(SCH_1):GND    I12 @S9S_MB_2U_LIB.S9S_MB_2U(SCH_1):PAGE40
   CH4    GND @S9S_MB_2U_LIB.S9S_MB_2U(SCH_1):GND    I12 @S9S_MB_2U_LIB.S9S_MB_2U(SCH_1):PAGE40
  CH20    GND @S9S_MB_2U_LIB.S9S_MB_2U(SCH_1):GND    I12 @S9S_MB_2U_LIB.S9S_MB_2U(SCH_1):PAGE40
  CH16    GND @S9S_MB_2U_LIB.S9S_MB_2U(SCH_1):GND    I12 @S9S_MB_2U_LIB.S9S_MB_2U(SCH_1):PAGE40
  CH12    GND @S9S_MB_2U_LIB.S9S_MB_2U(SCH_1):GND    I12 @S9S_MB_2U_LIB.S9S_MB_2U(SCH_1):PAGE40
   CG9    GND @S9S_MB_2U_LIB.S9S_MB_2U(SCH_1):GND    I12 @S9S_MB_2U_LIB.S9S_MB_2U(SCH_1):PAGE40
  CG78    GND @S9S_MB_2U_LIB.S9S_MB_2U(SCH_1):GND    I12 @S9S_MB_2U_LIB.S9S_MB_2U(SCH_1):PAGE40
  CG74    GND @S9S_MB_2U_LIB.S9S_MB_2U(SCH_1):GND    I12 @S9S_MB_2U_LIB.S9S_MB_2U(SCH_1):PAGE40
  CG72    GND @S9S_MB_2U_LIB.S9S_MB_2U(SCH_1):GND    I12 @S9S_MB_2U_LIB.S9S_MB_2U(SCH_1):PAGE40
  CG70    GND @S9S_MB_2U_LIB.S9S_MB_2U(SCH_1):GND    I12 @S9S_MB_2U_LIB.S9S_MB_2U(SCH_1):PAGE40
  CG64    GND @S9S_MB_2U_LIB.S9S_MB_2U(SCH_1):GND    I12 @S9S_MB_2U_LIB.S9S_MB_2U(SCH_1):PAGE40
  CG62    GND @S9S_MB_2U_LIB.S9S_MB_2U(SCH_1):GND    I12 @S9S_MB_2U_LIB.S9S_MB_2U(SCH_1):PAGE40
   CG5    GND @S9S_MB_2U_LIB.S9S_MB_2U(SCH_1):GND    I12 @S9S_MB_2U_LIB.S9S_MB_2U(SCH_1):PAGE40
  CG25    GND @S9S_MB_2U_LIB.S9S_MB_2U(SCH_1):GND    I12 @S9S_MB_2U_LIB.S9S_MB_2U(SCH_1):PAGE40
  CG23    GND @S9S_MB_2U_LIB.S9S_MB_2U(SCH_1):GND    I12 @S9S_MB_2U_LIB.S9S_MB_2U(SCH_1):PAGE40
  CG21    GND @S9S_MB_2U_LIB.S9S_MB_2U(SCH_1):GND    I12 @S9S_MB_2U_LIB.S9S_MB_2U(SCH_1):PAGE40
  CG17    GND @S9S_MB_2U_LIB.S9S_MB_2U(SCH_1):GND    I12 @S9S_MB_2U_LIB.S9S_MB_2U(SCH_1):PAGE40
  CG13    GND @S9S_MB_2U_LIB.S9S_MB_2U(SCH_1):GND    I12 @S9S_MB_2U_LIB.S9S_MB_2U(SCH_1):PAGE40
   CG1    GND @S9S_MB_2U_LIB.S9S_MB_2U(SCH_1):GND    I12 @S9S_MB_2U_LIB.S9S_MB_2U(SCH_1):PAGE40
   CF8    GND @S9S_MB_2U_LIB.S9S_MB_2U(SCH_1):GND    I12 @S9S_MB_2U_LIB.S9S_MB_2U(SCH_1):PAGE40
  CF71    GND @S9S_MB_2U_LIB.S9S_MB_2U(SCH_1):GND    I12 @S9S_MB_2U_LIB.S9S_MB_2U(SCH_1):PAGE40
  CF69    GND @S9S_MB_2U_LIB.S9S_MB_2U(SCH_1):GND    I12 @S9S_MB_2U_LIB.S9S_MB_2U(SCH_1):PAGE40
   CF4    GND @S9S_MB_2U_LIB.S9S_MB_2U(SCH_1):GND    I12 @S9S_MB_2U_LIB.S9S_MB_2U(SCH_1):PAGE40
  CF20    GND @S9S_MB_2U_LIB.S9S_MB_2U(SCH_1):GND    I12 @S9S_MB_2U_LIB.S9S_MB_2U(SCH_1):PAGE40
  CF16    GND @S9S_MB_2U_LIB.S9S_MB_2U(SCH_1):GND    I12 @S9S_MB_2U_LIB.S9S_MB_2U(SCH_1):PAGE40
  CF12    GND @S9S_MB_2U_LIB.S9S_MB_2U(SCH_1):GND    I12 @S9S_MB_2U_LIB.S9S_MB_2U(SCH_1):PAGE40
  CE78    GND @S9S_MB_2U_LIB.S9S_MB_2U(SCH_1):GND    I12 @S9S_MB_2U_LIB.S9S_MB_2U(SCH_1):PAGE40
  CE76    GND @S9S_MB_2U_LIB.S9S_MB_2U(SCH_1):GND    I12 @S9S_MB_2U_LIB.S9S_MB_2U(SCH_1):PAGE40
  CE72    GND @S9S_MB_2U_LIB.S9S_MB_2U(SCH_1):GND    I12 @S9S_MB_2U_LIB.S9S_MB_2U(SCH_1):PAGE40
  CE66    GND @S9S_MB_2U_LIB.S9S_MB_2U(SCH_1):GND    I12 @S9S_MB_2U_LIB.S9S_MB_2U(SCH_1):PAGE40
  CE60    GND @S9S_MB_2U_LIB.S9S_MB_2U(SCH_1):GND    I12 @S9S_MB_2U_LIB.S9S_MB_2U(SCH_1):PAGE40
   CE3    GND @S9S_MB_2U_LIB.S9S_MB_2U(SCH_1):GND    I12 @S9S_MB_2U_LIB.S9S_MB_2U(SCH_1):PAGE40
   CD8    GND @S9S_MB_2U_LIB.S9S_MB_2U(SCH_1):GND    I12 @S9S_MB_2U_LIB.S9S_MB_2U(SCH_1):PAGE40
  CD77    GND @S9S_MB_2U_LIB.S9S_MB_2U(SCH_1):GND    I12 @S9S_MB_2U_LIB.S9S_MB_2U(SCH_1):PAGE40
  CD75    GND @S9S_MB_2U_LIB.S9S_MB_2U(SCH_1):GND    I12 @S9S_MB_2U_LIB.S9S_MB_2U(SCH_1):PAGE40
  CD61    GND @S9S_MB_2U_LIB.S9S_MB_2U(SCH_1):GND    I12 @S9S_MB_2U_LIB.S9S_MB_2U(SCH_1):PAGE40
   CD4    GND @S9S_MB_2U_LIB.S9S_MB_2U(SCH_1):GND    I12 @S9S_MB_2U_LIB.S9S_MB_2U(SCH_1):PAGE40
  CD20    GND @S9S_MB_2U_LIB.S9S_MB_2U(SCH_1):GND    I12 @S9S_MB_2U_LIB.S9S_MB_2U(SCH_1):PAGE40
  CD16    GND @S9S_MB_2U_LIB.S9S_MB_2U(SCH_1):GND    I12 @S9S_MB_2U_LIB.S9S_MB_2U(SCH_1):PAGE40
  CD12    GND @S9S_MB_2U_LIB.S9S_MB_2U(SCH_1):GND    I12 @S9S_MB_2U_LIB.S9S_MB_2U(SCH_1):PAGE40
   CC9    GND @S9S_MB_2U_LIB.S9S_MB_2U(SCH_1):GND    I12 @S9S_MB_2U_LIB.S9S_MB_2U(SCH_1):PAGE40
  CC74    GND @S9S_MB_2U_LIB.S9S_MB_2U(SCH_1):GND    I12 @S9S_MB_2U_LIB.S9S_MB_2U(SCH_1):PAGE40
  CC72    GND @S9S_MB_2U_LIB.S9S_MB_2U(SCH_1):GND    I12 @S9S_MB_2U_LIB.S9S_MB_2U(SCH_1):PAGE40
  CC70    GND @S9S_MB_2U_LIB.S9S_MB_2U(SCH_1):GND    I12 @S9S_MB_2U_LIB.S9S_MB_2U(SCH_1):PAGE40
  CC62    GND @S9S_MB_2U_LIB.S9S_MB_2U(SCH_1):GND    I12 @S9S_MB_2U_LIB.S9S_MB_2U(SCH_1):PAGE40
   CC5    GND @S9S_MB_2U_LIB.S9S_MB_2U(SCH_1):GND    I12 @S9S_MB_2U_LIB.S9S_MB_2U(SCH_1):PAGE40
  CC31    GND @S9S_MB_2U_LIB.S9S_MB_2U(SCH_1):GND    I12 @S9S_MB_2U_LIB.S9S_MB_2U(SCH_1):PAGE40
  CC17    GND @S9S_MB_2U_LIB.S9S_MB_2U(SCH_1):GND    I12 @S9S_MB_2U_LIB.S9S_MB_2U(SCH_1):PAGE40
  CC13    GND @S9S_MB_2U_LIB.S9S_MB_2U(SCH_1):GND    I12 @S9S_MB_2U_LIB.S9S_MB_2U(SCH_1):PAGE40
  CB89    GND @S9S_MB_2U_LIB.S9S_MB_2U(SCH_1):GND    I12 @S9S_MB_2U_LIB.S9S_MB_2U(SCH_1):PAGE40
  CB87    GND @S9S_MB_2U_LIB.S9S_MB_2U(SCH_1):GND    I12 @S9S_MB_2U_LIB.S9S_MB_2U(SCH_1):PAGE40
  CB85    GND @S9S_MB_2U_LIB.S9S_MB_2U(SCH_1):GND    I12 @S9S_MB_2U_LIB.S9S_MB_2U(SCH_1):PAGE40
  CB83    GND @S9S_MB_2U_LIB.S9S_MB_2U(SCH_1):GND    I12 @S9S_MB_2U_LIB.S9S_MB_2U(SCH_1):PAGE40
  CB81    GND @S9S_MB_2U_LIB.S9S_MB_2U(SCH_1):GND    I12 @S9S_MB_2U_LIB.S9S_MB_2U(SCH_1):PAGE40
   CB8    GND @S9S_MB_2U_LIB.S9S_MB_2U(SCH_1):GND    I12 @S9S_MB_2U_LIB.S9S_MB_2U(SCH_1):PAGE40
  CB79    GND @S9S_MB_2U_LIB.S9S_MB_2U(SCH_1):GND    I12 @S9S_MB_2U_LIB.S9S_MB_2U(SCH_1):PAGE40
  CB73    GND @S9S_MB_2U_LIB.S9S_MB_2U(SCH_1):GND    I12 @S9S_MB_2U_LIB.S9S_MB_2U(SCH_1):PAGE40
  CB71    GND @S9S_MB_2U_LIB.S9S_MB_2U(SCH_1):GND    I12 @S9S_MB_2U_LIB.S9S_MB_2U(SCH_1):PAGE40
  CB69    GND @S9S_MB_2U_LIB.S9S_MB_2U(SCH_1):GND    I12 @S9S_MB_2U_LIB.S9S_MB_2U(SCH_1):PAGE40
  CB67    GND @S9S_MB_2U_LIB.S9S_MB_2U(SCH_1):GND    I12 @S9S_MB_2U_LIB.S9S_MB_2U(SCH_1):PAGE40
  CB65    GND @S9S_MB_2U_LIB.S9S_MB_2U(SCH_1):GND    I12 @S9S_MB_2U_LIB.S9S_MB_2U(SCH_1):PAGE40
  CB63    GND @S9S_MB_2U_LIB.S9S_MB_2U(SCH_1):GND    I12 @S9S_MB_2U_LIB.S9S_MB_2U(SCH_1):PAGE40
  CB59    GND @S9S_MB_2U_LIB.S9S_MB_2U(SCH_1):GND    I12 @S9S_MB_2U_LIB.S9S_MB_2U(SCH_1):PAGE40
  CB57    GND @S9S_MB_2U_LIB.S9S_MB_2U(SCH_1):GND    I12 @S9S_MB_2U_LIB.S9S_MB_2U(SCH_1):PAGE40
  CB55    GND @S9S_MB_2U_LIB.S9S_MB_2U(SCH_1):GND    I12 @S9S_MB_2U_LIB.S9S_MB_2U(SCH_1):PAGE40
  CB53    GND @S9S_MB_2U_LIB.S9S_MB_2U(SCH_1):GND    I12 @S9S_MB_2U_LIB.S9S_MB_2U(SCH_1):PAGE40
  CB51    GND @S9S_MB_2U_LIB.S9S_MB_2U(SCH_1):GND    I12 @S9S_MB_2U_LIB.S9S_MB_2U(SCH_1):PAGE40
  CB49    GND @S9S_MB_2U_LIB.S9S_MB_2U(SCH_1):GND    I12 @S9S_MB_2U_LIB.S9S_MB_2U(SCH_1):PAGE40
  CB47    GND @S9S_MB_2U_LIB.S9S_MB_2U(SCH_1):GND    I12 @S9S_MB_2U_LIB.S9S_MB_2U(SCH_1):PAGE40
  CB44    GND @S9S_MB_2U_LIB.S9S_MB_2U(SCH_1):GND    I12 @S9S_MB_2U_LIB.S9S_MB_2U(SCH_1):PAGE40
  CB42    GND @S9S_MB_2U_LIB.S9S_MB_2U(SCH_1):GND    I12 @S9S_MB_2U_LIB.S9S_MB_2U(SCH_1):PAGE40
  CB40    GND @S9S_MB_2U_LIB.S9S_MB_2U(SCH_1):GND    I12 @S9S_MB_2U_LIB.S9S_MB_2U(SCH_1):PAGE40
   CB4    GND @S9S_MB_2U_LIB.S9S_MB_2U(SCH_1):GND    I12 @S9S_MB_2U_LIB.S9S_MB_2U(SCH_1):PAGE40
  CB38    GND @S9S_MB_2U_LIB.S9S_MB_2U(SCH_1):GND    I12 @S9S_MB_2U_LIB.S9S_MB_2U(SCH_1):PAGE40
  CB36    GND @S9S_MB_2U_LIB.S9S_MB_2U(SCH_1):GND    I12 @S9S_MB_2U_LIB.S9S_MB_2U(SCH_1):PAGE40
  CB34    GND @S9S_MB_2U_LIB.S9S_MB_2U(SCH_1):GND    I12 @S9S_MB_2U_LIB.S9S_MB_2U(SCH_1):PAGE40
  CB32    GND @S9S_MB_2U_LIB.S9S_MB_2U(SCH_1):GND    I12 @S9S_MB_2U_LIB.S9S_MB_2U(SCH_1):PAGE40
  CB28    GND @S9S_MB_2U_LIB.S9S_MB_2U(SCH_1):GND    I12 @S9S_MB_2U_LIB.S9S_MB_2U(SCH_1):PAGE40
  CB26    GND @S9S_MB_2U_LIB.S9S_MB_2U(SCH_1):GND    I12 @S9S_MB_2U_LIB.S9S_MB_2U(SCH_1):PAGE40
  CB24    GND @S9S_MB_2U_LIB.S9S_MB_2U(SCH_1):GND    I12 @S9S_MB_2U_LIB.S9S_MB_2U(SCH_1):PAGE40
  CB22    GND @S9S_MB_2U_LIB.S9S_MB_2U(SCH_1):GND    I12 @S9S_MB_2U_LIB.S9S_MB_2U(SCH_1):PAGE40
  CB20    GND @S9S_MB_2U_LIB.S9S_MB_2U(SCH_1):GND    I12 @S9S_MB_2U_LIB.S9S_MB_2U(SCH_1):PAGE40
  CB16    GND @S9S_MB_2U_LIB.S9S_MB_2U(SCH_1):GND    I12 @S9S_MB_2U_LIB.S9S_MB_2U(SCH_1):PAGE40
  CB12    GND @S9S_MB_2U_LIB.S9S_MB_2U(SCH_1):GND    I12 @S9S_MB_2U_LIB.S9S_MB_2U(SCH_1):PAGE40
  CA31    GND @S9S_MB_2U_LIB.S9S_MB_2U(SCH_1):GND    I12 @S9S_MB_2U_LIB.S9S_MB_2U(SCH_1):PAGE40
   CA3    GND @S9S_MB_2U_LIB.S9S_MB_2U(SCH_1):GND    I12 @S9S_MB_2U_LIB.S9S_MB_2U(SCH_1):PAGE40
   BY8    GND @S9S_MB_2U_LIB.S9S_MB_2U(SCH_1):GND    I12 @S9S_MB_2U_LIB.S9S_MB_2U(SCH_1):PAGE40
   BY4    GND @S9S_MB_2U_LIB.S9S_MB_2U(SCH_1):GND    I12 @S9S_MB_2U_LIB.S9S_MB_2U(SCH_1):PAGE40
  BY20    GND @S9S_MB_2U_LIB.S9S_MB_2U(SCH_1):GND    I12 @S9S_MB_2U_LIB.S9S_MB_2U(SCH_1):PAGE40
  BY16    GND @S9S_MB_2U_LIB.S9S_MB_2U(SCH_1):GND    I12 @S9S_MB_2U_LIB.S9S_MB_2U(SCH_1):PAGE40
  BY12    GND @S9S_MB_2U_LIB.S9S_MB_2U(SCH_1):GND    I12 @S9S_MB_2U_LIB.S9S_MB_2U(SCH_1):PAGE40
   BW9    GND @S9S_MB_2U_LIB.S9S_MB_2U(SCH_1):GND    I12 @S9S_MB_2U_LIB.S9S_MB_2U(SCH_1):PAGE40
   BW5    GND @S9S_MB_2U_LIB.S9S_MB_2U(SCH_1):GND    I12 @S9S_MB_2U_LIB.S9S_MB_2U(SCH_1):PAGE40
  BW31    GND @S9S_MB_2U_LIB.S9S_MB_2U(SCH_1):GND    I12 @S9S_MB_2U_LIB.S9S_MB_2U(SCH_1):PAGE40
   BW3    GND @S9S_MB_2U_LIB.S9S_MB_2U(SCH_1):GND    I12 @S9S_MB_2U_LIB.S9S_MB_2U(SCH_1):PAGE40
  BW29    GND @S9S_MB_2U_LIB.S9S_MB_2U(SCH_1):GND    I12 @S9S_MB_2U_LIB.S9S_MB_2U(SCH_1):PAGE40
  BW27    GND @S9S_MB_2U_LIB.S9S_MB_2U(SCH_1):GND    I12 @S9S_MB_2U_LIB.S9S_MB_2U(SCH_1):PAGE40
  BW17    GND @S9S_MB_2U_LIB.S9S_MB_2U(SCH_1):GND    I12 @S9S_MB_2U_LIB.S9S_MB_2U(SCH_1):PAGE40
  BW13    GND @S9S_MB_2U_LIB.S9S_MB_2U(SCH_1):GND    I12 @S9S_MB_2U_LIB.S9S_MB_2U(SCH_1):PAGE40
   BV8    GND @S9S_MB_2U_LIB.S9S_MB_2U(SCH_1):GND    I12 @S9S_MB_2U_LIB.S9S_MB_2U(SCH_1):PAGE40
   BV6    GND @S9S_MB_2U_LIB.S9S_MB_2U(SCH_1):GND    I12 @S9S_MB_2U_LIB.S9S_MB_2U(SCH_1):PAGE40
   BV4    GND @S9S_MB_2U_LIB.S9S_MB_2U(SCH_1):GND    I12 @S9S_MB_2U_LIB.S9S_MB_2U(SCH_1):PAGE40
  BV20    GND @S9S_MB_2U_LIB.S9S_MB_2U(SCH_1):GND    I12 @S9S_MB_2U_LIB.S9S_MB_2U(SCH_1):PAGE40
   BV2    GND @S9S_MB_2U_LIB.S9S_MB_2U(SCH_1):GND    I12 @S9S_MB_2U_LIB.S9S_MB_2U(SCH_1):PAGE40
  BV18    GND @S9S_MB_2U_LIB.S9S_MB_2U(SCH_1):GND    I12 @S9S_MB_2U_LIB.S9S_MB_2U(SCH_1):PAGE40
  BV16    GND @S9S_MB_2U_LIB.S9S_MB_2U(SCH_1):GND    I12 @S9S_MB_2U_LIB.S9S_MB_2U(SCH_1):PAGE40
  BV12    GND @S9S_MB_2U_LIB.S9S_MB_2U(SCH_1):GND    I12 @S9S_MB_2U_LIB.S9S_MB_2U(SCH_1):PAGE40
   BU7    GND @S9S_MB_2U_LIB.S9S_MB_2U(SCH_1):GND    I12 @S9S_MB_2U_LIB.S9S_MB_2U(SCH_1):PAGE40
  BU31    GND @S9S_MB_2U_LIB.S9S_MB_2U(SCH_1):GND    I12 @S9S_MB_2U_LIB.S9S_MB_2U(SCH_1):PAGE40
  BU25    GND @S9S_MB_2U_LIB.S9S_MB_2U(SCH_1):GND    I12 @S9S_MB_2U_LIB.S9S_MB_2U(SCH_1):PAGE40
  BU23    GND @S9S_MB_2U_LIB.S9S_MB_2U(SCH_1):GND    I12 @S9S_MB_2U_LIB.S9S_MB_2U(SCH_1):PAGE40
  BU21    GND @S9S_MB_2U_LIB.S9S_MB_2U(SCH_1):GND    I12 @S9S_MB_2U_LIB.S9S_MB_2U(SCH_1):PAGE40
  BU19    GND @S9S_MB_2U_LIB.S9S_MB_2U(SCH_1):GND    I12 @S9S_MB_2U_LIB.S9S_MB_2U(SCH_1):PAGE40
  BU15    GND @S9S_MB_2U_LIB.S9S_MB_2U(SCH_1):GND    I12 @S9S_MB_2U_LIB.S9S_MB_2U(SCH_1):PAGE40
   BT8    GND @S9S_MB_2U_LIB.S9S_MB_2U(SCH_1):GND    I12 @S9S_MB_2U_LIB.S9S_MB_2U(SCH_1):PAGE40
   BT4    GND @S9S_MB_2U_LIB.S9S_MB_2U(SCH_1):GND    I12 @S9S_MB_2U_LIB.S9S_MB_2U(SCH_1):PAGE40
  BT20    GND @S9S_MB_2U_LIB.S9S_MB_2U(SCH_1):GND    I12 @S9S_MB_2U_LIB.S9S_MB_2U(SCH_1):PAGE40
  BT16    GND @S9S_MB_2U_LIB.S9S_MB_2U(SCH_1):GND    I12 @S9S_MB_2U_LIB.S9S_MB_2U(SCH_1):PAGE40
  BT12    GND @S9S_MB_2U_LIB.S9S_MB_2U(SCH_1):GND    I12 @S9S_MB_2U_LIB.S9S_MB_2U(SCH_1):PAGE40
  BR90    GND @S9S_MB_2U_LIB.S9S_MB_2U(SCH_1):GND    I12 @S9S_MB_2U_LIB.S9S_MB_2U(SCH_1):PAGE40
  BR88    GND @S9S_MB_2U_LIB.S9S_MB_2U(SCH_1):GND    I12 @S9S_MB_2U_LIB.S9S_MB_2U(SCH_1):PAGE40
  BR86    GND @S9S_MB_2U_LIB.S9S_MB_2U(SCH_1):GND    I12 @S9S_MB_2U_LIB.S9S_MB_2U(SCH_1):PAGE40
  BR84    GND @S9S_MB_2U_LIB.S9S_MB_2U(SCH_1):GND    I12 @S9S_MB_2U_LIB.S9S_MB_2U(SCH_1):PAGE40
  BR82    GND @S9S_MB_2U_LIB.S9S_MB_2U(SCH_1):GND    I12 @S9S_MB_2U_LIB.S9S_MB_2U(SCH_1):PAGE40
  BR80    GND @S9S_MB_2U_LIB.S9S_MB_2U(SCH_1):GND    I12 @S9S_MB_2U_LIB.S9S_MB_2U(SCH_1):PAGE40
  BR76    GND @S9S_MB_2U_LIB.S9S_MB_2U(SCH_1):GND    I12 @S9S_MB_2U_LIB.S9S_MB_2U(SCH_1):PAGE40
  BR74    GND @S9S_MB_2U_LIB.S9S_MB_2U(SCH_1):GND    I12 @S9S_MB_2U_LIB.S9S_MB_2U(SCH_1):PAGE40
  BR72    GND @S9S_MB_2U_LIB.S9S_MB_2U(SCH_1):GND    I12 @S9S_MB_2U_LIB.S9S_MB_2U(SCH_1):PAGE40
  BR70    GND @S9S_MB_2U_LIB.S9S_MB_2U(SCH_1):GND    I12 @S9S_MB_2U_LIB.S9S_MB_2U(SCH_1):PAGE40
  BR68    GND @S9S_MB_2U_LIB.S9S_MB_2U(SCH_1):GND    I12 @S9S_MB_2U_LIB.S9S_MB_2U(SCH_1):PAGE40
  BR66    GND @S9S_MB_2U_LIB.S9S_MB_2U(SCH_1):GND    I12 @S9S_MB_2U_LIB.S9S_MB_2U(SCH_1):PAGE40
  BR64    GND @S9S_MB_2U_LIB.S9S_MB_2U(SCH_1):GND    I12 @S9S_MB_2U_LIB.S9S_MB_2U(SCH_1):PAGE40
  BR58    GND @S9S_MB_2U_LIB.S9S_MB_2U(SCH_1):GND    I12 @S9S_MB_2U_LIB.S9S_MB_2U(SCH_1):PAGE40
  BR56    GND @S9S_MB_2U_LIB.S9S_MB_2U(SCH_1):GND    I12 @S9S_MB_2U_LIB.S9S_MB_2U(SCH_1):PAGE40
  BR54    GND @S9S_MB_2U_LIB.S9S_MB_2U(SCH_1):GND    I12 @S9S_MB_2U_LIB.S9S_MB_2U(SCH_1):PAGE40
  BR52    GND @S9S_MB_2U_LIB.S9S_MB_2U(SCH_1):GND    I12 @S9S_MB_2U_LIB.S9S_MB_2U(SCH_1):PAGE40
  BR50    GND @S9S_MB_2U_LIB.S9S_MB_2U(SCH_1):GND    I12 @S9S_MB_2U_LIB.S9S_MB_2U(SCH_1):PAGE40
  BR48    GND @S9S_MB_2U_LIB.S9S_MB_2U(SCH_1):GND    I12 @S9S_MB_2U_LIB.S9S_MB_2U(SCH_1):PAGE40
  BR45    GND @S9S_MB_2U_LIB.S9S_MB_2U(SCH_1):GND    I12 @S9S_MB_2U_LIB.S9S_MB_2U(SCH_1):PAGE40
  BR43    GND @S9S_MB_2U_LIB.S9S_MB_2U(SCH_1):GND    I12 @S9S_MB_2U_LIB.S9S_MB_2U(SCH_1):PAGE40
  BR41    GND @S9S_MB_2U_LIB.S9S_MB_2U(SCH_1):GND    I12 @S9S_MB_2U_LIB.S9S_MB_2U(SCH_1):PAGE40
  BR39    GND @S9S_MB_2U_LIB.S9S_MB_2U(SCH_1):GND    I12 @S9S_MB_2U_LIB.S9S_MB_2U(SCH_1):PAGE40
  BR37    GND @S9S_MB_2U_LIB.S9S_MB_2U(SCH_1):GND    I12 @S9S_MB_2U_LIB.S9S_MB_2U(SCH_1):PAGE40
  BR35    GND @S9S_MB_2U_LIB.S9S_MB_2U(SCH_1):GND    I12 @S9S_MB_2U_LIB.S9S_MB_2U(SCH_1):PAGE40
   CK4    GND @S9S_MB_2U_LIB.S9S_MB_2U(SCH_1):GND    I12 @S9S_MB_2U_LIB.S9S_MB_2U(SCH_1):PAGE40
  CJ76    GND @S9S_MB_2U_LIB.S9S_MB_2U(SCH_1):GND    I12 @S9S_MB_2U_LIB.S9S_MB_2U(SCH_1):PAGE40
   BR9    GND @S9S_MB_2U_LIB.S9S_MB_2U(SCH_1):GND     I9 @S9S_MB_2U_LIB.S9S_MB_2U(SCH_1):PAGE41
  BR33    GND @S9S_MB_2U_LIB.S9S_MB_2U(SCH_1):GND     I9 @S9S_MB_2U_LIB.S9S_MB_2U(SCH_1):PAGE41
  BR31    GND @S9S_MB_2U_LIB.S9S_MB_2U(SCH_1):GND     I9 @S9S_MB_2U_LIB.S9S_MB_2U(SCH_1):PAGE41
  BR29    GND @S9S_MB_2U_LIB.S9S_MB_2U(SCH_1):GND     I9 @S9S_MB_2U_LIB.S9S_MB_2U(SCH_1):PAGE41
  BR27    GND @S9S_MB_2U_LIB.S9S_MB_2U(SCH_1):GND     I9 @S9S_MB_2U_LIB.S9S_MB_2U(SCH_1):PAGE41
  BR17    GND @S9S_MB_2U_LIB.S9S_MB_2U(SCH_1):GND     I9 @S9S_MB_2U_LIB.S9S_MB_2U(SCH_1):PAGE41
  BR13    GND @S9S_MB_2U_LIB.S9S_MB_2U(SCH_1):GND     I9 @S9S_MB_2U_LIB.S9S_MB_2U(SCH_1):PAGE41
   BP8    GND @S9S_MB_2U_LIB.S9S_MB_2U(SCH_1):GND     I9 @S9S_MB_2U_LIB.S9S_MB_2U(SCH_1):PAGE41
  BP77    GND @S9S_MB_2U_LIB.S9S_MB_2U(SCH_1):GND     I9 @S9S_MB_2U_LIB.S9S_MB_2U(SCH_1):PAGE41
  BP75    GND @S9S_MB_2U_LIB.S9S_MB_2U(SCH_1):GND     I9 @S9S_MB_2U_LIB.S9S_MB_2U(SCH_1):PAGE41
  BP73    GND @S9S_MB_2U_LIB.S9S_MB_2U(SCH_1):GND     I9 @S9S_MB_2U_LIB.S9S_MB_2U(SCH_1):PAGE41
  BP71    GND @S9S_MB_2U_LIB.S9S_MB_2U(SCH_1):GND     I9 @S9S_MB_2U_LIB.S9S_MB_2U(SCH_1):PAGE41
  BP63    GND @S9S_MB_2U_LIB.S9S_MB_2U(SCH_1):GND     I9 @S9S_MB_2U_LIB.S9S_MB_2U(SCH_1):PAGE41
   BP4    GND @S9S_MB_2U_LIB.S9S_MB_2U(SCH_1):GND     I9 @S9S_MB_2U_LIB.S9S_MB_2U(SCH_1):PAGE41
  BP20    GND @S9S_MB_2U_LIB.S9S_MB_2U(SCH_1):GND     I9 @S9S_MB_2U_LIB.S9S_MB_2U(SCH_1):PAGE41
   BP2    GND @S9S_MB_2U_LIB.S9S_MB_2U(SCH_1):GND     I9 @S9S_MB_2U_LIB.S9S_MB_2U(SCH_1):PAGE41
  BP16    GND @S9S_MB_2U_LIB.S9S_MB_2U(SCH_1):GND     I9 @S9S_MB_2U_LIB.S9S_MB_2U(SCH_1):PAGE41
  BP12    GND @S9S_MB_2U_LIB.S9S_MB_2U(SCH_1):GND     I9 @S9S_MB_2U_LIB.S9S_MB_2U(SCH_1):PAGE41
  BN70    GND @S9S_MB_2U_LIB.S9S_MB_2U(SCH_1):GND     I9 @S9S_MB_2U_LIB.S9S_MB_2U(SCH_1):PAGE41
  BN62    GND @S9S_MB_2U_LIB.S9S_MB_2U(SCH_1):GND     I9 @S9S_MB_2U_LIB.S9S_MB_2U(SCH_1):PAGE41
  BN31    GND @S9S_MB_2U_LIB.S9S_MB_2U(SCH_1):GND     I9 @S9S_MB_2U_LIB.S9S_MB_2U(SCH_1):PAGE41
   BM8    GND @S9S_MB_2U_LIB.S9S_MB_2U(SCH_1):GND     I9 @S9S_MB_2U_LIB.S9S_MB_2U(SCH_1):PAGE41
  BM77    GND @S9S_MB_2U_LIB.S9S_MB_2U(SCH_1):GND     I9 @S9S_MB_2U_LIB.S9S_MB_2U(SCH_1):PAGE41
  BM73    GND @S9S_MB_2U_LIB.S9S_MB_2U(SCH_1):GND     I9 @S9S_MB_2U_LIB.S9S_MB_2U(SCH_1):PAGE41
  BM61    GND @S9S_MB_2U_LIB.S9S_MB_2U(SCH_1):GND     I9 @S9S_MB_2U_LIB.S9S_MB_2U(SCH_1):PAGE41
   BM4    GND @S9S_MB_2U_LIB.S9S_MB_2U(SCH_1):GND     I9 @S9S_MB_2U_LIB.S9S_MB_2U(SCH_1):PAGE41
  BM26    GND @S9S_MB_2U_LIB.S9S_MB_2U(SCH_1):GND     I9 @S9S_MB_2U_LIB.S9S_MB_2U(SCH_1):PAGE41
  BM24    GND @S9S_MB_2U_LIB.S9S_MB_2U(SCH_1):GND     I9 @S9S_MB_2U_LIB.S9S_MB_2U(SCH_1):PAGE41
  BM22    GND @S9S_MB_2U_LIB.S9S_MB_2U(SCH_1):GND     I9 @S9S_MB_2U_LIB.S9S_MB_2U(SCH_1):PAGE41
  BM20    GND @S9S_MB_2U_LIB.S9S_MB_2U(SCH_1):GND     I9 @S9S_MB_2U_LIB.S9S_MB_2U(SCH_1):PAGE41
  BM16    GND @S9S_MB_2U_LIB.S9S_MB_2U(SCH_1):GND     I9 @S9S_MB_2U_LIB.S9S_MB_2U(SCH_1):PAGE41
  BM12    GND @S9S_MB_2U_LIB.S9S_MB_2U(SCH_1):GND     I9 @S9S_MB_2U_LIB.S9S_MB_2U(SCH_1):PAGE41
   BL9    GND @S9S_MB_2U_LIB.S9S_MB_2U(SCH_1):GND     I9 @S9S_MB_2U_LIB.S9S_MB_2U(SCH_1):PAGE41
  BL78    GND @S9S_MB_2U_LIB.S9S_MB_2U(SCH_1):GND     I9 @S9S_MB_2U_LIB.S9S_MB_2U(SCH_1):PAGE41
  BL72    GND @S9S_MB_2U_LIB.S9S_MB_2U(SCH_1):GND     I9 @S9S_MB_2U_LIB.S9S_MB_2U(SCH_1):PAGE41
  BL70    GND @S9S_MB_2U_LIB.S9S_MB_2U(SCH_1):GND     I9 @S9S_MB_2U_LIB.S9S_MB_2U(SCH_1):PAGE41
  BL68    GND @S9S_MB_2U_LIB.S9S_MB_2U(SCH_1):GND     I9 @S9S_MB_2U_LIB.S9S_MB_2U(SCH_1):PAGE41
   BL5    GND @S9S_MB_2U_LIB.S9S_MB_2U(SCH_1):GND     I9 @S9S_MB_2U_LIB.S9S_MB_2U(SCH_1):PAGE41
  BL17    GND @S9S_MB_2U_LIB.S9S_MB_2U(SCH_1):GND     I9 @S9S_MB_2U_LIB.S9S_MB_2U(SCH_1):PAGE41
  BL13    GND @S9S_MB_2U_LIB.S9S_MB_2U(SCH_1):GND     I9 @S9S_MB_2U_LIB.S9S_MB_2U(SCH_1):PAGE41
   BL1    GND @S9S_MB_2U_LIB.S9S_MB_2U(SCH_1):GND     I9 @S9S_MB_2U_LIB.S9S_MB_2U(SCH_1):PAGE41
   BK8    GND @S9S_MB_2U_LIB.S9S_MB_2U(SCH_1):GND     I9 @S9S_MB_2U_LIB.S9S_MB_2U(SCH_1):PAGE41
  BK79    GND @S9S_MB_2U_LIB.S9S_MB_2U(SCH_1):GND     I9 @S9S_MB_2U_LIB.S9S_MB_2U(SCH_1):PAGE41
  BK75    GND @S9S_MB_2U_LIB.S9S_MB_2U(SCH_1):GND     I9 @S9S_MB_2U_LIB.S9S_MB_2U(SCH_1):PAGE41
  BK71    GND @S9S_MB_2U_LIB.S9S_MB_2U(SCH_1):GND     I9 @S9S_MB_2U_LIB.S9S_MB_2U(SCH_1):PAGE41
  BK65    GND @S9S_MB_2U_LIB.S9S_MB_2U(SCH_1):GND     I9 @S9S_MB_2U_LIB.S9S_MB_2U(SCH_1):PAGE41
   BK4    GND @S9S_MB_2U_LIB.S9S_MB_2U(SCH_1):GND     I9 @S9S_MB_2U_LIB.S9S_MB_2U(SCH_1):PAGE41
  BK20    GND @S9S_MB_2U_LIB.S9S_MB_2U(SCH_1):GND     I9 @S9S_MB_2U_LIB.S9S_MB_2U(SCH_1):PAGE41
  BK16    GND @S9S_MB_2U_LIB.S9S_MB_2U(SCH_1):GND     I9 @S9S_MB_2U_LIB.S9S_MB_2U(SCH_1):PAGE41
  BK12    GND @S9S_MB_2U_LIB.S9S_MB_2U(SCH_1):GND     I9 @S9S_MB_2U_LIB.S9S_MB_2U(SCH_1):PAGE41
  BJ90    GND @S9S_MB_2U_LIB.S9S_MB_2U(SCH_1):GND     I9 @S9S_MB_2U_LIB.S9S_MB_2U(SCH_1):PAGE41
  BJ88    GND @S9S_MB_2U_LIB.S9S_MB_2U(SCH_1):GND     I9 @S9S_MB_2U_LIB.S9S_MB_2U(SCH_1):PAGE41
  BJ86    GND @S9S_MB_2U_LIB.S9S_MB_2U(SCH_1):GND     I9 @S9S_MB_2U_LIB.S9S_MB_2U(SCH_1):PAGE41
  BJ84    GND @S9S_MB_2U_LIB.S9S_MB_2U(SCH_1):GND     I9 @S9S_MB_2U_LIB.S9S_MB_2U(SCH_1):PAGE41
  BJ82    GND @S9S_MB_2U_LIB.S9S_MB_2U(SCH_1):GND     I9 @S9S_MB_2U_LIB.S9S_MB_2U(SCH_1):PAGE41
  BJ80    GND @S9S_MB_2U_LIB.S9S_MB_2U(SCH_1):GND     I9 @S9S_MB_2U_LIB.S9S_MB_2U(SCH_1):PAGE41
  BJ68    GND @S9S_MB_2U_LIB.S9S_MB_2U(SCH_1):GND     I9 @S9S_MB_2U_LIB.S9S_MB_2U(SCH_1):PAGE41
  BJ62    GND @S9S_MB_2U_LIB.S9S_MB_2U(SCH_1):GND     I9 @S9S_MB_2U_LIB.S9S_MB_2U(SCH_1):PAGE41
  BH83    GND @S9S_MB_2U_LIB.S9S_MB_2U(SCH_1):GND     I9 @S9S_MB_2U_LIB.S9S_MB_2U(SCH_1):PAGE41
  BH81    GND @S9S_MB_2U_LIB.S9S_MB_2U(SCH_1):GND     I9 @S9S_MB_2U_LIB.S9S_MB_2U(SCH_1):PAGE41
   BH8    GND @S9S_MB_2U_LIB.S9S_MB_2U(SCH_1):GND     I9 @S9S_MB_2U_LIB.S9S_MB_2U(SCH_1):PAGE41
  BH77    GND @S9S_MB_2U_LIB.S9S_MB_2U(SCH_1):GND     I9 @S9S_MB_2U_LIB.S9S_MB_2U(SCH_1):PAGE41
  BH73    GND @S9S_MB_2U_LIB.S9S_MB_2U(SCH_1):GND     I9 @S9S_MB_2U_LIB.S9S_MB_2U(SCH_1):PAGE41
  BH67    GND @S9S_MB_2U_LIB.S9S_MB_2U(SCH_1):GND     I9 @S9S_MB_2U_LIB.S9S_MB_2U(SCH_1):PAGE41
   BH4    GND @S9S_MB_2U_LIB.S9S_MB_2U(SCH_1):GND     I9 @S9S_MB_2U_LIB.S9S_MB_2U(SCH_1):PAGE41
  BH20    GND @S9S_MB_2U_LIB.S9S_MB_2U(SCH_1):GND     I9 @S9S_MB_2U_LIB.S9S_MB_2U(SCH_1):PAGE41
  BH16    GND @S9S_MB_2U_LIB.S9S_MB_2U(SCH_1):GND     I9 @S9S_MB_2U_LIB.S9S_MB_2U(SCH_1):PAGE41
  BH12    GND @S9S_MB_2U_LIB.S9S_MB_2U(SCH_1):GND     I9 @S9S_MB_2U_LIB.S9S_MB_2U(SCH_1):PAGE41
   BG9    GND @S9S_MB_2U_LIB.S9S_MB_2U(SCH_1):GND     I9 @S9S_MB_2U_LIB.S9S_MB_2U(SCH_1):PAGE41
  BG70    GND @S9S_MB_2U_LIB.S9S_MB_2U(SCH_1):GND     I9 @S9S_MB_2U_LIB.S9S_MB_2U(SCH_1):PAGE41
   BG5    GND @S9S_MB_2U_LIB.S9S_MB_2U(SCH_1):GND     I9 @S9S_MB_2U_LIB.S9S_MB_2U(SCH_1):PAGE41
  BG25    GND @S9S_MB_2U_LIB.S9S_MB_2U(SCH_1):GND     I9 @S9S_MB_2U_LIB.S9S_MB_2U(SCH_1):PAGE41
  BG23    GND @S9S_MB_2U_LIB.S9S_MB_2U(SCH_1):GND     I9 @S9S_MB_2U_LIB.S9S_MB_2U(SCH_1):PAGE41
  BG21    GND @S9S_MB_2U_LIB.S9S_MB_2U(SCH_1):GND     I9 @S9S_MB_2U_LIB.S9S_MB_2U(SCH_1):PAGE41
  BG17    GND @S9S_MB_2U_LIB.S9S_MB_2U(SCH_1):GND     I9 @S9S_MB_2U_LIB.S9S_MB_2U(SCH_1):PAGE41
  BG13    GND @S9S_MB_2U_LIB.S9S_MB_2U(SCH_1):GND     I9 @S9S_MB_2U_LIB.S9S_MB_2U(SCH_1):PAGE41
   BG1    GND @S9S_MB_2U_LIB.S9S_MB_2U(SCH_1):GND     I9 @S9S_MB_2U_LIB.S9S_MB_2U(SCH_1):PAGE41
  BF83    GND @S9S_MB_2U_LIB.S9S_MB_2U(SCH_1):GND     I9 @S9S_MB_2U_LIB.S9S_MB_2U(SCH_1):PAGE41
   BF8    GND @S9S_MB_2U_LIB.S9S_MB_2U(SCH_1):GND     I9 @S9S_MB_2U_LIB.S9S_MB_2U(SCH_1):PAGE41
  BF79    GND @S9S_MB_2U_LIB.S9S_MB_2U(SCH_1):GND     I9 @S9S_MB_2U_LIB.S9S_MB_2U(SCH_1):PAGE41
  BF75    GND @S9S_MB_2U_LIB.S9S_MB_2U(SCH_1):GND     I9 @S9S_MB_2U_LIB.S9S_MB_2U(SCH_1):PAGE41
  BF73    GND @S9S_MB_2U_LIB.S9S_MB_2U(SCH_1):GND     I9 @S9S_MB_2U_LIB.S9S_MB_2U(SCH_1):PAGE41
  BF63    GND @S9S_MB_2U_LIB.S9S_MB_2U(SCH_1):GND     I9 @S9S_MB_2U_LIB.S9S_MB_2U(SCH_1):PAGE41
  BF61    GND @S9S_MB_2U_LIB.S9S_MB_2U(SCH_1):GND     I9 @S9S_MB_2U_LIB.S9S_MB_2U(SCH_1):PAGE41
   BF4    GND @S9S_MB_2U_LIB.S9S_MB_2U(SCH_1):GND     I9 @S9S_MB_2U_LIB.S9S_MB_2U(SCH_1):PAGE41
  BF20    GND @S9S_MB_2U_LIB.S9S_MB_2U(SCH_1):GND     I9 @S9S_MB_2U_LIB.S9S_MB_2U(SCH_1):PAGE41
  BF16    GND @S9S_MB_2U_LIB.S9S_MB_2U(SCH_1):GND     I9 @S9S_MB_2U_LIB.S9S_MB_2U(SCH_1):PAGE41
  BF12    GND @S9S_MB_2U_LIB.S9S_MB_2U(SCH_1):GND     I9 @S9S_MB_2U_LIB.S9S_MB_2U(SCH_1):PAGE41
  BE84    GND @S9S_MB_2U_LIB.S9S_MB_2U(SCH_1):GND     I9 @S9S_MB_2U_LIB.S9S_MB_2U(SCH_1):PAGE41
  BE78    GND @S9S_MB_2U_LIB.S9S_MB_2U(SCH_1):GND     I9 @S9S_MB_2U_LIB.S9S_MB_2U(SCH_1):PAGE41
  BE76    GND @S9S_MB_2U_LIB.S9S_MB_2U(SCH_1):GND     I9 @S9S_MB_2U_LIB.S9S_MB_2U(SCH_1):PAGE41
  BE74    GND @S9S_MB_2U_LIB.S9S_MB_2U(SCH_1):GND     I9 @S9S_MB_2U_LIB.S9S_MB_2U(SCH_1):PAGE41
  BE68    GND @S9S_MB_2U_LIB.S9S_MB_2U(SCH_1):GND     I9 @S9S_MB_2U_LIB.S9S_MB_2U(SCH_1):PAGE41
  BE66    GND @S9S_MB_2U_LIB.S9S_MB_2U(SCH_1):GND     I9 @S9S_MB_2U_LIB.S9S_MB_2U(SCH_1):PAGE41
  BE64    GND @S9S_MB_2U_LIB.S9S_MB_2U(SCH_1):GND     I9 @S9S_MB_2U_LIB.S9S_MB_2U(SCH_1):PAGE41
  BD89    GND @S9S_MB_2U_LIB.S9S_MB_2U(SCH_1):GND     I9 @S9S_MB_2U_LIB.S9S_MB_2U(SCH_1):PAGE41
  BD85    GND @S9S_MB_2U_LIB.S9S_MB_2U(SCH_1):GND     I9 @S9S_MB_2U_LIB.S9S_MB_2U(SCH_1):PAGE41
  BD81    GND @S9S_MB_2U_LIB.S9S_MB_2U(SCH_1):GND     I9 @S9S_MB_2U_LIB.S9S_MB_2U(SCH_1):PAGE41
   BD8    GND @S9S_MB_2U_LIB.S9S_MB_2U(SCH_1):GND     I9 @S9S_MB_2U_LIB.S9S_MB_2U(SCH_1):PAGE41
   BD4    GND @S9S_MB_2U_LIB.S9S_MB_2U(SCH_1):GND     I9 @S9S_MB_2U_LIB.S9S_MB_2U(SCH_1):PAGE41
  BD20    GND @S9S_MB_2U_LIB.S9S_MB_2U(SCH_1):GND     I9 @S9S_MB_2U_LIB.S9S_MB_2U(SCH_1):PAGE41
  BD16    GND @S9S_MB_2U_LIB.S9S_MB_2U(SCH_1):GND     I9 @S9S_MB_2U_LIB.S9S_MB_2U(SCH_1):PAGE41
  BD12    GND @S9S_MB_2U_LIB.S9S_MB_2U(SCH_1):GND     I9 @S9S_MB_2U_LIB.S9S_MB_2U(SCH_1):PAGE41
   BC9    GND @S9S_MB_2U_LIB.S9S_MB_2U(SCH_1):GND     I9 @S9S_MB_2U_LIB.S9S_MB_2U(SCH_1):PAGE41
  BC88    GND @S9S_MB_2U_LIB.S9S_MB_2U(SCH_1):GND     I9 @S9S_MB_2U_LIB.S9S_MB_2U(SCH_1):PAGE41
  BC86    GND @S9S_MB_2U_LIB.S9S_MB_2U(SCH_1):GND     I9 @S9S_MB_2U_LIB.S9S_MB_2U(SCH_1):PAGE41
  BC84    GND @S9S_MB_2U_LIB.S9S_MB_2U(SCH_1):GND     I9 @S9S_MB_2U_LIB.S9S_MB_2U(SCH_1):PAGE41
  BC78    GND @S9S_MB_2U_LIB.S9S_MB_2U(SCH_1):GND     I9 @S9S_MB_2U_LIB.S9S_MB_2U(SCH_1):PAGE41
  BC76    GND @S9S_MB_2U_LIB.S9S_MB_2U(SCH_1):GND     I9 @S9S_MB_2U_LIB.S9S_MB_2U(SCH_1):PAGE41
  BC72    GND @S9S_MB_2U_LIB.S9S_MB_2U(SCH_1):GND     I9 @S9S_MB_2U_LIB.S9S_MB_2U(SCH_1):PAGE41
  BC66    GND @S9S_MB_2U_LIB.S9S_MB_2U(SCH_1):GND     I9 @S9S_MB_2U_LIB.S9S_MB_2U(SCH_1):PAGE41
  BC62    GND @S9S_MB_2U_LIB.S9S_MB_2U(SCH_1):GND     I9 @S9S_MB_2U_LIB.S9S_MB_2U(SCH_1):PAGE41
   BC5    GND @S9S_MB_2U_LIB.S9S_MB_2U(SCH_1):GND     I9 @S9S_MB_2U_LIB.S9S_MB_2U(SCH_1):PAGE41
  BC17    GND @S9S_MB_2U_LIB.S9S_MB_2U(SCH_1):GND     I9 @S9S_MB_2U_LIB.S9S_MB_2U(SCH_1):PAGE41
  BC13    GND @S9S_MB_2U_LIB.S9S_MB_2U(SCH_1):GND     I9 @S9S_MB_2U_LIB.S9S_MB_2U(SCH_1):PAGE41
   BC1    GND @S9S_MB_2U_LIB.S9S_MB_2U(SCH_1):GND     I9 @S9S_MB_2U_LIB.S9S_MB_2U(SCH_1):PAGE41
  BB91    GND @S9S_MB_2U_LIB.S9S_MB_2U(SCH_1):GND     I9 @S9S_MB_2U_LIB.S9S_MB_2U(SCH_1):PAGE41
  BB87    GND @S9S_MB_2U_LIB.S9S_MB_2U(SCH_1):GND     I9 @S9S_MB_2U_LIB.S9S_MB_2U(SCH_1):PAGE41
  BB83    GND @S9S_MB_2U_LIB.S9S_MB_2U(SCH_1):GND     I9 @S9S_MB_2U_LIB.S9S_MB_2U(SCH_1):PAGE41
   BB8    GND @S9S_MB_2U_LIB.S9S_MB_2U(SCH_1):GND     I9 @S9S_MB_2U_LIB.S9S_MB_2U(SCH_1):PAGE41
  BB79    GND @S9S_MB_2U_LIB.S9S_MB_2U(SCH_1):GND     I9 @S9S_MB_2U_LIB.S9S_MB_2U(SCH_1):PAGE41
  BB77    GND @S9S_MB_2U_LIB.S9S_MB_2U(SCH_1):GND     I9 @S9S_MB_2U_LIB.S9S_MB_2U(SCH_1):PAGE41
  BB71    GND @S9S_MB_2U_LIB.S9S_MB_2U(SCH_1):GND     I9 @S9S_MB_2U_LIB.S9S_MB_2U(SCH_1):PAGE41
  BB69    GND @S9S_MB_2U_LIB.S9S_MB_2U(SCH_1):GND     I9 @S9S_MB_2U_LIB.S9S_MB_2U(SCH_1):PAGE41
  BB63    GND @S9S_MB_2U_LIB.S9S_MB_2U(SCH_1):GND     I9 @S9S_MB_2U_LIB.S9S_MB_2U(SCH_1):PAGE41
   BB4    GND @S9S_MB_2U_LIB.S9S_MB_2U(SCH_1):GND     I9 @S9S_MB_2U_LIB.S9S_MB_2U(SCH_1):PAGE41
  BB26    GND @S9S_MB_2U_LIB.S9S_MB_2U(SCH_1):GND     I9 @S9S_MB_2U_LIB.S9S_MB_2U(SCH_1):PAGE41
  BB24    GND @S9S_MB_2U_LIB.S9S_MB_2U(SCH_1):GND     I9 @S9S_MB_2U_LIB.S9S_MB_2U(SCH_1):PAGE41
  BB22    GND @S9S_MB_2U_LIB.S9S_MB_2U(SCH_1):GND     I9 @S9S_MB_2U_LIB.S9S_MB_2U(SCH_1):PAGE41
  BB20    GND @S9S_MB_2U_LIB.S9S_MB_2U(SCH_1):GND     I9 @S9S_MB_2U_LIB.S9S_MB_2U(SCH_1):PAGE41
  BB16    GND @S9S_MB_2U_LIB.S9S_MB_2U(SCH_1):GND     I9 @S9S_MB_2U_LIB.S9S_MB_2U(SCH_1):PAGE41
  BB12    GND @S9S_MB_2U_LIB.S9S_MB_2U(SCH_1):GND     I9 @S9S_MB_2U_LIB.S9S_MB_2U(SCH_1):PAGE41
  BB10    GND @S9S_MB_2U_LIB.S9S_MB_2U(SCH_1):GND     I9 @S9S_MB_2U_LIB.S9S_MB_2U(SCH_1):PAGE41
  BA88    GND @S9S_MB_2U_LIB.S9S_MB_2U(SCH_1):GND     I9 @S9S_MB_2U_LIB.S9S_MB_2U(SCH_1):PAGE41
  BA84    GND @S9S_MB_2U_LIB.S9S_MB_2U(SCH_1):GND     I9 @S9S_MB_2U_LIB.S9S_MB_2U(SCH_1):PAGE41
  BA74    GND @S9S_MB_2U_LIB.S9S_MB_2U(SCH_1):GND     I9 @S9S_MB_2U_LIB.S9S_MB_2U(SCH_1):PAGE41
  BA64    GND @S9S_MB_2U_LIB.S9S_MB_2U(SCH_1):GND     I9 @S9S_MB_2U_LIB.S9S_MB_2U(SCH_1):PAGE41
  BA60    GND @S9S_MB_2U_LIB.S9S_MB_2U(SCH_1):GND     I9 @S9S_MB_2U_LIB.S9S_MB_2U(SCH_1):PAGE41
  BA17    GND @S9S_MB_2U_LIB.S9S_MB_2U(SCH_1):GND     I9 @S9S_MB_2U_LIB.S9S_MB_2U(SCH_1):PAGE41
  AY83    GND @S9S_MB_2U_LIB.S9S_MB_2U(SCH_1):GND     I9 @S9S_MB_2U_LIB.S9S_MB_2U(SCH_1):PAGE41
  AY81    GND @S9S_MB_2U_LIB.S9S_MB_2U(SCH_1):GND     I9 @S9S_MB_2U_LIB.S9S_MB_2U(SCH_1):PAGE41
   AY8    GND @S9S_MB_2U_LIB.S9S_MB_2U(SCH_1):GND     I9 @S9S_MB_2U_LIB.S9S_MB_2U(SCH_1):PAGE41
  AY79    GND @S9S_MB_2U_LIB.S9S_MB_2U(SCH_1):GND     I9 @S9S_MB_2U_LIB.S9S_MB_2U(SCH_1):PAGE41
  AY77    GND @S9S_MB_2U_LIB.S9S_MB_2U(SCH_1):GND     I9 @S9S_MB_2U_LIB.S9S_MB_2U(SCH_1):PAGE41
  AY71    GND @S9S_MB_2U_LIB.S9S_MB_2U(SCH_1):GND     I9 @S9S_MB_2U_LIB.S9S_MB_2U(SCH_1):PAGE41
   AY4    GND @S9S_MB_2U_LIB.S9S_MB_2U(SCH_1):GND     I9 @S9S_MB_2U_LIB.S9S_MB_2U(SCH_1):PAGE41
  AY16    GND @S9S_MB_2U_LIB.S9S_MB_2U(SCH_1):GND     I9 @S9S_MB_2U_LIB.S9S_MB_2U(SCH_1):PAGE41
  AY12    GND @S9S_MB_2U_LIB.S9S_MB_2U(SCH_1):GND     I9 @S9S_MB_2U_LIB.S9S_MB_2U(SCH_1):PAGE41
  AW88    GND @S9S_MB_2U_LIB.S9S_MB_2U(SCH_1):GND     I9 @S9S_MB_2U_LIB.S9S_MB_2U(SCH_1):PAGE41
  AW84    GND @S9S_MB_2U_LIB.S9S_MB_2U(SCH_1):GND     I9 @S9S_MB_2U_LIB.S9S_MB_2U(SCH_1):PAGE41
  AW82    GND @S9S_MB_2U_LIB.S9S_MB_2U(SCH_1):GND     I9 @S9S_MB_2U_LIB.S9S_MB_2U(SCH_1):PAGE41
  AW80    GND @S9S_MB_2U_LIB.S9S_MB_2U(SCH_1):GND     I9 @S9S_MB_2U_LIB.S9S_MB_2U(SCH_1):PAGE41
  AW72    GND @S9S_MB_2U_LIB.S9S_MB_2U(SCH_1):GND     I9 @S9S_MB_2U_LIB.S9S_MB_2U(SCH_1):PAGE41
  AW68    GND @S9S_MB_2U_LIB.S9S_MB_2U(SCH_1):GND     I9 @S9S_MB_2U_LIB.S9S_MB_2U(SCH_1):PAGE41
  AW66    GND @S9S_MB_2U_LIB.S9S_MB_2U(SCH_1):GND     I9 @S9S_MB_2U_LIB.S9S_MB_2U(SCH_1):PAGE41
  AW62    GND @S9S_MB_2U_LIB.S9S_MB_2U(SCH_1):GND     I9 @S9S_MB_2U_LIB.S9S_MB_2U(SCH_1):PAGE41
  AW25    GND @S9S_MB_2U_LIB.S9S_MB_2U(SCH_1):GND     I9 @S9S_MB_2U_LIB.S9S_MB_2U(SCH_1):PAGE41
  AW23    GND @S9S_MB_2U_LIB.S9S_MB_2U(SCH_1):GND     I9 @S9S_MB_2U_LIB.S9S_MB_2U(SCH_1):PAGE41
  AW21    GND @S9S_MB_2U_LIB.S9S_MB_2U(SCH_1):GND     I9 @S9S_MB_2U_LIB.S9S_MB_2U(SCH_1):PAGE41
   BR5    GND @S9S_MB_2U_LIB.S9S_MB_2U(SCH_1):GND     I9 @S9S_MB_2U_LIB.S9S_MB_2U(SCH_1):PAGE41
   AW9    GND @S9S_MB_2U_LIB.S9S_MB_2U(SCH_1):GND    I10 @S9S_MB_2U_LIB.S9S_MB_2U(SCH_1):PAGE41
   AW5    GND @S9S_MB_2U_LIB.S9S_MB_2U(SCH_1):GND    I10 @S9S_MB_2U_LIB.S9S_MB_2U(SCH_1):PAGE41
  AW13    GND @S9S_MB_2U_LIB.S9S_MB_2U(SCH_1):GND    I10 @S9S_MB_2U_LIB.S9S_MB_2U(SCH_1):PAGE41
   AW1    GND @S9S_MB_2U_LIB.S9S_MB_2U(SCH_1):GND    I10 @S9S_MB_2U_LIB.S9S_MB_2U(SCH_1):PAGE41
  AV91    GND @S9S_MB_2U_LIB.S9S_MB_2U(SCH_1):GND    I10 @S9S_MB_2U_LIB.S9S_MB_2U(SCH_1):PAGE41
  AV87    GND @S9S_MB_2U_LIB.S9S_MB_2U(SCH_1):GND    I10 @S9S_MB_2U_LIB.S9S_MB_2U(SCH_1):PAGE41
   AV8    GND @S9S_MB_2U_LIB.S9S_MB_2U(SCH_1):GND    I10 @S9S_MB_2U_LIB.S9S_MB_2U(SCH_1):PAGE41
  AV77    GND @S9S_MB_2U_LIB.S9S_MB_2U(SCH_1):GND    I10 @S9S_MB_2U_LIB.S9S_MB_2U(SCH_1):PAGE41
   AV4    GND @S9S_MB_2U_LIB.S9S_MB_2U(SCH_1):GND    I10 @S9S_MB_2U_LIB.S9S_MB_2U(SCH_1):PAGE41
  AV16    GND @S9S_MB_2U_LIB.S9S_MB_2U(SCH_1):GND    I10 @S9S_MB_2U_LIB.S9S_MB_2U(SCH_1):PAGE41
  AV12    GND @S9S_MB_2U_LIB.S9S_MB_2U(SCH_1):GND    I10 @S9S_MB_2U_LIB.S9S_MB_2U(SCH_1):PAGE41
  AU88    GND @S9S_MB_2U_LIB.S9S_MB_2U(SCH_1):GND    I10 @S9S_MB_2U_LIB.S9S_MB_2U(SCH_1):PAGE41
  AU84    GND @S9S_MB_2U_LIB.S9S_MB_2U(SCH_1):GND    I10 @S9S_MB_2U_LIB.S9S_MB_2U(SCH_1):PAGE41
  AU80    GND @S9S_MB_2U_LIB.S9S_MB_2U(SCH_1):GND    I10 @S9S_MB_2U_LIB.S9S_MB_2U(SCH_1):PAGE41
  AU76    GND @S9S_MB_2U_LIB.S9S_MB_2U(SCH_1):GND    I10 @S9S_MB_2U_LIB.S9S_MB_2U(SCH_1):PAGE41
  AU74    GND @S9S_MB_2U_LIB.S9S_MB_2U(SCH_1):GND    I10 @S9S_MB_2U_LIB.S9S_MB_2U(SCH_1):PAGE41
  AU72    GND @S9S_MB_2U_LIB.S9S_MB_2U(SCH_1):GND    I10 @S9S_MB_2U_LIB.S9S_MB_2U(SCH_1):PAGE41
  AU70    GND @S9S_MB_2U_LIB.S9S_MB_2U(SCH_1):GND    I10 @S9S_MB_2U_LIB.S9S_MB_2U(SCH_1):PAGE41
  AU48    GND @S9S_MB_2U_LIB.S9S_MB_2U(SCH_1):GND    I10 @S9S_MB_2U_LIB.S9S_MB_2U(SCH_1):PAGE41
  AU45    GND @S9S_MB_2U_LIB.S9S_MB_2U(SCH_1):GND    I10 @S9S_MB_2U_LIB.S9S_MB_2U(SCH_1):PAGE41
  AU41    GND @S9S_MB_2U_LIB.S9S_MB_2U(SCH_1):GND    I10 @S9S_MB_2U_LIB.S9S_MB_2U(SCH_1):PAGE41
  AU39    GND @S9S_MB_2U_LIB.S9S_MB_2U(SCH_1):GND    I10 @S9S_MB_2U_LIB.S9S_MB_2U(SCH_1):PAGE41
  AU37    GND @S9S_MB_2U_LIB.S9S_MB_2U(SCH_1):GND    I10 @S9S_MB_2U_LIB.S9S_MB_2U(SCH_1):PAGE41
  AU31    GND @S9S_MB_2U_LIB.S9S_MB_2U(SCH_1):GND    I10 @S9S_MB_2U_LIB.S9S_MB_2U(SCH_1):PAGE41
  AU27    GND @S9S_MB_2U_LIB.S9S_MB_2U(SCH_1):GND    I10 @S9S_MB_2U_LIB.S9S_MB_2U(SCH_1):PAGE41
   AT8    GND @S9S_MB_2U_LIB.S9S_MB_2U(SCH_1):GND    I10 @S9S_MB_2U_LIB.S9S_MB_2U(SCH_1):PAGE41
  AT79    GND @S9S_MB_2U_LIB.S9S_MB_2U(SCH_1):GND    I10 @S9S_MB_2U_LIB.S9S_MB_2U(SCH_1):PAGE41
  AT77    GND @S9S_MB_2U_LIB.S9S_MB_2U(SCH_1):GND    I10 @S9S_MB_2U_LIB.S9S_MB_2U(SCH_1):PAGE41
  AT75    GND @S9S_MB_2U_LIB.S9S_MB_2U(SCH_1):GND    I10 @S9S_MB_2U_LIB.S9S_MB_2U(SCH_1):PAGE41
  AT71    GND @S9S_MB_2U_LIB.S9S_MB_2U(SCH_1):GND    I10 @S9S_MB_2U_LIB.S9S_MB_2U(SCH_1):PAGE41
  AT69    GND @S9S_MB_2U_LIB.S9S_MB_2U(SCH_1):GND    I10 @S9S_MB_2U_LIB.S9S_MB_2U(SCH_1):PAGE41
  AT65    GND @S9S_MB_2U_LIB.S9S_MB_2U(SCH_1):GND    I10 @S9S_MB_2U_LIB.S9S_MB_2U(SCH_1):PAGE41
  AT63    GND @S9S_MB_2U_LIB.S9S_MB_2U(SCH_1):GND    I10 @S9S_MB_2U_LIB.S9S_MB_2U(SCH_1):PAGE41
  AT59    GND @S9S_MB_2U_LIB.S9S_MB_2U(SCH_1):GND    I10 @S9S_MB_2U_LIB.S9S_MB_2U(SCH_1):PAGE41
  AT57    GND @S9S_MB_2U_LIB.S9S_MB_2U(SCH_1):GND    I10 @S9S_MB_2U_LIB.S9S_MB_2U(SCH_1):PAGE41
  AT53    GND @S9S_MB_2U_LIB.S9S_MB_2U(SCH_1):GND    I10 @S9S_MB_2U_LIB.S9S_MB_2U(SCH_1):PAGE41
  AT51    GND @S9S_MB_2U_LIB.S9S_MB_2U(SCH_1):GND    I10 @S9S_MB_2U_LIB.S9S_MB_2U(SCH_1):PAGE41
  AT44    GND @S9S_MB_2U_LIB.S9S_MB_2U(SCH_1):GND    I10 @S9S_MB_2U_LIB.S9S_MB_2U(SCH_1):PAGE41
  AT40    GND @S9S_MB_2U_LIB.S9S_MB_2U(SCH_1):GND    I10 @S9S_MB_2U_LIB.S9S_MB_2U(SCH_1):PAGE41
   AT4    GND @S9S_MB_2U_LIB.S9S_MB_2U(SCH_1):GND    I10 @S9S_MB_2U_LIB.S9S_MB_2U(SCH_1):PAGE41
  AT38    GND @S9S_MB_2U_LIB.S9S_MB_2U(SCH_1):GND    I10 @S9S_MB_2U_LIB.S9S_MB_2U(SCH_1):PAGE41
  AT34    GND @S9S_MB_2U_LIB.S9S_MB_2U(SCH_1):GND    I10 @S9S_MB_2U_LIB.S9S_MB_2U(SCH_1):PAGE41
  AT32    GND @S9S_MB_2U_LIB.S9S_MB_2U(SCH_1):GND    I10 @S9S_MB_2U_LIB.S9S_MB_2U(SCH_1):PAGE41
  AT28    GND @S9S_MB_2U_LIB.S9S_MB_2U(SCH_1):GND    I10 @S9S_MB_2U_LIB.S9S_MB_2U(SCH_1):PAGE41
  AT26    GND @S9S_MB_2U_LIB.S9S_MB_2U(SCH_1):GND    I10 @S9S_MB_2U_LIB.S9S_MB_2U(SCH_1):PAGE41
  AT22    GND @S9S_MB_2U_LIB.S9S_MB_2U(SCH_1):GND    I10 @S9S_MB_2U_LIB.S9S_MB_2U(SCH_1):PAGE41
  AT20    GND @S9S_MB_2U_LIB.S9S_MB_2U(SCH_1):GND    I10 @S9S_MB_2U_LIB.S9S_MB_2U(SCH_1):PAGE41
  AT16    GND @S9S_MB_2U_LIB.S9S_MB_2U(SCH_1):GND    I10 @S9S_MB_2U_LIB.S9S_MB_2U(SCH_1):PAGE41
  AT12    GND @S9S_MB_2U_LIB.S9S_MB_2U(SCH_1):GND    I10 @S9S_MB_2U_LIB.S9S_MB_2U(SCH_1):PAGE41
   AR9    GND @S9S_MB_2U_LIB.S9S_MB_2U(SCH_1):GND    I10 @S9S_MB_2U_LIB.S9S_MB_2U(SCH_1):PAGE41
  AR88    GND @S9S_MB_2U_LIB.S9S_MB_2U(SCH_1):GND    I10 @S9S_MB_2U_LIB.S9S_MB_2U(SCH_1):PAGE41
  AR84    GND @S9S_MB_2U_LIB.S9S_MB_2U(SCH_1):GND    I10 @S9S_MB_2U_LIB.S9S_MB_2U(SCH_1):PAGE41
  AR82    GND @S9S_MB_2U_LIB.S9S_MB_2U(SCH_1):GND    I10 @S9S_MB_2U_LIB.S9S_MB_2U(SCH_1):PAGE41
  AR78    GND @S9S_MB_2U_LIB.S9S_MB_2U(SCH_1):GND    I10 @S9S_MB_2U_LIB.S9S_MB_2U(SCH_1):PAGE41
  AR74    GND @S9S_MB_2U_LIB.S9S_MB_2U(SCH_1):GND    I10 @S9S_MB_2U_LIB.S9S_MB_2U(SCH_1):PAGE41
  AR72    GND @S9S_MB_2U_LIB.S9S_MB_2U(SCH_1):GND    I10 @S9S_MB_2U_LIB.S9S_MB_2U(SCH_1):PAGE41
  AR68    GND @S9S_MB_2U_LIB.S9S_MB_2U(SCH_1):GND    I10 @S9S_MB_2U_LIB.S9S_MB_2U(SCH_1):PAGE41
  AR66    GND @S9S_MB_2U_LIB.S9S_MB_2U(SCH_1):GND    I10 @S9S_MB_2U_LIB.S9S_MB_2U(SCH_1):PAGE41
  AR62    GND @S9S_MB_2U_LIB.S9S_MB_2U(SCH_1):GND    I10 @S9S_MB_2U_LIB.S9S_MB_2U(SCH_1):PAGE41
  AR60    GND @S9S_MB_2U_LIB.S9S_MB_2U(SCH_1):GND    I10 @S9S_MB_2U_LIB.S9S_MB_2U(SCH_1):PAGE41
  AR56    GND @S9S_MB_2U_LIB.S9S_MB_2U(SCH_1):GND    I10 @S9S_MB_2U_LIB.S9S_MB_2U(SCH_1):PAGE41
  AR54    GND @S9S_MB_2U_LIB.S9S_MB_2U(SCH_1):GND    I10 @S9S_MB_2U_LIB.S9S_MB_2U(SCH_1):PAGE41
  AR50    GND @S9S_MB_2U_LIB.S9S_MB_2U(SCH_1):GND    I10 @S9S_MB_2U_LIB.S9S_MB_2U(SCH_1):PAGE41
   AR5    GND @S9S_MB_2U_LIB.S9S_MB_2U(SCH_1):GND    I10 @S9S_MB_2U_LIB.S9S_MB_2U(SCH_1):PAGE41
  AR48    GND @S9S_MB_2U_LIB.S9S_MB_2U(SCH_1):GND    I10 @S9S_MB_2U_LIB.S9S_MB_2U(SCH_1):PAGE41
  AR43    GND @S9S_MB_2U_LIB.S9S_MB_2U(SCH_1):GND    I10 @S9S_MB_2U_LIB.S9S_MB_2U(SCH_1):PAGE41
  AR41    GND @S9S_MB_2U_LIB.S9S_MB_2U(SCH_1):GND    I10 @S9S_MB_2U_LIB.S9S_MB_2U(SCH_1):PAGE41
  AR37    GND @S9S_MB_2U_LIB.S9S_MB_2U(SCH_1):GND    I10 @S9S_MB_2U_LIB.S9S_MB_2U(SCH_1):PAGE41
  AR35    GND @S9S_MB_2U_LIB.S9S_MB_2U(SCH_1):GND    I10 @S9S_MB_2U_LIB.S9S_MB_2U(SCH_1):PAGE41
  AR31    GND @S9S_MB_2U_LIB.S9S_MB_2U(SCH_1):GND    I10 @S9S_MB_2U_LIB.S9S_MB_2U(SCH_1):PAGE41
  AR29    GND @S9S_MB_2U_LIB.S9S_MB_2U(SCH_1):GND    I10 @S9S_MB_2U_LIB.S9S_MB_2U(SCH_1):PAGE41
  AR25    GND @S9S_MB_2U_LIB.S9S_MB_2U(SCH_1):GND    I10 @S9S_MB_2U_LIB.S9S_MB_2U(SCH_1):PAGE41
  AR23    GND @S9S_MB_2U_LIB.S9S_MB_2U(SCH_1):GND    I10 @S9S_MB_2U_LIB.S9S_MB_2U(SCH_1):PAGE41
  AR19    GND @S9S_MB_2U_LIB.S9S_MB_2U(SCH_1):GND    I10 @S9S_MB_2U_LIB.S9S_MB_2U(SCH_1):PAGE41
  AR13    GND @S9S_MB_2U_LIB.S9S_MB_2U(SCH_1):GND    I10 @S9S_MB_2U_LIB.S9S_MB_2U(SCH_1):PAGE41
   AR1    GND @S9S_MB_2U_LIB.S9S_MB_2U(SCH_1):GND    I10 @S9S_MB_2U_LIB.S9S_MB_2U(SCH_1):PAGE41
  AP91    GND @S9S_MB_2U_LIB.S9S_MB_2U(SCH_1):GND    I10 @S9S_MB_2U_LIB.S9S_MB_2U(SCH_1):PAGE41
  AP87    GND @S9S_MB_2U_LIB.S9S_MB_2U(SCH_1):GND    I10 @S9S_MB_2U_LIB.S9S_MB_2U(SCH_1):PAGE41
  AP83    GND @S9S_MB_2U_LIB.S9S_MB_2U(SCH_1):GND    I10 @S9S_MB_2U_LIB.S9S_MB_2U(SCH_1):PAGE41
   AP8    GND @S9S_MB_2U_LIB.S9S_MB_2U(SCH_1):GND    I10 @S9S_MB_2U_LIB.S9S_MB_2U(SCH_1):PAGE41
  AP79    GND @S9S_MB_2U_LIB.S9S_MB_2U(SCH_1):GND    I10 @S9S_MB_2U_LIB.S9S_MB_2U(SCH_1):PAGE41
  AP73    GND @S9S_MB_2U_LIB.S9S_MB_2U(SCH_1):GND    I10 @S9S_MB_2U_LIB.S9S_MB_2U(SCH_1):PAGE41
  AP67    GND @S9S_MB_2U_LIB.S9S_MB_2U(SCH_1):GND    I10 @S9S_MB_2U_LIB.S9S_MB_2U(SCH_1):PAGE41
  AP61    GND @S9S_MB_2U_LIB.S9S_MB_2U(SCH_1):GND    I10 @S9S_MB_2U_LIB.S9S_MB_2U(SCH_1):PAGE41
  AP55    GND @S9S_MB_2U_LIB.S9S_MB_2U(SCH_1):GND    I10 @S9S_MB_2U_LIB.S9S_MB_2U(SCH_1):PAGE41
  AP49    GND @S9S_MB_2U_LIB.S9S_MB_2U(SCH_1):GND    I10 @S9S_MB_2U_LIB.S9S_MB_2U(SCH_1):PAGE41
  AP42    GND @S9S_MB_2U_LIB.S9S_MB_2U(SCH_1):GND    I10 @S9S_MB_2U_LIB.S9S_MB_2U(SCH_1):PAGE41
   AP4    GND @S9S_MB_2U_LIB.S9S_MB_2U(SCH_1):GND    I10 @S9S_MB_2U_LIB.S9S_MB_2U(SCH_1):PAGE41
  AP36    GND @S9S_MB_2U_LIB.S9S_MB_2U(SCH_1):GND    I10 @S9S_MB_2U_LIB.S9S_MB_2U(SCH_1):PAGE41
  AP30    GND @S9S_MB_2U_LIB.S9S_MB_2U(SCH_1):GND    I10 @S9S_MB_2U_LIB.S9S_MB_2U(SCH_1):PAGE41
  AP24    GND @S9S_MB_2U_LIB.S9S_MB_2U(SCH_1):GND    I10 @S9S_MB_2U_LIB.S9S_MB_2U(SCH_1):PAGE41
  AP18    GND @S9S_MB_2U_LIB.S9S_MB_2U(SCH_1):GND    I10 @S9S_MB_2U_LIB.S9S_MB_2U(SCH_1):PAGE41
  AP16    GND @S9S_MB_2U_LIB.S9S_MB_2U(SCH_1):GND    I10 @S9S_MB_2U_LIB.S9S_MB_2U(SCH_1):PAGE41
  AP12    GND @S9S_MB_2U_LIB.S9S_MB_2U(SCH_1):GND    I10 @S9S_MB_2U_LIB.S9S_MB_2U(SCH_1):PAGE41
  AN88    GND @S9S_MB_2U_LIB.S9S_MB_2U(SCH_1):GND    I10 @S9S_MB_2U_LIB.S9S_MB_2U(SCH_1):PAGE41
  AN84    GND @S9S_MB_2U_LIB.S9S_MB_2U(SCH_1):GND    I10 @S9S_MB_2U_LIB.S9S_MB_2U(SCH_1):PAGE41
  AN52    GND @S9S_MB_2U_LIB.S9S_MB_2U(SCH_1):GND    I10 @S9S_MB_2U_LIB.S9S_MB_2U(SCH_1):PAGE41
   AM8    GND @S9S_MB_2U_LIB.S9S_MB_2U(SCH_1):GND    I10 @S9S_MB_2U_LIB.S9S_MB_2U(SCH_1):PAGE41
  AM77    GND @S9S_MB_2U_LIB.S9S_MB_2U(SCH_1):GND    I10 @S9S_MB_2U_LIB.S9S_MB_2U(SCH_1):PAGE41
  AM75    GND @S9S_MB_2U_LIB.S9S_MB_2U(SCH_1):GND    I10 @S9S_MB_2U_LIB.S9S_MB_2U(SCH_1):PAGE41
  AM73    GND @S9S_MB_2U_LIB.S9S_MB_2U(SCH_1):GND    I10 @S9S_MB_2U_LIB.S9S_MB_2U(SCH_1):PAGE41
  AM71    GND @S9S_MB_2U_LIB.S9S_MB_2U(SCH_1):GND    I10 @S9S_MB_2U_LIB.S9S_MB_2U(SCH_1):PAGE41
  AM69    GND @S9S_MB_2U_LIB.S9S_MB_2U(SCH_1):GND    I10 @S9S_MB_2U_LIB.S9S_MB_2U(SCH_1):PAGE41
  AM67    GND @S9S_MB_2U_LIB.S9S_MB_2U(SCH_1):GND    I10 @S9S_MB_2U_LIB.S9S_MB_2U(SCH_1):PAGE41
  AM65    GND @S9S_MB_2U_LIB.S9S_MB_2U(SCH_1):GND    I10 @S9S_MB_2U_LIB.S9S_MB_2U(SCH_1):PAGE41
  AM63    GND @S9S_MB_2U_LIB.S9S_MB_2U(SCH_1):GND    I10 @S9S_MB_2U_LIB.S9S_MB_2U(SCH_1):PAGE41
  AM61    GND @S9S_MB_2U_LIB.S9S_MB_2U(SCH_1):GND    I10 @S9S_MB_2U_LIB.S9S_MB_2U(SCH_1):PAGE41
  AM59    GND @S9S_MB_2U_LIB.S9S_MB_2U(SCH_1):GND    I10 @S9S_MB_2U_LIB.S9S_MB_2U(SCH_1):PAGE41
  AM57    GND @S9S_MB_2U_LIB.S9S_MB_2U(SCH_1):GND    I10 @S9S_MB_2U_LIB.S9S_MB_2U(SCH_1):PAGE41
  AM55    GND @S9S_MB_2U_LIB.S9S_MB_2U(SCH_1):GND    I10 @S9S_MB_2U_LIB.S9S_MB_2U(SCH_1):PAGE41
  AM53    GND @S9S_MB_2U_LIB.S9S_MB_2U(SCH_1):GND    I10 @S9S_MB_2U_LIB.S9S_MB_2U(SCH_1):PAGE41
  AM51    GND @S9S_MB_2U_LIB.S9S_MB_2U(SCH_1):GND    I10 @S9S_MB_2U_LIB.S9S_MB_2U(SCH_1):PAGE41
  AM49    GND @S9S_MB_2U_LIB.S9S_MB_2U(SCH_1):GND    I10 @S9S_MB_2U_LIB.S9S_MB_2U(SCH_1):PAGE41
  AM47    GND @S9S_MB_2U_LIB.S9S_MB_2U(SCH_1):GND    I10 @S9S_MB_2U_LIB.S9S_MB_2U(SCH_1):PAGE41
  AM44    GND @S9S_MB_2U_LIB.S9S_MB_2U(SCH_1):GND    I10 @S9S_MB_2U_LIB.S9S_MB_2U(SCH_1):PAGE41
  AM42    GND @S9S_MB_2U_LIB.S9S_MB_2U(SCH_1):GND    I10 @S9S_MB_2U_LIB.S9S_MB_2U(SCH_1):PAGE41
  AM40    GND @S9S_MB_2U_LIB.S9S_MB_2U(SCH_1):GND    I10 @S9S_MB_2U_LIB.S9S_MB_2U(SCH_1):PAGE41
   AM4    GND @S9S_MB_2U_LIB.S9S_MB_2U(SCH_1):GND    I10 @S9S_MB_2U_LIB.S9S_MB_2U(SCH_1):PAGE41
  AM38    GND @S9S_MB_2U_LIB.S9S_MB_2U(SCH_1):GND    I10 @S9S_MB_2U_LIB.S9S_MB_2U(SCH_1):PAGE41
  AM36    GND @S9S_MB_2U_LIB.S9S_MB_2U(SCH_1):GND    I10 @S9S_MB_2U_LIB.S9S_MB_2U(SCH_1):PAGE41
  AM34    GND @S9S_MB_2U_LIB.S9S_MB_2U(SCH_1):GND    I10 @S9S_MB_2U_LIB.S9S_MB_2U(SCH_1):PAGE41
  AM32    GND @S9S_MB_2U_LIB.S9S_MB_2U(SCH_1):GND    I10 @S9S_MB_2U_LIB.S9S_MB_2U(SCH_1):PAGE41
  AM30    GND @S9S_MB_2U_LIB.S9S_MB_2U(SCH_1):GND    I10 @S9S_MB_2U_LIB.S9S_MB_2U(SCH_1):PAGE41
  AM28    GND @S9S_MB_2U_LIB.S9S_MB_2U(SCH_1):GND    I10 @S9S_MB_2U_LIB.S9S_MB_2U(SCH_1):PAGE41
  AM26    GND @S9S_MB_2U_LIB.S9S_MB_2U(SCH_1):GND    I10 @S9S_MB_2U_LIB.S9S_MB_2U(SCH_1):PAGE41
  AM24    GND @S9S_MB_2U_LIB.S9S_MB_2U(SCH_1):GND    I10 @S9S_MB_2U_LIB.S9S_MB_2U(SCH_1):PAGE41
  AM22    GND @S9S_MB_2U_LIB.S9S_MB_2U(SCH_1):GND    I10 @S9S_MB_2U_LIB.S9S_MB_2U(SCH_1):PAGE41
  AM20    GND @S9S_MB_2U_LIB.S9S_MB_2U(SCH_1):GND    I10 @S9S_MB_2U_LIB.S9S_MB_2U(SCH_1):PAGE41
  AM18    GND @S9S_MB_2U_LIB.S9S_MB_2U(SCH_1):GND    I10 @S9S_MB_2U_LIB.S9S_MB_2U(SCH_1):PAGE41
  AM16    GND @S9S_MB_2U_LIB.S9S_MB_2U(SCH_1):GND    I10 @S9S_MB_2U_LIB.S9S_MB_2U(SCH_1):PAGE41
  AM12    GND @S9S_MB_2U_LIB.S9S_MB_2U(SCH_1):GND    I10 @S9S_MB_2U_LIB.S9S_MB_2U(SCH_1):PAGE41
   AL9    GND @S9S_MB_2U_LIB.S9S_MB_2U(SCH_1):GND    I10 @S9S_MB_2U_LIB.S9S_MB_2U(SCH_1):PAGE41
  AL88    GND @S9S_MB_2U_LIB.S9S_MB_2U(SCH_1):GND    I10 @S9S_MB_2U_LIB.S9S_MB_2U(SCH_1):PAGE41
  AL84    GND @S9S_MB_2U_LIB.S9S_MB_2U(SCH_1):GND    I10 @S9S_MB_2U_LIB.S9S_MB_2U(SCH_1):PAGE41
  AL82    GND @S9S_MB_2U_LIB.S9S_MB_2U(SCH_1):GND    I10 @S9S_MB_2U_LIB.S9S_MB_2U(SCH_1):PAGE41
  AL80    GND @S9S_MB_2U_LIB.S9S_MB_2U(SCH_1):GND    I10 @S9S_MB_2U_LIB.S9S_MB_2U(SCH_1):PAGE41
  AL52    GND @S9S_MB_2U_LIB.S9S_MB_2U(SCH_1):GND    I10 @S9S_MB_2U_LIB.S9S_MB_2U(SCH_1):PAGE41
   AL5    GND @S9S_MB_2U_LIB.S9S_MB_2U(SCH_1):GND    I10 @S9S_MB_2U_LIB.S9S_MB_2U(SCH_1):PAGE41
  AL17    GND @S9S_MB_2U_LIB.S9S_MB_2U(SCH_1):GND    I10 @S9S_MB_2U_LIB.S9S_MB_2U(SCH_1):PAGE41
  AL13    GND @S9S_MB_2U_LIB.S9S_MB_2U(SCH_1):GND    I10 @S9S_MB_2U_LIB.S9S_MB_2U(SCH_1):PAGE41
   AL1    GND @S9S_MB_2U_LIB.S9S_MB_2U(SCH_1):GND    I10 @S9S_MB_2U_LIB.S9S_MB_2U(SCH_1):PAGE41
  AK91    GND @S9S_MB_2U_LIB.S9S_MB_2U(SCH_1):GND    I10 @S9S_MB_2U_LIB.S9S_MB_2U(SCH_1):PAGE41
  AK87    GND @S9S_MB_2U_LIB.S9S_MB_2U(SCH_1):GND    I10 @S9S_MB_2U_LIB.S9S_MB_2U(SCH_1):PAGE41
  AK83    GND @S9S_MB_2U_LIB.S9S_MB_2U(SCH_1):GND    I10 @S9S_MB_2U_LIB.S9S_MB_2U(SCH_1):PAGE41
  AK81    GND @S9S_MB_2U_LIB.S9S_MB_2U(SCH_1):GND    I10 @S9S_MB_2U_LIB.S9S_MB_2U(SCH_1):PAGE41
   AK8    GND @S9S_MB_2U_LIB.S9S_MB_2U(SCH_1):GND    I10 @S9S_MB_2U_LIB.S9S_MB_2U(SCH_1):PAGE41
  AK79    GND @S9S_MB_2U_LIB.S9S_MB_2U(SCH_1):GND    I10 @S9S_MB_2U_LIB.S9S_MB_2U(SCH_1):PAGE41
  AK73    GND @S9S_MB_2U_LIB.S9S_MB_2U(SCH_1):GND    I10 @S9S_MB_2U_LIB.S9S_MB_2U(SCH_1):PAGE41
  AK67    GND @S9S_MB_2U_LIB.S9S_MB_2U(SCH_1):GND    I10 @S9S_MB_2U_LIB.S9S_MB_2U(SCH_1):PAGE41
  AK61    GND @S9S_MB_2U_LIB.S9S_MB_2U(SCH_1):GND    I10 @S9S_MB_2U_LIB.S9S_MB_2U(SCH_1):PAGE41
  AK55    GND @S9S_MB_2U_LIB.S9S_MB_2U(SCH_1):GND    I10 @S9S_MB_2U_LIB.S9S_MB_2U(SCH_1):PAGE41
  AK49    GND @S9S_MB_2U_LIB.S9S_MB_2U(SCH_1):GND    I10 @S9S_MB_2U_LIB.S9S_MB_2U(SCH_1):PAGE41
  AK42    GND @S9S_MB_2U_LIB.S9S_MB_2U(SCH_1):GND    I10 @S9S_MB_2U_LIB.S9S_MB_2U(SCH_1):PAGE41
   AK4    GND @S9S_MB_2U_LIB.S9S_MB_2U(SCH_1):GND    I10 @S9S_MB_2U_LIB.S9S_MB_2U(SCH_1):PAGE41
  AK36    GND @S9S_MB_2U_LIB.S9S_MB_2U(SCH_1):GND    I10 @S9S_MB_2U_LIB.S9S_MB_2U(SCH_1):PAGE41
  AK30    GND @S9S_MB_2U_LIB.S9S_MB_2U(SCH_1):GND    I10 @S9S_MB_2U_LIB.S9S_MB_2U(SCH_1):PAGE41
  AK24    GND @S9S_MB_2U_LIB.S9S_MB_2U(SCH_1):GND    I10 @S9S_MB_2U_LIB.S9S_MB_2U(SCH_1):PAGE41
  AK18    GND @S9S_MB_2U_LIB.S9S_MB_2U(SCH_1):GND    I10 @S9S_MB_2U_LIB.S9S_MB_2U(SCH_1):PAGE41
  AK16    GND @S9S_MB_2U_LIB.S9S_MB_2U(SCH_1):GND    I10 @S9S_MB_2U_LIB.S9S_MB_2U(SCH_1):PAGE41
  AK12    GND @S9S_MB_2U_LIB.S9S_MB_2U(SCH_1):GND    I10 @S9S_MB_2U_LIB.S9S_MB_2U(SCH_1):PAGE41
  AJ88    GND @S9S_MB_2U_LIB.S9S_MB_2U(SCH_1):GND    I11 @S9S_MB_2U_LIB.S9S_MB_2U(SCH_1):PAGE41
  AJ84    GND @S9S_MB_2U_LIB.S9S_MB_2U(SCH_1):GND    I11 @S9S_MB_2U_LIB.S9S_MB_2U(SCH_1):PAGE41
  AJ78    GND @S9S_MB_2U_LIB.S9S_MB_2U(SCH_1):GND    I11 @S9S_MB_2U_LIB.S9S_MB_2U(SCH_1):PAGE41
  AJ74    GND @S9S_MB_2U_LIB.S9S_MB_2U(SCH_1):GND    I11 @S9S_MB_2U_LIB.S9S_MB_2U(SCH_1):PAGE41
  AJ72    GND @S9S_MB_2U_LIB.S9S_MB_2U(SCH_1):GND    I11 @S9S_MB_2U_LIB.S9S_MB_2U(SCH_1):PAGE41
  AJ68    GND @S9S_MB_2U_LIB.S9S_MB_2U(SCH_1):GND    I11 @S9S_MB_2U_LIB.S9S_MB_2U(SCH_1):PAGE41
  AJ66    GND @S9S_MB_2U_LIB.S9S_MB_2U(SCH_1):GND    I11 @S9S_MB_2U_LIB.S9S_MB_2U(SCH_1):PAGE41
  AJ62    GND @S9S_MB_2U_LIB.S9S_MB_2U(SCH_1):GND    I11 @S9S_MB_2U_LIB.S9S_MB_2U(SCH_1):PAGE41
  AJ60    GND @S9S_MB_2U_LIB.S9S_MB_2U(SCH_1):GND    I11 @S9S_MB_2U_LIB.S9S_MB_2U(SCH_1):PAGE41
  AJ56    GND @S9S_MB_2U_LIB.S9S_MB_2U(SCH_1):GND    I11 @S9S_MB_2U_LIB.S9S_MB_2U(SCH_1):PAGE41
  AJ54    GND @S9S_MB_2U_LIB.S9S_MB_2U(SCH_1):GND    I11 @S9S_MB_2U_LIB.S9S_MB_2U(SCH_1):PAGE41
  AJ50    GND @S9S_MB_2U_LIB.S9S_MB_2U(SCH_1):GND    I11 @S9S_MB_2U_LIB.S9S_MB_2U(SCH_1):PAGE41
  AJ48    GND @S9S_MB_2U_LIB.S9S_MB_2U(SCH_1):GND    I11 @S9S_MB_2U_LIB.S9S_MB_2U(SCH_1):PAGE41
  AJ43    GND @S9S_MB_2U_LIB.S9S_MB_2U(SCH_1):GND    I11 @S9S_MB_2U_LIB.S9S_MB_2U(SCH_1):PAGE41
  AJ41    GND @S9S_MB_2U_LIB.S9S_MB_2U(SCH_1):GND    I11 @S9S_MB_2U_LIB.S9S_MB_2U(SCH_1):PAGE41
  AJ37    GND @S9S_MB_2U_LIB.S9S_MB_2U(SCH_1):GND    I11 @S9S_MB_2U_LIB.S9S_MB_2U(SCH_1):PAGE41
  AJ35    GND @S9S_MB_2U_LIB.S9S_MB_2U(SCH_1):GND    I11 @S9S_MB_2U_LIB.S9S_MB_2U(SCH_1):PAGE41
  AJ31    GND @S9S_MB_2U_LIB.S9S_MB_2U(SCH_1):GND    I11 @S9S_MB_2U_LIB.S9S_MB_2U(SCH_1):PAGE41
  AJ29    GND @S9S_MB_2U_LIB.S9S_MB_2U(SCH_1):GND    I11 @S9S_MB_2U_LIB.S9S_MB_2U(SCH_1):PAGE41
  AJ25    GND @S9S_MB_2U_LIB.S9S_MB_2U(SCH_1):GND    I11 @S9S_MB_2U_LIB.S9S_MB_2U(SCH_1):PAGE41
  AJ23    GND @S9S_MB_2U_LIB.S9S_MB_2U(SCH_1):GND    I11 @S9S_MB_2U_LIB.S9S_MB_2U(SCH_1):PAGE41
  AJ19    GND @S9S_MB_2U_LIB.S9S_MB_2U(SCH_1):GND    I11 @S9S_MB_2U_LIB.S9S_MB_2U(SCH_1):PAGE41
  AH83    GND @S9S_MB_2U_LIB.S9S_MB_2U(SCH_1):GND    I11 @S9S_MB_2U_LIB.S9S_MB_2U(SCH_1):PAGE41
   AH8    GND @S9S_MB_2U_LIB.S9S_MB_2U(SCH_1):GND    I11 @S9S_MB_2U_LIB.S9S_MB_2U(SCH_1):PAGE41
  AH79    GND @S9S_MB_2U_LIB.S9S_MB_2U(SCH_1):GND    I11 @S9S_MB_2U_LIB.S9S_MB_2U(SCH_1):PAGE41
  AH77    GND @S9S_MB_2U_LIB.S9S_MB_2U(SCH_1):GND    I11 @S9S_MB_2U_LIB.S9S_MB_2U(SCH_1):PAGE41
  AH75    GND @S9S_MB_2U_LIB.S9S_MB_2U(SCH_1):GND    I11 @S9S_MB_2U_LIB.S9S_MB_2U(SCH_1):PAGE41
  AH71    GND @S9S_MB_2U_LIB.S9S_MB_2U(SCH_1):GND    I11 @S9S_MB_2U_LIB.S9S_MB_2U(SCH_1):PAGE41
  AH69    GND @S9S_MB_2U_LIB.S9S_MB_2U(SCH_1):GND    I11 @S9S_MB_2U_LIB.S9S_MB_2U(SCH_1):PAGE41
  AH65    GND @S9S_MB_2U_LIB.S9S_MB_2U(SCH_1):GND    I11 @S9S_MB_2U_LIB.S9S_MB_2U(SCH_1):PAGE41
  AH63    GND @S9S_MB_2U_LIB.S9S_MB_2U(SCH_1):GND    I11 @S9S_MB_2U_LIB.S9S_MB_2U(SCH_1):PAGE41
  AH59    GND @S9S_MB_2U_LIB.S9S_MB_2U(SCH_1):GND    I11 @S9S_MB_2U_LIB.S9S_MB_2U(SCH_1):PAGE41
  AH57    GND @S9S_MB_2U_LIB.S9S_MB_2U(SCH_1):GND    I11 @S9S_MB_2U_LIB.S9S_MB_2U(SCH_1):PAGE41
  AH53    GND @S9S_MB_2U_LIB.S9S_MB_2U(SCH_1):GND    I11 @S9S_MB_2U_LIB.S9S_MB_2U(SCH_1):PAGE41
  AH51    GND @S9S_MB_2U_LIB.S9S_MB_2U(SCH_1):GND    I11 @S9S_MB_2U_LIB.S9S_MB_2U(SCH_1):PAGE41
  AH47    GND @S9S_MB_2U_LIB.S9S_MB_2U(SCH_1):GND    I11 @S9S_MB_2U_LIB.S9S_MB_2U(SCH_1):PAGE41
  AH44    GND @S9S_MB_2U_LIB.S9S_MB_2U(SCH_1):GND    I11 @S9S_MB_2U_LIB.S9S_MB_2U(SCH_1):PAGE41
  AH40    GND @S9S_MB_2U_LIB.S9S_MB_2U(SCH_1):GND    I11 @S9S_MB_2U_LIB.S9S_MB_2U(SCH_1):PAGE41
   AH4    GND @S9S_MB_2U_LIB.S9S_MB_2U(SCH_1):GND    I11 @S9S_MB_2U_LIB.S9S_MB_2U(SCH_1):PAGE41
  AH38    GND @S9S_MB_2U_LIB.S9S_MB_2U(SCH_1):GND    I11 @S9S_MB_2U_LIB.S9S_MB_2U(SCH_1):PAGE41
  AH34    GND @S9S_MB_2U_LIB.S9S_MB_2U(SCH_1):GND    I11 @S9S_MB_2U_LIB.S9S_MB_2U(SCH_1):PAGE41
  AH32    GND @S9S_MB_2U_LIB.S9S_MB_2U(SCH_1):GND    I11 @S9S_MB_2U_LIB.S9S_MB_2U(SCH_1):PAGE41
  AH28    GND @S9S_MB_2U_LIB.S9S_MB_2U(SCH_1):GND    I11 @S9S_MB_2U_LIB.S9S_MB_2U(SCH_1):PAGE41
  AH26    GND @S9S_MB_2U_LIB.S9S_MB_2U(SCH_1):GND    I11 @S9S_MB_2U_LIB.S9S_MB_2U(SCH_1):PAGE41
  AH22    GND @S9S_MB_2U_LIB.S9S_MB_2U(SCH_1):GND    I11 @S9S_MB_2U_LIB.S9S_MB_2U(SCH_1):PAGE41
  AH20    GND @S9S_MB_2U_LIB.S9S_MB_2U(SCH_1):GND    I11 @S9S_MB_2U_LIB.S9S_MB_2U(SCH_1):PAGE41
  AH16    GND @S9S_MB_2U_LIB.S9S_MB_2U(SCH_1):GND    I11 @S9S_MB_2U_LIB.S9S_MB_2U(SCH_1):PAGE41
  AH12    GND @S9S_MB_2U_LIB.S9S_MB_2U(SCH_1):GND    I11 @S9S_MB_2U_LIB.S9S_MB_2U(SCH_1):PAGE41
   AG9    GND @S9S_MB_2U_LIB.S9S_MB_2U(SCH_1):GND    I11 @S9S_MB_2U_LIB.S9S_MB_2U(SCH_1):PAGE41
  AG88    GND @S9S_MB_2U_LIB.S9S_MB_2U(SCH_1):GND    I11 @S9S_MB_2U_LIB.S9S_MB_2U(SCH_1):PAGE41
  AG84    GND @S9S_MB_2U_LIB.S9S_MB_2U(SCH_1):GND    I11 @S9S_MB_2U_LIB.S9S_MB_2U(SCH_1):PAGE41
  AG76    GND @S9S_MB_2U_LIB.S9S_MB_2U(SCH_1):GND    I11 @S9S_MB_2U_LIB.S9S_MB_2U(SCH_1):PAGE41
  AG70    GND @S9S_MB_2U_LIB.S9S_MB_2U(SCH_1):GND    I11 @S9S_MB_2U_LIB.S9S_MB_2U(SCH_1):PAGE41
  AG64    GND @S9S_MB_2U_LIB.S9S_MB_2U(SCH_1):GND    I11 @S9S_MB_2U_LIB.S9S_MB_2U(SCH_1):PAGE41
  AG58    GND @S9S_MB_2U_LIB.S9S_MB_2U(SCH_1):GND    I11 @S9S_MB_2U_LIB.S9S_MB_2U(SCH_1):PAGE41
  AG52    GND @S9S_MB_2U_LIB.S9S_MB_2U(SCH_1):GND    I11 @S9S_MB_2U_LIB.S9S_MB_2U(SCH_1):PAGE41
   AG5    GND @S9S_MB_2U_LIB.S9S_MB_2U(SCH_1):GND    I11 @S9S_MB_2U_LIB.S9S_MB_2U(SCH_1):PAGE41
  AG45    GND @S9S_MB_2U_LIB.S9S_MB_2U(SCH_1):GND    I11 @S9S_MB_2U_LIB.S9S_MB_2U(SCH_1):PAGE41
  AG39    GND @S9S_MB_2U_LIB.S9S_MB_2U(SCH_1):GND    I11 @S9S_MB_2U_LIB.S9S_MB_2U(SCH_1):PAGE41
  AG33    GND @S9S_MB_2U_LIB.S9S_MB_2U(SCH_1):GND    I11 @S9S_MB_2U_LIB.S9S_MB_2U(SCH_1):PAGE41
  AG27    GND @S9S_MB_2U_LIB.S9S_MB_2U(SCH_1):GND    I11 @S9S_MB_2U_LIB.S9S_MB_2U(SCH_1):PAGE41
  AG21    GND @S9S_MB_2U_LIB.S9S_MB_2U(SCH_1):GND    I11 @S9S_MB_2U_LIB.S9S_MB_2U(SCH_1):PAGE41
  AG13    GND @S9S_MB_2U_LIB.S9S_MB_2U(SCH_1):GND    I11 @S9S_MB_2U_LIB.S9S_MB_2U(SCH_1):PAGE41
   AG1    GND @S9S_MB_2U_LIB.S9S_MB_2U(SCH_1):GND    I11 @S9S_MB_2U_LIB.S9S_MB_2U(SCH_1):PAGE41
  AF91    GND @S9S_MB_2U_LIB.S9S_MB_2U(SCH_1):GND    I11 @S9S_MB_2U_LIB.S9S_MB_2U(SCH_1):PAGE41
  AF87    GND @S9S_MB_2U_LIB.S9S_MB_2U(SCH_1):GND    I11 @S9S_MB_2U_LIB.S9S_MB_2U(SCH_1):PAGE41
  AF81    GND @S9S_MB_2U_LIB.S9S_MB_2U(SCH_1):GND    I11 @S9S_MB_2U_LIB.S9S_MB_2U(SCH_1):PAGE41
   AF8    GND @S9S_MB_2U_LIB.S9S_MB_2U(SCH_1):GND    I11 @S9S_MB_2U_LIB.S9S_MB_2U(SCH_1):PAGE41
  AF42    GND @S9S_MB_2U_LIB.S9S_MB_2U(SCH_1):GND    I11 @S9S_MB_2U_LIB.S9S_MB_2U(SCH_1):PAGE41
   AF4    GND @S9S_MB_2U_LIB.S9S_MB_2U(SCH_1):GND    I11 @S9S_MB_2U_LIB.S9S_MB_2U(SCH_1):PAGE41
  AF16    GND @S9S_MB_2U_LIB.S9S_MB_2U(SCH_1):GND    I11 @S9S_MB_2U_LIB.S9S_MB_2U(SCH_1):PAGE41
  AF12    GND @S9S_MB_2U_LIB.S9S_MB_2U(SCH_1):GND    I11 @S9S_MB_2U_LIB.S9S_MB_2U(SCH_1):PAGE41
  AE88    GND @S9S_MB_2U_LIB.S9S_MB_2U(SCH_1):GND    I11 @S9S_MB_2U_LIB.S9S_MB_2U(SCH_1):PAGE41
  AE84    GND @S9S_MB_2U_LIB.S9S_MB_2U(SCH_1):GND    I11 @S9S_MB_2U_LIB.S9S_MB_2U(SCH_1):PAGE41
  AE78    GND @S9S_MB_2U_LIB.S9S_MB_2U(SCH_1):GND    I11 @S9S_MB_2U_LIB.S9S_MB_2U(SCH_1):PAGE41
  AE76    GND @S9S_MB_2U_LIB.S9S_MB_2U(SCH_1):GND    I11 @S9S_MB_2U_LIB.S9S_MB_2U(SCH_1):PAGE41
  AE74    GND @S9S_MB_2U_LIB.S9S_MB_2U(SCH_1):GND    I11 @S9S_MB_2U_LIB.S9S_MB_2U(SCH_1):PAGE41
  AE72    GND @S9S_MB_2U_LIB.S9S_MB_2U(SCH_1):GND    I11 @S9S_MB_2U_LIB.S9S_MB_2U(SCH_1):PAGE41
  AE70    GND @S9S_MB_2U_LIB.S9S_MB_2U(SCH_1):GND    I11 @S9S_MB_2U_LIB.S9S_MB_2U(SCH_1):PAGE41
  AE68    GND @S9S_MB_2U_LIB.S9S_MB_2U(SCH_1):GND    I11 @S9S_MB_2U_LIB.S9S_MB_2U(SCH_1):PAGE41
  AE66    GND @S9S_MB_2U_LIB.S9S_MB_2U(SCH_1):GND    I11 @S9S_MB_2U_LIB.S9S_MB_2U(SCH_1):PAGE41
  AE64    GND @S9S_MB_2U_LIB.S9S_MB_2U(SCH_1):GND    I11 @S9S_MB_2U_LIB.S9S_MB_2U(SCH_1):PAGE41
  AE62    GND @S9S_MB_2U_LIB.S9S_MB_2U(SCH_1):GND    I11 @S9S_MB_2U_LIB.S9S_MB_2U(SCH_1):PAGE41
  AE60    GND @S9S_MB_2U_LIB.S9S_MB_2U(SCH_1):GND    I11 @S9S_MB_2U_LIB.S9S_MB_2U(SCH_1):PAGE41
  AE58    GND @S9S_MB_2U_LIB.S9S_MB_2U(SCH_1):GND    I11 @S9S_MB_2U_LIB.S9S_MB_2U(SCH_1):PAGE41
  AE56    GND @S9S_MB_2U_LIB.S9S_MB_2U(SCH_1):GND    I11 @S9S_MB_2U_LIB.S9S_MB_2U(SCH_1):PAGE41
  AE54    GND @S9S_MB_2U_LIB.S9S_MB_2U(SCH_1):GND    I11 @S9S_MB_2U_LIB.S9S_MB_2U(SCH_1):PAGE41
  AE52    GND @S9S_MB_2U_LIB.S9S_MB_2U(SCH_1):GND    I11 @S9S_MB_2U_LIB.S9S_MB_2U(SCH_1):PAGE41
  AE50    GND @S9S_MB_2U_LIB.S9S_MB_2U(SCH_1):GND    I11 @S9S_MB_2U_LIB.S9S_MB_2U(SCH_1):PAGE41
  AE48    GND @S9S_MB_2U_LIB.S9S_MB_2U(SCH_1):GND    I11 @S9S_MB_2U_LIB.S9S_MB_2U(SCH_1):PAGE41
  AE45    GND @S9S_MB_2U_LIB.S9S_MB_2U(SCH_1):GND    I11 @S9S_MB_2U_LIB.S9S_MB_2U(SCH_1):PAGE41
  AE43    GND @S9S_MB_2U_LIB.S9S_MB_2U(SCH_1):GND    I11 @S9S_MB_2U_LIB.S9S_MB_2U(SCH_1):PAGE41
  AE41    GND @S9S_MB_2U_LIB.S9S_MB_2U(SCH_1):GND    I11 @S9S_MB_2U_LIB.S9S_MB_2U(SCH_1):PAGE41
  AE39    GND @S9S_MB_2U_LIB.S9S_MB_2U(SCH_1):GND    I11 @S9S_MB_2U_LIB.S9S_MB_2U(SCH_1):PAGE41
  AE37    GND @S9S_MB_2U_LIB.S9S_MB_2U(SCH_1):GND    I11 @S9S_MB_2U_LIB.S9S_MB_2U(SCH_1):PAGE41
  AE35    GND @S9S_MB_2U_LIB.S9S_MB_2U(SCH_1):GND    I11 @S9S_MB_2U_LIB.S9S_MB_2U(SCH_1):PAGE41
  AE33    GND @S9S_MB_2U_LIB.S9S_MB_2U(SCH_1):GND    I11 @S9S_MB_2U_LIB.S9S_MB_2U(SCH_1):PAGE41
  AE31    GND @S9S_MB_2U_LIB.S9S_MB_2U(SCH_1):GND    I11 @S9S_MB_2U_LIB.S9S_MB_2U(SCH_1):PAGE41
  AE29    GND @S9S_MB_2U_LIB.S9S_MB_2U(SCH_1):GND    I11 @S9S_MB_2U_LIB.S9S_MB_2U(SCH_1):PAGE41
  AE27    GND @S9S_MB_2U_LIB.S9S_MB_2U(SCH_1):GND    I11 @S9S_MB_2U_LIB.S9S_MB_2U(SCH_1):PAGE41
  AE25    GND @S9S_MB_2U_LIB.S9S_MB_2U(SCH_1):GND    I11 @S9S_MB_2U_LIB.S9S_MB_2U(SCH_1):PAGE41
  AE23    GND @S9S_MB_2U_LIB.S9S_MB_2U(SCH_1):GND    I11 @S9S_MB_2U_LIB.S9S_MB_2U(SCH_1):PAGE41
  AE21    GND @S9S_MB_2U_LIB.S9S_MB_2U(SCH_1):GND    I11 @S9S_MB_2U_LIB.S9S_MB_2U(SCH_1):PAGE41
  AE19    GND @S9S_MB_2U_LIB.S9S_MB_2U(SCH_1):GND    I11 @S9S_MB_2U_LIB.S9S_MB_2U(SCH_1):PAGE41
  AE17    GND @S9S_MB_2U_LIB.S9S_MB_2U(SCH_1):GND    I11 @S9S_MB_2U_LIB.S9S_MB_2U(SCH_1):PAGE41
  AD83    GND @S9S_MB_2U_LIB.S9S_MB_2U(SCH_1):GND    I11 @S9S_MB_2U_LIB.S9S_MB_2U(SCH_1):PAGE41
   AD8    GND @S9S_MB_2U_LIB.S9S_MB_2U(SCH_1):GND    I11 @S9S_MB_2U_LIB.S9S_MB_2U(SCH_1):PAGE41
  AD79    GND @S9S_MB_2U_LIB.S9S_MB_2U(SCH_1):GND    I11 @S9S_MB_2U_LIB.S9S_MB_2U(SCH_1):PAGE41
  AD42    GND @S9S_MB_2U_LIB.S9S_MB_2U(SCH_1):GND    I11 @S9S_MB_2U_LIB.S9S_MB_2U(SCH_1):PAGE41
   AD4    GND @S9S_MB_2U_LIB.S9S_MB_2U(SCH_1):GND    I11 @S9S_MB_2U_LIB.S9S_MB_2U(SCH_1):PAGE41
  AD16    GND @S9S_MB_2U_LIB.S9S_MB_2U(SCH_1):GND    I11 @S9S_MB_2U_LIB.S9S_MB_2U(SCH_1):PAGE41
  AD12    GND @S9S_MB_2U_LIB.S9S_MB_2U(SCH_1):GND    I11 @S9S_MB_2U_LIB.S9S_MB_2U(SCH_1):PAGE41
   AC9    GND @S9S_MB_2U_LIB.S9S_MB_2U(SCH_1):GND    I11 @S9S_MB_2U_LIB.S9S_MB_2U(SCH_1):PAGE41
  AC88    GND @S9S_MB_2U_LIB.S9S_MB_2U(SCH_1):GND    I11 @S9S_MB_2U_LIB.S9S_MB_2U(SCH_1):PAGE41
  AC84    GND @S9S_MB_2U_LIB.S9S_MB_2U(SCH_1):GND    I11 @S9S_MB_2U_LIB.S9S_MB_2U(SCH_1):PAGE41
  AC76    GND @S9S_MB_2U_LIB.S9S_MB_2U(SCH_1):GND    I11 @S9S_MB_2U_LIB.S9S_MB_2U(SCH_1):PAGE41
  AC70    GND @S9S_MB_2U_LIB.S9S_MB_2U(SCH_1):GND    I11 @S9S_MB_2U_LIB.S9S_MB_2U(SCH_1):PAGE41
  AC64    GND @S9S_MB_2U_LIB.S9S_MB_2U(SCH_1):GND    I11 @S9S_MB_2U_LIB.S9S_MB_2U(SCH_1):PAGE41
  AC58    GND @S9S_MB_2U_LIB.S9S_MB_2U(SCH_1):GND    I11 @S9S_MB_2U_LIB.S9S_MB_2U(SCH_1):PAGE41
  AC52    GND @S9S_MB_2U_LIB.S9S_MB_2U(SCH_1):GND    I11 @S9S_MB_2U_LIB.S9S_MB_2U(SCH_1):PAGE41
   AC5    GND @S9S_MB_2U_LIB.S9S_MB_2U(SCH_1):GND    I11 @S9S_MB_2U_LIB.S9S_MB_2U(SCH_1):PAGE41
  AC45    GND @S9S_MB_2U_LIB.S9S_MB_2U(SCH_1):GND    I11 @S9S_MB_2U_LIB.S9S_MB_2U(SCH_1):PAGE41
  AC39    GND @S9S_MB_2U_LIB.S9S_MB_2U(SCH_1):GND    I11 @S9S_MB_2U_LIB.S9S_MB_2U(SCH_1):PAGE41
  AC33    GND @S9S_MB_2U_LIB.S9S_MB_2U(SCH_1):GND    I11 @S9S_MB_2U_LIB.S9S_MB_2U(SCH_1):PAGE41
  AC27    GND @S9S_MB_2U_LIB.S9S_MB_2U(SCH_1):GND    I11 @S9S_MB_2U_LIB.S9S_MB_2U(SCH_1):PAGE41
  AC21    GND @S9S_MB_2U_LIB.S9S_MB_2U(SCH_1):GND    I11 @S9S_MB_2U_LIB.S9S_MB_2U(SCH_1):PAGE41
  AC13    GND @S9S_MB_2U_LIB.S9S_MB_2U(SCH_1):GND    I11 @S9S_MB_2U_LIB.S9S_MB_2U(SCH_1):PAGE41
   AC1    GND @S9S_MB_2U_LIB.S9S_MB_2U(SCH_1):GND    I11 @S9S_MB_2U_LIB.S9S_MB_2U(SCH_1):PAGE41
  AB91    GND @S9S_MB_2U_LIB.S9S_MB_2U(SCH_1):GND    I11 @S9S_MB_2U_LIB.S9S_MB_2U(SCH_1):PAGE41
  AB87    GND @S9S_MB_2U_LIB.S9S_MB_2U(SCH_1):GND    I11 @S9S_MB_2U_LIB.S9S_MB_2U(SCH_1):PAGE41
  AB83    GND @S9S_MB_2U_LIB.S9S_MB_2U(SCH_1):GND    I11 @S9S_MB_2U_LIB.S9S_MB_2U(SCH_1):PAGE41
  AB81    GND @S9S_MB_2U_LIB.S9S_MB_2U(SCH_1):GND    I11 @S9S_MB_2U_LIB.S9S_MB_2U(SCH_1):PAGE41
   AB8    GND @S9S_MB_2U_LIB.S9S_MB_2U(SCH_1):GND    I11 @S9S_MB_2U_LIB.S9S_MB_2U(SCH_1):PAGE41
  AB79    GND @S9S_MB_2U_LIB.S9S_MB_2U(SCH_1):GND    I11 @S9S_MB_2U_LIB.S9S_MB_2U(SCH_1):PAGE41
  AB77    GND @S9S_MB_2U_LIB.S9S_MB_2U(SCH_1):GND    I11 @S9S_MB_2U_LIB.S9S_MB_2U(SCH_1):PAGE41
  AB75    GND @S9S_MB_2U_LIB.S9S_MB_2U(SCH_1):GND    I11 @S9S_MB_2U_LIB.S9S_MB_2U(SCH_1):PAGE41
  AB71    GND @S9S_MB_2U_LIB.S9S_MB_2U(SCH_1):GND    I11 @S9S_MB_2U_LIB.S9S_MB_2U(SCH_1):PAGE41
  AB69    GND @S9S_MB_2U_LIB.S9S_MB_2U(SCH_1):GND    I11 @S9S_MB_2U_LIB.S9S_MB_2U(SCH_1):PAGE41
  AB65    GND @S9S_MB_2U_LIB.S9S_MB_2U(SCH_1):GND    I11 @S9S_MB_2U_LIB.S9S_MB_2U(SCH_1):PAGE41
  AB63    GND @S9S_MB_2U_LIB.S9S_MB_2U(SCH_1):GND    I11 @S9S_MB_2U_LIB.S9S_MB_2U(SCH_1):PAGE41
  AB59    GND @S9S_MB_2U_LIB.S9S_MB_2U(SCH_1):GND    I11 @S9S_MB_2U_LIB.S9S_MB_2U(SCH_1):PAGE41
  AB57    GND @S9S_MB_2U_LIB.S9S_MB_2U(SCH_1):GND    I11 @S9S_MB_2U_LIB.S9S_MB_2U(SCH_1):PAGE41
  AB53    GND @S9S_MB_2U_LIB.S9S_MB_2U(SCH_1):GND    I11 @S9S_MB_2U_LIB.S9S_MB_2U(SCH_1):PAGE41
  AB51    GND @S9S_MB_2U_LIB.S9S_MB_2U(SCH_1):GND    I11 @S9S_MB_2U_LIB.S9S_MB_2U(SCH_1):PAGE41
  AB47    GND @S9S_MB_2U_LIB.S9S_MB_2U(SCH_1):GND    I11 @S9S_MB_2U_LIB.S9S_MB_2U(SCH_1):PAGE41
  AB44    GND @S9S_MB_2U_LIB.S9S_MB_2U(SCH_1):GND    I11 @S9S_MB_2U_LIB.S9S_MB_2U(SCH_1):PAGE41
  AB40    GND @S9S_MB_2U_LIB.S9S_MB_2U(SCH_1):GND    I11 @S9S_MB_2U_LIB.S9S_MB_2U(SCH_1):PAGE41
   AB4    GND @S9S_MB_2U_LIB.S9S_MB_2U(SCH_1):GND    I11 @S9S_MB_2U_LIB.S9S_MB_2U(SCH_1):PAGE41
  AB38    GND @S9S_MB_2U_LIB.S9S_MB_2U(SCH_1):GND    I11 @S9S_MB_2U_LIB.S9S_MB_2U(SCH_1):PAGE41
  AB34    GND @S9S_MB_2U_LIB.S9S_MB_2U(SCH_1):GND    I11 @S9S_MB_2U_LIB.S9S_MB_2U(SCH_1):PAGE41
  AB32    GND @S9S_MB_2U_LIB.S9S_MB_2U(SCH_1):GND    I11 @S9S_MB_2U_LIB.S9S_MB_2U(SCH_1):PAGE41
  AB28    GND @S9S_MB_2U_LIB.S9S_MB_2U(SCH_1):GND    I11 @S9S_MB_2U_LIB.S9S_MB_2U(SCH_1):PAGE41
  AB26    GND @S9S_MB_2U_LIB.S9S_MB_2U(SCH_1):GND    I11 @S9S_MB_2U_LIB.S9S_MB_2U(SCH_1):PAGE41
  AB22    GND @S9S_MB_2U_LIB.S9S_MB_2U(SCH_1):GND    I11 @S9S_MB_2U_LIB.S9S_MB_2U(SCH_1):PAGE41
  AB20    GND @S9S_MB_2U_LIB.S9S_MB_2U(SCH_1):GND    I11 @S9S_MB_2U_LIB.S9S_MB_2U(SCH_1):PAGE41
  AB16    GND @S9S_MB_2U_LIB.S9S_MB_2U(SCH_1):GND    I11 @S9S_MB_2U_LIB.S9S_MB_2U(SCH_1):PAGE41
  AB12    GND @S9S_MB_2U_LIB.S9S_MB_2U(SCH_1):GND    I11 @S9S_MB_2U_LIB.S9S_MB_2U(SCH_1):PAGE41
  AA88    GND @S9S_MB_2U_LIB.S9S_MB_2U(SCH_1):GND    I11 @S9S_MB_2U_LIB.S9S_MB_2U(SCH_1):PAGE41
  AA84    GND @S9S_MB_2U_LIB.S9S_MB_2U(SCH_1):GND    I11 @S9S_MB_2U_LIB.S9S_MB_2U(SCH_1):PAGE41
  AA82    GND @S9S_MB_2U_LIB.S9S_MB_2U(SCH_1):GND    I11 @S9S_MB_2U_LIB.S9S_MB_2U(SCH_1):PAGE41
   Y73    GND @S9S_MB_2U_LIB.S9S_MB_2U(SCH_1):GND    I10 @S9S_MB_2U_LIB.S9S_MB_2U(SCH_1):PAGE42
    Y8    GND @S9S_MB_2U_LIB.S9S_MB_2U(SCH_1):GND    I10 @S9S_MB_2U_LIB.S9S_MB_2U(SCH_1):PAGE42
   Y55    GND @S9S_MB_2U_LIB.S9S_MB_2U(SCH_1):GND    I10 @S9S_MB_2U_LIB.S9S_MB_2U(SCH_1):PAGE42
   Y49    GND @S9S_MB_2U_LIB.S9S_MB_2U(SCH_1):GND    I10 @S9S_MB_2U_LIB.S9S_MB_2U(SCH_1):PAGE42
   Y67    GND @S9S_MB_2U_LIB.S9S_MB_2U(SCH_1):GND    I10 @S9S_MB_2U_LIB.S9S_MB_2U(SCH_1):PAGE42
   Y61    GND @S9S_MB_2U_LIB.S9S_MB_2U(SCH_1):GND    I10 @S9S_MB_2U_LIB.S9S_MB_2U(SCH_1):PAGE42
   Y42    GND @S9S_MB_2U_LIB.S9S_MB_2U(SCH_1):GND    I10 @S9S_MB_2U_LIB.S9S_MB_2U(SCH_1):PAGE42
    Y4    GND @S9S_MB_2U_LIB.S9S_MB_2U(SCH_1):GND    I10 @S9S_MB_2U_LIB.S9S_MB_2U(SCH_1):PAGE42
   Y36    GND @S9S_MB_2U_LIB.S9S_MB_2U(SCH_1):GND    I10 @S9S_MB_2U_LIB.S9S_MB_2U(SCH_1):PAGE42
   Y30    GND @S9S_MB_2U_LIB.S9S_MB_2U(SCH_1):GND    I10 @S9S_MB_2U_LIB.S9S_MB_2U(SCH_1):PAGE42
   Y24    GND @S9S_MB_2U_LIB.S9S_MB_2U(SCH_1):GND    I10 @S9S_MB_2U_LIB.S9S_MB_2U(SCH_1):PAGE42
   Y18    GND @S9S_MB_2U_LIB.S9S_MB_2U(SCH_1):GND    I10 @S9S_MB_2U_LIB.S9S_MB_2U(SCH_1):PAGE42
   Y16    GND @S9S_MB_2U_LIB.S9S_MB_2U(SCH_1):GND    I10 @S9S_MB_2U_LIB.S9S_MB_2U(SCH_1):PAGE42
   Y12    GND @S9S_MB_2U_LIB.S9S_MB_2U(SCH_1):GND    I10 @S9S_MB_2U_LIB.S9S_MB_2U(SCH_1):PAGE42
    W9    GND @S9S_MB_2U_LIB.S9S_MB_2U(SCH_1):GND    I10 @S9S_MB_2U_LIB.S9S_MB_2U(SCH_1):PAGE42
   W88    GND @S9S_MB_2U_LIB.S9S_MB_2U(SCH_1):GND    I10 @S9S_MB_2U_LIB.S9S_MB_2U(SCH_1):PAGE42
   W84    GND @S9S_MB_2U_LIB.S9S_MB_2U(SCH_1):GND    I10 @S9S_MB_2U_LIB.S9S_MB_2U(SCH_1):PAGE42
   W39    GND @S9S_MB_2U_LIB.S9S_MB_2U(SCH_1):GND    I10 @S9S_MB_2U_LIB.S9S_MB_2U(SCH_1):PAGE42
   W52    GND @S9S_MB_2U_LIB.S9S_MB_2U(SCH_1):GND    I10 @S9S_MB_2U_LIB.S9S_MB_2U(SCH_1):PAGE42
    W5    GND @S9S_MB_2U_LIB.S9S_MB_2U(SCH_1):GND    I10 @S9S_MB_2U_LIB.S9S_MB_2U(SCH_1):PAGE42
   V87    GND @S9S_MB_2U_LIB.S9S_MB_2U(SCH_1):GND    I10 @S9S_MB_2U_LIB.S9S_MB_2U(SCH_1):PAGE42
    V8    GND @S9S_MB_2U_LIB.S9S_MB_2U(SCH_1):GND    I10 @S9S_MB_2U_LIB.S9S_MB_2U(SCH_1):PAGE42
   V79    GND @S9S_MB_2U_LIB.S9S_MB_2U(SCH_1):GND    I10 @S9S_MB_2U_LIB.S9S_MB_2U(SCH_1):PAGE42
   V77    GND @S9S_MB_2U_LIB.S9S_MB_2U(SCH_1):GND    I10 @S9S_MB_2U_LIB.S9S_MB_2U(SCH_1):PAGE42
   W13    GND @S9S_MB_2U_LIB.S9S_MB_2U(SCH_1):GND    I10 @S9S_MB_2U_LIB.S9S_MB_2U(SCH_1):PAGE42
    W1    GND @S9S_MB_2U_LIB.S9S_MB_2U(SCH_1):GND    I10 @S9S_MB_2U_LIB.S9S_MB_2U(SCH_1):PAGE42
   V91    GND @S9S_MB_2U_LIB.S9S_MB_2U(SCH_1):GND    I10 @S9S_MB_2U_LIB.S9S_MB_2U(SCH_1):PAGE42
   V75    GND @S9S_MB_2U_LIB.S9S_MB_2U(SCH_1):GND    I10 @S9S_MB_2U_LIB.S9S_MB_2U(SCH_1):PAGE42
   V69    GND @S9S_MB_2U_LIB.S9S_MB_2U(SCH_1):GND    I10 @S9S_MB_2U_LIB.S9S_MB_2U(SCH_1):PAGE42
   V67    GND @S9S_MB_2U_LIB.S9S_MB_2U(SCH_1):GND    I10 @S9S_MB_2U_LIB.S9S_MB_2U(SCH_1):PAGE42
   V65    GND @S9S_MB_2U_LIB.S9S_MB_2U(SCH_1):GND    I10 @S9S_MB_2U_LIB.S9S_MB_2U(SCH_1):PAGE42
   V63    GND @S9S_MB_2U_LIB.S9S_MB_2U(SCH_1):GND    I10 @S9S_MB_2U_LIB.S9S_MB_2U(SCH_1):PAGE42
   V73    GND @S9S_MB_2U_LIB.S9S_MB_2U(SCH_1):GND    I10 @S9S_MB_2U_LIB.S9S_MB_2U(SCH_1):PAGE42
   V71    GND @S9S_MB_2U_LIB.S9S_MB_2U(SCH_1):GND    I10 @S9S_MB_2U_LIB.S9S_MB_2U(SCH_1):PAGE42
   V61    GND @S9S_MB_2U_LIB.S9S_MB_2U(SCH_1):GND    I10 @S9S_MB_2U_LIB.S9S_MB_2U(SCH_1):PAGE42
   V59    GND @S9S_MB_2U_LIB.S9S_MB_2U(SCH_1):GND    I10 @S9S_MB_2U_LIB.S9S_MB_2U(SCH_1):PAGE42
   V57    GND @S9S_MB_2U_LIB.S9S_MB_2U(SCH_1):GND    I10 @S9S_MB_2U_LIB.S9S_MB_2U(SCH_1):PAGE42
   V55    GND @S9S_MB_2U_LIB.S9S_MB_2U(SCH_1):GND    I10 @S9S_MB_2U_LIB.S9S_MB_2U(SCH_1):PAGE42
   V53    GND @S9S_MB_2U_LIB.S9S_MB_2U(SCH_1):GND    I10 @S9S_MB_2U_LIB.S9S_MB_2U(SCH_1):PAGE42
   V51    GND @S9S_MB_2U_LIB.S9S_MB_2U(SCH_1):GND    I10 @S9S_MB_2U_LIB.S9S_MB_2U(SCH_1):PAGE42
   V47    GND @S9S_MB_2U_LIB.S9S_MB_2U(SCH_1):GND    I10 @S9S_MB_2U_LIB.S9S_MB_2U(SCH_1):PAGE42
   V44    GND @S9S_MB_2U_LIB.S9S_MB_2U(SCH_1):GND    I10 @S9S_MB_2U_LIB.S9S_MB_2U(SCH_1):PAGE42
   V42    GND @S9S_MB_2U_LIB.S9S_MB_2U(SCH_1):GND    I10 @S9S_MB_2U_LIB.S9S_MB_2U(SCH_1):PAGE42
   V40    GND @S9S_MB_2U_LIB.S9S_MB_2U(SCH_1):GND    I10 @S9S_MB_2U_LIB.S9S_MB_2U(SCH_1):PAGE42
   V49    GND @S9S_MB_2U_LIB.S9S_MB_2U(SCH_1):GND    I10 @S9S_MB_2U_LIB.S9S_MB_2U(SCH_1):PAGE42
    V4    GND @S9S_MB_2U_LIB.S9S_MB_2U(SCH_1):GND    I10 @S9S_MB_2U_LIB.S9S_MB_2U(SCH_1):PAGE42
   V38    GND @S9S_MB_2U_LIB.S9S_MB_2U(SCH_1):GND    I10 @S9S_MB_2U_LIB.S9S_MB_2U(SCH_1):PAGE42
   V36    GND @S9S_MB_2U_LIB.S9S_MB_2U(SCH_1):GND    I10 @S9S_MB_2U_LIB.S9S_MB_2U(SCH_1):PAGE42
   V34    GND @S9S_MB_2U_LIB.S9S_MB_2U(SCH_1):GND    I10 @S9S_MB_2U_LIB.S9S_MB_2U(SCH_1):PAGE42
   V32    GND @S9S_MB_2U_LIB.S9S_MB_2U(SCH_1):GND    I10 @S9S_MB_2U_LIB.S9S_MB_2U(SCH_1):PAGE42
   V30    GND @S9S_MB_2U_LIB.S9S_MB_2U(SCH_1):GND    I10 @S9S_MB_2U_LIB.S9S_MB_2U(SCH_1):PAGE42
   V28    GND @S9S_MB_2U_LIB.S9S_MB_2U(SCH_1):GND    I10 @S9S_MB_2U_LIB.S9S_MB_2U(SCH_1):PAGE42
   V26    GND @S9S_MB_2U_LIB.S9S_MB_2U(SCH_1):GND    I10 @S9S_MB_2U_LIB.S9S_MB_2U(SCH_1):PAGE42
   V24    GND @S9S_MB_2U_LIB.S9S_MB_2U(SCH_1):GND    I10 @S9S_MB_2U_LIB.S9S_MB_2U(SCH_1):PAGE42
   V22    GND @S9S_MB_2U_LIB.S9S_MB_2U(SCH_1):GND    I10 @S9S_MB_2U_LIB.S9S_MB_2U(SCH_1):PAGE42
   V20    GND @S9S_MB_2U_LIB.S9S_MB_2U(SCH_1):GND    I10 @S9S_MB_2U_LIB.S9S_MB_2U(SCH_1):PAGE42
   V18    GND @S9S_MB_2U_LIB.S9S_MB_2U(SCH_1):GND    I10 @S9S_MB_2U_LIB.S9S_MB_2U(SCH_1):PAGE42
   V16    GND @S9S_MB_2U_LIB.S9S_MB_2U(SCH_1):GND    I10 @S9S_MB_2U_LIB.S9S_MB_2U(SCH_1):PAGE42
   V12    GND @S9S_MB_2U_LIB.S9S_MB_2U(SCH_1):GND    I10 @S9S_MB_2U_LIB.S9S_MB_2U(SCH_1):PAGE42
   U88    GND @S9S_MB_2U_LIB.S9S_MB_2U(SCH_1):GND    I10 @S9S_MB_2U_LIB.S9S_MB_2U(SCH_1):PAGE42
   U84    GND @S9S_MB_2U_LIB.S9S_MB_2U(SCH_1):GND    I10 @S9S_MB_2U_LIB.S9S_MB_2U(SCH_1):PAGE42
   U82    GND @S9S_MB_2U_LIB.S9S_MB_2U(SCH_1):GND    I10 @S9S_MB_2U_LIB.S9S_MB_2U(SCH_1):PAGE42
   U39    GND @S9S_MB_2U_LIB.S9S_MB_2U(SCH_1):GND    I10 @S9S_MB_2U_LIB.S9S_MB_2U(SCH_1):PAGE42
   T83    GND @S9S_MB_2U_LIB.S9S_MB_2U(SCH_1):GND    I10 @S9S_MB_2U_LIB.S9S_MB_2U(SCH_1):PAGE42
    T8    GND @S9S_MB_2U_LIB.S9S_MB_2U(SCH_1):GND    I10 @S9S_MB_2U_LIB.S9S_MB_2U(SCH_1):PAGE42
   T79    GND @S9S_MB_2U_LIB.S9S_MB_2U(SCH_1):GND    I10 @S9S_MB_2U_LIB.S9S_MB_2U(SCH_1):PAGE42
   T73    GND @S9S_MB_2U_LIB.S9S_MB_2U(SCH_1):GND    I10 @S9S_MB_2U_LIB.S9S_MB_2U(SCH_1):PAGE42
   U52    GND @S9S_MB_2U_LIB.S9S_MB_2U(SCH_1):GND    I10 @S9S_MB_2U_LIB.S9S_MB_2U(SCH_1):PAGE42
   T67    GND @S9S_MB_2U_LIB.S9S_MB_2U(SCH_1):GND    I10 @S9S_MB_2U_LIB.S9S_MB_2U(SCH_1):PAGE42
   T61    GND @S9S_MB_2U_LIB.S9S_MB_2U(SCH_1):GND    I10 @S9S_MB_2U_LIB.S9S_MB_2U(SCH_1):PAGE42
   T42    GND @S9S_MB_2U_LIB.S9S_MB_2U(SCH_1):GND    I10 @S9S_MB_2U_LIB.S9S_MB_2U(SCH_1):PAGE42
    T4    GND @S9S_MB_2U_LIB.S9S_MB_2U(SCH_1):GND    I10 @S9S_MB_2U_LIB.S9S_MB_2U(SCH_1):PAGE42
   T30    GND @S9S_MB_2U_LIB.S9S_MB_2U(SCH_1):GND    I10 @S9S_MB_2U_LIB.S9S_MB_2U(SCH_1):PAGE42
   T24    GND @S9S_MB_2U_LIB.S9S_MB_2U(SCH_1):GND    I10 @S9S_MB_2U_LIB.S9S_MB_2U(SCH_1):PAGE42
    R9    GND @S9S_MB_2U_LIB.S9S_MB_2U(SCH_1):GND    I10 @S9S_MB_2U_LIB.S9S_MB_2U(SCH_1):PAGE42
   R88    GND @S9S_MB_2U_LIB.S9S_MB_2U(SCH_1):GND    I10 @S9S_MB_2U_LIB.S9S_MB_2U(SCH_1):PAGE42
   R84    GND @S9S_MB_2U_LIB.S9S_MB_2U(SCH_1):GND    I10 @S9S_MB_2U_LIB.S9S_MB_2U(SCH_1):PAGE42
   R78    GND @S9S_MB_2U_LIB.S9S_MB_2U(SCH_1):GND    I10 @S9S_MB_2U_LIB.S9S_MB_2U(SCH_1):PAGE42
   R74    GND @S9S_MB_2U_LIB.S9S_MB_2U(SCH_1):GND    I10 @S9S_MB_2U_LIB.S9S_MB_2U(SCH_1):PAGE42
   R72    GND @S9S_MB_2U_LIB.S9S_MB_2U(SCH_1):GND    I10 @S9S_MB_2U_LIB.S9S_MB_2U(SCH_1):PAGE42
   R68    GND @S9S_MB_2U_LIB.S9S_MB_2U(SCH_1):GND    I10 @S9S_MB_2U_LIB.S9S_MB_2U(SCH_1):PAGE42
   R62    GND @S9S_MB_2U_LIB.S9S_MB_2U(SCH_1):GND    I10 @S9S_MB_2U_LIB.S9S_MB_2U(SCH_1):PAGE42
   R56    GND @S9S_MB_2U_LIB.S9S_MB_2U(SCH_1):GND    I10 @S9S_MB_2U_LIB.S9S_MB_2U(SCH_1):PAGE42
   T55    GND @S9S_MB_2U_LIB.S9S_MB_2U(SCH_1):GND    I10 @S9S_MB_2U_LIB.S9S_MB_2U(SCH_1):PAGE42
   T49    GND @S9S_MB_2U_LIB.S9S_MB_2U(SCH_1):GND    I10 @S9S_MB_2U_LIB.S9S_MB_2U(SCH_1):PAGE42
   R54    GND @S9S_MB_2U_LIB.S9S_MB_2U(SCH_1):GND    I10 @S9S_MB_2U_LIB.S9S_MB_2U(SCH_1):PAGE42
   R50    GND @S9S_MB_2U_LIB.S9S_MB_2U(SCH_1):GND    I10 @S9S_MB_2U_LIB.S9S_MB_2U(SCH_1):PAGE42
   T36    GND @S9S_MB_2U_LIB.S9S_MB_2U(SCH_1):GND    I10 @S9S_MB_2U_LIB.S9S_MB_2U(SCH_1):PAGE42
    R5    GND @S9S_MB_2U_LIB.S9S_MB_2U(SCH_1):GND    I10 @S9S_MB_2U_LIB.S9S_MB_2U(SCH_1):PAGE42
   R43    GND @S9S_MB_2U_LIB.S9S_MB_2U(SCH_1):GND    I10 @S9S_MB_2U_LIB.S9S_MB_2U(SCH_1):PAGE42
   R41    GND @S9S_MB_2U_LIB.S9S_MB_2U(SCH_1):GND    I10 @S9S_MB_2U_LIB.S9S_MB_2U(SCH_1):PAGE42
   R37    GND @S9S_MB_2U_LIB.S9S_MB_2U(SCH_1):GND    I10 @S9S_MB_2U_LIB.S9S_MB_2U(SCH_1):PAGE42
   T18    GND @S9S_MB_2U_LIB.S9S_MB_2U(SCH_1):GND    I10 @S9S_MB_2U_LIB.S9S_MB_2U(SCH_1):PAGE42
   T16    GND @S9S_MB_2U_LIB.S9S_MB_2U(SCH_1):GND    I10 @S9S_MB_2U_LIB.S9S_MB_2U(SCH_1):PAGE42
   T12    GND @S9S_MB_2U_LIB.S9S_MB_2U(SCH_1):GND    I10 @S9S_MB_2U_LIB.S9S_MB_2U(SCH_1):PAGE42
   R35    GND @S9S_MB_2U_LIB.S9S_MB_2U(SCH_1):GND    I10 @S9S_MB_2U_LIB.S9S_MB_2U(SCH_1):PAGE42
   R31    GND @S9S_MB_2U_LIB.S9S_MB_2U(SCH_1):GND    I10 @S9S_MB_2U_LIB.S9S_MB_2U(SCH_1):PAGE42
   R29    GND @S9S_MB_2U_LIB.S9S_MB_2U(SCH_1):GND    I10 @S9S_MB_2U_LIB.S9S_MB_2U(SCH_1):PAGE42
   R25    GND @S9S_MB_2U_LIB.S9S_MB_2U(SCH_1):GND    I10 @S9S_MB_2U_LIB.S9S_MB_2U(SCH_1):PAGE42
   R17    GND @S9S_MB_2U_LIB.S9S_MB_2U(SCH_1):GND    I10 @S9S_MB_2U_LIB.S9S_MB_2U(SCH_1):PAGE42
   R13    GND @S9S_MB_2U_LIB.S9S_MB_2U(SCH_1):GND    I10 @S9S_MB_2U_LIB.S9S_MB_2U(SCH_1):PAGE42
   P91    GND @S9S_MB_2U_LIB.S9S_MB_2U(SCH_1):GND    I10 @S9S_MB_2U_LIB.S9S_MB_2U(SCH_1):PAGE42
   P87    GND @S9S_MB_2U_LIB.S9S_MB_2U(SCH_1):GND    I10 @S9S_MB_2U_LIB.S9S_MB_2U(SCH_1):PAGE42
   R66    GND @S9S_MB_2U_LIB.S9S_MB_2U(SCH_1):GND    I10 @S9S_MB_2U_LIB.S9S_MB_2U(SCH_1):PAGE42
    P8    GND @S9S_MB_2U_LIB.S9S_MB_2U(SCH_1):GND    I10 @S9S_MB_2U_LIB.S9S_MB_2U(SCH_1):PAGE42
   R60    GND @S9S_MB_2U_LIB.S9S_MB_2U(SCH_1):GND    I10 @S9S_MB_2U_LIB.S9S_MB_2U(SCH_1):PAGE42
   P77    GND @S9S_MB_2U_LIB.S9S_MB_2U(SCH_1):GND    I10 @S9S_MB_2U_LIB.S9S_MB_2U(SCH_1):PAGE42
   P75    GND @S9S_MB_2U_LIB.S9S_MB_2U(SCH_1):GND    I10 @S9S_MB_2U_LIB.S9S_MB_2U(SCH_1):PAGE42
   P69    GND @S9S_MB_2U_LIB.S9S_MB_2U(SCH_1):GND    I10 @S9S_MB_2U_LIB.S9S_MB_2U(SCH_1):PAGE42
   P65    GND @S9S_MB_2U_LIB.S9S_MB_2U(SCH_1):GND    I10 @S9S_MB_2U_LIB.S9S_MB_2U(SCH_1):PAGE42
   R48    GND @S9S_MB_2U_LIB.S9S_MB_2U(SCH_1):GND    I10 @S9S_MB_2U_LIB.S9S_MB_2U(SCH_1):PAGE42
   P63    GND @S9S_MB_2U_LIB.S9S_MB_2U(SCH_1):GND    I10 @S9S_MB_2U_LIB.S9S_MB_2U(SCH_1):PAGE42
   P59    GND @S9S_MB_2U_LIB.S9S_MB_2U(SCH_1):GND    I10 @S9S_MB_2U_LIB.S9S_MB_2U(SCH_1):PAGE42
   P53    GND @S9S_MB_2U_LIB.S9S_MB_2U(SCH_1):GND    I10 @S9S_MB_2U_LIB.S9S_MB_2U(SCH_1):PAGE42
   P47    GND @S9S_MB_2U_LIB.S9S_MB_2U(SCH_1):GND    I10 @S9S_MB_2U_LIB.S9S_MB_2U(SCH_1):PAGE42
   P44    GND @S9S_MB_2U_LIB.S9S_MB_2U(SCH_1):GND    I10 @S9S_MB_2U_LIB.S9S_MB_2U(SCH_1):PAGE42
   P40    GND @S9S_MB_2U_LIB.S9S_MB_2U(SCH_1):GND    I10 @S9S_MB_2U_LIB.S9S_MB_2U(SCH_1):PAGE42
    P4    GND @S9S_MB_2U_LIB.S9S_MB_2U(SCH_1):GND    I10 @S9S_MB_2U_LIB.S9S_MB_2U(SCH_1):PAGE42
   R23    GND @S9S_MB_2U_LIB.S9S_MB_2U(SCH_1):GND    I10 @S9S_MB_2U_LIB.S9S_MB_2U(SCH_1):PAGE42
   R19    GND @S9S_MB_2U_LIB.S9S_MB_2U(SCH_1):GND    I10 @S9S_MB_2U_LIB.S9S_MB_2U(SCH_1):PAGE42
   P38    GND @S9S_MB_2U_LIB.S9S_MB_2U(SCH_1):GND    I10 @S9S_MB_2U_LIB.S9S_MB_2U(SCH_1):PAGE42
   P34    GND @S9S_MB_2U_LIB.S9S_MB_2U(SCH_1):GND    I10 @S9S_MB_2U_LIB.S9S_MB_2U(SCH_1):PAGE42
    R1    GND @S9S_MB_2U_LIB.S9S_MB_2U(SCH_1):GND    I10 @S9S_MB_2U_LIB.S9S_MB_2U(SCH_1):PAGE42
   P28    GND @S9S_MB_2U_LIB.S9S_MB_2U(SCH_1):GND    I10 @S9S_MB_2U_LIB.S9S_MB_2U(SCH_1):PAGE42
   P26    GND @S9S_MB_2U_LIB.S9S_MB_2U(SCH_1):GND    I10 @S9S_MB_2U_LIB.S9S_MB_2U(SCH_1):PAGE42
   P22    GND @S9S_MB_2U_LIB.S9S_MB_2U(SCH_1):GND    I10 @S9S_MB_2U_LIB.S9S_MB_2U(SCH_1):PAGE42
   P20    GND @S9S_MB_2U_LIB.S9S_MB_2U(SCH_1):GND    I10 @S9S_MB_2U_LIB.S9S_MB_2U(SCH_1):PAGE42
   P16    GND @S9S_MB_2U_LIB.S9S_MB_2U(SCH_1):GND    I10 @S9S_MB_2U_LIB.S9S_MB_2U(SCH_1):PAGE42
   P12    GND @S9S_MB_2U_LIB.S9S_MB_2U(SCH_1):GND    I10 @S9S_MB_2U_LIB.S9S_MB_2U(SCH_1):PAGE42
   P71    GND @S9S_MB_2U_LIB.S9S_MB_2U(SCH_1):GND    I10 @S9S_MB_2U_LIB.S9S_MB_2U(SCH_1):PAGE42
   N88    GND @S9S_MB_2U_LIB.S9S_MB_2U(SCH_1):GND    I10 @S9S_MB_2U_LIB.S9S_MB_2U(SCH_1):PAGE42
   N84    GND @S9S_MB_2U_LIB.S9S_MB_2U(SCH_1):GND    I10 @S9S_MB_2U_LIB.S9S_MB_2U(SCH_1):PAGE42
   N82    GND @S9S_MB_2U_LIB.S9S_MB_2U(SCH_1):GND    I10 @S9S_MB_2U_LIB.S9S_MB_2U(SCH_1):PAGE42
   N80    GND @S9S_MB_2U_LIB.S9S_MB_2U(SCH_1):GND    I10 @S9S_MB_2U_LIB.S9S_MB_2U(SCH_1):PAGE42
   P57    GND @S9S_MB_2U_LIB.S9S_MB_2U(SCH_1):GND    I10 @S9S_MB_2U_LIB.S9S_MB_2U(SCH_1):PAGE42
   N78    GND @S9S_MB_2U_LIB.S9S_MB_2U(SCH_1):GND    I10 @S9S_MB_2U_LIB.S9S_MB_2U(SCH_1):PAGE42
   P51    GND @S9S_MB_2U_LIB.S9S_MB_2U(SCH_1):GND    I10 @S9S_MB_2U_LIB.S9S_MB_2U(SCH_1):PAGE42
   N76    GND @S9S_MB_2U_LIB.S9S_MB_2U(SCH_1):GND    I10 @S9S_MB_2U_LIB.S9S_MB_2U(SCH_1):PAGE42
   P32    GND @S9S_MB_2U_LIB.S9S_MB_2U(SCH_1):GND    I10 @S9S_MB_2U_LIB.S9S_MB_2U(SCH_1):PAGE42
  AA80    GND @S9S_MB_2U_LIB.S9S_MB_2U(SCH_1):GND    I10 @S9S_MB_2U_LIB.S9S_MB_2U(SCH_1):PAGE42
  AA78    GND @S9S_MB_2U_LIB.S9S_MB_2U(SCH_1):GND    I10 @S9S_MB_2U_LIB.S9S_MB_2U(SCH_1):PAGE42
  AA74    GND @S9S_MB_2U_LIB.S9S_MB_2U(SCH_1):GND    I10 @S9S_MB_2U_LIB.S9S_MB_2U(SCH_1):PAGE42
  AA72    GND @S9S_MB_2U_LIB.S9S_MB_2U(SCH_1):GND    I10 @S9S_MB_2U_LIB.S9S_MB_2U(SCH_1):PAGE42
  AA68    GND @S9S_MB_2U_LIB.S9S_MB_2U(SCH_1):GND    I10 @S9S_MB_2U_LIB.S9S_MB_2U(SCH_1):PAGE42
  AA66    GND @S9S_MB_2U_LIB.S9S_MB_2U(SCH_1):GND    I10 @S9S_MB_2U_LIB.S9S_MB_2U(SCH_1):PAGE42
  AA62    GND @S9S_MB_2U_LIB.S9S_MB_2U(SCH_1):GND    I10 @S9S_MB_2U_LIB.S9S_MB_2U(SCH_1):PAGE42
  AA60    GND @S9S_MB_2U_LIB.S9S_MB_2U(SCH_1):GND    I10 @S9S_MB_2U_LIB.S9S_MB_2U(SCH_1):PAGE42
  AA56    GND @S9S_MB_2U_LIB.S9S_MB_2U(SCH_1):GND    I10 @S9S_MB_2U_LIB.S9S_MB_2U(SCH_1):PAGE42
  AA54    GND @S9S_MB_2U_LIB.S9S_MB_2U(SCH_1):GND    I10 @S9S_MB_2U_LIB.S9S_MB_2U(SCH_1):PAGE42
  AA50    GND @S9S_MB_2U_LIB.S9S_MB_2U(SCH_1):GND    I10 @S9S_MB_2U_LIB.S9S_MB_2U(SCH_1):PAGE42
  AA48    GND @S9S_MB_2U_LIB.S9S_MB_2U(SCH_1):GND    I10 @S9S_MB_2U_LIB.S9S_MB_2U(SCH_1):PAGE42
  AA43    GND @S9S_MB_2U_LIB.S9S_MB_2U(SCH_1):GND    I10 @S9S_MB_2U_LIB.S9S_MB_2U(SCH_1):PAGE42
  AA41    GND @S9S_MB_2U_LIB.S9S_MB_2U(SCH_1):GND    I10 @S9S_MB_2U_LIB.S9S_MB_2U(SCH_1):PAGE42
  AA37    GND @S9S_MB_2U_LIB.S9S_MB_2U(SCH_1):GND    I10 @S9S_MB_2U_LIB.S9S_MB_2U(SCH_1):PAGE42
  AA35    GND @S9S_MB_2U_LIB.S9S_MB_2U(SCH_1):GND    I10 @S9S_MB_2U_LIB.S9S_MB_2U(SCH_1):PAGE42
  AA31    GND @S9S_MB_2U_LIB.S9S_MB_2U(SCH_1):GND    I10 @S9S_MB_2U_LIB.S9S_MB_2U(SCH_1):PAGE42
  AA29    GND @S9S_MB_2U_LIB.S9S_MB_2U(SCH_1):GND    I10 @S9S_MB_2U_LIB.S9S_MB_2U(SCH_1):PAGE42
  AA25    GND @S9S_MB_2U_LIB.S9S_MB_2U(SCH_1):GND    I10 @S9S_MB_2U_LIB.S9S_MB_2U(SCH_1):PAGE42
  AA23    GND @S9S_MB_2U_LIB.S9S_MB_2U(SCH_1):GND    I10 @S9S_MB_2U_LIB.S9S_MB_2U(SCH_1):PAGE42
  AA19    GND @S9S_MB_2U_LIB.S9S_MB_2U(SCH_1):GND    I10 @S9S_MB_2U_LIB.S9S_MB_2U(SCH_1):PAGE42
   N70    GND @S9S_MB_2U_LIB.S9S_MB_2U(SCH_1):GND    I11 @S9S_MB_2U_LIB.S9S_MB_2U(SCH_1):PAGE42
   N58    GND @S9S_MB_2U_LIB.S9S_MB_2U(SCH_1):GND    I11 @S9S_MB_2U_LIB.S9S_MB_2U(SCH_1):PAGE42
   N52    GND @S9S_MB_2U_LIB.S9S_MB_2U(SCH_1):GND    I11 @S9S_MB_2U_LIB.S9S_MB_2U(SCH_1):PAGE42
   N45    GND @S9S_MB_2U_LIB.S9S_MB_2U(SCH_1):GND    I11 @S9S_MB_2U_LIB.S9S_MB_2U(SCH_1):PAGE42
   N33    GND @S9S_MB_2U_LIB.S9S_MB_2U(SCH_1):GND    I11 @S9S_MB_2U_LIB.S9S_MB_2U(SCH_1):PAGE42
   N27    GND @S9S_MB_2U_LIB.S9S_MB_2U(SCH_1):GND    I11 @S9S_MB_2U_LIB.S9S_MB_2U(SCH_1):PAGE42
   N15    GND @S9S_MB_2U_LIB.S9S_MB_2U(SCH_1):GND    I11 @S9S_MB_2U_LIB.S9S_MB_2U(SCH_1):PAGE42
   M83    GND @S9S_MB_2U_LIB.S9S_MB_2U(SCH_1):GND    I11 @S9S_MB_2U_LIB.S9S_MB_2U(SCH_1):PAGE42
   M81    GND @S9S_MB_2U_LIB.S9S_MB_2U(SCH_1):GND    I11 @S9S_MB_2U_LIB.S9S_MB_2U(SCH_1):PAGE42
   L78    GND @S9S_MB_2U_LIB.S9S_MB_2U(SCH_1):GND    I11 @S9S_MB_2U_LIB.S9S_MB_2U(SCH_1):PAGE42
   L76    GND @S9S_MB_2U_LIB.S9S_MB_2U(SCH_1):GND    I11 @S9S_MB_2U_LIB.S9S_MB_2U(SCH_1):PAGE42
   L74    GND @S9S_MB_2U_LIB.S9S_MB_2U(SCH_1):GND    I11 @S9S_MB_2U_LIB.S9S_MB_2U(SCH_1):PAGE42
   L72    GND @S9S_MB_2U_LIB.S9S_MB_2U(SCH_1):GND    I11 @S9S_MB_2U_LIB.S9S_MB_2U(SCH_1):PAGE42
   L68    GND @S9S_MB_2U_LIB.S9S_MB_2U(SCH_1):GND    I11 @S9S_MB_2U_LIB.S9S_MB_2U(SCH_1):PAGE42
   L66    GND @S9S_MB_2U_LIB.S9S_MB_2U(SCH_1):GND    I11 @S9S_MB_2U_LIB.S9S_MB_2U(SCH_1):PAGE42
   L64    GND @S9S_MB_2U_LIB.S9S_MB_2U(SCH_1):GND    I11 @S9S_MB_2U_LIB.S9S_MB_2U(SCH_1):PAGE42
   L62    GND @S9S_MB_2U_LIB.S9S_MB_2U(SCH_1):GND    I11 @S9S_MB_2U_LIB.S9S_MB_2U(SCH_1):PAGE42
   L60    GND @S9S_MB_2U_LIB.S9S_MB_2U(SCH_1):GND    I11 @S9S_MB_2U_LIB.S9S_MB_2U(SCH_1):PAGE42
   L56    GND @S9S_MB_2U_LIB.S9S_MB_2U(SCH_1):GND    I11 @S9S_MB_2U_LIB.S9S_MB_2U(SCH_1):PAGE42
   N64    GND @S9S_MB_2U_LIB.S9S_MB_2U(SCH_1):GND    I11 @S9S_MB_2U_LIB.S9S_MB_2U(SCH_1):PAGE42
   L54    GND @S9S_MB_2U_LIB.S9S_MB_2U(SCH_1):GND    I11 @S9S_MB_2U_LIB.S9S_MB_2U(SCH_1):PAGE42
   L52    GND @S9S_MB_2U_LIB.S9S_MB_2U(SCH_1):GND    I11 @S9S_MB_2U_LIB.S9S_MB_2U(SCH_1):PAGE42
   L50    GND @S9S_MB_2U_LIB.S9S_MB_2U(SCH_1):GND    I11 @S9S_MB_2U_LIB.S9S_MB_2U(SCH_1):PAGE42
    L5    GND @S9S_MB_2U_LIB.S9S_MB_2U(SCH_1):GND    I11 @S9S_MB_2U_LIB.S9S_MB_2U(SCH_1):PAGE42
   L48    GND @S9S_MB_2U_LIB.S9S_MB_2U(SCH_1):GND    I11 @S9S_MB_2U_LIB.S9S_MB_2U(SCH_1):PAGE42
   N39    GND @S9S_MB_2U_LIB.S9S_MB_2U(SCH_1):GND    I11 @S9S_MB_2U_LIB.S9S_MB_2U(SCH_1):PAGE42
   L45    GND @S9S_MB_2U_LIB.S9S_MB_2U(SCH_1):GND    I11 @S9S_MB_2U_LIB.S9S_MB_2U(SCH_1):PAGE42
   L43    GND @S9S_MB_2U_LIB.S9S_MB_2U(SCH_1):GND    I11 @S9S_MB_2U_LIB.S9S_MB_2U(SCH_1):PAGE42
   L41    GND @S9S_MB_2U_LIB.S9S_MB_2U(SCH_1):GND    I11 @S9S_MB_2U_LIB.S9S_MB_2U(SCH_1):PAGE42
   L39    GND @S9S_MB_2U_LIB.S9S_MB_2U(SCH_1):GND    I11 @S9S_MB_2U_LIB.S9S_MB_2U(SCH_1):PAGE42
   N21    GND @S9S_MB_2U_LIB.S9S_MB_2U(SCH_1):GND    I11 @S9S_MB_2U_LIB.S9S_MB_2U(SCH_1):PAGE42
   L37    GND @S9S_MB_2U_LIB.S9S_MB_2U(SCH_1):GND    I11 @S9S_MB_2U_LIB.S9S_MB_2U(SCH_1):PAGE42
   L35    GND @S9S_MB_2U_LIB.S9S_MB_2U(SCH_1):GND    I11 @S9S_MB_2U_LIB.S9S_MB_2U(SCH_1):PAGE42
   L33    GND @S9S_MB_2U_LIB.S9S_MB_2U(SCH_1):GND    I11 @S9S_MB_2U_LIB.S9S_MB_2U(SCH_1):PAGE42
   L31    GND @S9S_MB_2U_LIB.S9S_MB_2U(SCH_1):GND    I11 @S9S_MB_2U_LIB.S9S_MB_2U(SCH_1):PAGE42
   L29    GND @S9S_MB_2U_LIB.S9S_MB_2U(SCH_1):GND    I11 @S9S_MB_2U_LIB.S9S_MB_2U(SCH_1):PAGE42
   L27    GND @S9S_MB_2U_LIB.S9S_MB_2U(SCH_1):GND    I11 @S9S_MB_2U_LIB.S9S_MB_2U(SCH_1):PAGE42
    M8    GND @S9S_MB_2U_LIB.S9S_MB_2U(SCH_1):GND    I11 @S9S_MB_2U_LIB.S9S_MB_2U(SCH_1):PAGE42
   L25    GND @S9S_MB_2U_LIB.S9S_MB_2U(SCH_1):GND    I11 @S9S_MB_2U_LIB.S9S_MB_2U(SCH_1):PAGE42
   L23    GND @S9S_MB_2U_LIB.S9S_MB_2U(SCH_1):GND    I11 @S9S_MB_2U_LIB.S9S_MB_2U(SCH_1):PAGE42
   M49    GND @S9S_MB_2U_LIB.S9S_MB_2U(SCH_1):GND    I11 @S9S_MB_2U_LIB.S9S_MB_2U(SCH_1):PAGE42
   M42    GND @S9S_MB_2U_LIB.S9S_MB_2U(SCH_1):GND    I11 @S9S_MB_2U_LIB.S9S_MB_2U(SCH_1):PAGE42
    M4    GND @S9S_MB_2U_LIB.S9S_MB_2U(SCH_1):GND    I11 @S9S_MB_2U_LIB.S9S_MB_2U(SCH_1):PAGE42
   L21    GND @S9S_MB_2U_LIB.S9S_MB_2U(SCH_1):GND    I11 @S9S_MB_2U_LIB.S9S_MB_2U(SCH_1):PAGE42
   L17    GND @S9S_MB_2U_LIB.S9S_MB_2U(SCH_1):GND    I11 @S9S_MB_2U_LIB.S9S_MB_2U(SCH_1):PAGE42
   M12    GND @S9S_MB_2U_LIB.S9S_MB_2U(SCH_1):GND    I11 @S9S_MB_2U_LIB.S9S_MB_2U(SCH_1):PAGE42
   L90    GND @S9S_MB_2U_LIB.S9S_MB_2U(SCH_1):GND    I11 @S9S_MB_2U_LIB.S9S_MB_2U(SCH_1):PAGE42
    L9    GND @S9S_MB_2U_LIB.S9S_MB_2U(SCH_1):GND    I11 @S9S_MB_2U_LIB.S9S_MB_2U(SCH_1):PAGE42
   L88    GND @S9S_MB_2U_LIB.S9S_MB_2U(SCH_1):GND    I11 @S9S_MB_2U_LIB.S9S_MB_2U(SCH_1):PAGE42
   L15    GND @S9S_MB_2U_LIB.S9S_MB_2U(SCH_1):GND    I11 @S9S_MB_2U_LIB.S9S_MB_2U(SCH_1):PAGE42
   L13    GND @S9S_MB_2U_LIB.S9S_MB_2U(SCH_1):GND    I11 @S9S_MB_2U_LIB.S9S_MB_2U(SCH_1):PAGE42
   K85    GND @S9S_MB_2U_LIB.S9S_MB_2U(SCH_1):GND    I11 @S9S_MB_2U_LIB.S9S_MB_2U(SCH_1):PAGE42
   K83    GND @S9S_MB_2U_LIB.S9S_MB_2U(SCH_1):GND    I11 @S9S_MB_2U_LIB.S9S_MB_2U(SCH_1):PAGE42
    K8    GND @S9S_MB_2U_LIB.S9S_MB_2U(SCH_1):GND    I11 @S9S_MB_2U_LIB.S9S_MB_2U(SCH_1):PAGE42
   L70    GND @S9S_MB_2U_LIB.S9S_MB_2U(SCH_1):GND    I11 @S9S_MB_2U_LIB.S9S_MB_2U(SCH_1):PAGE42
   K77    GND @S9S_MB_2U_LIB.S9S_MB_2U(SCH_1):GND    I11 @S9S_MB_2U_LIB.S9S_MB_2U(SCH_1):PAGE42
   J86    GND @S9S_MB_2U_LIB.S9S_MB_2U(SCH_1):GND    I11 @S9S_MB_2U_LIB.S9S_MB_2U(SCH_1):PAGE42
   J84    GND @S9S_MB_2U_LIB.S9S_MB_2U(SCH_1):GND    I11 @S9S_MB_2U_LIB.S9S_MB_2U(SCH_1):PAGE42
   J78    GND @S9S_MB_2U_LIB.S9S_MB_2U(SCH_1):GND    I11 @S9S_MB_2U_LIB.S9S_MB_2U(SCH_1):PAGE42
   J76    GND @S9S_MB_2U_LIB.S9S_MB_2U(SCH_1):GND    I11 @S9S_MB_2U_LIB.S9S_MB_2U(SCH_1):PAGE42
   L58    GND @S9S_MB_2U_LIB.S9S_MB_2U(SCH_1):GND    I11 @S9S_MB_2U_LIB.S9S_MB_2U(SCH_1):PAGE42
   J58    GND @S9S_MB_2U_LIB.S9S_MB_2U(SCH_1):GND    I11 @S9S_MB_2U_LIB.S9S_MB_2U(SCH_1):PAGE42
   J52    GND @S9S_MB_2U_LIB.S9S_MB_2U(SCH_1):GND    I11 @S9S_MB_2U_LIB.S9S_MB_2U(SCH_1):PAGE42
   J45    GND @S9S_MB_2U_LIB.S9S_MB_2U(SCH_1):GND    I11 @S9S_MB_2U_LIB.S9S_MB_2U(SCH_1):PAGE42
   J33    GND @S9S_MB_2U_LIB.S9S_MB_2U(SCH_1):GND    I11 @S9S_MB_2U_LIB.S9S_MB_2U(SCH_1):PAGE42
   J27    GND @S9S_MB_2U_LIB.S9S_MB_2U(SCH_1):GND    I11 @S9S_MB_2U_LIB.S9S_MB_2U(SCH_1):PAGE42
   J15    GND @S9S_MB_2U_LIB.S9S_MB_2U(SCH_1):GND    I11 @S9S_MB_2U_LIB.S9S_MB_2U(SCH_1):PAGE42
   H81    GND @S9S_MB_2U_LIB.S9S_MB_2U(SCH_1):GND    I11 @S9S_MB_2U_LIB.S9S_MB_2U(SCH_1):PAGE42
    H8    GND @S9S_MB_2U_LIB.S9S_MB_2U(SCH_1):GND    I11 @S9S_MB_2U_LIB.S9S_MB_2U(SCH_1):PAGE42
   H79    GND @S9S_MB_2U_LIB.S9S_MB_2U(SCH_1):GND    I11 @S9S_MB_2U_LIB.S9S_MB_2U(SCH_1):PAGE42
   H71    GND @S9S_MB_2U_LIB.S9S_MB_2U(SCH_1):GND    I11 @S9S_MB_2U_LIB.S9S_MB_2U(SCH_1):PAGE42
   H69    GND @S9S_MB_2U_LIB.S9S_MB_2U(SCH_1):GND    I11 @S9S_MB_2U_LIB.S9S_MB_2U(SCH_1):PAGE42
   H63    GND @S9S_MB_2U_LIB.S9S_MB_2U(SCH_1):GND    I11 @S9S_MB_2U_LIB.S9S_MB_2U(SCH_1):PAGE42
    H6    GND @S9S_MB_2U_LIB.S9S_MB_2U(SCH_1):GND    I11 @S9S_MB_2U_LIB.S9S_MB_2U(SCH_1):PAGE42
   H59    GND @S9S_MB_2U_LIB.S9S_MB_2U(SCH_1):GND    I11 @S9S_MB_2U_LIB.S9S_MB_2U(SCH_1):PAGE42
   H53    GND @S9S_MB_2U_LIB.S9S_MB_2U(SCH_1):GND    I11 @S9S_MB_2U_LIB.S9S_MB_2U(SCH_1):PAGE42
   H47    GND @S9S_MB_2U_LIB.S9S_MB_2U(SCH_1):GND    I11 @S9S_MB_2U_LIB.S9S_MB_2U(SCH_1):PAGE42
   H44    GND @S9S_MB_2U_LIB.S9S_MB_2U(SCH_1):GND    I11 @S9S_MB_2U_LIB.S9S_MB_2U(SCH_1):PAGE42
   H40    GND @S9S_MB_2U_LIB.S9S_MB_2U(SCH_1):GND    I11 @S9S_MB_2U_LIB.S9S_MB_2U(SCH_1):PAGE42
    H4    GND @S9S_MB_2U_LIB.S9S_MB_2U(SCH_1):GND    I11 @S9S_MB_2U_LIB.S9S_MB_2U(SCH_1):PAGE42
   L19    GND @S9S_MB_2U_LIB.S9S_MB_2U(SCH_1):GND    I11 @S9S_MB_2U_LIB.S9S_MB_2U(SCH_1):PAGE42
   H38    GND @S9S_MB_2U_LIB.S9S_MB_2U(SCH_1):GND    I11 @S9S_MB_2U_LIB.S9S_MB_2U(SCH_1):PAGE42
   H34    GND @S9S_MB_2U_LIB.S9S_MB_2U(SCH_1):GND    I11 @S9S_MB_2U_LIB.S9S_MB_2U(SCH_1):PAGE42
   H32    GND @S9S_MB_2U_LIB.S9S_MB_2U(SCH_1):GND    I11 @S9S_MB_2U_LIB.S9S_MB_2U(SCH_1):PAGE42
   H28    GND @S9S_MB_2U_LIB.S9S_MB_2U(SCH_1):GND    I11 @S9S_MB_2U_LIB.S9S_MB_2U(SCH_1):PAGE42
   H26    GND @S9S_MB_2U_LIB.S9S_MB_2U(SCH_1):GND    I11 @S9S_MB_2U_LIB.S9S_MB_2U(SCH_1):PAGE42
   H22    GND @S9S_MB_2U_LIB.S9S_MB_2U(SCH_1):GND    I11 @S9S_MB_2U_LIB.S9S_MB_2U(SCH_1):PAGE42
   H20    GND @S9S_MB_2U_LIB.S9S_MB_2U(SCH_1):GND    I11 @S9S_MB_2U_LIB.S9S_MB_2U(SCH_1):PAGE42
   H16    GND @S9S_MB_2U_LIB.S9S_MB_2U(SCH_1):GND    I11 @S9S_MB_2U_LIB.S9S_MB_2U(SCH_1):PAGE42
   H10    GND @S9S_MB_2U_LIB.S9S_MB_2U(SCH_1):GND    I11 @S9S_MB_2U_LIB.S9S_MB_2U(SCH_1):PAGE42
   G90    GND @S9S_MB_2U_LIB.S9S_MB_2U(SCH_1):GND    I11 @S9S_MB_2U_LIB.S9S_MB_2U(SCH_1):PAGE42
   K49    GND @S9S_MB_2U_LIB.S9S_MB_2U(SCH_1):GND    I11 @S9S_MB_2U_LIB.S9S_MB_2U(SCH_1):PAGE42
   K42    GND @S9S_MB_2U_LIB.S9S_MB_2U(SCH_1):GND    I11 @S9S_MB_2U_LIB.S9S_MB_2U(SCH_1):PAGE42
   G88    GND @S9S_MB_2U_LIB.S9S_MB_2U(SCH_1):GND    I11 @S9S_MB_2U_LIB.S9S_MB_2U(SCH_1):PAGE42
   G84    GND @S9S_MB_2U_LIB.S9S_MB_2U(SCH_1):GND    I11 @S9S_MB_2U_LIB.S9S_MB_2U(SCH_1):PAGE42
    K2    GND @S9S_MB_2U_LIB.S9S_MB_2U(SCH_1):GND    I11 @S9S_MB_2U_LIB.S9S_MB_2U(SCH_1):PAGE42
   K14    GND @S9S_MB_2U_LIB.S9S_MB_2U(SCH_1):GND    I11 @S9S_MB_2U_LIB.S9S_MB_2U(SCH_1):PAGE42
   K12    GND @S9S_MB_2U_LIB.S9S_MB_2U(SCH_1):GND    I11 @S9S_MB_2U_LIB.S9S_MB_2U(SCH_1):PAGE42
    J9    GND @S9S_MB_2U_LIB.S9S_MB_2U(SCH_1):GND    I11 @S9S_MB_2U_LIB.S9S_MB_2U(SCH_1):PAGE42
   J88    GND @S9S_MB_2U_LIB.S9S_MB_2U(SCH_1):GND    I11 @S9S_MB_2U_LIB.S9S_MB_2U(SCH_1):PAGE42
   G72    GND @S9S_MB_2U_LIB.S9S_MB_2U(SCH_1):GND    I11 @S9S_MB_2U_LIB.S9S_MB_2U(SCH_1):PAGE42
   G62    GND @S9S_MB_2U_LIB.S9S_MB_2U(SCH_1):GND    I11 @S9S_MB_2U_LIB.S9S_MB_2U(SCH_1):PAGE42
   G56    GND @S9S_MB_2U_LIB.S9S_MB_2U(SCH_1):GND    I11 @S9S_MB_2U_LIB.S9S_MB_2U(SCH_1):PAGE42
   G54    GND @S9S_MB_2U_LIB.S9S_MB_2U(SCH_1):GND    I11 @S9S_MB_2U_LIB.S9S_MB_2U(SCH_1):PAGE42
   G50    GND @S9S_MB_2U_LIB.S9S_MB_2U(SCH_1):GND    I11 @S9S_MB_2U_LIB.S9S_MB_2U(SCH_1):PAGE42
   J70    GND @S9S_MB_2U_LIB.S9S_MB_2U(SCH_1):GND    I11 @S9S_MB_2U_LIB.S9S_MB_2U(SCH_1):PAGE42
   G43    GND @S9S_MB_2U_LIB.S9S_MB_2U(SCH_1):GND    I11 @S9S_MB_2U_LIB.S9S_MB_2U(SCH_1):PAGE42
   J64    GND @S9S_MB_2U_LIB.S9S_MB_2U(SCH_1):GND    I11 @S9S_MB_2U_LIB.S9S_MB_2U(SCH_1):PAGE42
   G41    GND @S9S_MB_2U_LIB.S9S_MB_2U(SCH_1):GND    I11 @S9S_MB_2U_LIB.S9S_MB_2U(SCH_1):PAGE42
   G37    GND @S9S_MB_2U_LIB.S9S_MB_2U(SCH_1):GND    I11 @S9S_MB_2U_LIB.S9S_MB_2U(SCH_1):PAGE42
   G31    GND @S9S_MB_2U_LIB.S9S_MB_2U(SCH_1):GND    I11 @S9S_MB_2U_LIB.S9S_MB_2U(SCH_1):PAGE42
   G29    GND @S9S_MB_2U_LIB.S9S_MB_2U(SCH_1):GND    I11 @S9S_MB_2U_LIB.S9S_MB_2U(SCH_1):PAGE42
    J5    GND @S9S_MB_2U_LIB.S9S_MB_2U(SCH_1):GND    I11 @S9S_MB_2U_LIB.S9S_MB_2U(SCH_1):PAGE42
   G23    GND @S9S_MB_2U_LIB.S9S_MB_2U(SCH_1):GND    I11 @S9S_MB_2U_LIB.S9S_MB_2U(SCH_1):PAGE42
   J39    GND @S9S_MB_2U_LIB.S9S_MB_2U(SCH_1):GND    I11 @S9S_MB_2U_LIB.S9S_MB_2U(SCH_1):PAGE42
   G19    GND @S9S_MB_2U_LIB.S9S_MB_2U(SCH_1):GND    I11 @S9S_MB_2U_LIB.S9S_MB_2U(SCH_1):PAGE42
   G13    GND @S9S_MB_2U_LIB.S9S_MB_2U(SCH_1):GND    I11 @S9S_MB_2U_LIB.S9S_MB_2U(SCH_1):PAGE42
   F89    GND @S9S_MB_2U_LIB.S9S_MB_2U(SCH_1):GND    I11 @S9S_MB_2U_LIB.S9S_MB_2U(SCH_1):PAGE42
   F83    GND @S9S_MB_2U_LIB.S9S_MB_2U(SCH_1):GND    I11 @S9S_MB_2U_LIB.S9S_MB_2U(SCH_1):PAGE42
   J21    GND @S9S_MB_2U_LIB.S9S_MB_2U(SCH_1):GND    I11 @S9S_MB_2U_LIB.S9S_MB_2U(SCH_1):PAGE42
   F49    GND @S9S_MB_2U_LIB.S9S_MB_2U(SCH_1):GND    I11 @S9S_MB_2U_LIB.S9S_MB_2U(SCH_1):PAGE42
    F4    GND @S9S_MB_2U_LIB.S9S_MB_2U(SCH_1):GND    I11 @S9S_MB_2U_LIB.S9S_MB_2U(SCH_1):PAGE42
   F36    GND @S9S_MB_2U_LIB.S9S_MB_2U(SCH_1):GND    I11 @S9S_MB_2U_LIB.S9S_MB_2U(SCH_1):PAGE42
   F30    GND @S9S_MB_2U_LIB.S9S_MB_2U(SCH_1):GND    I11 @S9S_MB_2U_LIB.S9S_MB_2U(SCH_1):PAGE42
   F24    GND @S9S_MB_2U_LIB.S9S_MB_2U(SCH_1):GND    I11 @S9S_MB_2U_LIB.S9S_MB_2U(SCH_1):PAGE42
   H75    GND @S9S_MB_2U_LIB.S9S_MB_2U(SCH_1):GND    I11 @S9S_MB_2U_LIB.S9S_MB_2U(SCH_1):PAGE42
   H65    GND @S9S_MB_2U_LIB.S9S_MB_2U(SCH_1):GND    I11 @S9S_MB_2U_LIB.S9S_MB_2U(SCH_1):PAGE42
   H57    GND @S9S_MB_2U_LIB.S9S_MB_2U(SCH_1):GND    I11 @S9S_MB_2U_LIB.S9S_MB_2U(SCH_1):PAGE42
   H51    GND @S9S_MB_2U_LIB.S9S_MB_2U(SCH_1):GND    I11 @S9S_MB_2U_LIB.S9S_MB_2U(SCH_1):PAGE42
    H2    GND @S9S_MB_2U_LIB.S9S_MB_2U(SCH_1):GND    I11 @S9S_MB_2U_LIB.S9S_MB_2U(SCH_1):PAGE42
   H14    GND @S9S_MB_2U_LIB.S9S_MB_2U(SCH_1):GND    I11 @S9S_MB_2U_LIB.S9S_MB_2U(SCH_1):PAGE42
   G74    GND @S9S_MB_2U_LIB.S9S_MB_2U(SCH_1):GND    I11 @S9S_MB_2U_LIB.S9S_MB_2U(SCH_1):PAGE42
    G7    GND @S9S_MB_2U_LIB.S9S_MB_2U(SCH_1):GND    I11 @S9S_MB_2U_LIB.S9S_MB_2U(SCH_1):PAGE42
   G68    GND @S9S_MB_2U_LIB.S9S_MB_2U(SCH_1):GND    I11 @S9S_MB_2U_LIB.S9S_MB_2U(SCH_1):PAGE42
   G66    GND @S9S_MB_2U_LIB.S9S_MB_2U(SCH_1):GND    I11 @S9S_MB_2U_LIB.S9S_MB_2U(SCH_1):PAGE42
   G60    GND @S9S_MB_2U_LIB.S9S_MB_2U(SCH_1):GND    I11 @S9S_MB_2U_LIB.S9S_MB_2U(SCH_1):PAGE42
   G48    GND @S9S_MB_2U_LIB.S9S_MB_2U(SCH_1):GND    I11 @S9S_MB_2U_LIB.S9S_MB_2U(SCH_1):PAGE42
   G35    GND @S9S_MB_2U_LIB.S9S_MB_2U(SCH_1):GND    I11 @S9S_MB_2U_LIB.S9S_MB_2U(SCH_1):PAGE42
    G3    GND @S9S_MB_2U_LIB.S9S_MB_2U(SCH_1):GND    I11 @S9S_MB_2U_LIB.S9S_MB_2U(SCH_1):PAGE42
   G25    GND @S9S_MB_2U_LIB.S9S_MB_2U(SCH_1):GND    I11 @S9S_MB_2U_LIB.S9S_MB_2U(SCH_1):PAGE42
   G17    GND @S9S_MB_2U_LIB.S9S_MB_2U(SCH_1):GND    I11 @S9S_MB_2U_LIB.S9S_MB_2U(SCH_1):PAGE42
   G11    GND @S9S_MB_2U_LIB.S9S_MB_2U(SCH_1):GND    I11 @S9S_MB_2U_LIB.S9S_MB_2U(SCH_1):PAGE42
   F79    GND @S9S_MB_2U_LIB.S9S_MB_2U(SCH_1):GND    I11 @S9S_MB_2U_LIB.S9S_MB_2U(SCH_1):PAGE42
   F73    GND @S9S_MB_2U_LIB.S9S_MB_2U(SCH_1):GND    I11 @S9S_MB_2U_LIB.S9S_MB_2U(SCH_1):PAGE42
   F67    GND @S9S_MB_2U_LIB.S9S_MB_2U(SCH_1):GND    I11 @S9S_MB_2U_LIB.S9S_MB_2U(SCH_1):PAGE42
   F61    GND @S9S_MB_2U_LIB.S9S_MB_2U(SCH_1):GND    I11 @S9S_MB_2U_LIB.S9S_MB_2U(SCH_1):PAGE42
    F6    GND @S9S_MB_2U_LIB.S9S_MB_2U(SCH_1):GND    I11 @S9S_MB_2U_LIB.S9S_MB_2U(SCH_1):PAGE42
   F55    GND @S9S_MB_2U_LIB.S9S_MB_2U(SCH_1):GND    I11 @S9S_MB_2U_LIB.S9S_MB_2U(SCH_1):PAGE42
   F42    GND @S9S_MB_2U_LIB.S9S_MB_2U(SCH_1):GND    I11 @S9S_MB_2U_LIB.S9S_MB_2U(SCH_1):PAGE42
   F18    GND @S9S_MB_2U_LIB.S9S_MB_2U(SCH_1):GND    I11 @S9S_MB_2U_LIB.S9S_MB_2U(SCH_1):PAGE42
   F12    GND @S9S_MB_2U_LIB.S9S_MB_2U(SCH_1):GND    I11 @S9S_MB_2U_LIB.S9S_MB_2U(SCH_1):PAGE42
   E86    GND @S9S_MB_2U_LIB.S9S_MB_2U(SCH_1):GND    I11 @S9S_MB_2U_LIB.S9S_MB_2U(SCH_1):PAGE42
   E76    GND @S9S_MB_2U_LIB.S9S_MB_2U(SCH_1):GND    I11 @S9S_MB_2U_LIB.S9S_MB_2U(SCH_1):PAGE42
   E78    GND @S9S_MB_2U_LIB.S9S_MB_2U(SCH_1):GND    I11 @S9S_MB_2U_LIB.S9S_MB_2U(SCH_1):PAGE42
   E74    GND @S9S_MB_2U_LIB.S9S_MB_2U(SCH_1):GND    I11 @S9S_MB_2U_LIB.S9S_MB_2U(SCH_1):PAGE42
   E52    GND @S9S_MB_2U_LIB.S9S_MB_2U(SCH_1):GND    I11 @S9S_MB_2U_LIB.S9S_MB_2U(SCH_1):PAGE42
   E39    GND @S9S_MB_2U_LIB.S9S_MB_2U(SCH_1):GND    I12 @S9S_MB_2U_LIB.S9S_MB_2U(SCH_1):PAGE42
    E5    GND @S9S_MB_2U_LIB.S9S_MB_2U(SCH_1):GND    I12 @S9S_MB_2U_LIB.S9S_MB_2U(SCH_1):PAGE42
   D83    GND @S9S_MB_2U_LIB.S9S_MB_2U(SCH_1):GND    I12 @S9S_MB_2U_LIB.S9S_MB_2U(SCH_1):PAGE42
   D81    GND @S9S_MB_2U_LIB.S9S_MB_2U(SCH_1):GND    I12 @S9S_MB_2U_LIB.S9S_MB_2U(SCH_1):PAGE42
   D71    GND @S9S_MB_2U_LIB.S9S_MB_2U(SCH_1):GND    I12 @S9S_MB_2U_LIB.S9S_MB_2U(SCH_1):PAGE42
   D69    GND @S9S_MB_2U_LIB.S9S_MB_2U(SCH_1):GND    I12 @S9S_MB_2U_LIB.S9S_MB_2U(SCH_1):PAGE42
   D61    GND @S9S_MB_2U_LIB.S9S_MB_2U(SCH_1):GND    I12 @S9S_MB_2U_LIB.S9S_MB_2U(SCH_1):PAGE42
    D6    GND @S9S_MB_2U_LIB.S9S_MB_2U(SCH_1):GND    I12 @S9S_MB_2U_LIB.S9S_MB_2U(SCH_1):PAGE42
   D59    GND @S9S_MB_2U_LIB.S9S_MB_2U(SCH_1):GND    I12 @S9S_MB_2U_LIB.S9S_MB_2U(SCH_1):PAGE42
   D57    GND @S9S_MB_2U_LIB.S9S_MB_2U(SCH_1):GND    I12 @S9S_MB_2U_LIB.S9S_MB_2U(SCH_1):PAGE42
   D55    GND @S9S_MB_2U_LIB.S9S_MB_2U(SCH_1):GND    I12 @S9S_MB_2U_LIB.S9S_MB_2U(SCH_1):PAGE42
   D53    GND @S9S_MB_2U_LIB.S9S_MB_2U(SCH_1):GND    I12 @S9S_MB_2U_LIB.S9S_MB_2U(SCH_1):PAGE42
   D51    GND @S9S_MB_2U_LIB.S9S_MB_2U(SCH_1):GND    I12 @S9S_MB_2U_LIB.S9S_MB_2U(SCH_1):PAGE42
   D49    GND @S9S_MB_2U_LIB.S9S_MB_2U(SCH_1):GND    I12 @S9S_MB_2U_LIB.S9S_MB_2U(SCH_1):PAGE42
   D47    GND @S9S_MB_2U_LIB.S9S_MB_2U(SCH_1):GND    I12 @S9S_MB_2U_LIB.S9S_MB_2U(SCH_1):PAGE42
   D44    GND @S9S_MB_2U_LIB.S9S_MB_2U(SCH_1):GND    I12 @S9S_MB_2U_LIB.S9S_MB_2U(SCH_1):PAGE42
   D42    GND @S9S_MB_2U_LIB.S9S_MB_2U(SCH_1):GND    I12 @S9S_MB_2U_LIB.S9S_MB_2U(SCH_1):PAGE42
   D40    GND @S9S_MB_2U_LIB.S9S_MB_2U(SCH_1):GND    I12 @S9S_MB_2U_LIB.S9S_MB_2U(SCH_1):PAGE42
   D38    GND @S9S_MB_2U_LIB.S9S_MB_2U(SCH_1):GND    I12 @S9S_MB_2U_LIB.S9S_MB_2U(SCH_1):PAGE42
   D36    GND @S9S_MB_2U_LIB.S9S_MB_2U(SCH_1):GND    I12 @S9S_MB_2U_LIB.S9S_MB_2U(SCH_1):PAGE42
   D34    GND @S9S_MB_2U_LIB.S9S_MB_2U(SCH_1):GND    I12 @S9S_MB_2U_LIB.S9S_MB_2U(SCH_1):PAGE42
   D32    GND @S9S_MB_2U_LIB.S9S_MB_2U(SCH_1):GND    I12 @S9S_MB_2U_LIB.S9S_MB_2U(SCH_1):PAGE42
   D30    GND @S9S_MB_2U_LIB.S9S_MB_2U(SCH_1):GND    I12 @S9S_MB_2U_LIB.S9S_MB_2U(SCH_1):PAGE42
   D28    GND @S9S_MB_2U_LIB.S9S_MB_2U(SCH_1):GND    I12 @S9S_MB_2U_LIB.S9S_MB_2U(SCH_1):PAGE42
   D26    GND @S9S_MB_2U_LIB.S9S_MB_2U(SCH_1):GND    I12 @S9S_MB_2U_LIB.S9S_MB_2U(SCH_1):PAGE42
   D24    GND @S9S_MB_2U_LIB.S9S_MB_2U(SCH_1):GND    I12 @S9S_MB_2U_LIB.S9S_MB_2U(SCH_1):PAGE42
   D22    GND @S9S_MB_2U_LIB.S9S_MB_2U(SCH_1):GND    I12 @S9S_MB_2U_LIB.S9S_MB_2U(SCH_1):PAGE42
   D20    GND @S9S_MB_2U_LIB.S9S_MB_2U(SCH_1):GND    I12 @S9S_MB_2U_LIB.S9S_MB_2U(SCH_1):PAGE42
   D18    GND @S9S_MB_2U_LIB.S9S_MB_2U(SCH_1):GND    I12 @S9S_MB_2U_LIB.S9S_MB_2U(SCH_1):PAGE42
   D16    GND @S9S_MB_2U_LIB.S9S_MB_2U(SCH_1):GND    I12 @S9S_MB_2U_LIB.S9S_MB_2U(SCH_1):PAGE42
   D14    GND @S9S_MB_2U_LIB.S9S_MB_2U(SCH_1):GND    I12 @S9S_MB_2U_LIB.S9S_MB_2U(SCH_1):PAGE42
   D12    GND @S9S_MB_2U_LIB.S9S_MB_2U(SCH_1):GND    I12 @S9S_MB_2U_LIB.S9S_MB_2U(SCH_1):PAGE42
   D10    GND @S9S_MB_2U_LIB.S9S_MB_2U(SCH_1):GND    I12 @S9S_MB_2U_LIB.S9S_MB_2U(SCH_1):PAGE42
    D8    GND @S9S_MB_2U_LIB.S9S_MB_2U(SCH_1):GND    I12 @S9S_MB_2U_LIB.S9S_MB_2U(SCH_1):PAGE42
   D79    GND @S9S_MB_2U_LIB.S9S_MB_2U(SCH_1):GND    I12 @S9S_MB_2U_LIB.S9S_MB_2U(SCH_1):PAGE42
   D67    GND @S9S_MB_2U_LIB.S9S_MB_2U(SCH_1):GND    I12 @S9S_MB_2U_LIB.S9S_MB_2U(SCH_1):PAGE42
   D65    GND @S9S_MB_2U_LIB.S9S_MB_2U(SCH_1):GND    I12 @S9S_MB_2U_LIB.S9S_MB_2U(SCH_1):PAGE42
   D63    GND @S9S_MB_2U_LIB.S9S_MB_2U(SCH_1):GND    I12 @S9S_MB_2U_LIB.S9S_MB_2U(SCH_1):PAGE42
   C86    GND @S9S_MB_2U_LIB.S9S_MB_2U(SCH_1):GND    I12 @S9S_MB_2U_LIB.S9S_MB_2U(SCH_1):PAGE42
   C82    GND @S9S_MB_2U_LIB.S9S_MB_2U(SCH_1):GND    I12 @S9S_MB_2U_LIB.S9S_MB_2U(SCH_1):PAGE42
   C80    GND @S9S_MB_2U_LIB.S9S_MB_2U(SCH_1):GND    I12 @S9S_MB_2U_LIB.S9S_MB_2U(SCH_1):PAGE42
   C78    GND @S9S_MB_2U_LIB.S9S_MB_2U(SCH_1):GND    I12 @S9S_MB_2U_LIB.S9S_MB_2U(SCH_1):PAGE42
   C74    GND @S9S_MB_2U_LIB.S9S_MB_2U(SCH_1):GND    I12 @S9S_MB_2U_LIB.S9S_MB_2U(SCH_1):PAGE42
   C72    GND @S9S_MB_2U_LIB.S9S_MB_2U(SCH_1):GND    I12 @S9S_MB_2U_LIB.S9S_MB_2U(SCH_1):PAGE42
   C52    GND @S9S_MB_2U_LIB.S9S_MB_2U(SCH_1):GND    I12 @S9S_MB_2U_LIB.S9S_MB_2U(SCH_1):PAGE42
    C5    GND @S9S_MB_2U_LIB.S9S_MB_2U(SCH_1):GND    I12 @S9S_MB_2U_LIB.S9S_MB_2U(SCH_1):PAGE42
   C45    GND @S9S_MB_2U_LIB.S9S_MB_2U(SCH_1):GND    I12 @S9S_MB_2U_LIB.S9S_MB_2U(SCH_1):PAGE42
   C39    GND @S9S_MB_2U_LIB.S9S_MB_2U(SCH_1):GND    I12 @S9S_MB_2U_LIB.S9S_MB_2U(SCH_1):PAGE42
   B87    GND @S9S_MB_2U_LIB.S9S_MB_2U(SCH_1):GND    I12 @S9S_MB_2U_LIB.S9S_MB_2U(SCH_1):PAGE42
   B83    GND @S9S_MB_2U_LIB.S9S_MB_2U(SCH_1):GND    I12 @S9S_MB_2U_LIB.S9S_MB_2U(SCH_1):PAGE42
   B75    GND @S9S_MB_2U_LIB.S9S_MB_2U(SCH_1):GND    I12 @S9S_MB_2U_LIB.S9S_MB_2U(SCH_1):PAGE42
   B67    GND @S9S_MB_2U_LIB.S9S_MB_2U(SCH_1):GND    I12 @S9S_MB_2U_LIB.S9S_MB_2U(SCH_1):PAGE42
   B61    GND @S9S_MB_2U_LIB.S9S_MB_2U(SCH_1):GND    I12 @S9S_MB_2U_LIB.S9S_MB_2U(SCH_1):PAGE42
    B6    GND @S9S_MB_2U_LIB.S9S_MB_2U(SCH_1):GND    I12 @S9S_MB_2U_LIB.S9S_MB_2U(SCH_1):PAGE42
   B55    GND @S9S_MB_2U_LIB.S9S_MB_2U(SCH_1):GND    I12 @S9S_MB_2U_LIB.S9S_MB_2U(SCH_1):PAGE42
   B49    GND @S9S_MB_2U_LIB.S9S_MB_2U(SCH_1):GND    I12 @S9S_MB_2U_LIB.S9S_MB_2U(SCH_1):PAGE42
   B42    GND @S9S_MB_2U_LIB.S9S_MB_2U(SCH_1):GND    I12 @S9S_MB_2U_LIB.S9S_MB_2U(SCH_1):PAGE42
   B36    GND @S9S_MB_2U_LIB.S9S_MB_2U(SCH_1):GND    I12 @S9S_MB_2U_LIB.S9S_MB_2U(SCH_1):PAGE42
   B30    GND @S9S_MB_2U_LIB.S9S_MB_2U(SCH_1):GND    I12 @S9S_MB_2U_LIB.S9S_MB_2U(SCH_1):PAGE42
   B24    GND @S9S_MB_2U_LIB.S9S_MB_2U(SCH_1):GND    I12 @S9S_MB_2U_LIB.S9S_MB_2U(SCH_1):PAGE42
   B18    GND @S9S_MB_2U_LIB.S9S_MB_2U(SCH_1):GND    I12 @S9S_MB_2U_LIB.S9S_MB_2U(SCH_1):PAGE42
   B12    GND @S9S_MB_2U_LIB.S9S_MB_2U(SCH_1):GND    I12 @S9S_MB_2U_LIB.S9S_MB_2U(SCH_1):PAGE42
   A62    GND @S9S_MB_2U_LIB.S9S_MB_2U(SCH_1):GND    I12 @S9S_MB_2U_LIB.S9S_MB_2U(SCH_1):PAGE42
   A60    GND @S9S_MB_2U_LIB.S9S_MB_2U(SCH_1):GND    I12 @S9S_MB_2U_LIB.S9S_MB_2U(SCH_1):PAGE42
   A56    GND @S9S_MB_2U_LIB.S9S_MB_2U(SCH_1):GND    I12 @S9S_MB_2U_LIB.S9S_MB_2U(SCH_1):PAGE42
   A54    GND @S9S_MB_2U_LIB.S9S_MB_2U(SCH_1):GND    I12 @S9S_MB_2U_LIB.S9S_MB_2U(SCH_1):PAGE42
   A50    GND @S9S_MB_2U_LIB.S9S_MB_2U(SCH_1):GND    I12 @S9S_MB_2U_LIB.S9S_MB_2U(SCH_1):PAGE42
   A41    GND @S9S_MB_2U_LIB.S9S_MB_2U(SCH_1):GND    I12 @S9S_MB_2U_LIB.S9S_MB_2U(SCH_1):PAGE42
   A37    GND @S9S_MB_2U_LIB.S9S_MB_2U(SCH_1):GND    I12 @S9S_MB_2U_LIB.S9S_MB_2U(SCH_1):PAGE42
   A35    GND @S9S_MB_2U_LIB.S9S_MB_2U(SCH_1):GND    I12 @S9S_MB_2U_LIB.S9S_MB_2U(SCH_1):PAGE42
   A31    GND @S9S_MB_2U_LIB.S9S_MB_2U(SCH_1):GND    I12 @S9S_MB_2U_LIB.S9S_MB_2U(SCH_1):PAGE42
   A29    GND @S9S_MB_2U_LIB.S9S_MB_2U(SCH_1):GND    I12 @S9S_MB_2U_LIB.S9S_MB_2U(SCH_1):PAGE42
   A25    GND @S9S_MB_2U_LIB.S9S_MB_2U(SCH_1):GND    I12 @S9S_MB_2U_LIB.S9S_MB_2U(SCH_1):PAGE42
   A23    GND @S9S_MB_2U_LIB.S9S_MB_2U(SCH_1):GND    I12 @S9S_MB_2U_LIB.S9S_MB_2U(SCH_1):PAGE42
   A19    GND @S9S_MB_2U_LIB.S9S_MB_2U(SCH_1):GND    I12 @S9S_MB_2U_LIB.S9S_MB_2U(SCH_1):PAGE42
   A17    GND @S9S_MB_2U_LIB.S9S_MB_2U(SCH_1):GND    I12 @S9S_MB_2U_LIB.S9S_MB_2U(SCH_1):PAGE42
   A13    GND @S9S_MB_2U_LIB.S9S_MB_2U(SCH_1):GND    I12 @S9S_MB_2U_LIB.S9S_MB_2U(SCH_1):PAGE42
   A11    GND @S9S_MB_2U_LIB.S9S_MB_2U(SCH_1):GND    I12 @S9S_MB_2U_LIB.S9S_MB_2U(SCH_1):PAGE42

U2_BL TP_TP_BOM ONLY-NA,TP12_BOM
     1     NC     NC    I41 @S9S_MB_2U_LIB.S9S_MB_2U(SCH_1):PAGE290

U2_BP TP_TP_BOM ONLY-NA,TP12_BOM
     1     NC     NC    I42 @S9S_MB_2U_LIB.S9S_MB_2U(SCH_1):PAGE290

U2_DC TP_TP_BOM ONLY-NA,TP12_BOM
     1     NC     NC    I45 @S9S_MB_2U_LIB.S9S_MB_2U(SCH_1):PAGE290

  U4 EMMITSBURG_REV0P9-GFNOCPU04302A
   J23 TP_PCH_RSVD<19> @S9S_MB_2U_LIB.S9S_MB_2U(SCH_1):TP_PCH_RSVD(19)    I78 @S9S_MB_2U_LIB.S9S_MB_2U(SCH_1):PAGE171
   H24 TP_PCH_RSVD<18> @S9S_MB_2U_LIB.S9S_MB_2U(SCH_1):TP_PCH_RSVD(18)    I78 @S9S_MB_2U_LIB.S9S_MB_2U(SCH_1):PAGE171
   N29 PD_PCH_XCLK_BIASREF @S9S_MB_2U_LIB.S9S_MB_2U(SCH_1):PD_PCH_XCLK_BIASREF    I78 @S9S_MB_2U_LIB.S9S_MB_2U(SCH_1):PAGE171
   A16 TP_CLK_100M_PCH_0_DN @S9S_MB_2U_LIB.S9S_MB_2U(SCH_1):TP_CLK_100M_PCH_0_DN    I78 @S9S_MB_2U_LIB.S9S_MB_2U(SCH_1):PAGE171
   G23 TP_CLK_100M_PCH_1_DN @S9S_MB_2U_LIB.S9S_MB_2U(SCH_1):TP_CLK_100M_PCH_1_DN    I78 @S9S_MB_2U_LIB.S9S_MB_2U(SCH_1):PAGE171
   J16 TP_CLK_100M_PCH_10_DN @S9S_MB_2U_LIB.S9S_MB_2U(SCH_1):TP_CLK_100M_PCH_10_DN    I78 @S9S_MB_2U_LIB.S9S_MB_2U(SCH_1):PAGE171
   G16 TP_CLK_100M_PCH_11_DN @S9S_MB_2U_LIB.S9S_MB_2U(SCH_1):TP_CLK_100M_PCH_11_DN    I78 @S9S_MB_2U_LIB.S9S_MB_2U(SCH_1):PAGE171
   A10 TP_CLK_100M_PCH_12_DN @S9S_MB_2U_LIB.S9S_MB_2U(SCH_1):TP_CLK_100M_PCH_12_DN    I78 @S9S_MB_2U_LIB.S9S_MB_2U(SCH_1):PAGE171
    A8 TP_CLK_100M_PCH_13_DN @S9S_MB_2U_LIB.S9S_MB_2U(SCH_1):TP_CLK_100M_PCH_13_DN    I78 @S9S_MB_2U_LIB.S9S_MB_2U(SCH_1):PAGE171
    B7 TP_CLK_100M_PCH_14_DN @S9S_MB_2U_LIB.S9S_MB_2U(SCH_1):TP_CLK_100M_PCH_14_DN    I78 @S9S_MB_2U_LIB.S9S_MB_2U(SCH_1):PAGE171
    B5 TP_CLK_100M_PCH_15_DN @S9S_MB_2U_LIB.S9S_MB_2U(SCH_1):TP_CLK_100M_PCH_15_DN    I78 @S9S_MB_2U_LIB.S9S_MB_2U(SCH_1):PAGE171
   A18 TP_CLK_100M_PCH_16_DN @S9S_MB_2U_LIB.S9S_MB_2U(SCH_1):TP_CLK_100M_PCH_16_DN    I78 @S9S_MB_2U_LIB.S9S_MB_2U(SCH_1):PAGE171
   H21 CLK_100M_PE_M2_0_R_DN @S9S_MB_2U_LIB.S9S_MB_2U(SCH_1):CLK_100M_PE_M2_0_R_DN    I78 @S9S_MB_2U_LIB.S9S_MB_2U(SCH_1):PAGE171
   B17 CLK_100M_E1S_0_R_DN @S9S_MB_2U_LIB.S9S_MB_2U(SCH_1):CLK_100M_E1S_0_R_DN    I78 @S9S_MB_2U_LIB.S9S_MB_2U(SCH_1):PAGE171
   B19 TP_CLK_100M_PCH_4_DN @S9S_MB_2U_LIB.S9S_MB_2U(SCH_1):TP_CLK_100M_PCH_4_DN    I78 @S9S_MB_2U_LIB.S9S_MB_2U(SCH_1):PAGE171
   A12 TP_CLK_100M_PCH_5_DN @S9S_MB_2U_LIB.S9S_MB_2U(SCH_1):TP_CLK_100M_PCH_5_DN    I78 @S9S_MB_2U_LIB.S9S_MB_2U(SCH_1):PAGE171
   B11 CLK_100M_BMC_P3E_DN @S9S_MB_2U_LIB.S9S_MB_2U(SCH_1):CLK_100M_BMC_P3E_DN    I78 @S9S_MB_2U_LIB.S9S_MB_2U(SCH_1):PAGE171
   A14 TP_CLK_100M_PCH_7_DN @S9S_MB_2U_LIB.S9S_MB_2U(SCH_1):TP_CLK_100M_PCH_7_DN    I78 @S9S_MB_2U_LIB.S9S_MB_2U(SCH_1):PAGE171
   F18 TP_CLK_100M_PCH_8_DN @S9S_MB_2U_LIB.S9S_MB_2U(SCH_1):TP_CLK_100M_PCH_8_DN    I78 @S9S_MB_2U_LIB.S9S_MB_2U(SCH_1):PAGE171
   B15 TP_CLK_100M_PCH_9_DN @S9S_MB_2U_LIB.S9S_MB_2U(SCH_1):TP_CLK_100M_PCH_9_DN    I78 @S9S_MB_2U_LIB.S9S_MB_2U(SCH_1):PAGE171
   C16 TP_CLK_100M_PCH_0_DP @S9S_MB_2U_LIB.S9S_MB_2U(SCH_1):TP_CLK_100M_PCH_0_DP    I78 @S9S_MB_2U_LIB.S9S_MB_2U(SCH_1):PAGE171
   F21 TP_CLK_100M_PCH_1_DP @S9S_MB_2U_LIB.S9S_MB_2U(SCH_1):TP_CLK_100M_PCH_1_DP    I78 @S9S_MB_2U_LIB.S9S_MB_2U(SCH_1):PAGE171
   K18 TP_CLK_100M_PCH_10_DP @S9S_MB_2U_LIB.S9S_MB_2U(SCH_1):TP_CLK_100M_PCH_10_DP    I78 @S9S_MB_2U_LIB.S9S_MB_2U(SCH_1):PAGE171
   H15 TP_CLK_100M_PCH_11_DP @S9S_MB_2U_LIB.S9S_MB_2U(SCH_1):TP_CLK_100M_PCH_11_DP    I78 @S9S_MB_2U_LIB.S9S_MB_2U(SCH_1):PAGE171
   C10 TP_CLK_100M_PCH_12_DP @S9S_MB_2U_LIB.S9S_MB_2U(SCH_1):TP_CLK_100M_PCH_12_DP    I78 @S9S_MB_2U_LIB.S9S_MB_2U(SCH_1):PAGE171
    C8 TP_CLK_100M_PCH_13_DP @S9S_MB_2U_LIB.S9S_MB_2U(SCH_1):TP_CLK_100M_PCH_13_DP    I78 @S9S_MB_2U_LIB.S9S_MB_2U(SCH_1):PAGE171
    D7 TP_CLK_100M_PCH_14_DP @S9S_MB_2U_LIB.S9S_MB_2U(SCH_1):TP_CLK_100M_PCH_14_DP    I78 @S9S_MB_2U_LIB.S9S_MB_2U(SCH_1):PAGE171
    C6 TP_CLK_100M_PCH_15_DP @S9S_MB_2U_LIB.S9S_MB_2U(SCH_1):TP_CLK_100M_PCH_15_DP    I78 @S9S_MB_2U_LIB.S9S_MB_2U(SCH_1):PAGE171
   C18 TP_CLK_100M_PCH_16_DP @S9S_MB_2U_LIB.S9S_MB_2U(SCH_1):TP_CLK_100M_PCH_16_DP    I78 @S9S_MB_2U_LIB.S9S_MB_2U(SCH_1):PAGE171
   K21 CLK_100M_PE_M2_0_R_DP @S9S_MB_2U_LIB.S9S_MB_2U(SCH_1):CLK_100M_PE_M2_0_R_DP    I78 @S9S_MB_2U_LIB.S9S_MB_2U(SCH_1):PAGE171
   D17 CLK_100M_E1S_0_R_DP @S9S_MB_2U_LIB.S9S_MB_2U(SCH_1):CLK_100M_E1S_0_R_DP    I78 @S9S_MB_2U_LIB.S9S_MB_2U(SCH_1):PAGE171
   D19 TP_CLK_100M_PCH_4_DP @S9S_MB_2U_LIB.S9S_MB_2U(SCH_1):TP_CLK_100M_PCH_4_DP    I78 @S9S_MB_2U_LIB.S9S_MB_2U(SCH_1):PAGE171
   C12 TP_CLK_100M_PCH_5_DP @S9S_MB_2U_LIB.S9S_MB_2U(SCH_1):TP_CLK_100M_PCH_5_DP    I78 @S9S_MB_2U_LIB.S9S_MB_2U(SCH_1):PAGE171
   D11 CLK_100M_BMC_P3E_DP @S9S_MB_2U_LIB.S9S_MB_2U(SCH_1):CLK_100M_BMC_P3E_DP    I78 @S9S_MB_2U_LIB.S9S_MB_2U(SCH_1):PAGE171
   C14 TP_CLK_100M_PCH_7_DP @S9S_MB_2U_LIB.S9S_MB_2U(SCH_1):TP_CLK_100M_PCH_7_DP    I78 @S9S_MB_2U_LIB.S9S_MB_2U(SCH_1):PAGE171
   H18 TP_CLK_100M_PCH_8_DP @S9S_MB_2U_LIB.S9S_MB_2U(SCH_1):TP_CLK_100M_PCH_8_DP    I78 @S9S_MB_2U_LIB.S9S_MB_2U(SCH_1):PAGE171
   D15 TP_CLK_100M_PCH_9_DP @S9S_MB_2U_LIB.S9S_MB_2U(SCH_1):TP_CLK_100M_PCH_9_DP    I78 @S9S_MB_2U_LIB.S9S_MB_2U(SCH_1):PAGE171
   D27 CLK_25M_PCH_CPU0_DN @S9S_MB_2U_LIB.S9S_MB_2U(SCH_1):CLK_25M_PCH_CPU0_DN    I78 @S9S_MB_2U_LIB.S9S_MB_2U(SCH_1):PAGE171
   C28 CLK_25M_PCH_CPU1_DN @S9S_MB_2U_LIB.S9S_MB_2U(SCH_1):CLK_25M_PCH_CPU1_DN    I78 @S9S_MB_2U_LIB.S9S_MB_2U(SCH_1):PAGE171
   B27 CLK_25M_PCH_CPU0_DP @S9S_MB_2U_LIB.S9S_MB_2U(SCH_1):CLK_25M_PCH_CPU0_DP    I78 @S9S_MB_2U_LIB.S9S_MB_2U(SCH_1):PAGE171
   A28 CLK_25M_PCH_CPU1_DP @S9S_MB_2U_LIB.S9S_MB_2U(SCH_1):CLK_25M_PCH_CPU1_DP    I78 @S9S_MB_2U_LIB.S9S_MB_2U(SCH_1):PAGE171
   D25 CLK_25M_PCH_REF_NS_DN @S9S_MB_2U_LIB.S9S_MB_2U(SCH_1):CLK_25M_PCH_REF_NS_DN    I78 @S9S_MB_2U_LIB.S9S_MB_2U(SCH_1):PAGE171
   B25 CLK_25M_PCH_REF_NS_DP @S9S_MB_2U_LIB.S9S_MB_2U(SCH_1):CLK_25M_PCH_REF_NS_DP    I78 @S9S_MB_2U_LIB.S9S_MB_2U(SCH_1):PAGE171
   D21 CLK_100M_CK440_PCH_EXTCLK_DN @S9S_MB_2U_LIB.S9S_MB_2U(SCH_1):CLK_100M_CK440_PCH_EXTCLK_DN    I78 @S9S_MB_2U_LIB.S9S_MB_2U(SCH_1):PAGE171
   B21 CLK_100M_CK440_PCH_EXTCLK_DP @S9S_MB_2U_LIB.S9S_MB_2U(SCH_1):CLK_100M_CK440_PCH_EXTCLK_DP    I78 @S9S_MB_2U_LIB.S9S_MB_2U(SCH_1):PAGE171
   BE6 XTAL_PCH_RTC1 @S9S_MB_2U_LIB.S9S_MB_2U(SCH_1):XTAL_PCH_RTC1    I78 @S9S_MB_2U_LIB.S9S_MB_2U(SCH_1):PAGE171
   BF7 XTAL_PCH_RTC2 @S9S_MB_2U_LIB.S9S_MB_2U(SCH_1):XTAL_PCH_RTC2    I78 @S9S_MB_2U_LIB.S9S_MB_2U(SCH_1):PAGE171
   BF5 RTC_EXT_CAP @S9S_MB_2U_LIB.S9S_MB_2U(SCH_1):RTC_EXT_CAP    I78 @S9S_MB_2U_LIB.S9S_MB_2U(SCH_1):PAGE171
   B23 XTAL_PCH_25M_IN @S9S_MB_2U_LIB.S9S_MB_2U(SCH_1):XTAL_PCH_25M_IN    I78 @S9S_MB_2U_LIB.S9S_MB_2U(SCH_1):PAGE171
   D23 XTAL_PCH_25M_OUT @S9S_MB_2U_LIB.S9S_MB_2U(SCH_1):XTAL_PCH_25M_OUT    I78 @S9S_MB_2U_LIB.S9S_MB_2U(SCH_1):PAGE171
  BC40 NC_PCH_RSVD<14> @S9S_MB_2U_LIB.S9S_MB_2U(SCH_1):NC_PCH_RSVD(14)    I11 @S9S_MB_2U_LIB.S9S_MB_2U(SCH_1):PAGE172
  AR42 USB2_0_DN @S9S_MB_2U_LIB.S9S_MB_2U(SCH_1):USB2_0_DN    I11 @S9S_MB_2U_LIB.S9S_MB_2U(SCH_1):PAGE172
  AP43 TP_USB2_1_DN @S9S_MB_2U_LIB.S9S_MB_2U(SCH_1):TP_USB2_1_DN    I11 @S9S_MB_2U_LIB.S9S_MB_2U(SCH_1):PAGE172
  AY43 TP_USB2_10_DN @S9S_MB_2U_LIB.S9S_MB_2U(SCH_1):TP_USB2_10_DN    I11 @S9S_MB_2U_LIB.S9S_MB_2U(SCH_1):PAGE172
  AH42 TP_USB2_11_DN @S9S_MB_2U_LIB.S9S_MB_2U(SCH_1):TP_USB2_11_DN    I11 @S9S_MB_2U_LIB.S9S_MB_2U(SCH_1):PAGE172
  BA42 TP_USB2_12_DN @S9S_MB_2U_LIB.S9S_MB_2U(SCH_1):TP_USB2_12_DN    I11 @S9S_MB_2U_LIB.S9S_MB_2U(SCH_1):PAGE172
  AG43 TP_USB2_13_DN @S9S_MB_2U_LIB.S9S_MB_2U(SCH_1):TP_USB2_13_DN    I11 @S9S_MB_2U_LIB.S9S_MB_2U(SCH_1):PAGE172
  AT43 TP_USB2_2_DN @S9S_MB_2U_LIB.S9S_MB_2U(SCH_1):TP_USB2_2_DN    I11 @S9S_MB_2U_LIB.S9S_MB_2U(SCH_1):PAGE172
  AN42 USB2_3_DN @S9S_MB_2U_LIB.S9S_MB_2U(SCH_1):USB2_3_DN    I11 @S9S_MB_2U_LIB.S9S_MB_2U(SCH_1):PAGE172
  AU42 TP_USB2_4_DN @S9S_MB_2U_LIB.S9S_MB_2U(SCH_1):TP_USB2_4_DN    I11 @S9S_MB_2U_LIB.S9S_MB_2U(SCH_1):PAGE172
  AL43 USB2_5_DN @S9S_MB_2U_LIB.S9S_MB_2U(SCH_1):USB2_5_DN    I11 @S9S_MB_2U_LIB.S9S_MB_2U(SCH_1):PAGE172
  AV43 TP_USB2_6_DN @S9S_MB_2U_LIB.S9S_MB_2U(SCH_1):TP_USB2_6_DN    I11 @S9S_MB_2U_LIB.S9S_MB_2U(SCH_1):PAGE172
  AK42 USB2_7_DN @S9S_MB_2U_LIB.S9S_MB_2U(SCH_1):USB2_7_DN    I11 @S9S_MB_2U_LIB.S9S_MB_2U(SCH_1):PAGE172
  AW42 USB2_8_DN @S9S_MB_2U_LIB.S9S_MB_2U(SCH_1):USB2_8_DN    I11 @S9S_MB_2U_LIB.S9S_MB_2U(SCH_1):PAGE172
  AJ43 TP_USB2_9_DN @S9S_MB_2U_LIB.S9S_MB_2U(SCH_1):TP_USB2_9_DN    I11 @S9S_MB_2U_LIB.S9S_MB_2U(SCH_1):PAGE172
  AR40 USB2_0_DP @S9S_MB_2U_LIB.S9S_MB_2U(SCH_1):USB2_0_DP    I11 @S9S_MB_2U_LIB.S9S_MB_2U(SCH_1):PAGE172
  AP41 TP_USB2_1_DP @S9S_MB_2U_LIB.S9S_MB_2U(SCH_1):TP_USB2_1_DP    I11 @S9S_MB_2U_LIB.S9S_MB_2U(SCH_1):PAGE172
  AY41 TP_USB2_10_DP @S9S_MB_2U_LIB.S9S_MB_2U(SCH_1):TP_USB2_10_DP    I11 @S9S_MB_2U_LIB.S9S_MB_2U(SCH_1):PAGE172
  AH40 TP_USB2_11_DP @S9S_MB_2U_LIB.S9S_MB_2U(SCH_1):TP_USB2_11_DP    I11 @S9S_MB_2U_LIB.S9S_MB_2U(SCH_1):PAGE172
  BA40 TP_USB2_12_DP @S9S_MB_2U_LIB.S9S_MB_2U(SCH_1):TP_USB2_12_DP    I11 @S9S_MB_2U_LIB.S9S_MB_2U(SCH_1):PAGE172
  AG41 TP_USB2_13_DP @S9S_MB_2U_LIB.S9S_MB_2U(SCH_1):TP_USB2_13_DP    I11 @S9S_MB_2U_LIB.S9S_MB_2U(SCH_1):PAGE172
  AT41 TP_USB2_2_DP @S9S_MB_2U_LIB.S9S_MB_2U(SCH_1):TP_USB2_2_DP    I11 @S9S_MB_2U_LIB.S9S_MB_2U(SCH_1):PAGE172
  AN40 USB2_3_DP @S9S_MB_2U_LIB.S9S_MB_2U(SCH_1):USB2_3_DP    I11 @S9S_MB_2U_LIB.S9S_MB_2U(SCH_1):PAGE172
  AU40 TP_USB2_4_DP @S9S_MB_2U_LIB.S9S_MB_2U(SCH_1):TP_USB2_4_DP    I11 @S9S_MB_2U_LIB.S9S_MB_2U(SCH_1):PAGE172
  AL41 USB2_5_DP @S9S_MB_2U_LIB.S9S_MB_2U(SCH_1):USB2_5_DP    I11 @S9S_MB_2U_LIB.S9S_MB_2U(SCH_1):PAGE172
  AV41 TP_USB2_6_DP @S9S_MB_2U_LIB.S9S_MB_2U(SCH_1):TP_USB2_6_DP    I11 @S9S_MB_2U_LIB.S9S_MB_2U(SCH_1):PAGE172
  AK40 USB2_7_DP @S9S_MB_2U_LIB.S9S_MB_2U(SCH_1):USB2_7_DP    I11 @S9S_MB_2U_LIB.S9S_MB_2U(SCH_1):PAGE172
  AW40 USB2_8_DP @S9S_MB_2U_LIB.S9S_MB_2U(SCH_1):USB2_8_DP    I11 @S9S_MB_2U_LIB.S9S_MB_2U(SCH_1):PAGE172
  AJ41 TP_USB2_9_DP @S9S_MB_2U_LIB.S9S_MB_2U(SCH_1):TP_USB2_9_DP    I11 @S9S_MB_2U_LIB.S9S_MB_2U(SCH_1):PAGE172
  BB41 PD_PCH_USB2_COMP @S9S_MB_2U_LIB.S9S_MB_2U(SCH_1):PD_PCH_USB2_COMP    I11 @S9S_MB_2U_LIB.S9S_MB_2U(SCH_1):PAGE172
   A30 DMI_CPU0_PCH_TX_C_DN<0> @S9S_MB_2U_LIB.S9S_MB_2U(SCH_1):DMI_CPU0_PCH_TX_C_DN(0)   I110 @S9S_MB_2U_LIB.S9S_MB_2U(SCH_1):PAGE173
   C30 DMI_CPU0_PCH_TX_C_DP<0> @S9S_MB_2U_LIB.S9S_MB_2U(SCH_1):DMI_CPU0_PCH_TX_C_DP(0)   I110 @S9S_MB_2U_LIB.S9S_MB_2U(SCH_1):PAGE173
   K28 DMI_CPU0_PCH_RX_DN<0> @S9S_MB_2U_LIB.S9S_MB_2U(SCH_1):DMI_CPU0_PCH_RX_DN(0)   I110 @S9S_MB_2U_LIB.S9S_MB_2U(SCH_1):PAGE173
   H28 DMI_CPU0_PCH_RX_DP<0> @S9S_MB_2U_LIB.S9S_MB_2U(SCH_1):DMI_CPU0_PCH_RX_DP(0)   I110 @S9S_MB_2U_LIB.S9S_MB_2U(SCH_1):PAGE173
   B31 DMI_CPU0_PCH_TX_C_DN<1> @S9S_MB_2U_LIB.S9S_MB_2U(SCH_1):DMI_CPU0_PCH_TX_C_DN(1)   I110 @S9S_MB_2U_LIB.S9S_MB_2U(SCH_1):PAGE173
   D31 DMI_CPU0_PCH_TX_C_DP<1> @S9S_MB_2U_LIB.S9S_MB_2U(SCH_1):DMI_CPU0_PCH_TX_C_DP(1)   I110 @S9S_MB_2U_LIB.S9S_MB_2U(SCH_1):PAGE173
   G29 DMI_CPU0_PCH_RX_DN<1> @S9S_MB_2U_LIB.S9S_MB_2U(SCH_1):DMI_CPU0_PCH_RX_DN(1)   I110 @S9S_MB_2U_LIB.S9S_MB_2U(SCH_1):PAGE173
   F28 DMI_CPU0_PCH_RX_DP<1> @S9S_MB_2U_LIB.S9S_MB_2U(SCH_1):DMI_CPU0_PCH_RX_DP(1)   I110 @S9S_MB_2U_LIB.S9S_MB_2U(SCH_1):PAGE173
   A32 DMI_CPU0_PCH_TX_C_DN<2> @S9S_MB_2U_LIB.S9S_MB_2U(SCH_1):DMI_CPU0_PCH_TX_C_DN(2)   I110 @S9S_MB_2U_LIB.S9S_MB_2U(SCH_1):PAGE173
   C32 DMI_CPU0_PCH_TX_C_DP<2> @S9S_MB_2U_LIB.S9S_MB_2U(SCH_1):DMI_CPU0_PCH_TX_C_DP(2)   I110 @S9S_MB_2U_LIB.S9S_MB_2U(SCH_1):PAGE173
   J29 DMI_CPU0_PCH_RX_DN<2> @S9S_MB_2U_LIB.S9S_MB_2U(SCH_1):DMI_CPU0_PCH_RX_DN(2)   I110 @S9S_MB_2U_LIB.S9S_MB_2U(SCH_1):PAGE173
   H31 DMI_CPU0_PCH_RX_DP<2> @S9S_MB_2U_LIB.S9S_MB_2U(SCH_1):DMI_CPU0_PCH_RX_DP(2)   I110 @S9S_MB_2U_LIB.S9S_MB_2U(SCH_1):PAGE173
   B33 DMI_CPU0_PCH_TX_C_DN<3> @S9S_MB_2U_LIB.S9S_MB_2U(SCH_1):DMI_CPU0_PCH_TX_C_DN(3)   I110 @S9S_MB_2U_LIB.S9S_MB_2U(SCH_1):PAGE173
   D33 DMI_CPU0_PCH_TX_C_DP<3> @S9S_MB_2U_LIB.S9S_MB_2U(SCH_1):DMI_CPU0_PCH_TX_C_DP(3)   I110 @S9S_MB_2U_LIB.S9S_MB_2U(SCH_1):PAGE173
   L32 DMI_CPU0_PCH_RX_DN<3> @S9S_MB_2U_LIB.S9S_MB_2U(SCH_1):DMI_CPU0_PCH_RX_DN(3)   I110 @S9S_MB_2U_LIB.S9S_MB_2U(SCH_1):PAGE173
   K31 DMI_CPU0_PCH_RX_DP<3> @S9S_MB_2U_LIB.S9S_MB_2U(SCH_1):DMI_CPU0_PCH_RX_DP(3)   I110 @S9S_MB_2U_LIB.S9S_MB_2U(SCH_1):PAGE173
   A34 DMI_CPU0_PCH_TX_C_DN<4> @S9S_MB_2U_LIB.S9S_MB_2U(SCH_1):DMI_CPU0_PCH_TX_C_DN(4)   I110 @S9S_MB_2U_LIB.S9S_MB_2U(SCH_1):PAGE173
   C34 DMI_CPU0_PCH_TX_C_DP<4> @S9S_MB_2U_LIB.S9S_MB_2U(SCH_1):DMI_CPU0_PCH_TX_C_DP(4)   I110 @S9S_MB_2U_LIB.S9S_MB_2U(SCH_1):PAGE173
   J32 DMI_CPU0_PCH_RX_DN<4> @S9S_MB_2U_LIB.S9S_MB_2U(SCH_1):DMI_CPU0_PCH_RX_DN(4)   I110 @S9S_MB_2U_LIB.S9S_MB_2U(SCH_1):PAGE173
   G32 DMI_CPU0_PCH_RX_DP<4> @S9S_MB_2U_LIB.S9S_MB_2U(SCH_1):DMI_CPU0_PCH_RX_DP(4)   I110 @S9S_MB_2U_LIB.S9S_MB_2U(SCH_1):PAGE173
   B35 DMI_CPU0_PCH_TX_C_DN<5> @S9S_MB_2U_LIB.S9S_MB_2U(SCH_1):DMI_CPU0_PCH_TX_C_DN(5)   I110 @S9S_MB_2U_LIB.S9S_MB_2U(SCH_1):PAGE173
   D35 DMI_CPU0_PCH_TX_C_DP<5> @S9S_MB_2U_LIB.S9S_MB_2U(SCH_1):DMI_CPU0_PCH_TX_C_DP(5)   I110 @S9S_MB_2U_LIB.S9S_MB_2U(SCH_1):PAGE173
   G36 DMI_CPU0_PCH_RX_DN<5> @S9S_MB_2U_LIB.S9S_MB_2U(SCH_1):DMI_CPU0_PCH_RX_DN(5)   I110 @S9S_MB_2U_LIB.S9S_MB_2U(SCH_1):PAGE173
   H34 DMI_CPU0_PCH_RX_DP<5> @S9S_MB_2U_LIB.S9S_MB_2U(SCH_1):DMI_CPU0_PCH_RX_DP(5)   I110 @S9S_MB_2U_LIB.S9S_MB_2U(SCH_1):PAGE173
   A36 DMI_CPU0_PCH_TX_C_DN<6> @S9S_MB_2U_LIB.S9S_MB_2U(SCH_1):DMI_CPU0_PCH_TX_C_DN(6)   I110 @S9S_MB_2U_LIB.S9S_MB_2U(SCH_1):PAGE173
   C36 DMI_CPU0_PCH_TX_C_DP<6> @S9S_MB_2U_LIB.S9S_MB_2U(SCH_1):DMI_CPU0_PCH_TX_C_DP(6)   I110 @S9S_MB_2U_LIB.S9S_MB_2U(SCH_1):PAGE173
   K37 DMI_CPU0_PCH_RX_DN<6> @S9S_MB_2U_LIB.S9S_MB_2U(SCH_1):DMI_CPU0_PCH_RX_DN(6)   I110 @S9S_MB_2U_LIB.S9S_MB_2U(SCH_1):PAGE173
   J36 DMI_CPU0_PCH_RX_DP<6> @S9S_MB_2U_LIB.S9S_MB_2U(SCH_1):DMI_CPU0_PCH_RX_DP(6)   I110 @S9S_MB_2U_LIB.S9S_MB_2U(SCH_1):PAGE173
   B37 DMI_CPU0_PCH_TX_C_DN<7> @S9S_MB_2U_LIB.S9S_MB_2U(SCH_1):DMI_CPU0_PCH_TX_C_DN(7)   I110 @S9S_MB_2U_LIB.S9S_MB_2U(SCH_1):PAGE173
   D37 DMI_CPU0_PCH_TX_C_DP<7> @S9S_MB_2U_LIB.S9S_MB_2U(SCH_1):DMI_CPU0_PCH_TX_C_DP(7)   I110 @S9S_MB_2U_LIB.S9S_MB_2U(SCH_1):PAGE173
   F37 DMI_CPU0_PCH_RX_DN<7> @S9S_MB_2U_LIB.S9S_MB_2U(SCH_1):DMI_CPU0_PCH_RX_DN(7)   I110 @S9S_MB_2U_LIB.S9S_MB_2U(SCH_1):PAGE173
   H37 DMI_CPU0_PCH_RX_DP<7> @S9S_MB_2U_LIB.S9S_MB_2U(SCH_1):DMI_CPU0_PCH_RX_DP(7)   I110 @S9S_MB_2U_LIB.S9S_MB_2U(SCH_1):PAGE173
  AP31 PCH_PCIEUP_RCOMPN @S9S_MB_2U_LIB.S9S_MB_2U(SCH_1):PCH_PCIEUP_RCOMPN   I110 @S9S_MB_2U_LIB.S9S_MB_2U(SCH_1):PAGE173
  AR29 PCH_PCIEUP_RCOMPP @S9S_MB_2U_LIB.S9S_MB_2U(SCH_1):PCH_PCIEUP_RCOMPP   I110 @S9S_MB_2U_LIB.S9S_MB_2U(SCH_1):PAGE173
   N42 NC_PCH_RSVD<11> @S9S_MB_2U_LIB.S9S_MB_2U(SCH_1):NC_PCH_RSVD(11)   I110 @S9S_MB_2U_LIB.S9S_MB_2U(SCH_1):PAGE173
   N40 NC_PCH_RSVD<10> @S9S_MB_2U_LIB.S9S_MB_2U(SCH_1):NC_PCH_RSVD(10)   I110 @S9S_MB_2U_LIB.S9S_MB_2U(SCH_1):PAGE173
   D39 NC_PCH_RSVD<9> @S9S_MB_2U_LIB.S9S_MB_2U(SCH_1):NC_PCH_RSVD(9)   I110 @S9S_MB_2U_LIB.S9S_MB_2U(SCH_1):PAGE173
   C40 NC_PCH_RSVD<8> @S9S_MB_2U_LIB.S9S_MB_2U(SCH_1):NC_PCH_RSVD(8)   I110 @S9S_MB_2U_LIB.S9S_MB_2U(SCH_1):PAGE173
  AE41 P3E_PCH_M2_RX_DN<0> @S9S_MB_2U_LIB.S9S_MB_2U(SCH_1):P3E_PCH_M2_RX_DN(0)   I110 @S9S_MB_2U_LIB.S9S_MB_2U(SCH_1):PAGE173
  AE43 P3E_PCH_M2_RX_DP<0> @S9S_MB_2U_LIB.S9S_MB_2U(SCH_1):P3E_PCH_M2_RX_DP(0)   I110 @S9S_MB_2U_LIB.S9S_MB_2U(SCH_1):PAGE173
  AL32 P3E_PCH_M2_TX_DN<0> @S9S_MB_2U_LIB.S9S_MB_2U(SCH_1):P3E_PCH_M2_TX_DN(0)   I110 @S9S_MB_2U_LIB.S9S_MB_2U(SCH_1):PAGE173
  AK31 P3E_PCH_M2_TX_DP<0> @S9S_MB_2U_LIB.S9S_MB_2U(SCH_1):P3E_PCH_M2_TX_DP(0)   I110 @S9S_MB_2U_LIB.S9S_MB_2U(SCH_1):PAGE173
   M41 P3E_PCH_NVS_RX_DN<0> @S9S_MB_2U_LIB.S9S_MB_2U(SCH_1):P3E_PCH_NVS_RX_DN(0)   I110 @S9S_MB_2U_LIB.S9S_MB_2U(SCH_1):PAGE173
   M43 P3E_PCH_NVS_RX_DP<0> @S9S_MB_2U_LIB.S9S_MB_2U(SCH_1):P3E_PCH_NVS_RX_DP(0)   I110 @S9S_MB_2U_LIB.S9S_MB_2U(SCH_1):PAGE173
   W36 P3E_PCH_NVS_TX_DN<0> @S9S_MB_2U_LIB.S9S_MB_2U(SCH_1):P3E_PCH_NVS_TX_DN(0)   I110 @S9S_MB_2U_LIB.S9S_MB_2U(SCH_1):PAGE173
   Y37 P3E_PCH_NVS_TX_DP<0> @S9S_MB_2U_LIB.S9S_MB_2U(SCH_1):P3E_PCH_NVS_TX_DP(0)   I110 @S9S_MB_2U_LIB.S9S_MB_2U(SCH_1):PAGE173
   L40 P3E_PCH_NVS_RX_DN<1> @S9S_MB_2U_LIB.S9S_MB_2U(SCH_1):P3E_PCH_NVS_RX_DN(1)   I110 @S9S_MB_2U_LIB.S9S_MB_2U(SCH_1):PAGE173
   L42 P3E_PCH_NVS_RX_DP<1> @S9S_MB_2U_LIB.S9S_MB_2U(SCH_1):P3E_PCH_NVS_RX_DP(1)   I110 @S9S_MB_2U_LIB.S9S_MB_2U(SCH_1):PAGE173
   T37 P3E_PCH_NVS_TX_DN<1> @S9S_MB_2U_LIB.S9S_MB_2U(SCH_1):P3E_PCH_NVS_TX_DN(1)   I110 @S9S_MB_2U_LIB.S9S_MB_2U(SCH_1):PAGE173
   V37 P3E_PCH_NVS_TX_DP<1> @S9S_MB_2U_LIB.S9S_MB_2U(SCH_1):P3E_PCH_NVS_TX_DP(1)   I110 @S9S_MB_2U_LIB.S9S_MB_2U(SCH_1):PAGE173
   K41 TP_P3E_PCH_12_RX_DN @S9S_MB_2U_LIB.S9S_MB_2U(SCH_1):TP_P3E_PCH_12_RX_DN   I110 @S9S_MB_2U_LIB.S9S_MB_2U(SCH_1):PAGE173
   K43 TP_P3E_PCH_12_RX_DP @S9S_MB_2U_LIB.S9S_MB_2U(SCH_1):TP_P3E_PCH_12_RX_DP   I110 @S9S_MB_2U_LIB.S9S_MB_2U(SCH_1):PAGE173
   V34 TP_P3E_PCH_12_TX_DN @S9S_MB_2U_LIB.S9S_MB_2U(SCH_1):TP_P3E_PCH_12_TX_DN   I110 @S9S_MB_2U_LIB.S9S_MB_2U(SCH_1):PAGE173
   U36 TP_P3E_PCH_12_TX_DP @S9S_MB_2U_LIB.S9S_MB_2U(SCH_1):TP_P3E_PCH_12_TX_DP   I110 @S9S_MB_2U_LIB.S9S_MB_2U(SCH_1):PAGE173
   J40 TP_P3E_PCH_13_RX_DN @S9S_MB_2U_LIB.S9S_MB_2U(SCH_1):TP_P3E_PCH_13_RX_DN   I110 @S9S_MB_2U_LIB.S9S_MB_2U(SCH_1):PAGE173
   J42 TP_P3E_PCH_13_RX_DP @S9S_MB_2U_LIB.S9S_MB_2U(SCH_1):TP_P3E_PCH_13_RX_DP   I110 @S9S_MB_2U_LIB.S9S_MB_2U(SCH_1):PAGE173
   U32 TP_P3E_PCH_13_TX_DN @S9S_MB_2U_LIB.S9S_MB_2U(SCH_1):TP_P3E_PCH_13_TX_DN   I110 @S9S_MB_2U_LIB.S9S_MB_2U(SCH_1):PAGE173
   W32 TP_P3E_PCH_13_TX_DP @S9S_MB_2U_LIB.S9S_MB_2U(SCH_1):TP_P3E_PCH_13_TX_DP   I110 @S9S_MB_2U_LIB.S9S_MB_2U(SCH_1):PAGE173
   H41 TP_P3E_PCH_14_RX_DN @S9S_MB_2U_LIB.S9S_MB_2U(SCH_1):TP_P3E_PCH_14_RX_DN   I110 @S9S_MB_2U_LIB.S9S_MB_2U(SCH_1):PAGE173
   H43 TP_P3E_PCH_14_RX_DP @S9S_MB_2U_LIB.S9S_MB_2U(SCH_1):TP_P3E_PCH_14_RX_DP   I110 @S9S_MB_2U_LIB.S9S_MB_2U(SCH_1):PAGE173
   R32 TP_P3E_PCH_14_TX_DN @S9S_MB_2U_LIB.S9S_MB_2U(SCH_1):TP_P3E_PCH_14_TX_DN   I110 @S9S_MB_2U_LIB.S9S_MB_2U(SCH_1):PAGE173
   T34 TP_P3E_PCH_14_TX_DP @S9S_MB_2U_LIB.S9S_MB_2U(SCH_1):TP_P3E_PCH_14_TX_DP   I110 @S9S_MB_2U_LIB.S9S_MB_2U(SCH_1):PAGE173
   G40 TP_P3E_PCH_15_RX_DN @S9S_MB_2U_LIB.S9S_MB_2U(SCH_1):TP_P3E_PCH_15_RX_DN   I110 @S9S_MB_2U_LIB.S9S_MB_2U(SCH_1):PAGE173
   G42 TP_P3E_PCH_15_RX_DP @S9S_MB_2U_LIB.S9S_MB_2U(SCH_1):TP_P3E_PCH_15_RX_DP   I110 @S9S_MB_2U_LIB.S9S_MB_2U(SCH_1):PAGE173
   P34 TP_P3E_PCH_15_TX_DN @S9S_MB_2U_LIB.S9S_MB_2U(SCH_1):TP_P3E_PCH_15_TX_DN   I110 @S9S_MB_2U_LIB.S9S_MB_2U(SCH_1):PAGE173
   N36 TP_P3E_PCH_15_TX_DP @S9S_MB_2U_LIB.S9S_MB_2U(SCH_1):TP_P3E_PCH_15_TX_DP   I110 @S9S_MB_2U_LIB.S9S_MB_2U(SCH_1):PAGE173
  AD40 P3E_PCH_M2_RX_DN<1> @S9S_MB_2U_LIB.S9S_MB_2U(SCH_1):P3E_PCH_M2_RX_DN(1)   I110 @S9S_MB_2U_LIB.S9S_MB_2U(SCH_1):PAGE173
  AD42 P3E_PCH_M2_RX_DP<1> @S9S_MB_2U_LIB.S9S_MB_2U(SCH_1):P3E_PCH_M2_RX_DP(1)   I110 @S9S_MB_2U_LIB.S9S_MB_2U(SCH_1):PAGE173
  AN36 P3E_PCH_M2_TX_DN<1> @S9S_MB_2U_LIB.S9S_MB_2U(SCH_1):P3E_PCH_M2_TX_DN(1)   I110 @S9S_MB_2U_LIB.S9S_MB_2U(SCH_1):PAGE173
  AP34 P3E_PCH_M2_TX_DP<1> @S9S_MB_2U_LIB.S9S_MB_2U(SCH_1):P3E_PCH_M2_TX_DP(1)   I110 @S9S_MB_2U_LIB.S9S_MB_2U(SCH_1):PAGE173
  AC41 P3E_PCH_M2_RX_DN<2> @S9S_MB_2U_LIB.S9S_MB_2U(SCH_1):P3E_PCH_M2_RX_DN(2)   I110 @S9S_MB_2U_LIB.S9S_MB_2U(SCH_1):PAGE173
  AC43 P3E_PCH_M2_RX_DP<2> @S9S_MB_2U_LIB.S9S_MB_2U(SCH_1):P3E_PCH_M2_RX_DP(2)   I110 @S9S_MB_2U_LIB.S9S_MB_2U(SCH_1):PAGE173
  AR36 P3E_PCH_M2_TX_DN<2> @S9S_MB_2U_LIB.S9S_MB_2U(SCH_1):P3E_PCH_M2_TX_DN(2)   I110 @S9S_MB_2U_LIB.S9S_MB_2U(SCH_1):PAGE173
  AT37 P3E_PCH_M2_TX_DP<2> @S9S_MB_2U_LIB.S9S_MB_2U(SCH_1):P3E_PCH_M2_TX_DP(2)   I110 @S9S_MB_2U_LIB.S9S_MB_2U(SCH_1):PAGE173
  AB40 P3E_PCH_M2_RX_DN<3> @S9S_MB_2U_LIB.S9S_MB_2U(SCH_1):P3E_PCH_M2_RX_DN(3)   I110 @S9S_MB_2U_LIB.S9S_MB_2U(SCH_1):PAGE173
  AB42 P3E_PCH_M2_RX_DP<3> @S9S_MB_2U_LIB.S9S_MB_2U(SCH_1):P3E_PCH_M2_RX_DP(3)   I110 @S9S_MB_2U_LIB.S9S_MB_2U(SCH_1):PAGE173
  AK34 P3E_PCH_M2_TX_DN<3> @S9S_MB_2U_LIB.S9S_MB_2U(SCH_1):P3E_PCH_M2_TX_DN(3)   I110 @S9S_MB_2U_LIB.S9S_MB_2U(SCH_1):PAGE173
  AM34 P3E_PCH_M2_TX_DP<3> @S9S_MB_2U_LIB.S9S_MB_2U(SCH_1):P3E_PCH_M2_TX_DP(3)   I110 @S9S_MB_2U_LIB.S9S_MB_2U(SCH_1):PAGE173
  AA41 P3E_PCH_E1S_RX_DN<0> @S9S_MB_2U_LIB.S9S_MB_2U(SCH_1):P3E_PCH_E1S_RX_DN(0)   I110 @S9S_MB_2U_LIB.S9S_MB_2U(SCH_1):PAGE173
  AA43 P3E_PCH_E1S_RX_DP<0> @S9S_MB_2U_LIB.S9S_MB_2U(SCH_1):P3E_PCH_E1S_RX_DP(0)   I110 @S9S_MB_2U_LIB.S9S_MB_2U(SCH_1):PAGE173
  AL36 P3E_PCH_E1S_TX_DN<0> @S9S_MB_2U_LIB.S9S_MB_2U(SCH_1):P3E_PCH_E1S_TX_DN(0)   I110 @S9S_MB_2U_LIB.S9S_MB_2U(SCH_1):PAGE173
  AM37 P3E_PCH_E1S_TX_DP<0> @S9S_MB_2U_LIB.S9S_MB_2U(SCH_1):P3E_PCH_E1S_TX_DP(0)   I110 @S9S_MB_2U_LIB.S9S_MB_2U(SCH_1):PAGE173
   Y40 P3E_PCH_E1S_RX_DN<1> @S9S_MB_2U_LIB.S9S_MB_2U(SCH_1):P3E_PCH_E1S_RX_DN(1)   I110 @S9S_MB_2U_LIB.S9S_MB_2U(SCH_1):PAGE173
   Y42 P3E_PCH_E1S_RX_DP<1> @S9S_MB_2U_LIB.S9S_MB_2U(SCH_1):P3E_PCH_E1S_RX_DP(1)   I110 @S9S_MB_2U_LIB.S9S_MB_2U(SCH_1):PAGE173
  AH34 P3E_PCH_E1S_TX_DN<1> @S9S_MB_2U_LIB.S9S_MB_2U(SCH_1):P3E_PCH_E1S_TX_DN(1)   I110 @S9S_MB_2U_LIB.S9S_MB_2U(SCH_1):PAGE173
  AJ32 P3E_PCH_E1S_TX_DP<1> @S9S_MB_2U_LIB.S9S_MB_2U(SCH_1):P3E_PCH_E1S_TX_DP(1)   I110 @S9S_MB_2U_LIB.S9S_MB_2U(SCH_1):PAGE173
   W41 P3E_PCH_E1S_RX_DN<2> @S9S_MB_2U_LIB.S9S_MB_2U(SCH_1):P3E_PCH_E1S_RX_DN(2)   I110 @S9S_MB_2U_LIB.S9S_MB_2U(SCH_1):PAGE173
   W43 P3E_PCH_E1S_RX_DP<2> @S9S_MB_2U_LIB.S9S_MB_2U(SCH_1):P3E_PCH_E1S_RX_DP(2)   I110 @S9S_MB_2U_LIB.S9S_MB_2U(SCH_1):PAGE173
  AF37 P3E_PCH_E1S_TX_DN<2> @S9S_MB_2U_LIB.S9S_MB_2U(SCH_1):P3E_PCH_E1S_TX_DN(2)   I110 @S9S_MB_2U_LIB.S9S_MB_2U(SCH_1):PAGE173
  AH37 P3E_PCH_E1S_TX_DP<2> @S9S_MB_2U_LIB.S9S_MB_2U(SCH_1):P3E_PCH_E1S_TX_DP(2)   I110 @S9S_MB_2U_LIB.S9S_MB_2U(SCH_1):PAGE173
   V40 P3E_PCH_E1S_RX_DN<3> @S9S_MB_2U_LIB.S9S_MB_2U(SCH_1):P3E_PCH_E1S_RX_DN(3)   I110 @S9S_MB_2U_LIB.S9S_MB_2U(SCH_1):PAGE173
   V42 P3E_PCH_E1S_RX_DP<3> @S9S_MB_2U_LIB.S9S_MB_2U(SCH_1):P3E_PCH_E1S_RX_DP(3)   I110 @S9S_MB_2U_LIB.S9S_MB_2U(SCH_1):PAGE173
  AF34 P3E_PCH_E1S_TX_DN<3> @S9S_MB_2U_LIB.S9S_MB_2U(SCH_1):P3E_PCH_E1S_TX_DN(3)   I110 @S9S_MB_2U_LIB.S9S_MB_2U(SCH_1):PAGE173
  AG36 P3E_PCH_E1S_TX_DP<3> @S9S_MB_2U_LIB.S9S_MB_2U(SCH_1):P3E_PCH_E1S_TX_DP(3)   I110 @S9S_MB_2U_LIB.S9S_MB_2U(SCH_1):PAGE173
   U41 P3E_PCH_BMC_RX_DN @S9S_MB_2U_LIB.S9S_MB_2U(SCH_1):P3E_PCH_BMC_RX_DN   I110 @S9S_MB_2U_LIB.S9S_MB_2U(SCH_1):PAGE173
   U43 P3E_PCH_BMC_RX_DP @S9S_MB_2U_LIB.S9S_MB_2U(SCH_1):P3E_PCH_BMC_RX_DP   I110 @S9S_MB_2U_LIB.S9S_MB_2U(SCH_1):PAGE173
  AE36 P3E_PCH_BMC_TX_DN @S9S_MB_2U_LIB.S9S_MB_2U(SCH_1):P3E_PCH_BMC_TX_DN   I110 @S9S_MB_2U_LIB.S9S_MB_2U(SCH_1):PAGE173
  AD37 P3E_PCH_BMC_TX_DP @S9S_MB_2U_LIB.S9S_MB_2U(SCH_1):P3E_PCH_BMC_TX_DP   I110 @S9S_MB_2U_LIB.S9S_MB_2U(SCH_1):PAGE173
   R40 USB3_PCH_RX_BUF_DN<4> @S9S_MB_2U_LIB.S9S_MB_2U(SCH_1):USB3_PCH_RX_BUF_DN(4)   I110 @S9S_MB_2U_LIB.S9S_MB_2U(SCH_1):PAGE173
   R42 USB3_PCH_RX_BUF_DP<4> @S9S_MB_2U_LIB.S9S_MB_2U(SCH_1):USB3_PCH_RX_BUF_DP(4)   I110 @S9S_MB_2U_LIB.S9S_MB_2U(SCH_1):PAGE173
  AE32 USB3_PCH_TX_DN<4> @S9S_MB_2U_LIB.S9S_MB_2U(SCH_1):USB3_PCH_TX_DN(4)   I110 @S9S_MB_2U_LIB.S9S_MB_2U(SCH_1):PAGE173
  AG32 USB3_PCH_TX_DP<4> @S9S_MB_2U_LIB.S9S_MB_2U(SCH_1):USB3_PCH_TX_DP(4)   I110 @S9S_MB_2U_LIB.S9S_MB_2U(SCH_1):PAGE173
   AN7 PU_ACPRESENT @S9S_MB_2U_LIB.S9S_MB_2U(SCH_1):PU_ACPRESENT    I36 @S9S_MB_2U_LIB.S9S_MB_2U(SCH_1):PAGE174
   G10 PWRGD_CPUPWRGD_GTL @S9S_MB_2U_LIB.S9S_MB_2U(SCH_1):PWRGD_CPUPWRGD_GTL    I36 @S9S_MB_2U_LIB.S9S_MB_2U(SCH_1):PAGE174
    F8 FM_PCIE_EV_BIF_EN @S9S_MB_2U_LIB.S9S_MB_2U(SCH_1):FM_PCIE_EV_BIF_EN    I36 @S9S_MB_2U_LIB.S9S_MB_2U(SCH_1):PAGE174
    J7 H_CPU_ERR0_PCH_R_N @S9S_MB_2U_LIB.S9S_MB_2U(SCH_1):H_CPU_ERR0_PCH_R_N    I36 @S9S_MB_2U_LIB.S9S_MB_2U(SCH_1):PAGE174
    G7 H_CPU_ERR1_PCH_R_N @S9S_MB_2U_LIB.S9S_MB_2U(SCH_1):H_CPU_ERR1_PCH_R_N    I36 @S9S_MB_2U_LIB.S9S_MB_2U(SCH_1):PAGE174
    L7 H_CPU_ERR2_PCH_R_N @S9S_MB_2U_LIB.S9S_MB_2U(SCH_1):H_CPU_ERR2_PCH_R_N    I36 @S9S_MB_2U_LIB.S9S_MB_2U(SCH_1):PAGE174
    E4 TP_PCH_CPU_MEMTRIP_N @S9S_MB_2U_LIB.S9S_MB_2U(SCH_1):TP_PCH_CPU_MEMTRIP_N    I36 @S9S_MB_2U_LIB.S9S_MB_2U(SCH_1):PAGE174
   F11 TP_PCH_CPU_MSMI_N @S9S_MB_2U_LIB.S9S_MB_2U(SCH_1):TP_PCH_CPU_MSMI_N    I36 @S9S_MB_2U_LIB.S9S_MB_2U(SCH_1):PAGE174
    F5 FM_PCH_CPU_PWR_DEBUG_N @S9S_MB_2U_LIB.S9S_MB_2U(SCH_1):FM_PCH_CPU_PWR_DEBUG_N    I36 @S9S_MB_2U_LIB.S9S_MB_2U(SCH_1):PAGE174
    F3 H_THERMTRIP_LVC1_N @S9S_MB_2U_LIB.S9S_MB_2U(SCH_1):H_THERMTRIP_LVC1_N    I36 @S9S_MB_2U_LIB.S9S_MB_2U(SCH_1):PAGE174
  BE40 JTAG_DBP_PMODE @S9S_MB_2U_LIB.S9S_MB_2U(SCH_1):JTAG_DBP_PMODE    I36 @S9S_MB_2U_LIB.S9S_MB_2U(SCH_1):PAGE174
   BE8 PWRGD_DSW_PWROK @S9S_MB_2U_LIB.S9S_MB_2U(SCH_1):PWRGD_DSW_PWROK    I36 @S9S_MB_2U_LIB.S9S_MB_2U(SCH_1):PAGE174
  AN10 FM_PCH_SPARE0 @S9S_MB_2U_LIB.S9S_MB_2U(SCH_1):FM_PCH_SPARE0    I36 @S9S_MB_2U_LIB.S9S_MB_2U(SCH_1):PAGE174
  AU10 FM_PCH_SKIP_RTC_CLOCK @S9S_MB_2U_LIB.S9S_MB_2U(SCH_1):FM_PCH_SKIP_RTC_CLOCK    I36 @S9S_MB_2U_LIB.S9S_MB_2U(SCH_1):PAGE174
   BG8 FM_INTRUDER_HDR_PCH_N @S9S_MB_2U_LIB.S9S_MB_2U(SCH_1):FM_INTRUDER_HDR_PCH_N    I36 @S9S_MB_2U_LIB.S9S_MB_2U(SCH_1):PAGE174
  BD35 JTAG_DBP_CPU_GTL_TCK @S9S_MB_2U_LIB.S9S_MB_2U(SCH_1):JTAG_DBP_CPU_GTL_TCK    I36 @S9S_MB_2U_LIB.S9S_MB_2U(SCH_1):PAGE174
  BF35 JTAG_DBP_TCK_PCH @S9S_MB_2U_LIB.S9S_MB_2U(SCH_1):JTAG_DBP_TCK_PCH    I36 @S9S_MB_2U_LIB.S9S_MB_2U(SCH_1):PAGE174
  BE38 JTAG_DBP_TDI_PCH @S9S_MB_2U_LIB.S9S_MB_2U(SCH_1):JTAG_DBP_TDI_PCH    I36 @S9S_MB_2U_LIB.S9S_MB_2U(SCH_1):PAGE174
  BE36 JTAG_DBP_TDO_PCH @S9S_MB_2U_LIB.S9S_MB_2U(SCH_1):JTAG_DBP_TDO_PCH    I36 @S9S_MB_2U_LIB.S9S_MB_2U(SCH_1):PAGE174
  BD37 JTAG_DBP_TMS_PCH @S9S_MB_2U_LIB.S9S_MB_2U(SCH_1):JTAG_DBP_TMS_PCH    I36 @S9S_MB_2U_LIB.S9S_MB_2U(SCH_1):PAGE174
   AJ7 TP_PCH_GPP_O_11 @S9S_MB_2U_LIB.S9S_MB_2U(SCH_1):TP_PCH_GPP_O_11    I36 @S9S_MB_2U_LIB.S9S_MB_2U(SCH_1):PAGE174
   AU7 PU_LAN_WAKE_N @S9S_MB_2U_LIB.S9S_MB_2U(SCH_1):PU_LAN_WAKE_N    I36 @S9S_MB_2U_LIB.S9S_MB_2U(SCH_1):PAGE174
   J10 PECI_PCH @S9S_MB_2U_LIB.S9S_MB_2U(SCH_1):PECI_PCH    I36 @S9S_MB_2U_LIB.S9S_MB_2U(SCH_1):PAGE174
   BE4 PWRGD_PCH_PWROK @S9S_MB_2U_LIB.S9S_MB_2U(SCH_1):PWRGD_PCH_PWROK    I36 @S9S_MB_2U_LIB.S9S_MB_2U(SCH_1):PAGE174
    M8 TP_PLTRST_N @S9S_MB_2U_LIB.S9S_MB_2U(SCH_1):TP_PLTRST_N    I36 @S9S_MB_2U_LIB.S9S_MB_2U(SCH_1):PAGE174
  BB37 H_DBP_PRDY_N_PCH @S9S_MB_2U_LIB.S9S_MB_2U(SCH_1):H_DBP_PRDY_N_PCH    I36 @S9S_MB_2U_LIB.S9S_MB_2U(SCH_1):PAGE174
  BF37 H_DBP_PREQ_N_PCH @S9S_MB_2U_LIB.S9S_MB_2U(SCH_1):H_DBP_PREQ_N_PCH    I36 @S9S_MB_2U_LIB.S9S_MB_2U(SCH_1):PAGE174
  AR10 FM_BMC_PWRBTN_N @S9S_MB_2U_LIB.S9S_MB_2U(SCH_1):FM_BMC_PWRBTN_N    I36 @S9S_MB_2U_LIB.S9S_MB_2U(SCH_1):PAGE174
   BD9 RST_RSMRST_PCH_N @S9S_MB_2U_LIB.S9S_MB_2U(SCH_1):RST_RSMRST_PCH_N    I36 @S9S_MB_2U_LIB.S9S_MB_2U(SCH_1):PAGE174
  BG36 NC_PCH_RSVD<17> @S9S_MB_2U_LIB.S9S_MB_2U(SCH_1):NC_PCH_RSVD(17)    I36 @S9S_MB_2U_LIB.S9S_MB_2U(SCH_1):PAGE174
  BF39 NC_PCH_RSVD<5> @S9S_MB_2U_LIB.S9S_MB_2U(SCH_1):NC_PCH_RSVD(5)    I36 @S9S_MB_2U_LIB.S9S_MB_2U(SCH_1):PAGE174
  AV21 NC_PCH_RSVD<4> @S9S_MB_2U_LIB.S9S_MB_2U(SCH_1):NC_PCH_RSVD(4)    I36 @S9S_MB_2U_LIB.S9S_MB_2U(SCH_1):PAGE174
  AW26 NC_PCH_RSVD<3> @S9S_MB_2U_LIB.S9S_MB_2U(SCH_1):NC_PCH_RSVD(3)    I36 @S9S_MB_2U_LIB.S9S_MB_2U(SCH_1):PAGE174
  AM11 TP_PCH_SLP_A_N @S9S_MB_2U_LIB.S9S_MB_2U(SCH_1):TP_PCH_SLP_A_N    I36 @S9S_MB_2U_LIB.S9S_MB_2U(SCH_1):PAGE174
   AK8 TP_SLP_LAN_N @S9S_MB_2U_LIB.S9S_MB_2U(SCH_1):TP_SLP_LAN_N    I36 @S9S_MB_2U_LIB.S9S_MB_2U(SCH_1):PAGE174
   AP8 FM_PCH_SLP_S3_N @S9S_MB_2U_LIB.S9S_MB_2U(SCH_1):FM_PCH_SLP_S3_N    I36 @S9S_MB_2U_LIB.S9S_MB_2U(SCH_1):PAGE174
  AL13 FM_PCH_SLP_S4_N @S9S_MB_2U_LIB.S9S_MB_2U(SCH_1):FM_PCH_SLP_S4_N    I36 @S9S_MB_2U_LIB.S9S_MB_2U(SCH_1):PAGE174
  AJ13 TP_PCH_SLP_S5_N @S9S_MB_2U_LIB.S9S_MB_2U(SCH_1):TP_PCH_SLP_S5_N    I36 @S9S_MB_2U_LIB.S9S_MB_2U(SCH_1):PAGE174
   AL7 FM_PCH_SLP_SUS_N @S9S_MB_2U_LIB.S9S_MB_2U(SCH_1):FM_PCH_SLP_SUS_N    I36 @S9S_MB_2U_LIB.S9S_MB_2U(SCH_1):PAGE174
   AR7 PD_SUSCLK @S9S_MB_2U_LIB.S9S_MB_2U(SCH_1):PD_SUSCLK    I36 @S9S_MB_2U_LIB.S9S_MB_2U(SCH_1):PAGE174
  AL10 PWRGD_SYS_PWROK @S9S_MB_2U_LIB.S9S_MB_2U(SCH_1):PWRGD_SYS_PWROK    I36 @S9S_MB_2U_LIB.S9S_MB_2U(SCH_1):PAGE174
  AJ10 RST_PCH_RSTBTN_R_N @S9S_MB_2U_LIB.S9S_MB_2U(SCH_1):RST_PCH_RSTBTN_R_N    I36 @S9S_MB_2U_LIB.S9S_MB_2U(SCH_1):PAGE174
   H11 FM_PCH_TRIGGER0_R_N @S9S_MB_2U_LIB.S9S_MB_2U(SCH_1):FM_PCH_TRIGGER0_R_N    I36 @S9S_MB_2U_LIB.S9S_MB_2U(SCH_1):PAGE174
    K8 FM_PCH_TRIGGER1_R_N @S9S_MB_2U_LIB.S9S_MB_2U(SCH_1):FM_PCH_TRIGGER1_R_N    I36 @S9S_MB_2U_LIB.S9S_MB_2U(SCH_1):PAGE174
  AH11 IRQ_LVC3_WAKE_N @S9S_MB_2U_LIB.S9S_MB_2U(SCH_1):IRQ_LVC3_WAKE_N    I36 @S9S_MB_2U_LIB.S9S_MB_2U(SCH_1):PAGE174
  BD25 JTAG_TRC_PCH_PTI<11> @S9S_MB_2U_LIB.S9S_MB_2U(SCH_1):JTAG_TRC_PCH_PTI(11)    I93 @S9S_MB_2U_LIB.S9S_MB_2U(SCH_1):PAGE175
  BG20 IRQ_LPC_PIRQA_N_ESPI_ALERT0_N @S9S_MB_2U_LIB.S9S_MB_2U(SCH_1):IRQ_LPC_PIRQA_N_ESPI_ALERT0_N    I93 @S9S_MB_2U_LIB.S9S_MB_2U(SCH_1):PAGE175
  BD17 PD_PCH_GPPC_A_10 @S9S_MB_2U_LIB.S9S_MB_2U(SCH_1):PD_PCH_GPPC_A_10    I93 @S9S_MB_2U_LIB.S9S_MB_2U(SCH_1):PAGE175
  BG18 E1S_0_CLKREQ_N @S9S_MB_2U_LIB.S9S_MB_2U(SCH_1):E1S_0_CLKREQ_N    I93 @S9S_MB_2U_LIB.S9S_MB_2U(SCH_1):PAGE175
  BG16 M2_SSD0_CLKREQ_EN_N @S9S_MB_2U_LIB.S9S_MB_2U(SCH_1):M2_SSD0_CLKREQ_EN_N    I93 @S9S_MB_2U_LIB.S9S_MB_2U(SCH_1):PAGE175
  BF15 FM_BMC_READY_R_N @S9S_MB_2U_LIB.S9S_MB_2U(SCH_1):FM_BMC_READY_R_N    I93 @S9S_MB_2U_LIB.S9S_MB_2U(SCH_1):PAGE175
  BE12 PD_PCH_GPPC_A_14 @S9S_MB_2U_LIB.S9S_MB_2U(SCH_1):PD_PCH_GPPC_A_14    I93 @S9S_MB_2U_LIB.S9S_MB_2U(SCH_1):PAGE175
  BE14 PD_PCH_GPPC_A_15 @S9S_MB_2U_LIB.S9S_MB_2U(SCH_1):PD_PCH_GPPC_A_15    I93 @S9S_MB_2U_LIB.S9S_MB_2U(SCH_1):PAGE175
  BD11 FM_PCH_SATA_RAID_KEY @S9S_MB_2U_LIB.S9S_MB_2U(SCH_1):FM_PCH_SATA_RAID_KEY    I93 @S9S_MB_2U_LIB.S9S_MB_2U(SCH_1):PAGE175
  BF13 IRQ_BMC_PCH_NMI @S9S_MB_2U_LIB.S9S_MB_2U(SCH_1):IRQ_BMC_PCH_NMI    I93 @S9S_MB_2U_LIB.S9S_MB_2U(SCH_1):PAGE175
  BF11 PD_PCH_GPPC_A_18 @S9S_MB_2U_LIB.S9S_MB_2U(SCH_1):PD_PCH_GPPC_A_18    I93 @S9S_MB_2U_LIB.S9S_MB_2U(SCH_1):PAGE175
  BG14 PD_PCH_GPPC_A_19 @S9S_MB_2U_LIB.S9S_MB_2U(SCH_1):PD_PCH_GPPC_A_19    I93 @S9S_MB_2U_LIB.S9S_MB_2U(SCH_1):PAGE175
  BD15 ESPI_ALERT1_N_LPC_RCIN_N @S9S_MB_2U_LIB.S9S_MB_2U(SCH_1):ESPI_ALERT1_N_LPC_RCIN_N    I93 @S9S_MB_2U_LIB.S9S_MB_2U(SCH_1):PAGE175
  BG12 ESPI_LAD0_DATA_IO0 @S9S_MB_2U_LIB.S9S_MB_2U(SCH_1):ESPI_LAD0_DATA_IO0    I93 @S9S_MB_2U_LIB.S9S_MB_2U(SCH_1):PAGE175
  BF19 ESPI_LAD0_DATA_IO1 @S9S_MB_2U_LIB.S9S_MB_2U(SCH_1):ESPI_LAD0_DATA_IO1    I93 @S9S_MB_2U_LIB.S9S_MB_2U(SCH_1):PAGE175
  BE18 ESPI_LAD0_DATA_IO2 @S9S_MB_2U_LIB.S9S_MB_2U(SCH_1):ESPI_LAD0_DATA_IO2    I93 @S9S_MB_2U_LIB.S9S_MB_2U(SCH_1):PAGE175
  BD19 ESPI_LAD0_DATA_IO3 @S9S_MB_2U_LIB.S9S_MB_2U(SCH_1):ESPI_LAD0_DATA_IO3    I93 @S9S_MB_2U_LIB.S9S_MB_2U(SCH_1):PAGE175
  BE20 ESPI_LFRAME_N_BMC_CS0_N @S9S_MB_2U_LIB.S9S_MB_2U(SCH_1):ESPI_LFRAME_N_BMC_CS0_N    I93 @S9S_MB_2U_LIB.S9S_MB_2U(SCH_1):PAGE175
  BE16 IRQ_LPC_SERIRQ_ESPI_CS1_N @S9S_MB_2U_LIB.S9S_MB_2U(SCH_1):IRQ_LPC_SERIRQ_ESPI_CS1_N    I93 @S9S_MB_2U_LIB.S9S_MB_2U(SCH_1):PAGE175
  BF17 RST_ESPI_RESET_N @S9S_MB_2U_LIB.S9S_MB_2U(SCH_1):RST_ESPI_RESET_N    I93 @S9S_MB_2U_LIB.S9S_MB_2U(SCH_1):PAGE175
  BD13 CLK_24M_66M_LPC0_ESPI @S9S_MB_2U_LIB.S9S_MB_2U(SCH_1):CLK_24M_66M_LPC0_ESPI    I93 @S9S_MB_2U_LIB.S9S_MB_2U(SCH_1):PAGE175
  BD33 JTAG_TRC_PCH_PTI0_CLK @S9S_MB_2U_LIB.S9S_MB_2U(SCH_1):JTAG_TRC_PCH_PTI0_CLK    I93 @S9S_MB_2U_LIB.S9S_MB_2U(SCH_1):PAGE175
  BG24 PU_OC5_USB_N @S9S_MB_2U_LIB.S9S_MB_2U(SCH_1):PU_OC5_USB_N    I93 @S9S_MB_2U_LIB.S9S_MB_2U(SCH_1):PAGE175
  BG22 PU_OC6_USB_N @S9S_MB_2U_LIB.S9S_MB_2U(SCH_1):PU_OC6_USB_N    I93 @S9S_MB_2U_LIB.S9S_MB_2U(SCH_1):PAGE175
  BD29 JTAG_TRC_PCH_PTI<5> @S9S_MB_2U_LIB.S9S_MB_2U(SCH_1):JTAG_TRC_PCH_PTI(5)    I93 @S9S_MB_2U_LIB.S9S_MB_2U(SCH_1):PAGE175
  BE28 JTAG_TRC_PCH_PTI<6> @S9S_MB_2U_LIB.S9S_MB_2U(SCH_1):JTAG_TRC_PCH_PTI(6)    I93 @S9S_MB_2U_LIB.S9S_MB_2U(SCH_1):PAGE175
  BF29 JTAG_TRC_PCH_PTI<7> @S9S_MB_2U_LIB.S9S_MB_2U(SCH_1):JTAG_TRC_PCH_PTI(7)    I93 @S9S_MB_2U_LIB.S9S_MB_2U(SCH_1):PAGE175
  BD27 JTAG_TRC_PCH_PTI<8> @S9S_MB_2U_LIB.S9S_MB_2U(SCH_1):JTAG_TRC_PCH_PTI(8)    I93 @S9S_MB_2U_LIB.S9S_MB_2U(SCH_1):PAGE175
  BE26 JTAG_TRC_PCH_PTI<9> @S9S_MB_2U_LIB.S9S_MB_2U(SCH_1):JTAG_TRC_PCH_PTI(9)    I93 @S9S_MB_2U_LIB.S9S_MB_2U(SCH_1):PAGE175
  BF27 JTAG_TRC_PCH_PTI<10> @S9S_MB_2U_LIB.S9S_MB_2U(SCH_1):JTAG_TRC_PCH_PTI(10)    I93 @S9S_MB_2U_LIB.S9S_MB_2U(SCH_1):PAGE175
  BF25 JTAG_TRC_PCH_PTI<12> @S9S_MB_2U_LIB.S9S_MB_2U(SCH_1):JTAG_TRC_PCH_PTI(12)    I93 @S9S_MB_2U_LIB.S9S_MB_2U(SCH_1):PAGE175
  BE32 JTAG_TRC_PCH_PTI<0> @S9S_MB_2U_LIB.S9S_MB_2U(SCH_1):JTAG_TRC_PCH_PTI(0)    I93 @S9S_MB_2U_LIB.S9S_MB_2U(SCH_1):PAGE175
  BE24 JTAG_TRC_PCH_PTI<13> @S9S_MB_2U_LIB.S9S_MB_2U(SCH_1):JTAG_TRC_PCH_PTI(13)    I93 @S9S_MB_2U_LIB.S9S_MB_2U(SCH_1):PAGE175
  BF23 JTAG_TRC_PCH_PTI<14> @S9S_MB_2U_LIB.S9S_MB_2U(SCH_1):JTAG_TRC_PCH_PTI(14)    I93 @S9S_MB_2U_LIB.S9S_MB_2U(SCH_1):PAGE175
  BE22 JTAG_TRC_PCH_PTI<15> @S9S_MB_2U_LIB.S9S_MB_2U(SCH_1):JTAG_TRC_PCH_PTI(15)    I93 @S9S_MB_2U_LIB.S9S_MB_2U(SCH_1):PAGE175
  BD23 JTAG_TRC_PCH_PTI1_CLK @S9S_MB_2U_LIB.S9S_MB_2U(SCH_1):JTAG_TRC_PCH_PTI1_CLK    I93 @S9S_MB_2U_LIB.S9S_MB_2U(SCH_1):PAGE175
  BF33 JTAG_TRC_PCH_PTI<1> @S9S_MB_2U_LIB.S9S_MB_2U(SCH_1):JTAG_TRC_PCH_PTI(1)    I93 @S9S_MB_2U_LIB.S9S_MB_2U(SCH_1):PAGE175
  BD31 JTAG_TRC_PCH_PTI<2> @S9S_MB_2U_LIB.S9S_MB_2U(SCH_1):JTAG_TRC_PCH_PTI(2)    I93 @S9S_MB_2U_LIB.S9S_MB_2U(SCH_1):PAGE175
  BE30 JTAG_TRC_PCH_PTI<3> @S9S_MB_2U_LIB.S9S_MB_2U(SCH_1):JTAG_TRC_PCH_PTI(3)    I93 @S9S_MB_2U_LIB.S9S_MB_2U(SCH_1):PAGE175
  BF31 JTAG_TRC_PCH_PTI<4> @S9S_MB_2U_LIB.S9S_MB_2U(SCH_1):JTAG_TRC_PCH_PTI(4)    I93 @S9S_MB_2U_LIB.S9S_MB_2U(SCH_1):PAGE175
  BG32 USB_OC1_REAR_R_N @S9S_MB_2U_LIB.S9S_MB_2U(SCH_1):USB_OC1_REAR_R_N    I93 @S9S_MB_2U_LIB.S9S_MB_2U(SCH_1):PAGE175
  BG30 PU_OC2_USB_N @S9S_MB_2U_LIB.S9S_MB_2U(SCH_1):PU_OC2_USB_N    I93 @S9S_MB_2U_LIB.S9S_MB_2U(SCH_1):PAGE175
  BG28 PU_OC3_USB_N @S9S_MB_2U_LIB.S9S_MB_2U(SCH_1):PU_OC3_USB_N    I93 @S9S_MB_2U_LIB.S9S_MB_2U(SCH_1):PAGE175
  BG26 PU_OC4_USB_N @S9S_MB_2U_LIB.S9S_MB_2U(SCH_1):PU_OC4_USB_N    I93 @S9S_MB_2U_LIB.S9S_MB_2U(SCH_1):PAGE175
   BC4 SMB_SML0_3V3AUX_PCH_SCL @S9S_MB_2U_LIB.S9S_MB_2U(SCH_1):SMB_SML0_3V3AUX_PCH_SCL    I93 @S9S_MB_2U_LIB.S9S_MB_2U(SCH_1):PAGE175
   AP3 PD_PCH_GPPC_C10 @S9S_MB_2U_LIB.S9S_MB_2U(SCH_1):PD_PCH_GPPC_C10    I93 @S9S_MB_2U_LIB.S9S_MB_2U(SCH_1):PAGE175
   AV3 FM_PMBUS_ALERT_B_EN @S9S_MB_2U_LIB.S9S_MB_2U(SCH_1):FM_PMBUS_ALERT_B_EN    I93 @S9S_MB_2U_LIB.S9S_MB_2U(SCH_1):PAGE175
   AN4 PU_SMB_SML3_3V3AUX_PCH_SCL @S9S_MB_2U_LIB.S9S_MB_2U(SCH_1):PU_SMB_SML3_3V3AUX_PCH_SCL    I93 @S9S_MB_2U_LIB.S9S_MB_2U(SCH_1):PAGE175
   AY1 PU_SMB_SML3_3V3AUX_PCH_SDA @S9S_MB_2U_LIB.S9S_MB_2U(SCH_1):PU_SMB_SML3_3V3AUX_PCH_SDA    I93 @S9S_MB_2U_LIB.S9S_MB_2U(SCH_1):PAGE175
   AW2 FM_THROTTLE_N @S9S_MB_2U_LIB.S9S_MB_2U(SCH_1):FM_THROTTLE_N    I93 @S9S_MB_2U_LIB.S9S_MB_2U(SCH_1):PAGE175
   BA2 PU_SMB_SML4_3V3AUX_PCH_SCL @S9S_MB_2U_LIB.S9S_MB_2U(SCH_1):PU_SMB_SML4_3V3AUX_PCH_SCL    I93 @S9S_MB_2U_LIB.S9S_MB_2U(SCH_1):PAGE175
   AV1 PU_SMB_SML4_3V3AUX_PCH_SDA @S9S_MB_2U_LIB.S9S_MB_2U(SCH_1):PU_SMB_SML4_3V3AUX_PCH_SDA    I93 @S9S_MB_2U_LIB.S9S_MB_2U(SCH_1):PAGE175
   AL3 FM_BIOS_POST_CMPLT_N @S9S_MB_2U_LIB.S9S_MB_2U(SCH_1):FM_BIOS_POST_CMPLT_N    I93 @S9S_MB_2U_LIB.S9S_MB_2U(SCH_1):PAGE175
   AL5 FM_ADR_MODE1 @S9S_MB_2U_LIB.S9S_MB_2U(SCH_1):FM_ADR_MODE1    I93 @S9S_MB_2U_LIB.S9S_MB_2U(SCH_1):PAGE175
   AL1 PU_SMB_PCH_PLD_3V3AUX_SCL @S9S_MB_2U_LIB.S9S_MB_2U(SCH_1):PU_SMB_PCH_PLD_3V3AUX_SCL    I93 @S9S_MB_2U_LIB.S9S_MB_2U(SCH_1):PAGE175
   BA4 SMB_SML0_3V3AUX_PCH_SDA @S9S_MB_2U_LIB.S9S_MB_2U(SCH_1):SMB_SML0_3V3AUX_PCH_SDA    I93 @S9S_MB_2U_LIB.S9S_MB_2U(SCH_1):PAGE175
   AT1 PU_SMB_PCH_PLD_3V3AUX_SDA @S9S_MB_2U_LIB.S9S_MB_2U(SCH_1):PU_SMB_PCH_PLD_3V3AUX_SDA    I93 @S9S_MB_2U_LIB.S9S_MB_2U(SCH_1):PAGE175
   AN2 PU_PCH_PLD_3V3AUX_ALERT_N @S9S_MB_2U_LIB.S9S_MB_2U(SCH_1):PU_PCH_PLD_3V3AUX_ALERT_N    I93 @S9S_MB_2U_LIB.S9S_MB_2U(SCH_1):PAGE175
   AU2 IRQ_SML0_ALERT_N @S9S_MB_2U_LIB.S9S_MB_2U(SCH_1):IRQ_SML0_ALERT_N    I93 @S9S_MB_2U_LIB.S9S_MB_2U(SCH_1):PAGE175
   AU4 SMB_SML0B_3V3AUX_SDA @S9S_MB_2U_LIB.S9S_MB_2U(SCH_1):SMB_SML0B_3V3AUX_SDA    I93 @S9S_MB_2U_LIB.S9S_MB_2U(SCH_1):PAGE175
   BB3 SMB_SML0B_3V3AUX_SCL @S9S_MB_2U_LIB.S9S_MB_2U(SCH_1):SMB_SML0B_3V3AUX_SCL    I93 @S9S_MB_2U_LIB.S9S_MB_2U(SCH_1):PAGE175
   AT3 PD_PCH_GPPC_C5 @S9S_MB_2U_LIB.S9S_MB_2U(SCH_1):PD_PCH_GPPC_C5    I93 @S9S_MB_2U_LIB.S9S_MB_2U(SCH_1):PAGE175
   AP1 SMB_SML1_PMBUS_3V3AUX_PCH_SCL_1 @S9S_MB_2U_LIB.S9S_MB_2U(SCH_1):SMB_SML1_PMBUS_3V3AUX_PCH_SCL_R1    I93 @S9S_MB_2U_LIB.S9S_MB_2U(SCH_1):PAGE175
   AW4 SMB_SML1_PMBUS_3V3AUX_PCH_SDA_1 @S9S_MB_2U_LIB.S9S_MB_2U(SCH_1):SMB_SML1_PMBUS_3V3AUX_PCH_SDA_R1    I93 @S9S_MB_2U_LIB.S9S_MB_2U(SCH_1):PAGE175
   AR4 IRQ_SML1_PMBUS_ALERT_N @S9S_MB_2U_LIB.S9S_MB_2U(SCH_1):IRQ_SML1_PMBUS_ALERT_N    I93 @S9S_MB_2U_LIB.S9S_MB_2U(SCH_1):PAGE175
   AR2 PD_PCH_GPPC_C9 @S9S_MB_2U_LIB.S9S_MB_2U(SCH_1):PD_PCH_GPPC_C9    I93 @S9S_MB_2U_LIB.S9S_MB_2U(SCH_1):PAGE175
   AF2 SMB_HOST_BMC_3V3AUX_SCL @S9S_MB_2U_LIB.S9S_MB_2U(SCH_1):SMB_HOST_BMC_3V3AUX_SCL    I93 @S9S_MB_2U_LIB.S9S_MB_2U(SCH_1):PAGE175
   AB2 IRQ_PCH_SCI_WHEA_N @S9S_MB_2U_LIB.S9S_MB_2U(SCH_1):IRQ_PCH_SCI_WHEA_N    I93 @S9S_MB_2U_LIB.S9S_MB_2U(SCH_1):PAGE175
   AB4 RST_PLTRST_N @S9S_MB_2U_LIB.S9S_MB_2U(SCH_1):RST_PLTRST_N    I93 @S9S_MB_2U_LIB.S9S_MB_2U(SCH_1):PAGE175
   AH2 FM_PCHHOT_N @S9S_MB_2U_LIB.S9S_MB_2U(SCH_1):FM_PCHHOT_N    I93 @S9S_MB_2U_LIB.S9S_MB_2U(SCH_1):PAGE175
   AC1 FM_ADR_COMPLETE @S9S_MB_2U_LIB.S9S_MB_2U(SCH_1):FM_ADR_COMPLETE    I93 @S9S_MB_2U_LIB.S9S_MB_2U(SCH_1):PAGE175
   AH4 FM_ADR_TRIGGER_R_N @S9S_MB_2U_LIB.S9S_MB_2U(SCH_1):FM_ADR_TRIGGER_R_N    I93 @S9S_MB_2U_LIB.S9S_MB_2U(SCH_1):PAGE175
   AC3 PU_PCH_VRALERT_N @S9S_MB_2U_LIB.S9S_MB_2U(SCH_1):PU_PCH_VRALERT_N    I93 @S9S_MB_2U_LIB.S9S_MB_2U(SCH_1):PAGE175
   AD4 FM_ADR_ACK @S9S_MB_2U_LIB.S9S_MB_2U(SCH_1):FM_ADR_ACK    I93 @S9S_MB_2U_LIB.S9S_MB_2U(SCH_1):PAGE175
    Y2 FM_PLT_BMC_THERMTRIP_R_N @S9S_MB_2U_LIB.S9S_MB_2U(SCH_1):FM_PLT_BMC_THERMTRIP_R_N    I93 @S9S_MB_2U_LIB.S9S_MB_2U(SCH_1):PAGE175
   AF4 FM_CPU_RMCA_CATERR_DLY_N @S9S_MB_2U_LIB.S9S_MB_2U(SCH_1):FM_CPU_RMCA_CATERR_DLY_N    I93 @S9S_MB_2U_LIB.S9S_MB_2U(SCH_1):PAGE175
    Y4 FM_BIOS_IMAGE_SWAP_N @S9S_MB_2U_LIB.S9S_MB_2U(SCH_1):FM_BIOS_IMAGE_SWAP_N    I93 @S9S_MB_2U_LIB.S9S_MB_2U(SCH_1):PAGE175
   AE1 SMB_HOST_BMC_3V3AUX_SDA @S9S_MB_2U_LIB.S9S_MB_2U(SCH_1):SMB_HOST_BMC_3V3AUX_SDA    I93 @S9S_MB_2U_LIB.S9S_MB_2U(SCH_1):PAGE175
   AG3 TP_PCH_GPP_D_20 @S9S_MB_2U_LIB.S9S_MB_2U(SCH_1):TP_PCH_GPP_D_20    I93 @S9S_MB_2U_LIB.S9S_MB_2U(SCH_1):PAGE175
   AA1 FM_PCH_GLB_RST_WARN_N @S9S_MB_2U_LIB.S9S_MB_2U(SCH_1):FM_PCH_GLB_RST_WARN_N    I93 @S9S_MB_2U_LIB.S9S_MB_2U(SCH_1):PAGE175
   AA3 FM_BIOS_DEBUG_EN_R_N @S9S_MB_2U_LIB.S9S_MB_2U(SCH_1):FM_BIOS_DEBUG_EN_R_N    I93 @S9S_MB_2U_LIB.S9S_MB_2U(SCH_1):PAGE175
    W1 FM_PCH_BOOT_BIOS_STRAP @S9S_MB_2U_LIB.S9S_MB_2U(SCH_1):FM_PCH_BOOT_BIOS_STRAP    I93 @S9S_MB_2U_LIB.S9S_MB_2U(SCH_1):PAGE175
   AD2 TP_PCH_GPP_D_2 @S9S_MB_2U_LIB.S9S_MB_2U(SCH_1):TP_PCH_GPP_D_2    I93 @S9S_MB_2U_LIB.S9S_MB_2U(SCH_1):PAGE175
   AJ1 FM_FLASH_SECURITY_STRAP @S9S_MB_2U_LIB.S9S_MB_2U(SCH_1):FM_FLASH_SECURITY_STRAP    I93 @S9S_MB_2U_LIB.S9S_MB_2U(SCH_1):PAGE175
   AG1 FM_ESPI_FLASH_MODE @S9S_MB_2U_LIB.S9S_MB_2U(SCH_1):FM_ESPI_FLASH_MODE    I93 @S9S_MB_2U_LIB.S9S_MB_2U(SCH_1):PAGE175
   AE3 FM_PCH_CRASHLOG_TRIG_N @S9S_MB_2U_LIB.S9S_MB_2U(SCH_1):FM_PCH_CRASHLOG_TRIG_N    I93 @S9S_MB_2U_LIB.S9S_MB_2U(SCH_1):PAGE175
   AJ3 PU_LPC_PME_N @S9S_MB_2U_LIB.S9S_MB_2U(SCH_1):PU_LPC_PME_N    I93 @S9S_MB_2U_LIB.S9S_MB_2U(SCH_1):PAGE175
    G4 FM_PCH_VISA_DEFAULT @S9S_MB_2U_LIB.S9S_MB_2U(SCH_1):FM_PCH_VISA_DEFAULT    I22 @S9S_MB_2U_LIB.S9S_MB_2U(SCH_1):PAGE176
    K1 FM_PCH_IO_EXPANDER @S9S_MB_2U_LIB.S9S_MB_2U(SCH_1):FM_PCH_IO_EXPANDER    I22 @S9S_MB_2U_LIB.S9S_MB_2U(SCH_1):PAGE176
    J2 TP_PCH_MGPIO_TEST1 @S9S_MB_2U_LIB.S9S_MB_2U(SCH_1):TP_PCH_MGPIO_TEST1    I22 @S9S_MB_2U_LIB.S9S_MB_2U(SCH_1):PAGE176
    G2 FM_PCH_RING_OSC_BYPASS_MGPIO_TE @S9S_MB_2U_LIB.S9S_MB_2U(SCH_1):FM_PCH_RING_OSC_BYPASS_MGPIO_TEST2    I22 @S9S_MB_2U_LIB.S9S_MB_2U(SCH_1):PAGE176
    H3 FM_PCH_XTAL_INPUT_MODE_MGPIO_TE @S9S_MB_2U_LIB.S9S_MB_2U(SCH_1):FM_PCH_XTAL_INPUT_MODE_MGPIO_TEST3    I22 @S9S_MB_2U_LIB.S9S_MB_2U(SCH_1):PAGE176
    J4 PU_PCH_PMCALERT_N @S9S_MB_2U_LIB.S9S_MB_2U(SCH_1):PU_PCH_PMCALERT_N    I22 @S9S_MB_2U_LIB.S9S_MB_2U(SCH_1):PAGE176
    L4 FM_LT_KEY_DOWNGRADE_N @S9S_MB_2U_LIB.S9S_MB_2U(SCH_1):FM_LT_KEY_DOWNGRADE_N    I22 @S9S_MB_2U_LIB.S9S_MB_2U(SCH_1):PAGE176
    L2 FM_PCH_EXTERNALCLKMODE @S9S_MB_2U_LIB.S9S_MB_2U(SCH_1):FM_PCH_EXTERNALCLKMODE    I22 @S9S_MB_2U_LIB.S9S_MB_2U(SCH_1):PAGE176
    K3 FM_PCH_MCRO_LDO @S9S_MB_2U_LIB.S9S_MB_2U(SCH_1):FM_PCH_MCRO_LDO    I22 @S9S_MB_2U_LIB.S9S_MB_2U(SCH_1):PAGE176
  BA26 TP_PCH_GPP_E_0 @S9S_MB_2U_LIB.S9S_MB_2U(SCH_1):TP_PCH_GPP_E_0    I22 @S9S_MB_2U_LIB.S9S_MB_2U(SCH_1):PAGE176
  AV31 PD_PCH_GPP_E_10 @S9S_MB_2U_LIB.S9S_MB_2U(SCH_1):PD_PCH_GPP_E_10    I22 @S9S_MB_2U_LIB.S9S_MB_2U(SCH_1):PAGE176
  AV34 PD_PCH_GPP_E_11 @S9S_MB_2U_LIB.S9S_MB_2U(SCH_1):PD_PCH_GPP_E_11    I22 @S9S_MB_2U_LIB.S9S_MB_2U(SCH_1):PAGE176
  BB28 PD_PCH_GPP_E_12 @S9S_MB_2U_LIB.S9S_MB_2U(SCH_1):PD_PCH_GPP_E_12    I22 @S9S_MB_2U_LIB.S9S_MB_2U(SCH_1):PAGE176
  BA32 PD_PCH_GPP_E_13 @S9S_MB_2U_LIB.S9S_MB_2U(SCH_1):PD_PCH_GPP_E_13    I22 @S9S_MB_2U_LIB.S9S_MB_2U(SCH_1):PAGE176
  BB34 PD_PCH_GPP_E_14 @S9S_MB_2U_LIB.S9S_MB_2U(SCH_1):PD_PCH_GPP_E_14    I22 @S9S_MB_2U_LIB.S9S_MB_2U(SCH_1):PAGE176
  AW20 FM_ME_AUTHN_FAIL @S9S_MB_2U_LIB.S9S_MB_2U(SCH_1):FM_ME_AUTHN_FAIL    I22 @S9S_MB_2U_LIB.S9S_MB_2U(SCH_1):PAGE176
  AW29 FM_ME_BT_DONE @S9S_MB_2U_LIB.S9S_MB_2U(SCH_1):FM_ME_BT_DONE    I22 @S9S_MB_2U_LIB.S9S_MB_2U(SCH_1):PAGE176
  BA36 FM_DEBUG_PORT_PRSNT_R_N @S9S_MB_2U_LIB.S9S_MB_2U(SCH_1):FM_DEBUG_PORT_PRSNT_R_N    I22 @S9S_MB_2U_LIB.S9S_MB_2U(SCH_1):PAGE176
  BA20 FM_PS_PWROK_DLY_R_SEL @S9S_MB_2U_LIB.S9S_MB_2U(SCH_1):FM_PS_PWROK_DLY_R_SEL    I22 @S9S_MB_2U_LIB.S9S_MB_2U(SCH_1):PAGE176
  BB31 FM_TPM_PRSNT_N @S9S_MB_2U_LIB.S9S_MB_2U(SCH_1):FM_TPM_PRSNT_N    I22 @S9S_MB_2U_LIB.S9S_MB_2U(SCH_1):PAGE176
  BA23 TP_PCH_GPP_E_1 @S9S_MB_2U_LIB.S9S_MB_2U(SCH_1):TP_PCH_GPP_E_1    I22 @S9S_MB_2U_LIB.S9S_MB_2U(SCH_1):PAGE176
  AW23 TP_PCH_GPP_E_2 @S9S_MB_2U_LIB.S9S_MB_2U(SCH_1):TP_PCH_GPP_E_2    I22 @S9S_MB_2U_LIB.S9S_MB_2U(SCH_1):PAGE176
  BB21 PD_PCH_GPP_E_3 @S9S_MB_2U_LIB.S9S_MB_2U(SCH_1):PD_PCH_GPP_E_3    I22 @S9S_MB_2U_LIB.S9S_MB_2U(SCH_1):PAGE176
  AV24 TP_EDSFF1A_TYPE_ID @S9S_MB_2U_LIB.S9S_MB_2U(SCH_1):TP_EDSFF1A_TYPE_ID    I22 @S9S_MB_2U_LIB.S9S_MB_2U(SCH_1):PAGE176
  AV28 TP_EDSFF1B_TYPE_ID @S9S_MB_2U_LIB.S9S_MB_2U(SCH_1):TP_EDSFF1B_TYPE_ID    I22 @S9S_MB_2U_LIB.S9S_MB_2U(SCH_1):PAGE176
  BB24 FM_M2_E1S_E6_PEDET @S9S_MB_2U_LIB.S9S_MB_2U(SCH_1):FM_M2_E1S_E6_PEDET    I22 @S9S_MB_2U_LIB.S9S_MB_2U(SCH_1):PAGE176
  AW32 FM_M2_SSD0_E7_PEDET @S9S_MB_2U_LIB.S9S_MB_2U(SCH_1):FM_M2_SSD0_E7_PEDET    I22 @S9S_MB_2U_LIB.S9S_MB_2U(SCH_1):PAGE176
  AW36 PD_PCH_GPP_E_8 @S9S_MB_2U_LIB.S9S_MB_2U(SCH_1):PD_PCH_GPP_E_8    I22 @S9S_MB_2U_LIB.S9S_MB_2U(SCH_1):PAGE176
  BA29 PD_PCH_GPP_E_9 @S9S_MB_2U_LIB.S9S_MB_2U(SCH_1):PD_PCH_GPP_E_9    I22 @S9S_MB_2U_LIB.S9S_MB_2U(SCH_1):PAGE176
    U3 FM_PCH_BMC_RST_R_N @S9S_MB_2U_LIB.S9S_MB_2U(SCH_1):FM_PCH_BMC_RST_R_N    I22 @S9S_MB_2U_LIB.S9S_MB_2U(SCH_1):PAGE176
    N2 PD_GPP_I_13 @S9S_MB_2U_LIB.S9S_MB_2U(SCH_1):PD_GPP_I_13    I22 @S9S_MB_2U_LIB.S9S_MB_2U(SCH_1):PAGE176
    P1 PD_GPP_I_14 @S9S_MB_2U_LIB.S9S_MB_2U(SCH_1):PD_GPP_I_14    I22 @S9S_MB_2U_LIB.S9S_MB_2U(SCH_1):PAGE176
    R2 PD_GPP_I_15 @S9S_MB_2U_LIB.S9S_MB_2U(SCH_1):PD_GPP_I_15    I22 @S9S_MB_2U_LIB.S9S_MB_2U(SCH_1):PAGE176
    U1 PD_GPP_I_16 @S9S_MB_2U_LIB.S9S_MB_2U(SCH_1):PD_GPP_I_16    I22 @S9S_MB_2U_LIB.S9S_MB_2U(SCH_1):PAGE176
    V4 PD_GPP_I_17 @S9S_MB_2U_LIB.S9S_MB_2U(SCH_1):PD_GPP_I_17    I22 @S9S_MB_2U_LIB.S9S_MB_2U(SCH_1):PAGE176
    N4 IRQ_TPM_SPI_N @S9S_MB_2U_LIB.S9S_MB_2U(SCH_1):IRQ_TPM_SPI_N    I22 @S9S_MB_2U_LIB.S9S_MB_2U(SCH_1):PAGE176
    P3 FM_PCH_DFXTESTMODE @S9S_MB_2U_LIB.S9S_MB_2U(SCH_1):FM_PCH_DFXTESTMODE    I22 @S9S_MB_2U_LIB.S9S_MB_2U(SCH_1):PAGE176
    R4 FM_PCH_XTALSEL @S9S_MB_2U_LIB.S9S_MB_2U(SCH_1):FM_PCH_XTALSEL    I22 @S9S_MB_2U_LIB.S9S_MB_2U(SCH_1):PAGE176
   AF8 H_CPU0_PMSYNC_PCH_R2 @S9S_MB_2U_LIB.S9S_MB_2U(SCH_1):H_CPU0_PMSYNC_PCH_R2    I22 @S9S_MB_2U_LIB.S9S_MB_2U(SCH_1):PAGE176
   AE7 H_CPU0_PMDOWN_PCH @S9S_MB_2U_LIB.S9S_MB_2U(SCH_1):H_CPU0_PMDOWN_PCH    I22 @S9S_MB_2U_LIB.S9S_MB_2U(SCH_1):PAGE176
  AC10 TP_GPP_L_2 @S9S_MB_2U_LIB.S9S_MB_2U(SCH_1):TP_GPP_L_2    I22 @S9S_MB_2U_LIB.S9S_MB_2U(SCH_1):PAGE176
  AF11 FM_BIOS_ADV_FUNCTIONS @S9S_MB_2U_LIB.S9S_MB_2U(SCH_1):FM_BIOS_ADV_FUNCTIONS    I22 @S9S_MB_2U_LIB.S9S_MB_2U(SCH_1):PAGE176
   AG7 FM_ME_RCVR_N @S9S_MB_2U_LIB.S9S_MB_2U(SCH_1):FM_ME_RCVR_N    I22 @S9S_MB_2U_LIB.S9S_MB_2U(SCH_1):PAGE176
   AB8 FM_PASSWORD_CLEAR_N @S9S_MB_2U_LIB.S9S_MB_2U(SCH_1):FM_PASSWORD_CLEAR_N    I22 @S9S_MB_2U_LIB.S9S_MB_2U(SCH_1):PAGE176
  AG10 FM_MFG_MODE @S9S_MB_2U_LIB.S9S_MB_2U(SCH_1):FM_MFG_MODE    I22 @S9S_MB_2U_LIB.S9S_MB_2U(SCH_1):PAGE176
   AC7 TP_GPP_L_7 @S9S_MB_2U_LIB.S9S_MB_2U(SCH_1):TP_GPP_L_7    I22 @S9S_MB_2U_LIB.S9S_MB_2U(SCH_1):PAGE176
  AE10 TP_GPP_L_8 @S9S_MB_2U_LIB.S9S_MB_2U(SCH_1):TP_GPP_L_8    I22 @S9S_MB_2U_LIB.S9S_MB_2U(SCH_1):PAGE176
    N7 FAB_REV_ID0 @S9S_MB_2U_LIB.S9S_MB_2U(SCH_1):FAB_REV_ID0    I22 @S9S_MB_2U_LIB.S9S_MB_2U(SCH_1):PAGE176
  AA13 FAB_REV_ID1 @S9S_MB_2U_LIB.S9S_MB_2U(SCH_1):FAB_REV_ID1    I22 @S9S_MB_2U_LIB.S9S_MB_2U(SCH_1):PAGE176
    R7 FM_PCH_BIOS_RCVR_MODE @S9S_MB_2U_LIB.S9S_MB_2U(SCH_1):FM_PCH_BIOS_RCVR_MODE    I22 @S9S_MB_2U_LIB.S9S_MB_2U(SCH_1):PAGE176
    U7 TP_GPP_M_12 @S9S_MB_2U_LIB.S9S_MB_2U(SCH_1):TP_GPP_M_12    I22 @S9S_MB_2U_LIB.S9S_MB_2U(SCH_1):PAGE176
    T8 PD_GPP_M_15 @S9S_MB_2U_LIB.S9S_MB_2U(SCH_1):PD_GPP_M_15    I22 @S9S_MB_2U_LIB.S9S_MB_2U(SCH_1):PAGE176
   N10 PD_GPP_M_16 @S9S_MB_2U_LIB.S9S_MB_2U(SCH_1):PD_GPP_M_16    I22 @S9S_MB_2U_LIB.S9S_MB_2U(SCH_1):PAGE176
   W13 PD_GPP_M_17 @S9S_MB_2U_LIB.S9S_MB_2U(SCH_1):PD_GPP_M_17    I22 @S9S_MB_2U_LIB.S9S_MB_2U(SCH_1):PAGE176
   AA7 FAB_REV_ID2 @S9S_MB_2U_LIB.S9S_MB_2U(SCH_1):FAB_REV_ID2    I22 @S9S_MB_2U_LIB.S9S_MB_2U(SCH_1):PAGE176
  AA10 FM_BOARD_SKU_ID0 @S9S_MB_2U_LIB.S9S_MB_2U(SCH_1):FM_BOARD_SKU_ID0    I22 @S9S_MB_2U_LIB.S9S_MB_2U(SCH_1):PAGE176
    W7 FM_BOARD_SKU_ID1 @S9S_MB_2U_LIB.S9S_MB_2U(SCH_1):FM_BOARD_SKU_ID1    I22 @S9S_MB_2U_LIB.S9S_MB_2U(SCH_1):PAGE176
    V8 FM_BOARD_SKU_ID2 @S9S_MB_2U_LIB.S9S_MB_2U(SCH_1):FM_BOARD_SKU_ID2    I22 @S9S_MB_2U_LIB.S9S_MB_2U(SCH_1):PAGE176
   R10 FM_BOARD_SKU_ID3 @S9S_MB_2U_LIB.S9S_MB_2U(SCH_1):FM_BOARD_SKU_ID3    I22 @S9S_MB_2U_LIB.S9S_MB_2U(SCH_1):PAGE176
  AB11 FM_BOARD_SKU_ID4 @S9S_MB_2U_LIB.S9S_MB_2U(SCH_1):FM_BOARD_SKU_ID4    I22 @S9S_MB_2U_LIB.S9S_MB_2U(SCH_1):PAGE176
   W10 PD_GPP_M_8 @S9S_MB_2U_LIB.S9S_MB_2U(SCH_1):PD_GPP_M_8    I22 @S9S_MB_2U_LIB.S9S_MB_2U(SCH_1):PAGE176
  BB18 FM_XTAL_INPUT_FREQUENCY_0_MGPIO @S9S_MB_2U_LIB.S9S_MB_2U(SCH_1):FM_XTAL_INPUT_FREQUENCY_0_MGPIO_TEST4    I27 @S9S_MB_2U_LIB.S9S_MB_2U(SCH_1):PAGE177
  AW10 FM_JTAG_ODT_DISABLE @S9S_MB_2U_LIB.S9S_MB_2U(SCH_1):FM_JTAG_ODT_DISABLE    I27 @S9S_MB_2U_LIB.S9S_MB_2U(SCH_1):PAGE177
   BB8 FM_ESPI_CS_SWIZZLE @S9S_MB_2U_LIB.S9S_MB_2U(SCH_1):FM_ESPI_CS_SWIZZLE    I27 @S9S_MB_2U_LIB.S9S_MB_2U(SCH_1):PAGE177
  AU16 FM_PCH_SPKR @S9S_MB_2U_LIB.S9S_MB_2U(SCH_1):FM_PCH_SPKR    I27 @S9S_MB_2U_LIB.S9S_MB_2U(SCH_1):PAGE177
  AR16 FM_XTAL_INPUT_FREQUENCY_1_MGPIO @S9S_MB_2U_LIB.S9S_MB_2U(SCH_1):FM_XTAL_INPUT_FREQUENCY_1_MGPIO_TEST5    I27 @S9S_MB_2U_LIB.S9S_MB_2U(SCH_1):PAGE177
  AV11 FM_ADR_MODE0 @S9S_MB_2U_LIB.S9S_MB_2U(SCH_1):FM_ADR_MODE0    I27 @S9S_MB_2U_LIB.S9S_MB_2U(SCH_1):PAGE177
  AU13 FM_SPI_3V3_1V8_VOLTAGE @S9S_MB_2U_LIB.S9S_MB_2U(SCH_1):FM_SPI_3V3_1V8_VOLTAGE    I27 @S9S_MB_2U_LIB.S9S_MB_2U(SCH_1):PAGE177
  AT18 FM_PCH_CONSENT_STRAP_N @S9S_MB_2U_LIB.S9S_MB_2U(SCH_1):FM_PCH_CONSENT_STRAP_N    I27 @S9S_MB_2U_LIB.S9S_MB_2U(SCH_1):PAGE177
  AR13 FM_EUP_LOT6_N @S9S_MB_2U_LIB.S9S_MB_2U(SCH_1):FM_EUP_LOT6_N    I27 @S9S_MB_2U_LIB.S9S_MB_2U(SCH_1):PAGE177
   BA7 FM_SUSACK_N @S9S_MB_2U_LIB.S9S_MB_2U(SCH_1):FM_SUSACK_N    I27 @S9S_MB_2U_LIB.S9S_MB_2U(SCH_1):PAGE177
  AP15 IRQ_PCH_CPU_NMI_EVENT_R_N @S9S_MB_2U_LIB.S9S_MB_2U(SCH_1):IRQ_PCH_CPU_NMI_EVENT_R_N    I27 @S9S_MB_2U_LIB.S9S_MB_2U(SCH_1):PAGE177
  AV18 IRQ_SMI_ACTIVE_N @S9S_MB_2U_LIB.S9S_MB_2U(SCH_1):IRQ_SMI_ACTIVE_N    I27 @S9S_MB_2U_LIB.S9S_MB_2U(SCH_1):PAGE177
   T11 TP_PCH_GPP_N_1 @S9S_MB_2U_LIB.S9S_MB_2U(SCH_1):TP_PCH_GPP_N_1    I27 @S9S_MB_2U_LIB.S9S_MB_2U(SCH_1):PAGE177
   V11 TP_PCH_GPP_N_4 @S9S_MB_2U_LIB.S9S_MB_2U(SCH_1):TP_PCH_GPP_N_4    I27 @S9S_MB_2U_LIB.S9S_MB_2U(SCH_1):PAGE177
   BG3 TP_PCH_CGC_DUT_DETECTED @S9S_MB_2U_LIB.S9S_MB_2U(SCH_1):TP_PCH_CGC_DUT_DETECTED    I27 @S9S_MB_2U_LIB.S9S_MB_2U(SCH_1):PAGE177
   BD7 RST_RTCRST_N @S9S_MB_2U_LIB.S9S_MB_2U(SCH_1):RST_RTCRST_N    I27 @S9S_MB_2U_LIB.S9S_MB_2U(SCH_1):PAGE177
  BB15 SPI_PCH_CLK @S9S_MB_2U_LIB.S9S_MB_2U(SCH_1):SPI_PCH_CLK    I27 @S9S_MB_2U_LIB.S9S_MB_2U(SCH_1):PAGE177
  AW13 SPI_PCH_CS0_R_N @S9S_MB_2U_LIB.S9S_MB_2U(SCH_1):SPI_PCH_CS0_R_N    I27 @S9S_MB_2U_LIB.S9S_MB_2U(SCH_1):PAGE177
  BA10 TP_SPI_PCH_CS1_R_N @S9S_MB_2U_LIB.S9S_MB_2U(SCH_1):TP_SPI_PCH_CS1_R_N    I27 @S9S_MB_2U_LIB.S9S_MB_2U(SCH_1):PAGE177
  AV15 SPI_PCH_IO2 @S9S_MB_2U_LIB.S9S_MB_2U(SCH_1):SPI_PCH_IO2    I27 @S9S_MB_2U_LIB.S9S_MB_2U(SCH_1):PAGE177
  BA16 SPI_PCH_IO3 @S9S_MB_2U_LIB.S9S_MB_2U(SCH_1):SPI_PCH_IO3    I27 @S9S_MB_2U_LIB.S9S_MB_2U(SCH_1):PAGE177
  BA13 SPI_PCH_IO0 @S9S_MB_2U_LIB.S9S_MB_2U(SCH_1):SPI_PCH_IO0    I27 @S9S_MB_2U_LIB.S9S_MB_2U(SCH_1):PAGE177
  AW16 SPI_PCH_IO1 @S9S_MB_2U_LIB.S9S_MB_2U(SCH_1):SPI_PCH_IO1    I27 @S9S_MB_2U_LIB.S9S_MB_2U(SCH_1):PAGE177
  BB11 SPI_PCH_TPM_CS_N @S9S_MB_2U_LIB.S9S_MB_2U(SCH_1):SPI_PCH_TPM_CS_N    I27 @S9S_MB_2U_LIB.S9S_MB_2U(SCH_1):PAGE177
   BF9 RST_SRTCRST_N @S9S_MB_2U_LIB.S9S_MB_2U(SCH_1):RST_SRTCRST_N    I27 @S9S_MB_2U_LIB.S9S_MB_2U(SCH_1):PAGE177
   A41 FM_PCH_PRSNT_N @S9S_MB_2U_LIB.S9S_MB_2U(SCH_1):FM_PCH_PRSNT_N    I27 @S9S_MB_2U_LIB.S9S_MB_2U(SCH_1):PAGE177
  AF15 TP_PCH_RSVD<16> @S9S_MB_2U_LIB.S9S_MB_2U(SCH_1):TP_PCH_RSVD(16)    I11 @S9S_MB_2U_LIB.S9S_MB_2U(SCH_1):PAGE178
  AN26 TP_PCH_RSVD<15> @S9S_MB_2U_LIB.S9S_MB_2U(SCH_1):TP_PCH_RSVD(15)    I11 @S9S_MB_2U_LIB.S9S_MB_2U(SCH_1):PAGE178
   W24 P1V05_PCH_AUX @S9S_MB_2U_LIB.S9S_MB_2U(SCH_1):P1V05_PCH_AUX    I11 @S9S_MB_2U_LIB.S9S_MB_2U(SCH_1):PAGE178
   W22 P1V05_PCH_AUX @S9S_MB_2U_LIB.S9S_MB_2U(SCH_1):P1V05_PCH_AUX    I11 @S9S_MB_2U_LIB.S9S_MB_2U(SCH_1):PAGE178
   W20 P1V05_PCH_AUX @S9S_MB_2U_LIB.S9S_MB_2U(SCH_1):P1V05_PCH_AUX    I11 @S9S_MB_2U_LIB.S9S_MB_2U(SCH_1):PAGE178
   W19 P1V05_PCH_AUX @S9S_MB_2U_LIB.S9S_MB_2U(SCH_1):P1V05_PCH_AUX    I11 @S9S_MB_2U_LIB.S9S_MB_2U(SCH_1):PAGE178
   W17 P1V05_PCH_AUX @S9S_MB_2U_LIB.S9S_MB_2U(SCH_1):P1V05_PCH_AUX    I11 @S9S_MB_2U_LIB.S9S_MB_2U(SCH_1):PAGE178
  AB24 P1V05_PCH_AUX @S9S_MB_2U_LIB.S9S_MB_2U(SCH_1):P1V05_PCH_AUX    I11 @S9S_MB_2U_LIB.S9S_MB_2U(SCH_1):PAGE178
  AB22 P1V05_PCH_AUX @S9S_MB_2U_LIB.S9S_MB_2U(SCH_1):P1V05_PCH_AUX    I11 @S9S_MB_2U_LIB.S9S_MB_2U(SCH_1):PAGE178
  AB20 P1V05_PCH_AUX @S9S_MB_2U_LIB.S9S_MB_2U(SCH_1):P1V05_PCH_AUX    I11 @S9S_MB_2U_LIB.S9S_MB_2U(SCH_1):PAGE178
  AB19 P1V05_PCH_AUX @S9S_MB_2U_LIB.S9S_MB_2U(SCH_1):P1V05_PCH_AUX    I11 @S9S_MB_2U_LIB.S9S_MB_2U(SCH_1):PAGE178
  AJ27 P1V05_PCH_AUX @S9S_MB_2U_LIB.S9S_MB_2U(SCH_1):P1V05_PCH_AUX    I11 @S9S_MB_2U_LIB.S9S_MB_2U(SCH_1):PAGE178
  AJ25 P1V05_PCH_AUX @S9S_MB_2U_LIB.S9S_MB_2U(SCH_1):P1V05_PCH_AUX    I11 @S9S_MB_2U_LIB.S9S_MB_2U(SCH_1):PAGE178
  AG27 P1V05_PCH_AUX @S9S_MB_2U_LIB.S9S_MB_2U(SCH_1):P1V05_PCH_AUX    I11 @S9S_MB_2U_LIB.S9S_MB_2U(SCH_1):PAGE178
  AG25 P1V05_PCH_AUX @S9S_MB_2U_LIB.S9S_MB_2U(SCH_1):P1V05_PCH_AUX    I11 @S9S_MB_2U_LIB.S9S_MB_2U(SCH_1):PAGE178
  AF27 P1V05_PCH_AUX @S9S_MB_2U_LIB.S9S_MB_2U(SCH_1):P1V05_PCH_AUX    I11 @S9S_MB_2U_LIB.S9S_MB_2U(SCH_1):PAGE178
  AF25 P1V05_PCH_AUX @S9S_MB_2U_LIB.S9S_MB_2U(SCH_1):P1V05_PCH_AUX    I11 @S9S_MB_2U_LIB.S9S_MB_2U(SCH_1):PAGE178
  AD27 P1V05_PCH_AUX @S9S_MB_2U_LIB.S9S_MB_2U(SCH_1):P1V05_PCH_AUX    I11 @S9S_MB_2U_LIB.S9S_MB_2U(SCH_1):PAGE178
  AD25 P1V05_PCH_AUX @S9S_MB_2U_LIB.S9S_MB_2U(SCH_1):P1V05_PCH_AUX    I11 @S9S_MB_2U_LIB.S9S_MB_2U(SCH_1):PAGE178
  AB27 P1V05_PCH_PLL_AUX @S9S_MB_2U_LIB.S9S_MB_2U(SCH_1):P1V05_PCH_PLL_AUX    I11 @S9S_MB_2U_LIB.S9S_MB_2U(SCH_1):PAGE178
   N26 P1V05_PCH_AUX @S9S_MB_2U_LIB.S9S_MB_2U(SCH_1):P1V05_PCH_AUX    I11 @S9S_MB_2U_LIB.S9S_MB_2U(SCH_1):PAGE178
   N23 P1V05_PCH_AUX @S9S_MB_2U_LIB.S9S_MB_2U(SCH_1):P1V05_PCH_AUX    I11 @S9S_MB_2U_LIB.S9S_MB_2U(SCH_1):PAGE178
  AR26 P1V05_PCH_AUX @S9S_MB_2U_LIB.S9S_MB_2U(SCH_1):P1V05_PCH_AUX    I11 @S9S_MB_2U_LIB.S9S_MB_2U(SCH_1):PAGE178
   M24 P1V05_PCH_AUX @S9S_MB_2U_LIB.S9S_MB_2U(SCH_1):P1V05_PCH_AUX    I11 @S9S_MB_2U_LIB.S9S_MB_2U(SCH_1):PAGE178
   P15 P1V05_PCH_AUX @S9S_MB_2U_LIB.S9S_MB_2U(SCH_1):P1V05_PCH_AUX    I11 @S9S_MB_2U_LIB.S9S_MB_2U(SCH_1):PAGE178
  AL25 P1V05_PCH_PLL_AUX @S9S_MB_2U_LIB.S9S_MB_2U(SCH_1):P1V05_PCH_PLL_AUX    I11 @S9S_MB_2U_LIB.S9S_MB_2U(SCH_1):PAGE178
  AG29 P1V05_PCH_PLL_AUX @S9S_MB_2U_LIB.S9S_MB_2U(SCH_1):P1V05_PCH_PLL_AUX    I11 @S9S_MB_2U_LIB.S9S_MB_2U(SCH_1):PAGE178
  AE29 P1V05_PCH_PLL_AUX @S9S_MB_2U_LIB.S9S_MB_2U(SCH_1):P1V05_PCH_PLL_AUX    I11 @S9S_MB_2U_LIB.S9S_MB_2U(SCH_1):PAGE178
   R29 P1V05_PCH_PLL_AUX @S9S_MB_2U_LIB.S9S_MB_2U(SCH_1):P1V05_PCH_PLL_AUX    I11 @S9S_MB_2U_LIB.S9S_MB_2U(SCH_1):PAGE178
   U27 P1V05_PCH_PLL_AUX @S9S_MB_2U_LIB.S9S_MB_2U(SCH_1):P1V05_PCH_PLL_AUX    I11 @S9S_MB_2U_LIB.S9S_MB_2U(SCH_1):PAGE178
  AA29 P1V05_PCH_PLL_AUX @S9S_MB_2U_LIB.S9S_MB_2U(SCH_1):P1V05_PCH_PLL_AUX    I11 @S9S_MB_2U_LIB.S9S_MB_2U(SCH_1):PAGE178
   R26 P1V05_PCH_PLL_AUX @S9S_MB_2U_LIB.S9S_MB_2U(SCH_1):P1V05_PCH_PLL_AUX    I11 @S9S_MB_2U_LIB.S9S_MB_2U(SCH_1):PAGE178
   R23 P1V05_PCH_PLL_AUX @S9S_MB_2U_LIB.S9S_MB_2U(SCH_1):P1V05_PCH_PLL_AUX    I11 @S9S_MB_2U_LIB.S9S_MB_2U(SCH_1):PAGE178
   N20 P1V8_PCH_AUX @S9S_MB_2U_LIB.S9S_MB_2U(SCH_1):P1V8_PCH_AUX    I11 @S9S_MB_2U_LIB.S9S_MB_2U(SCH_1):PAGE178
   U24 P1V8_PCH_AUX @S9S_MB_2U_LIB.S9S_MB_2U(SCH_1):P1V8_PCH_AUX    I11 @S9S_MB_2U_LIB.S9S_MB_2U(SCH_1):PAGE178
   U22 P1V8_PCH_AUX @S9S_MB_2U_LIB.S9S_MB_2U(SCH_1):P1V8_PCH_AUX    I11 @S9S_MB_2U_LIB.S9S_MB_2U(SCH_1):PAGE178
   U20 P1V8_PCH_AUX @S9S_MB_2U_LIB.S9S_MB_2U(SCH_1):P1V8_PCH_AUX    I11 @S9S_MB_2U_LIB.S9S_MB_2U(SCH_1):PAGE178
   U19 P1V8_PCH_AUX @S9S_MB_2U_LIB.S9S_MB_2U(SCH_1):P1V8_PCH_AUX    I11 @S9S_MB_2U_LIB.S9S_MB_2U(SCH_1):PAGE178
   U17 P1V8_PCH_AUX @S9S_MB_2U_LIB.S9S_MB_2U(SCH_1):P1V8_PCH_AUX    I11 @S9S_MB_2U_LIB.S9S_MB_2U(SCH_1):PAGE178
  AB34 P1V8_PCH_PLL_AUX @S9S_MB_2U_LIB.S9S_MB_2U(SCH_1):P1V8_PCH_PLL_AUX    I11 @S9S_MB_2U_LIB.S9S_MB_2U(SCH_1):PAGE178
   W29 P1V8_PCH_PLL_AUX @S9S_MB_2U_LIB.S9S_MB_2U(SCH_1):P1V8_PCH_PLL_AUX    I11 @S9S_MB_2U_LIB.S9S_MB_2U(SCH_1):PAGE178
   U29 P1V8_PCH_PLL_AUX @S9S_MB_2U_LIB.S9S_MB_2U(SCH_1):P1V8_PCH_PLL_AUX    I11 @S9S_MB_2U_LIB.S9S_MB_2U(SCH_1):PAGE178
   W27 P1V8_PCH_PLL_AUX @S9S_MB_2U_LIB.S9S_MB_2U(SCH_1):P1V8_PCH_PLL_AUX    I11 @S9S_MB_2U_LIB.S9S_MB_2U(SCH_1):PAGE178
  AB31 P1V8_PCH_PLL_AUX @S9S_MB_2U_LIB.S9S_MB_2U(SCH_1):P1V8_PCH_PLL_AUX    I11 @S9S_MB_2U_LIB.S9S_MB_2U(SCH_1):PAGE178
   P21 P3V3_AUX @S9S_MB_2U_LIB.S9S_MB_2U(SCH_1):P3V3_AUX    I11 @S9S_MB_2U_LIB.S9S_MB_2U(SCH_1):PAGE178
  AL17 P3V3_AUX @S9S_MB_2U_LIB.S9S_MB_2U(SCH_1):P3V3_AUX    I11 @S9S_MB_2U_LIB.S9S_MB_2U(SCH_1):PAGE178
  AJ17 P3V3_AUX @S9S_MB_2U_LIB.S9S_MB_2U(SCH_1):P3V3_AUX    I11 @S9S_MB_2U_LIB.S9S_MB_2U(SCH_1):PAGE178
  AG17 P3V3_AUX @S9S_MB_2U_LIB.S9S_MB_2U(SCH_1):P3V3_AUX    I11 @S9S_MB_2U_LIB.S9S_MB_2U(SCH_1):PAGE178
  AF17 P3V3_AUX @S9S_MB_2U_LIB.S9S_MB_2U(SCH_1):P3V3_AUX    I11 @S9S_MB_2U_LIB.S9S_MB_2U(SCH_1):PAGE178
  AK15 P3V3_AUX @S9S_MB_2U_LIB.S9S_MB_2U(SCH_1):P3V3_AUX    I11 @S9S_MB_2U_LIB.S9S_MB_2U(SCH_1):PAGE178
  AD15 P3V3_AUX @S9S_MB_2U_LIB.S9S_MB_2U(SCH_1):P3V3_AUX    I11 @S9S_MB_2U_LIB.S9S_MB_2U(SCH_1):PAGE178
   V15 P3V3_AUX @S9S_MB_2U_LIB.S9S_MB_2U(SCH_1):P3V3_AUX    I11 @S9S_MB_2U_LIB.S9S_MB_2U(SCH_1):PAGE178
   T15 P3V3_AUX @S9S_MB_2U_LIB.S9S_MB_2U(SCH_1):P3V3_AUX    I11 @S9S_MB_2U_LIB.S9S_MB_2U(SCH_1):PAGE178
  AN20 P3V3_AUX @S9S_MB_2U_LIB.S9S_MB_2U(SCH_1):P3V3_AUX    I11 @S9S_MB_2U_LIB.S9S_MB_2U(SCH_1):PAGE178
  AD17 P3V3_AUX @S9S_MB_2U_LIB.S9S_MB_2U(SCH_1):P3V3_AUX    I11 @S9S_MB_2U_LIB.S9S_MB_2U(SCH_1):PAGE178
  AR23 P1V05_PCH_AUX @S9S_MB_2U_LIB.S9S_MB_2U(SCH_1):P1V05_PCH_AUX    I11 @S9S_MB_2U_LIB.S9S_MB_2U(SCH_1):PAGE178
  AP21 P1V05_PCH_AUX @S9S_MB_2U_LIB.S9S_MB_2U(SCH_1):P1V05_PCH_AUX    I11 @S9S_MB_2U_LIB.S9S_MB_2U(SCH_1):PAGE178
  AN23 P1V05_PCH_AUX @S9S_MB_2U_LIB.S9S_MB_2U(SCH_1):P1V05_PCH_AUX    I11 @S9S_MB_2U_LIB.S9S_MB_2U(SCH_1):PAGE178
  AL22 P1V05_PCH_AUX @S9S_MB_2U_LIB.S9S_MB_2U(SCH_1):P1V05_PCH_AUX    I11 @S9S_MB_2U_LIB.S9S_MB_2U(SCH_1):PAGE178
  AL20 P1V05_PCH_AUX @S9S_MB_2U_LIB.S9S_MB_2U(SCH_1):P1V05_PCH_AUX    I11 @S9S_MB_2U_LIB.S9S_MB_2U(SCH_1):PAGE178
  AJ22 P1V05_PCH_AUX @S9S_MB_2U_LIB.S9S_MB_2U(SCH_1):P1V05_PCH_AUX    I11 @S9S_MB_2U_LIB.S9S_MB_2U(SCH_1):PAGE178
  AJ20 P1V05_PCH_AUX @S9S_MB_2U_LIB.S9S_MB_2U(SCH_1):P1V05_PCH_AUX    I11 @S9S_MB_2U_LIB.S9S_MB_2U(SCH_1):PAGE178
  AG22 P1V05_PCH_AUX @S9S_MB_2U_LIB.S9S_MB_2U(SCH_1):P1V05_PCH_AUX    I11 @S9S_MB_2U_LIB.S9S_MB_2U(SCH_1):PAGE178
  AG20 P1V05_PCH_AUX @S9S_MB_2U_LIB.S9S_MB_2U(SCH_1):P1V05_PCH_AUX    I11 @S9S_MB_2U_LIB.S9S_MB_2U(SCH_1):PAGE178
  AF22 P1V05_PCH_AUX @S9S_MB_2U_LIB.S9S_MB_2U(SCH_1):P1V05_PCH_AUX    I11 @S9S_MB_2U_LIB.S9S_MB_2U(SCH_1):PAGE178
  AF20 P1V05_PCH_AUX @S9S_MB_2U_LIB.S9S_MB_2U(SCH_1):P1V05_PCH_AUX    I11 @S9S_MB_2U_LIB.S9S_MB_2U(SCH_1):PAGE178
  AH15 P3V3_RTC_AUX @S9S_MB_2U_LIB.S9S_MB_2U(SCH_1):P3V3_RTC_AUX    I11 @S9S_MB_2U_LIB.S9S_MB_2U(SCH_1):PAGE178
  BG40    GND @S9S_MB_2U_LIB.S9S_MB_2U(SCH_1):GND    I11 @S9S_MB_2U_LIB.S9S_MB_2U(SCH_1):PAGE178
  AC13 PD_RCOMP_1P8_3P3 @S9S_MB_2U_LIB.S9S_MB_2U(SCH_1):PD_RCOMP_1P8_3P3     I4 @S9S_MB_2U_LIB.S9S_MB_2U(SCH_1):PAGE179
   L13 TP_PCH_RSVD<13> @S9S_MB_2U_LIB.S9S_MB_2U(SCH_1):TP_PCH_RSVD(13)     I4 @S9S_MB_2U_LIB.S9S_MB_2U(SCH_1):PAGE179
   N13 TP_PCH_RSVD<12> @S9S_MB_2U_LIB.S9S_MB_2U(SCH_1):TP_PCH_RSVD(12)     I4 @S9S_MB_2U_LIB.S9S_MB_2U(SCH_1):PAGE179
  BB43 TP_PCH_RSVD<7> @S9S_MB_2U_LIB.S9S_MB_2U(SCH_1):TP_PCH_RSVD(7)     I4 @S9S_MB_2U_LIB.S9S_MB_2U(SCH_1):PAGE179
   P18 TP_PCH_RSVD<6> @S9S_MB_2U_LIB.S9S_MB_2U(SCH_1):TP_PCH_RSVD(6)     I4 @S9S_MB_2U_LIB.S9S_MB_2U(SCH_1):PAGE179
    A4 TP_PCH_RSVD<2> @S9S_MB_2U_LIB.S9S_MB_2U(SCH_1):TP_PCH_RSVD(2)     I4 @S9S_MB_2U_LIB.S9S_MB_2U(SCH_1):PAGE179
    F1 TP_PCH_RSVD<1> @S9S_MB_2U_LIB.S9S_MB_2U(SCH_1):TP_PCH_RSVD(1)     I4 @S9S_MB_2U_LIB.S9S_MB_2U(SCH_1):PAGE179
    H1 TP_PCH_RSVD<0> @S9S_MB_2U_LIB.S9S_MB_2U(SCH_1):TP_PCH_RSVD(0)     I4 @S9S_MB_2U_LIB.S9S_MB_2U(SCH_1):PAGE179
    Y8    GND @S9S_MB_2U_LIB.S9S_MB_2U(SCH_1):GND     I7 @S9S_MB_2U_LIB.S9S_MB_2U(SCH_1):PAGE180
   Y34    GND @S9S_MB_2U_LIB.S9S_MB_2U(SCH_1):GND     I7 @S9S_MB_2U_LIB.S9S_MB_2U(SCH_1):PAGE180
   Y31    GND @S9S_MB_2U_LIB.S9S_MB_2U(SCH_1):GND     I7 @S9S_MB_2U_LIB.S9S_MB_2U(SCH_1):PAGE180
   Y15    GND @S9S_MB_2U_LIB.S9S_MB_2U(SCH_1):GND     I7 @S9S_MB_2U_LIB.S9S_MB_2U(SCH_1):PAGE180
   Y11    GND @S9S_MB_2U_LIB.S9S_MB_2U(SCH_1):GND     I7 @S9S_MB_2U_LIB.S9S_MB_2U(SCH_1):PAGE180
    W5    GND @S9S_MB_2U_LIB.S9S_MB_2U(SCH_1):GND     I7 @S9S_MB_2U_LIB.S9S_MB_2U(SCH_1):PAGE180
   W39    GND @S9S_MB_2U_LIB.S9S_MB_2U(SCH_1):GND     I7 @S9S_MB_2U_LIB.S9S_MB_2U(SCH_1):PAGE180
    W3    GND @S9S_MB_2U_LIB.S9S_MB_2U(SCH_1):GND     I7 @S9S_MB_2U_LIB.S9S_MB_2U(SCH_1):PAGE180
   W25    GND @S9S_MB_2U_LIB.S9S_MB_2U(SCH_1):GND     I7 @S9S_MB_2U_LIB.S9S_MB_2U(SCH_1):PAGE180
   V31    GND @S9S_MB_2U_LIB.S9S_MB_2U(SCH_1):GND     I7 @S9S_MB_2U_LIB.S9S_MB_2U(SCH_1):PAGE180
    V2    GND @S9S_MB_2U_LIB.S9S_MB_2U(SCH_1):GND     I7 @S9S_MB_2U_LIB.S9S_MB_2U(SCH_1):PAGE180
    U5    GND @S9S_MB_2U_LIB.S9S_MB_2U(SCH_1):GND     I7 @S9S_MB_2U_LIB.S9S_MB_2U(SCH_1):PAGE180
   U39    GND @S9S_MB_2U_LIB.S9S_MB_2U(SCH_1):GND     I7 @S9S_MB_2U_LIB.S9S_MB_2U(SCH_1):PAGE180
   U25    GND @S9S_MB_2U_LIB.S9S_MB_2U(SCH_1):GND     I7 @S9S_MB_2U_LIB.S9S_MB_2U(SCH_1):PAGE180
   U13    GND @S9S_MB_2U_LIB.S9S_MB_2U(SCH_1):GND     I7 @S9S_MB_2U_LIB.S9S_MB_2U(SCH_1):PAGE180
   U10    GND @S9S_MB_2U_LIB.S9S_MB_2U(SCH_1):GND     I7 @S9S_MB_2U_LIB.S9S_MB_2U(SCH_1):PAGE180
   T31    GND @S9S_MB_2U_LIB.S9S_MB_2U(SCH_1):GND     I7 @S9S_MB_2U_LIB.S9S_MB_2U(SCH_1):PAGE180
   R36    GND @S9S_MB_2U_LIB.S9S_MB_2U(SCH_1):GND     I7 @S9S_MB_2U_LIB.S9S_MB_2U(SCH_1):PAGE180
   R20    GND @S9S_MB_2U_LIB.S9S_MB_2U(SCH_1):GND     I7 @S9S_MB_2U_LIB.S9S_MB_2U(SCH_1):PAGE180
   R16    GND @S9S_MB_2U_LIB.S9S_MB_2U(SCH_1):GND     I7 @S9S_MB_2U_LIB.S9S_MB_2U(SCH_1):PAGE180
   R13    GND @S9S_MB_2U_LIB.S9S_MB_2U(SCH_1):GND     I7 @S9S_MB_2U_LIB.S9S_MB_2U(SCH_1):PAGE180
    P8    GND @S9S_MB_2U_LIB.S9S_MB_2U(SCH_1):GND     I7 @S9S_MB_2U_LIB.S9S_MB_2U(SCH_1):PAGE180
    P5    GND @S9S_MB_2U_LIB.S9S_MB_2U(SCH_1):GND     I7 @S9S_MB_2U_LIB.S9S_MB_2U(SCH_1):PAGE180
   P43    GND @S9S_MB_2U_LIB.S9S_MB_2U(SCH_1):GND     I7 @S9S_MB_2U_LIB.S9S_MB_2U(SCH_1):PAGE180
   P41    GND @S9S_MB_2U_LIB.S9S_MB_2U(SCH_1):GND     I7 @S9S_MB_2U_LIB.S9S_MB_2U(SCH_1):PAGE180
   P39    GND @S9S_MB_2U_LIB.S9S_MB_2U(SCH_1):GND     I7 @S9S_MB_2U_LIB.S9S_MB_2U(SCH_1):PAGE180
   P37    GND @S9S_MB_2U_LIB.S9S_MB_2U(SCH_1):GND     I7 @S9S_MB_2U_LIB.S9S_MB_2U(SCH_1):PAGE180
   P31    GND @S9S_MB_2U_LIB.S9S_MB_2U(SCH_1):GND     I7 @S9S_MB_2U_LIB.S9S_MB_2U(SCH_1):PAGE180
   P28    GND @S9S_MB_2U_LIB.S9S_MB_2U(SCH_1):GND     I7 @S9S_MB_2U_LIB.S9S_MB_2U(SCH_1):PAGE180
   P24    GND @S9S_MB_2U_LIB.S9S_MB_2U(SCH_1):GND     I7 @S9S_MB_2U_LIB.S9S_MB_2U(SCH_1):PAGE180
   P11    GND @S9S_MB_2U_LIB.S9S_MB_2U(SCH_1):GND     I7 @S9S_MB_2U_LIB.S9S_MB_2U(SCH_1):PAGE180
   N32    GND @S9S_MB_2U_LIB.S9S_MB_2U(SCH_1):GND     I7 @S9S_MB_2U_LIB.S9S_MB_2U(SCH_1):PAGE180
   N16    GND @S9S_MB_2U_LIB.S9S_MB_2U(SCH_1):GND     I7 @S9S_MB_2U_LIB.S9S_MB_2U(SCH_1):PAGE180
    M5    GND @S9S_MB_2U_LIB.S9S_MB_2U(SCH_1):GND     I7 @S9S_MB_2U_LIB.S9S_MB_2U(SCH_1):PAGE180
   M39    GND @S9S_MB_2U_LIB.S9S_MB_2U(SCH_1):GND     I7 @S9S_MB_2U_LIB.S9S_MB_2U(SCH_1):PAGE180
   M37    GND @S9S_MB_2U_LIB.S9S_MB_2U(SCH_1):GND     I7 @S9S_MB_2U_LIB.S9S_MB_2U(SCH_1):PAGE180
   M34    GND @S9S_MB_2U_LIB.S9S_MB_2U(SCH_1):GND     I7 @S9S_MB_2U_LIB.S9S_MB_2U(SCH_1):PAGE180
   M31    GND @S9S_MB_2U_LIB.S9S_MB_2U(SCH_1):GND     I7 @S9S_MB_2U_LIB.S9S_MB_2U(SCH_1):PAGE180
    M3    GND @S9S_MB_2U_LIB.S9S_MB_2U(SCH_1):GND     I7 @S9S_MB_2U_LIB.S9S_MB_2U(SCH_1):PAGE180
   M28    GND @S9S_MB_2U_LIB.S9S_MB_2U(SCH_1):GND     I7 @S9S_MB_2U_LIB.S9S_MB_2U(SCH_1):PAGE180
   M21    GND @S9S_MB_2U_LIB.S9S_MB_2U(SCH_1):GND     I7 @S9S_MB_2U_LIB.S9S_MB_2U(SCH_1):PAGE180
   M18    GND @S9S_MB_2U_LIB.S9S_MB_2U(SCH_1):GND     I7 @S9S_MB_2U_LIB.S9S_MB_2U(SCH_1):PAGE180
   M15    GND @S9S_MB_2U_LIB.S9S_MB_2U(SCH_1):GND     I7 @S9S_MB_2U_LIB.S9S_MB_2U(SCH_1):PAGE180
   M11    GND @S9S_MB_2U_LIB.S9S_MB_2U(SCH_1):GND     I7 @S9S_MB_2U_LIB.S9S_MB_2U(SCH_1):PAGE180
    M1    GND @S9S_MB_2U_LIB.S9S_MB_2U(SCH_1):GND     I7 @S9S_MB_2U_LIB.S9S_MB_2U(SCH_1):PAGE180
   L36    GND @S9S_MB_2U_LIB.S9S_MB_2U(SCH_1):GND     I7 @S9S_MB_2U_LIB.S9S_MB_2U(SCH_1):PAGE180
   L29    GND @S9S_MB_2U_LIB.S9S_MB_2U(SCH_1):GND     I7 @S9S_MB_2U_LIB.S9S_MB_2U(SCH_1):PAGE180
   L26    GND @S9S_MB_2U_LIB.S9S_MB_2U(SCH_1):GND     I7 @S9S_MB_2U_LIB.S9S_MB_2U(SCH_1):PAGE180
   L23    GND @S9S_MB_2U_LIB.S9S_MB_2U(SCH_1):GND     I7 @S9S_MB_2U_LIB.S9S_MB_2U(SCH_1):PAGE180
   L20    GND @S9S_MB_2U_LIB.S9S_MB_2U(SCH_1):GND     I7 @S9S_MB_2U_LIB.S9S_MB_2U(SCH_1):PAGE180
   L16    GND @S9S_MB_2U_LIB.S9S_MB_2U(SCH_1):GND     I7 @S9S_MB_2U_LIB.S9S_MB_2U(SCH_1):PAGE180
   L10    GND @S9S_MB_2U_LIB.S9S_MB_2U(SCH_1):GND     I7 @S9S_MB_2U_LIB.S9S_MB_2U(SCH_1):PAGE180
    K5    GND @S9S_MB_2U_LIB.S9S_MB_2U(SCH_1):GND     I7 @S9S_MB_2U_LIB.S9S_MB_2U(SCH_1):PAGE180
   K39    GND @S9S_MB_2U_LIB.S9S_MB_2U(SCH_1):GND     I7 @S9S_MB_2U_LIB.S9S_MB_2U(SCH_1):PAGE180
   K34    GND @S9S_MB_2U_LIB.S9S_MB_2U(SCH_1):GND     I7 @S9S_MB_2U_LIB.S9S_MB_2U(SCH_1):PAGE180
   K24    GND @S9S_MB_2U_LIB.S9S_MB_2U(SCH_1):GND     I7 @S9S_MB_2U_LIB.S9S_MB_2U(SCH_1):PAGE180
   K15    GND @S9S_MB_2U_LIB.S9S_MB_2U(SCH_1):GND     I7 @S9S_MB_2U_LIB.S9S_MB_2U(SCH_1):PAGE180
   K11    GND @S9S_MB_2U_LIB.S9S_MB_2U(SCH_1):GND     I7 @S9S_MB_2U_LIB.S9S_MB_2U(SCH_1):PAGE180
   J26    GND @S9S_MB_2U_LIB.S9S_MB_2U(SCH_1):GND     I7 @S9S_MB_2U_LIB.S9S_MB_2U(SCH_1):PAGE180
   J20    GND @S9S_MB_2U_LIB.S9S_MB_2U(SCH_1):GND     I7 @S9S_MB_2U_LIB.S9S_MB_2U(SCH_1):PAGE180
   J13    GND @S9S_MB_2U_LIB.S9S_MB_2U(SCH_1):GND     I7 @S9S_MB_2U_LIB.S9S_MB_2U(SCH_1):PAGE180
    H8    GND @S9S_MB_2U_LIB.S9S_MB_2U(SCH_1):GND     I7 @S9S_MB_2U_LIB.S9S_MB_2U(SCH_1):PAGE180
    H5    GND @S9S_MB_2U_LIB.S9S_MB_2U(SCH_1):GND     I7 @S9S_MB_2U_LIB.S9S_MB_2U(SCH_1):PAGE180
   H39    GND @S9S_MB_2U_LIB.S9S_MB_2U(SCH_1):GND     I7 @S9S_MB_2U_LIB.S9S_MB_2U(SCH_1):PAGE180
   G26    GND @S9S_MB_2U_LIB.S9S_MB_2U(SCH_1):GND     I7 @S9S_MB_2U_LIB.S9S_MB_2U(SCH_1):PAGE180
   G20    GND @S9S_MB_2U_LIB.S9S_MB_2U(SCH_1):GND     I7 @S9S_MB_2U_LIB.S9S_MB_2U(SCH_1):PAGE180
   G13    GND @S9S_MB_2U_LIB.S9S_MB_2U(SCH_1):GND     I7 @S9S_MB_2U_LIB.S9S_MB_2U(SCH_1):PAGE180
   F39    GND @S9S_MB_2U_LIB.S9S_MB_2U(SCH_1):GND     I7 @S9S_MB_2U_LIB.S9S_MB_2U(SCH_1):PAGE180
   F34    GND @S9S_MB_2U_LIB.S9S_MB_2U(SCH_1):GND     I7 @S9S_MB_2U_LIB.S9S_MB_2U(SCH_1):PAGE180
   F31    GND @S9S_MB_2U_LIB.S9S_MB_2U(SCH_1):GND     I7 @S9S_MB_2U_LIB.S9S_MB_2U(SCH_1):PAGE180
   F24    GND @S9S_MB_2U_LIB.S9S_MB_2U(SCH_1):GND     I7 @S9S_MB_2U_LIB.S9S_MB_2U(SCH_1):PAGE180
   F15    GND @S9S_MB_2U_LIB.S9S_MB_2U(SCH_1):GND     I7 @S9S_MB_2U_LIB.S9S_MB_2U(SCH_1):PAGE180
    E6    GND @S9S_MB_2U_LIB.S9S_MB_2U(SCH_1):GND     I7 @S9S_MB_2U_LIB.S9S_MB_2U(SCH_1):PAGE180
   E38    GND @S9S_MB_2U_LIB.S9S_MB_2U(SCH_1):GND     I7 @S9S_MB_2U_LIB.S9S_MB_2U(SCH_1):PAGE180
   E36    GND @S9S_MB_2U_LIB.S9S_MB_2U(SCH_1):GND     I7 @S9S_MB_2U_LIB.S9S_MB_2U(SCH_1):PAGE180
   E34    GND @S9S_MB_2U_LIB.S9S_MB_2U(SCH_1):GND     I7 @S9S_MB_2U_LIB.S9S_MB_2U(SCH_1):PAGE180
   E32    GND @S9S_MB_2U_LIB.S9S_MB_2U(SCH_1):GND     I7 @S9S_MB_2U_LIB.S9S_MB_2U(SCH_1):PAGE180
   E30    GND @S9S_MB_2U_LIB.S9S_MB_2U(SCH_1):GND     I7 @S9S_MB_2U_LIB.S9S_MB_2U(SCH_1):PAGE180
   E28    GND @S9S_MB_2U_LIB.S9S_MB_2U(SCH_1):GND     I7 @S9S_MB_2U_LIB.S9S_MB_2U(SCH_1):PAGE180
   E26    GND @S9S_MB_2U_LIB.S9S_MB_2U(SCH_1):GND     I7 @S9S_MB_2U_LIB.S9S_MB_2U(SCH_1):PAGE180
   E24    GND @S9S_MB_2U_LIB.S9S_MB_2U(SCH_1):GND     I7 @S9S_MB_2U_LIB.S9S_MB_2U(SCH_1):PAGE180
   E22    GND @S9S_MB_2U_LIB.S9S_MB_2U(SCH_1):GND     I7 @S9S_MB_2U_LIB.S9S_MB_2U(SCH_1):PAGE180
   E20    GND @S9S_MB_2U_LIB.S9S_MB_2U(SCH_1):GND     I7 @S9S_MB_2U_LIB.S9S_MB_2U(SCH_1):PAGE180
   E18    GND @S9S_MB_2U_LIB.S9S_MB_2U(SCH_1):GND     I7 @S9S_MB_2U_LIB.S9S_MB_2U(SCH_1):PAGE180
   E16    GND @S9S_MB_2U_LIB.S9S_MB_2U(SCH_1):GND     I7 @S9S_MB_2U_LIB.S9S_MB_2U(SCH_1):PAGE180
   E14    GND @S9S_MB_2U_LIB.S9S_MB_2U(SCH_1):GND     I7 @S9S_MB_2U_LIB.S9S_MB_2U(SCH_1):PAGE180
   E12    GND @S9S_MB_2U_LIB.S9S_MB_2U(SCH_1):GND     I7 @S9S_MB_2U_LIB.S9S_MB_2U(SCH_1):PAGE180
   E10    GND @S9S_MB_2U_LIB.S9S_MB_2U(SCH_1):GND     I7 @S9S_MB_2U_LIB.S9S_MB_2U(SCH_1):PAGE180
    D9    GND @S9S_MB_2U_LIB.S9S_MB_2U(SCH_1):GND     I7 @S9S_MB_2U_LIB.S9S_MB_2U(SCH_1):PAGE180
    D5    GND @S9S_MB_2U_LIB.S9S_MB_2U(SCH_1):GND     I7 @S9S_MB_2U_LIB.S9S_MB_2U(SCH_1):PAGE180
   D29    GND @S9S_MB_2U_LIB.S9S_MB_2U(SCH_1):GND     I7 @S9S_MB_2U_LIB.S9S_MB_2U(SCH_1):PAGE180
   D13    GND @S9S_MB_2U_LIB.S9S_MB_2U(SCH_1):GND     I7 @S9S_MB_2U_LIB.S9S_MB_2U(SCH_1):PAGE180
    C4    GND @S9S_MB_2U_LIB.S9S_MB_2U(SCH_1):GND     I7 @S9S_MB_2U_LIB.S9S_MB_2U(SCH_1):PAGE180
   C26    GND @S9S_MB_2U_LIB.S9S_MB_2U(SCH_1):GND     I7 @S9S_MB_2U_LIB.S9S_MB_2U(SCH_1):PAGE180
   C24    GND @S9S_MB_2U_LIB.S9S_MB_2U(SCH_1):GND     I7 @S9S_MB_2U_LIB.S9S_MB_2U(SCH_1):PAGE180
   C22    GND @S9S_MB_2U_LIB.S9S_MB_2U(SCH_1):GND     I7 @S9S_MB_2U_LIB.S9S_MB_2U(SCH_1):PAGE180
   C20    GND @S9S_MB_2U_LIB.S9S_MB_2U(SCH_1):GND     I7 @S9S_MB_2U_LIB.S9S_MB_2U(SCH_1):PAGE180
  BG34    GND @S9S_MB_2U_LIB.S9S_MB_2U(SCH_1):GND     I7 @S9S_MB_2U_LIB.S9S_MB_2U(SCH_1):PAGE180
  BG10    GND @S9S_MB_2U_LIB.S9S_MB_2U(SCH_1):GND     I7 @S9S_MB_2U_LIB.S9S_MB_2U(SCH_1):PAGE180
  BF21    GND @S9S_MB_2U_LIB.S9S_MB_2U(SCH_1):GND     I7 @S9S_MB_2U_LIB.S9S_MB_2U(SCH_1):PAGE180
  BE34    GND @S9S_MB_2U_LIB.S9S_MB_2U(SCH_1):GND     I7 @S9S_MB_2U_LIB.S9S_MB_2U(SCH_1):PAGE180
  BE10    GND @S9S_MB_2U_LIB.S9S_MB_2U(SCH_1):GND     I7 @S9S_MB_2U_LIB.S9S_MB_2U(SCH_1):PAGE180
  BD39    GND @S9S_MB_2U_LIB.S9S_MB_2U(SCH_1):GND     I7 @S9S_MB_2U_LIB.S9S_MB_2U(SCH_1):PAGE180
  BD21    GND @S9S_MB_2U_LIB.S9S_MB_2U(SCH_1):GND     I7 @S9S_MB_2U_LIB.S9S_MB_2U(SCH_1):PAGE180
   BC8    GND @S9S_MB_2U_LIB.S9S_MB_2U(SCH_1):GND     I7 @S9S_MB_2U_LIB.S9S_MB_2U(SCH_1):PAGE180
   BC6    GND @S9S_MB_2U_LIB.S9S_MB_2U(SCH_1):GND     I7 @S9S_MB_2U_LIB.S9S_MB_2U(SCH_1):PAGE180
  BC38    GND @S9S_MB_2U_LIB.S9S_MB_2U(SCH_1):GND     I7 @S9S_MB_2U_LIB.S9S_MB_2U(SCH_1):PAGE180
  BC34    GND @S9S_MB_2U_LIB.S9S_MB_2U(SCH_1):GND     I7 @S9S_MB_2U_LIB.S9S_MB_2U(SCH_1):PAGE180
  BC32    GND @S9S_MB_2U_LIB.S9S_MB_2U(SCH_1):GND     I7 @S9S_MB_2U_LIB.S9S_MB_2U(SCH_1):PAGE180
  BC30    GND @S9S_MB_2U_LIB.S9S_MB_2U(SCH_1):GND     I7 @S9S_MB_2U_LIB.S9S_MB_2U(SCH_1):PAGE180
  BC28    GND @S9S_MB_2U_LIB.S9S_MB_2U(SCH_1):GND     I7 @S9S_MB_2U_LIB.S9S_MB_2U(SCH_1):PAGE180
  BC26    GND @S9S_MB_2U_LIB.S9S_MB_2U(SCH_1):GND     I7 @S9S_MB_2U_LIB.S9S_MB_2U(SCH_1):PAGE180
  BC24    GND @S9S_MB_2U_LIB.S9S_MB_2U(SCH_1):GND     I7 @S9S_MB_2U_LIB.S9S_MB_2U(SCH_1):PAGE180
  BC22    GND @S9S_MB_2U_LIB.S9S_MB_2U(SCH_1):GND     I7 @S9S_MB_2U_LIB.S9S_MB_2U(SCH_1):PAGE180
  BC20    GND @S9S_MB_2U_LIB.S9S_MB_2U(SCH_1):GND     I7 @S9S_MB_2U_LIB.S9S_MB_2U(SCH_1):PAGE180
  BC18    GND @S9S_MB_2U_LIB.S9S_MB_2U(SCH_1):GND     I7 @S9S_MB_2U_LIB.S9S_MB_2U(SCH_1):PAGE180
  BC16    GND @S9S_MB_2U_LIB.S9S_MB_2U(SCH_1):GND     I7 @S9S_MB_2U_LIB.S9S_MB_2U(SCH_1):PAGE180
  BC14    GND @S9S_MB_2U_LIB.S9S_MB_2U(SCH_1):GND     I7 @S9S_MB_2U_LIB.S9S_MB_2U(SCH_1):PAGE180
  BC12    GND @S9S_MB_2U_LIB.S9S_MB_2U(SCH_1):GND     I7 @S9S_MB_2U_LIB.S9S_MB_2U(SCH_1):PAGE180
  BC10    GND @S9S_MB_2U_LIB.S9S_MB_2U(SCH_1):GND     I7 @S9S_MB_2U_LIB.S9S_MB_2U(SCH_1):PAGE180
   BB5    GND @S9S_MB_2U_LIB.S9S_MB_2U(SCH_1):GND     I7 @S9S_MB_2U_LIB.S9S_MB_2U(SCH_1):PAGE180
  BB39    GND @S9S_MB_2U_LIB.S9S_MB_2U(SCH_1):GND     I7 @S9S_MB_2U_LIB.S9S_MB_2U(SCH_1):PAGE180
    B9    GND @S9S_MB_2U_LIB.S9S_MB_2U(SCH_1):GND     I7 @S9S_MB_2U_LIB.S9S_MB_2U(SCH_1):PAGE180
   B29    GND @S9S_MB_2U_LIB.S9S_MB_2U(SCH_1):GND     I7 @S9S_MB_2U_LIB.S9S_MB_2U(SCH_1):PAGE180
   B13    GND @S9S_MB_2U_LIB.S9S_MB_2U(SCH_1):GND     I7 @S9S_MB_2U_LIB.S9S_MB_2U(SCH_1):PAGE180
   AY8    GND @S9S_MB_2U_LIB.S9S_MB_2U(SCH_1):GND     I7 @S9S_MB_2U_LIB.S9S_MB_2U(SCH_1):PAGE180
   AY5    GND @S9S_MB_2U_LIB.S9S_MB_2U(SCH_1):GND     I7 @S9S_MB_2U_LIB.S9S_MB_2U(SCH_1):PAGE180
  AY37    GND @S9S_MB_2U_LIB.S9S_MB_2U(SCH_1):GND     I7 @S9S_MB_2U_LIB.S9S_MB_2U(SCH_1):PAGE180
  AY34    GND @S9S_MB_2U_LIB.S9S_MB_2U(SCH_1):GND     I7 @S9S_MB_2U_LIB.S9S_MB_2U(SCH_1):PAGE180
  AY31    GND @S9S_MB_2U_LIB.S9S_MB_2U(SCH_1):GND     I7 @S9S_MB_2U_LIB.S9S_MB_2U(SCH_1):PAGE180
  AY28    GND @S9S_MB_2U_LIB.S9S_MB_2U(SCH_1):GND     I7 @S9S_MB_2U_LIB.S9S_MB_2U(SCH_1):PAGE180
  AY39    GND @S9S_MB_2U_LIB.S9S_MB_2U(SCH_1):GND     I7 @S9S_MB_2U_LIB.S9S_MB_2U(SCH_1):PAGE180
   F41    GND @S9S_MB_2U_LIB.S9S_MB_2U(SCH_1):GND     I7 @S9S_MB_2U_LIB.S9S_MB_2U(SCH_1):PAGE180
   E40    GND @S9S_MB_2U_LIB.S9S_MB_2U(SCH_1):GND     I7 @S9S_MB_2U_LIB.S9S_MB_2U(SCH_1):PAGE180
   BD5    GND @S9S_MB_2U_LIB.S9S_MB_2U(SCH_1):GND     I7 @S9S_MB_2U_LIB.S9S_MB_2U(SCH_1):PAGE180
  BC36    GND @S9S_MB_2U_LIB.S9S_MB_2U(SCH_1):GND     I7 @S9S_MB_2U_LIB.S9S_MB_2U(SCH_1):PAGE180
   AY3    GND @S9S_MB_2U_LIB.S9S_MB_2U(SCH_1):GND     I7 @S9S_MB_2U_LIB.S9S_MB_2U(SCH_1):PAGE180
   C38    GND @S9S_MB_2U_LIB.S9S_MB_2U(SCH_1):GND     I7 @S9S_MB_2U_LIB.S9S_MB_2U(SCH_1):PAGE180
   B39    GND @S9S_MB_2U_LIB.S9S_MB_2U(SCH_1):GND     I7 @S9S_MB_2U_LIB.S9S_MB_2U(SCH_1):PAGE180
    E8    GND @S9S_MB_2U_LIB.S9S_MB_2U(SCH_1):GND     I7 @S9S_MB_2U_LIB.S9S_MB_2U(SCH_1):PAGE180
   D43    GND @S9S_MB_2U_LIB.S9S_MB_2U(SCH_1):GND     I9 @S9S_MB_2U_LIB.S9S_MB_2U(SCH_1):PAGE180
    D1    GND @S9S_MB_2U_LIB.S9S_MB_2U(SCH_1):GND     I9 @S9S_MB_2U_LIB.S9S_MB_2U(SCH_1):PAGE180
   C43    GND @S9S_MB_2U_LIB.S9S_MB_2U(SCH_1):GND     I9 @S9S_MB_2U_LIB.S9S_MB_2U(SCH_1):PAGE180
   C41    GND @S9S_MB_2U_LIB.S9S_MB_2U(SCH_1):GND     I9 @S9S_MB_2U_LIB.S9S_MB_2U(SCH_1):PAGE180
    C3    GND @S9S_MB_2U_LIB.S9S_MB_2U(SCH_1):GND     I9 @S9S_MB_2U_LIB.S9S_MB_2U(SCH_1):PAGE180
  BG41    GND @S9S_MB_2U_LIB.S9S_MB_2U(SCH_1):GND     I9 @S9S_MB_2U_LIB.S9S_MB_2U(SCH_1):PAGE180
  BE43    GND @S9S_MB_2U_LIB.S9S_MB_2U(SCH_1):GND     I9 @S9S_MB_2U_LIB.S9S_MB_2U(SCH_1):PAGE180
  BE41    GND @S9S_MB_2U_LIB.S9S_MB_2U(SCH_1):GND     I9 @S9S_MB_2U_LIB.S9S_MB_2U(SCH_1):PAGE180
   BE3    GND @S9S_MB_2U_LIB.S9S_MB_2U(SCH_1):GND     I9 @S9S_MB_2U_LIB.S9S_MB_2U(SCH_1):PAGE180
   BE1    GND @S9S_MB_2U_LIB.S9S_MB_2U(SCH_1):GND     I9 @S9S_MB_2U_LIB.S9S_MB_2U(SCH_1):PAGE180
  BD43    GND @S9S_MB_2U_LIB.S9S_MB_2U(SCH_1):GND     I9 @S9S_MB_2U_LIB.S9S_MB_2U(SCH_1):PAGE180
   BD1    GND @S9S_MB_2U_LIB.S9S_MB_2U(SCH_1):GND     I9 @S9S_MB_2U_LIB.S9S_MB_2U(SCH_1):PAGE180
   E42    GND @S9S_MB_2U_LIB.S9S_MB_2U(SCH_1):GND     I9 @S9S_MB_2U_LIB.S9S_MB_2U(SCH_1):PAGE180
    E2    GND @S9S_MB_2U_LIB.S9S_MB_2U(SCH_1):GND     I9 @S9S_MB_2U_LIB.S9S_MB_2U(SCH_1):PAGE180
   D41    GND @S9S_MB_2U_LIB.S9S_MB_2U(SCH_1):GND     I9 @S9S_MB_2U_LIB.S9S_MB_2U(SCH_1):PAGE180
    D3    GND @S9S_MB_2U_LIB.S9S_MB_2U(SCH_1):GND     I9 @S9S_MB_2U_LIB.S9S_MB_2U(SCH_1):PAGE180
  BD41    GND @S9S_MB_2U_LIB.S9S_MB_2U(SCH_1):GND     I9 @S9S_MB_2U_LIB.S9S_MB_2U(SCH_1):PAGE180
   BD3    GND @S9S_MB_2U_LIB.S9S_MB_2U(SCH_1):GND     I9 @S9S_MB_2U_LIB.S9S_MB_2U(SCH_1):PAGE180
  BC42    GND @S9S_MB_2U_LIB.S9S_MB_2U(SCH_1):GND     I9 @S9S_MB_2U_LIB.S9S_MB_2U(SCH_1):PAGE180
   BC2    GND @S9S_MB_2U_LIB.S9S_MB_2U(SCH_1):GND     I9 @S9S_MB_2U_LIB.S9S_MB_2U(SCH_1):PAGE180
   F43    GND @S9S_MB_2U_LIB.S9S_MB_2U(SCH_1):GND     I9 @S9S_MB_2U_LIB.S9S_MB_2U(SCH_1):PAGE180
   BG6    GND @S9S_MB_2U_LIB.S9S_MB_2U(SCH_1):GND     I9 @S9S_MB_2U_LIB.S9S_MB_2U(SCH_1):PAGE180
   BG4    GND @S9S_MB_2U_LIB.S9S_MB_2U(SCH_1):GND     I9 @S9S_MB_2U_LIB.S9S_MB_2U(SCH_1):PAGE180
  BG38    GND @S9S_MB_2U_LIB.S9S_MB_2U(SCH_1):GND     I9 @S9S_MB_2U_LIB.S9S_MB_2U(SCH_1):PAGE180
   BB1    GND @S9S_MB_2U_LIB.S9S_MB_2U(SCH_1):GND     I9 @S9S_MB_2U_LIB.S9S_MB_2U(SCH_1):PAGE180
    A6    GND @S9S_MB_2U_LIB.S9S_MB_2U(SCH_1):GND     I9 @S9S_MB_2U_LIB.S9S_MB_2U(SCH_1):PAGE180
   A40    GND @S9S_MB_2U_LIB.S9S_MB_2U(SCH_1):GND     I9 @S9S_MB_2U_LIB.S9S_MB_2U(SCH_1):PAGE180
   A38    GND @S9S_MB_2U_LIB.S9S_MB_2U(SCH_1):GND     I9 @S9S_MB_2U_LIB.S9S_MB_2U(SCH_1):PAGE180
  AY24    GND @S9S_MB_2U_LIB.S9S_MB_2U(SCH_1):GND     I9 @S9S_MB_2U_LIB.S9S_MB_2U(SCH_1):PAGE180
  AY21    GND @S9S_MB_2U_LIB.S9S_MB_2U(SCH_1):GND     I9 @S9S_MB_2U_LIB.S9S_MB_2U(SCH_1):PAGE180
  AY18    GND @S9S_MB_2U_LIB.S9S_MB_2U(SCH_1):GND     I9 @S9S_MB_2U_LIB.S9S_MB_2U(SCH_1):PAGE180
  AY15    GND @S9S_MB_2U_LIB.S9S_MB_2U(SCH_1):GND     I9 @S9S_MB_2U_LIB.S9S_MB_2U(SCH_1):PAGE180
  AY11    GND @S9S_MB_2U_LIB.S9S_MB_2U(SCH_1):GND     I9 @S9S_MB_2U_LIB.S9S_MB_2U(SCH_1):PAGE180
   AW7    GND @S9S_MB_2U_LIB.S9S_MB_2U(SCH_1):GND     I9 @S9S_MB_2U_LIB.S9S_MB_2U(SCH_1):PAGE180
   AV8    GND @S9S_MB_2U_LIB.S9S_MB_2U(SCH_1):GND     I9 @S9S_MB_2U_LIB.S9S_MB_2U(SCH_1):PAGE180
   AV5    GND @S9S_MB_2U_LIB.S9S_MB_2U(SCH_1):GND     I9 @S9S_MB_2U_LIB.S9S_MB_2U(SCH_1):PAGE180
  AV39    GND @S9S_MB_2U_LIB.S9S_MB_2U(SCH_1):GND     I9 @S9S_MB_2U_LIB.S9S_MB_2U(SCH_1):PAGE180
  AV37    GND @S9S_MB_2U_LIB.S9S_MB_2U(SCH_1):GND     I9 @S9S_MB_2U_LIB.S9S_MB_2U(SCH_1):PAGE180
  AU36    GND @S9S_MB_2U_LIB.S9S_MB_2U(SCH_1):GND     I9 @S9S_MB_2U_LIB.S9S_MB_2U(SCH_1):PAGE180
  AU32    GND @S9S_MB_2U_LIB.S9S_MB_2U(SCH_1):GND     I9 @S9S_MB_2U_LIB.S9S_MB_2U(SCH_1):PAGE180
  AU29    GND @S9S_MB_2U_LIB.S9S_MB_2U(SCH_1):GND     I9 @S9S_MB_2U_LIB.S9S_MB_2U(SCH_1):PAGE180
  AU26    GND @S9S_MB_2U_LIB.S9S_MB_2U(SCH_1):GND     I9 @S9S_MB_2U_LIB.S9S_MB_2U(SCH_1):PAGE180
  AU23    GND @S9S_MB_2U_LIB.S9S_MB_2U(SCH_1):GND     I9 @S9S_MB_2U_LIB.S9S_MB_2U(SCH_1):PAGE180
  AU20    GND @S9S_MB_2U_LIB.S9S_MB_2U(SCH_1):GND     I9 @S9S_MB_2U_LIB.S9S_MB_2U(SCH_1):PAGE180
   AT8    GND @S9S_MB_2U_LIB.S9S_MB_2U(SCH_1):GND     I9 @S9S_MB_2U_LIB.S9S_MB_2U(SCH_1):PAGE180
   AT5    GND @S9S_MB_2U_LIB.S9S_MB_2U(SCH_1):GND     I9 @S9S_MB_2U_LIB.S9S_MB_2U(SCH_1):PAGE180
  AT39    GND @S9S_MB_2U_LIB.S9S_MB_2U(SCH_1):GND     I9 @S9S_MB_2U_LIB.S9S_MB_2U(SCH_1):PAGE180
  AT34    GND @S9S_MB_2U_LIB.S9S_MB_2U(SCH_1):GND     I9 @S9S_MB_2U_LIB.S9S_MB_2U(SCH_1):PAGE180
  AT31    GND @S9S_MB_2U_LIB.S9S_MB_2U(SCH_1):GND     I9 @S9S_MB_2U_LIB.S9S_MB_2U(SCH_1):PAGE180
  AT28    GND @S9S_MB_2U_LIB.S9S_MB_2U(SCH_1):GND     I9 @S9S_MB_2U_LIB.S9S_MB_2U(SCH_1):PAGE180
  AT24    GND @S9S_MB_2U_LIB.S9S_MB_2U(SCH_1):GND     I9 @S9S_MB_2U_LIB.S9S_MB_2U(SCH_1):PAGE180
  AT21    GND @S9S_MB_2U_LIB.S9S_MB_2U(SCH_1):GND     I9 @S9S_MB_2U_LIB.S9S_MB_2U(SCH_1):PAGE180
  AT15    GND @S9S_MB_2U_LIB.S9S_MB_2U(SCH_1):GND     I9 @S9S_MB_2U_LIB.S9S_MB_2U(SCH_1):PAGE180
  AT11    GND @S9S_MB_2U_LIB.S9S_MB_2U(SCH_1):GND     I9 @S9S_MB_2U_LIB.S9S_MB_2U(SCH_1):PAGE180
  AR32    GND @S9S_MB_2U_LIB.S9S_MB_2U(SCH_1):GND     I9 @S9S_MB_2U_LIB.S9S_MB_2U(SCH_1):PAGE180
  AR20    GND @S9S_MB_2U_LIB.S9S_MB_2U(SCH_1):GND     I9 @S9S_MB_2U_LIB.S9S_MB_2U(SCH_1):PAGE180
   AP5    GND @S9S_MB_2U_LIB.S9S_MB_2U(SCH_1):GND     I9 @S9S_MB_2U_LIB.S9S_MB_2U(SCH_1):PAGE180
  AP39    GND @S9S_MB_2U_LIB.S9S_MB_2U(SCH_1):GND     I9 @S9S_MB_2U_LIB.S9S_MB_2U(SCH_1):PAGE180
  AP37    GND @S9S_MB_2U_LIB.S9S_MB_2U(SCH_1):GND     I9 @S9S_MB_2U_LIB.S9S_MB_2U(SCH_1):PAGE180
  AP28    GND @S9S_MB_2U_LIB.S9S_MB_2U(SCH_1):GND     I9 @S9S_MB_2U_LIB.S9S_MB_2U(SCH_1):PAGE180
  AP24    GND @S9S_MB_2U_LIB.S9S_MB_2U(SCH_1):GND     I9 @S9S_MB_2U_LIB.S9S_MB_2U(SCH_1):PAGE180
  AP18    GND @S9S_MB_2U_LIB.S9S_MB_2U(SCH_1):GND     I9 @S9S_MB_2U_LIB.S9S_MB_2U(SCH_1):PAGE180
  AP11    GND @S9S_MB_2U_LIB.S9S_MB_2U(SCH_1):GND     I9 @S9S_MB_2U_LIB.S9S_MB_2U(SCH_1):PAGE180
  AN32    GND @S9S_MB_2U_LIB.S9S_MB_2U(SCH_1):GND     I9 @S9S_MB_2U_LIB.S9S_MB_2U(SCH_1):PAGE180
  AN29    GND @S9S_MB_2U_LIB.S9S_MB_2U(SCH_1):GND     I9 @S9S_MB_2U_LIB.S9S_MB_2U(SCH_1):PAGE180
  AN16    GND @S9S_MB_2U_LIB.S9S_MB_2U(SCH_1):GND     I9 @S9S_MB_2U_LIB.S9S_MB_2U(SCH_1):PAGE180
  AN13    GND @S9S_MB_2U_LIB.S9S_MB_2U(SCH_1):GND     I9 @S9S_MB_2U_LIB.S9S_MB_2U(SCH_1):PAGE180
   AM8    GND @S9S_MB_2U_LIB.S9S_MB_2U(SCH_1):GND     I9 @S9S_MB_2U_LIB.S9S_MB_2U(SCH_1):PAGE180
  AM31    GND @S9S_MB_2U_LIB.S9S_MB_2U(SCH_1):GND     I9 @S9S_MB_2U_LIB.S9S_MB_2U(SCH_1):PAGE180
  AM15    GND @S9S_MB_2U_LIB.S9S_MB_2U(SCH_1):GND     I9 @S9S_MB_2U_LIB.S9S_MB_2U(SCH_1):PAGE180
  AL39    GND @S9S_MB_2U_LIB.S9S_MB_2U(SCH_1):GND     I9 @S9S_MB_2U_LIB.S9S_MB_2U(SCH_1):PAGE180
  AL29    GND @S9S_MB_2U_LIB.S9S_MB_2U(SCH_1):GND     I9 @S9S_MB_2U_LIB.S9S_MB_2U(SCH_1):PAGE180
  AL27    GND @S9S_MB_2U_LIB.S9S_MB_2U(SCH_1):GND     I9 @S9S_MB_2U_LIB.S9S_MB_2U(SCH_1):PAGE180
  AL24    GND @S9S_MB_2U_LIB.S9S_MB_2U(SCH_1):GND     I9 @S9S_MB_2U_LIB.S9S_MB_2U(SCH_1):PAGE180
  AL19    GND @S9S_MB_2U_LIB.S9S_MB_2U(SCH_1):GND     I9 @S9S_MB_2U_LIB.S9S_MB_2U(SCH_1):PAGE180
   AK4    GND @S9S_MB_2U_LIB.S9S_MB_2U(SCH_1):GND     I9 @S9S_MB_2U_LIB.S9S_MB_2U(SCH_1):PAGE180
  AK37    GND @S9S_MB_2U_LIB.S9S_MB_2U(SCH_1):GND     I9 @S9S_MB_2U_LIB.S9S_MB_2U(SCH_1):PAGE180
   AK2    GND @S9S_MB_2U_LIB.S9S_MB_2U(SCH_1):GND     I9 @S9S_MB_2U_LIB.S9S_MB_2U(SCH_1):PAGE180
  AK11    GND @S9S_MB_2U_LIB.S9S_MB_2U(SCH_1):GND     I9 @S9S_MB_2U_LIB.S9S_MB_2U(SCH_1):PAGE180
   AJ5    GND @S9S_MB_2U_LIB.S9S_MB_2U(SCH_1):GND     I9 @S9S_MB_2U_LIB.S9S_MB_2U(SCH_1):PAGE180
  AJ39    GND @S9S_MB_2U_LIB.S9S_MB_2U(SCH_1):GND     I9 @S9S_MB_2U_LIB.S9S_MB_2U(SCH_1):PAGE180
  AJ36    GND @S9S_MB_2U_LIB.S9S_MB_2U(SCH_1):GND     I9 @S9S_MB_2U_LIB.S9S_MB_2U(SCH_1):PAGE180
  AJ29    GND @S9S_MB_2U_LIB.S9S_MB_2U(SCH_1):GND     I9 @S9S_MB_2U_LIB.S9S_MB_2U(SCH_1):PAGE180
  AJ24    GND @S9S_MB_2U_LIB.S9S_MB_2U(SCH_1):GND     I9 @S9S_MB_2U_LIB.S9S_MB_2U(SCH_1):PAGE180
  AJ19    GND @S9S_MB_2U_LIB.S9S_MB_2U(SCH_1):GND     I9 @S9S_MB_2U_LIB.S9S_MB_2U(SCH_1):PAGE180
   AH8    GND @S9S_MB_2U_LIB.S9S_MB_2U(SCH_1):GND     I9 @S9S_MB_2U_LIB.S9S_MB_2U(SCH_1):PAGE180
  AH31    GND @S9S_MB_2U_LIB.S9S_MB_2U(SCH_1):GND     I9 @S9S_MB_2U_LIB.S9S_MB_2U(SCH_1):PAGE180
   AG5    GND @S9S_MB_2U_LIB.S9S_MB_2U(SCH_1):GND     I9 @S9S_MB_2U_LIB.S9S_MB_2U(SCH_1):PAGE180
  AG39    GND @S9S_MB_2U_LIB.S9S_MB_2U(SCH_1):GND     I9 @S9S_MB_2U_LIB.S9S_MB_2U(SCH_1):PAGE180
  AG24    GND @S9S_MB_2U_LIB.S9S_MB_2U(SCH_1):GND     I9 @S9S_MB_2U_LIB.S9S_MB_2U(SCH_1):PAGE180
  AG19    GND @S9S_MB_2U_LIB.S9S_MB_2U(SCH_1):GND     I9 @S9S_MB_2U_LIB.S9S_MB_2U(SCH_1):PAGE180
  AG13    GND @S9S_MB_2U_LIB.S9S_MB_2U(SCH_1):GND     I9 @S9S_MB_2U_LIB.S9S_MB_2U(SCH_1):PAGE180
  AF42    GND @S9S_MB_2U_LIB.S9S_MB_2U(SCH_1):GND     I9 @S9S_MB_2U_LIB.S9S_MB_2U(SCH_1):PAGE180
  AF40    GND @S9S_MB_2U_LIB.S9S_MB_2U(SCH_1):GND     I9 @S9S_MB_2U_LIB.S9S_MB_2U(SCH_1):PAGE180
  AF31    GND @S9S_MB_2U_LIB.S9S_MB_2U(SCH_1):GND     I9 @S9S_MB_2U_LIB.S9S_MB_2U(SCH_1):PAGE180
  AF24    GND @S9S_MB_2U_LIB.S9S_MB_2U(SCH_1):GND     I9 @S9S_MB_2U_LIB.S9S_MB_2U(SCH_1):PAGE180
  AF19    GND @S9S_MB_2U_LIB.S9S_MB_2U(SCH_1):GND     I9 @S9S_MB_2U_LIB.S9S_MB_2U(SCH_1):PAGE180
   AE5    GND @S9S_MB_2U_LIB.S9S_MB_2U(SCH_1):GND     I9 @S9S_MB_2U_LIB.S9S_MB_2U(SCH_1):PAGE180
  AE39    GND @S9S_MB_2U_LIB.S9S_MB_2U(SCH_1):GND     I9 @S9S_MB_2U_LIB.S9S_MB_2U(SCH_1):PAGE180
  AE13    GND @S9S_MB_2U_LIB.S9S_MB_2U(SCH_1):GND     I9 @S9S_MB_2U_LIB.S9S_MB_2U(SCH_1):PAGE180
   AD8    GND @S9S_MB_2U_LIB.S9S_MB_2U(SCH_1):GND     I9 @S9S_MB_2U_LIB.S9S_MB_2U(SCH_1):PAGE180
  AD34    GND @S9S_MB_2U_LIB.S9S_MB_2U(SCH_1):GND     I9 @S9S_MB_2U_LIB.S9S_MB_2U(SCH_1):PAGE180
  AD31    GND @S9S_MB_2U_LIB.S9S_MB_2U(SCH_1):GND     I9 @S9S_MB_2U_LIB.S9S_MB_2U(SCH_1):PAGE180
  AD24    GND @S9S_MB_2U_LIB.S9S_MB_2U(SCH_1):GND     I9 @S9S_MB_2U_LIB.S9S_MB_2U(SCH_1):PAGE180
  AD22    GND @S9S_MB_2U_LIB.S9S_MB_2U(SCH_1):GND     I9 @S9S_MB_2U_LIB.S9S_MB_2U(SCH_1):PAGE180
  AD20    GND @S9S_MB_2U_LIB.S9S_MB_2U(SCH_1):GND     I9 @S9S_MB_2U_LIB.S9S_MB_2U(SCH_1):PAGE180
  AD19    GND @S9S_MB_2U_LIB.S9S_MB_2U(SCH_1):GND     I9 @S9S_MB_2U_LIB.S9S_MB_2U(SCH_1):PAGE180
  AD11    GND @S9S_MB_2U_LIB.S9S_MB_2U(SCH_1):GND     I9 @S9S_MB_2U_LIB.S9S_MB_2U(SCH_1):PAGE180
   AC5    GND @S9S_MB_2U_LIB.S9S_MB_2U(SCH_1):GND     I9 @S9S_MB_2U_LIB.S9S_MB_2U(SCH_1):PAGE180
  AC39    GND @S9S_MB_2U_LIB.S9S_MB_2U(SCH_1):GND     I9 @S9S_MB_2U_LIB.S9S_MB_2U(SCH_1):PAGE180
  AC36    GND @S9S_MB_2U_LIB.S9S_MB_2U(SCH_1):GND     I9 @S9S_MB_2U_LIB.S9S_MB_2U(SCH_1):PAGE180
  AC32    GND @S9S_MB_2U_LIB.S9S_MB_2U(SCH_1):GND     I9 @S9S_MB_2U_LIB.S9S_MB_2U(SCH_1):PAGE180
  AC29    GND @S9S_MB_2U_LIB.S9S_MB_2U(SCH_1):GND     I9 @S9S_MB_2U_LIB.S9S_MB_2U(SCH_1):PAGE180
  AB37    GND @S9S_MB_2U_LIB.S9S_MB_2U(SCH_1):GND     I9 @S9S_MB_2U_LIB.S9S_MB_2U(SCH_1):PAGE180
  AB25    GND @S9S_MB_2U_LIB.S9S_MB_2U(SCH_1):GND     I9 @S9S_MB_2U_LIB.S9S_MB_2U(SCH_1):PAGE180
  AB17    GND @S9S_MB_2U_LIB.S9S_MB_2U(SCH_1):GND     I9 @S9S_MB_2U_LIB.S9S_MB_2U(SCH_1):PAGE180
  AB15    GND @S9S_MB_2U_LIB.S9S_MB_2U(SCH_1):GND     I9 @S9S_MB_2U_LIB.S9S_MB_2U(SCH_1):PAGE180
   AA5    GND @S9S_MB_2U_LIB.S9S_MB_2U(SCH_1):GND     I9 @S9S_MB_2U_LIB.S9S_MB_2U(SCH_1):PAGE180
  AA39    GND @S9S_MB_2U_LIB.S9S_MB_2U(SCH_1):GND     I9 @S9S_MB_2U_LIB.S9S_MB_2U(SCH_1):PAGE180
  AA36    GND @S9S_MB_2U_LIB.S9S_MB_2U(SCH_1):GND     I9 @S9S_MB_2U_LIB.S9S_MB_2U(SCH_1):PAGE180
  AA32    GND @S9S_MB_2U_LIB.S9S_MB_2U(SCH_1):GND     I9 @S9S_MB_2U_LIB.S9S_MB_2U(SCH_1):PAGE180
  AA27    GND @S9S_MB_2U_LIB.S9S_MB_2U(SCH_1):GND     I9 @S9S_MB_2U_LIB.S9S_MB_2U(SCH_1):PAGE180
  AA25    GND @S9S_MB_2U_LIB.S9S_MB_2U(SCH_1):GND     I9 @S9S_MB_2U_LIB.S9S_MB_2U(SCH_1):PAGE180
  AA24    GND @S9S_MB_2U_LIB.S9S_MB_2U(SCH_1):GND     I9 @S9S_MB_2U_LIB.S9S_MB_2U(SCH_1):PAGE180
  AA22    GND @S9S_MB_2U_LIB.S9S_MB_2U(SCH_1):GND     I9 @S9S_MB_2U_LIB.S9S_MB_2U(SCH_1):PAGE180
  AA20    GND @S9S_MB_2U_LIB.S9S_MB_2U(SCH_1):GND     I9 @S9S_MB_2U_LIB.S9S_MB_2U(SCH_1):PAGE180
  AA19    GND @S9S_MB_2U_LIB.S9S_MB_2U(SCH_1):GND     I9 @S9S_MB_2U_LIB.S9S_MB_2U(SCH_1):PAGE180
  AA17    GND @S9S_MB_2U_LIB.S9S_MB_2U(SCH_1):GND     I9 @S9S_MB_2U_LIB.S9S_MB_2U(SCH_1):PAGE180
   A26    GND @S9S_MB_2U_LIB.S9S_MB_2U(SCH_1):GND     I9 @S9S_MB_2U_LIB.S9S_MB_2U(SCH_1):PAGE180
   A24    GND @S9S_MB_2U_LIB.S9S_MB_2U(SCH_1):GND     I9 @S9S_MB_2U_LIB.S9S_MB_2U(SCH_1):PAGE180
   A22    GND @S9S_MB_2U_LIB.S9S_MB_2U(SCH_1):GND     I9 @S9S_MB_2U_LIB.S9S_MB_2U(SCH_1):PAGE180
   A20    GND @S9S_MB_2U_LIB.S9S_MB_2U(SCH_1):GND     I9 @S9S_MB_2U_LIB.S9S_MB_2U(SCH_1):PAGE180

 U13 9SQ440NQQI8-9SQ440NQQI8,SMLF,IA
    A2 CLK_25M_CK440_CPU1_DN @S9S_MB_2U_LIB.S9S_MB_2U(SCH_1):CLK_25M_CK440_CPU1_DN   I180 @S9S_MB_2U_LIB.S9S_MB_2U(SCH_1):PAGE197
    C1    GND @S9S_MB_2U_LIB.S9S_MB_2U(SCH_1):GND   I180 @S9S_MB_2U_LIB.S9S_MB_2U(SCH_1):PAGE197
   A14    GND @S9S_MB_2U_LIB.S9S_MB_2U(SCH_1):GND   I180 @S9S_MB_2U_LIB.S9S_MB_2U(SCH_1):PAGE197
    B9 CLK_CK440_SMB_ADDR1 @S9S_MB_2U_LIB.S9S_MB_2U(SCH_1):CLK_CK440_SMB_ADDR1   I180 @S9S_MB_2U_LIB.S9S_MB_2U(SCH_1):PAGE197
   A54 PD_CK440_SBI_CLK @S9S_MB_2U_LIB.S9S_MB_2U(SCH_1):PD_CK440_SBI_CLK   I180 @S9S_MB_2U_LIB.S9S_MB_2U(SCH_1):PAGE197
   B42 PU_CK440_SHFT_LD_N @S9S_MB_2U_LIB.S9S_MB_2U(SCH_1):PU_CK440_SHFT_LD_N   I180 @S9S_MB_2U_LIB.S9S_MB_2U(SCH_1):PAGE197
   A29 CK440Q_OE_2 @S9S_MB_2U_LIB.S9S_MB_2U(SCH_1):CK440Q_OE_2   I180 @S9S_MB_2U_LIB.S9S_MB_2U(SCH_1):PAGE197
   A26 CK440Q_OE_3 @S9S_MB_2U_LIB.S9S_MB_2U(SCH_1):CK440Q_OE_3   I180 @S9S_MB_2U_LIB.S9S_MB_2U(SCH_1):PAGE197
   B19 CK440Q_OE_4 @S9S_MB_2U_LIB.S9S_MB_2U(SCH_1):CK440Q_OE_4   I180 @S9S_MB_2U_LIB.S9S_MB_2U(SCH_1):PAGE197
   A30 CK440Q_OE_1 @S9S_MB_2U_LIB.S9S_MB_2U(SCH_1):CK440Q_OE_1   I180 @S9S_MB_2U_LIB.S9S_MB_2U(SCH_1):PAGE197
   B15 CK440Q_OE_5 @S9S_MB_2U_LIB.S9S_MB_2U(SCH_1):CK440Q_OE_5   I180 @S9S_MB_2U_LIB.S9S_MB_2U(SCH_1):PAGE197
    A4 CLK_25M_CK440_CPU0_DN @S9S_MB_2U_LIB.S9S_MB_2U(SCH_1):CLK_25M_CK440_CPU0_DN   I180 @S9S_MB_2U_LIB.S9S_MB_2U(SCH_1):PAGE197
    A5 CLK_25M_CK440_CPU0_DP @S9S_MB_2U_LIB.S9S_MB_2U(SCH_1):CLK_25M_CK440_CPU0_DP   I180 @S9S_MB_2U_LIB.S9S_MB_2U(SCH_1):PAGE197
    A3 CLK_25M_CK440_CPU1_DP @S9S_MB_2U_LIB.S9S_MB_2U(SCH_1):CLK_25M_CK440_CPU1_DP   I180 @S9S_MB_2U_LIB.S9S_MB_2U(SCH_1):PAGE197
   A55 CLK_25M_CK440_ISCLK_REF_DN @S9S_MB_2U_LIB.S9S_MB_2U(SCH_1):CLK_25M_CK440_ISCLK_REF_DN   I180 @S9S_MB_2U_LIB.S9S_MB_2U(SCH_1):PAGE197
   A56 CLK_25M_CK440_ISCLK_REF_DP @S9S_MB_2U_LIB.S9S_MB_2U(SCH_1):CLK_25M_CK440_ISCLK_REF_DP   I180 @S9S_MB_2U_LIB.S9S_MB_2U(SCH_1):PAGE197
    A1 FM_CK440Q_DEV_25M_EN @S9S_MB_2U_LIB.S9S_MB_2U(SCH_1):FM_CK440Q_DEV_25M_EN   I180 @S9S_MB_2U_LIB.S9S_MB_2U(SCH_1):PAGE197
   A33 CLK_100M_DB2000_DN @S9S_MB_2U_LIB.S9S_MB_2U(SCH_1):CLK_100M_DB2000_DN   I180 @S9S_MB_2U_LIB.S9S_MB_2U(SCH_1):PAGE197
   A34 CLK_100M_DB2000_DP @S9S_MB_2U_LIB.S9S_MB_2U(SCH_1):CLK_100M_DB2000_DP   I180 @S9S_MB_2U_LIB.S9S_MB_2U(SCH_1):PAGE197
   A31 NC_CLK_CK440_100M1_DN @S9S_MB_2U_LIB.S9S_MB_2U(SCH_1):NC_CLK_CK440_100M1_DN   I180 @S9S_MB_2U_LIB.S9S_MB_2U(SCH_1):PAGE197
   A32 NC_CLK_CK440_100M1_DP @S9S_MB_2U_LIB.S9S_MB_2U(SCH_1):NC_CLK_CK440_100M1_DP   I180 @S9S_MB_2U_LIB.S9S_MB_2U(SCH_1):PAGE197
   A27 NC_CLK_CK440_100M2_DN @S9S_MB_2U_LIB.S9S_MB_2U(SCH_1):NC_CLK_CK440_100M2_DN   I180 @S9S_MB_2U_LIB.S9S_MB_2U(SCH_1):PAGE197
   A28 NC_CLK_CK440_100M2_DP @S9S_MB_2U_LIB.S9S_MB_2U(SCH_1):NC_CLK_CK440_100M2_DP   I180 @S9S_MB_2U_LIB.S9S_MB_2U(SCH_1):PAGE197
   A24 NC_CLK_CK440_100M3_DN @S9S_MB_2U_LIB.S9S_MB_2U(SCH_1):NC_CLK_CK440_100M3_DN   I180 @S9S_MB_2U_LIB.S9S_MB_2U(SCH_1):PAGE197
   A25 NC_CLK_CK440_100M3_DP @S9S_MB_2U_LIB.S9S_MB_2U(SCH_1):NC_CLK_CK440_100M3_DP   I180 @S9S_MB_2U_LIB.S9S_MB_2U(SCH_1):PAGE197
   A22 NC_CLK_CK440_100M4_DN @S9S_MB_2U_LIB.S9S_MB_2U(SCH_1):NC_CLK_CK440_100M4_DN   I180 @S9S_MB_2U_LIB.S9S_MB_2U(SCH_1):PAGE197
   A23 NC_CLK_CK440_100M4_DP @S9S_MB_2U_LIB.S9S_MB_2U(SCH_1):NC_CLK_CK440_100M4_DP   I180 @S9S_MB_2U_LIB.S9S_MB_2U(SCH_1):PAGE197
   A20 NC_CLK_CK440_100M5_DN @S9S_MB_2U_LIB.S9S_MB_2U(SCH_1):NC_CLK_CK440_100M5_DN   I180 @S9S_MB_2U_LIB.S9S_MB_2U(SCH_1):PAGE197
   A21 NC_CLK_CK440_100M5_DP @S9S_MB_2U_LIB.S9S_MB_2U(SCH_1):NC_CLK_CK440_100M5_DP   I180 @S9S_MB_2U_LIB.S9S_MB_2U(SCH_1):PAGE197
   A18 NC_CLK_CK440_100M6_DN @S9S_MB_2U_LIB.S9S_MB_2U(SCH_1):NC_CLK_CK440_100M6_DN   I180 @S9S_MB_2U_LIB.S9S_MB_2U(SCH_1):PAGE197
   A19 NC_CLK_CK440_100M6_DP @S9S_MB_2U_LIB.S9S_MB_2U(SCH_1):NC_CLK_CK440_100M6_DP   I180 @S9S_MB_2U_LIB.S9S_MB_2U(SCH_1):PAGE197
   B10    GND @S9S_MB_2U_LIB.S9S_MB_2U(SCH_1):GND   I180 @S9S_MB_2U_LIB.S9S_MB_2U(SCH_1):PAGE197
   A51 NC_CLK_CK440_MXCK0_DN @S9S_MB_2U_LIB.S9S_MB_2U(SCH_1):NC_CLK_CK440_MXCK0_DN   I180 @S9S_MB_2U_LIB.S9S_MB_2U(SCH_1):PAGE197
   A52 NC_CLK_CK440_MXCK0_DP @S9S_MB_2U_LIB.S9S_MB_2U(SCH_1):NC_CLK_CK440_MXCK0_DP   I180 @S9S_MB_2U_LIB.S9S_MB_2U(SCH_1):PAGE197
   A49 NC_CLK_CK440_MXCK1_DN @S9S_MB_2U_LIB.S9S_MB_2U(SCH_1):NC_CLK_CK440_MXCK1_DN   I180 @S9S_MB_2U_LIB.S9S_MB_2U(SCH_1):PAGE197
   A50 NC_CLK_CK440_MXCK1_DP @S9S_MB_2U_LIB.S9S_MB_2U(SCH_1):NC_CLK_CK440_MXCK1_DP   I180 @S9S_MB_2U_LIB.S9S_MB_2U(SCH_1):PAGE197
   A47 CLK_100M_CK440_PCH_EXTCLK_R_DN @S9S_MB_2U_LIB.S9S_MB_2U(SCH_1):CLK_100M_CK440_PCH_EXTCLK_R_DN   I180 @S9S_MB_2U_LIB.S9S_MB_2U(SCH_1):PAGE197
   A48 CLK_100M_CK440_PCH_EXTCLK_R_DP @S9S_MB_2U_LIB.S9S_MB_2U(SCH_1):CLK_100M_CK440_PCH_EXTCLK_R_DP   I180 @S9S_MB_2U_LIB.S9S_MB_2U(SCH_1):PAGE197
   A45 NC_CLK_CK440_MXCK3_DN @S9S_MB_2U_LIB.S9S_MB_2U(SCH_1):NC_CLK_CK440_MXCK3_DN   I180 @S9S_MB_2U_LIB.S9S_MB_2U(SCH_1):PAGE197
   A46 NC_CLK_CK440_MXCK3_DP @S9S_MB_2U_LIB.S9S_MB_2U(SCH_1):NC_CLK_CK440_MXCK3_DP   I180 @S9S_MB_2U_LIB.S9S_MB_2U(SCH_1):PAGE197
   A43 NC_CLK_CK440_MXCK4_DN @S9S_MB_2U_LIB.S9S_MB_2U(SCH_1):NC_CLK_CK440_MXCK4_DN   I180 @S9S_MB_2U_LIB.S9S_MB_2U(SCH_1):PAGE197
   A44 NC_CLK_CK440_MXCK4_DP @S9S_MB_2U_LIB.S9S_MB_2U(SCH_1):NC_CLK_CK440_MXCK4_DP   I180 @S9S_MB_2U_LIB.S9S_MB_2U(SCH_1):PAGE197
   A41 NC_CLK_CK440_MXCK5_DN @S9S_MB_2U_LIB.S9S_MB_2U(SCH_1):NC_CLK_CK440_MXCK5_DN   I180 @S9S_MB_2U_LIB.S9S_MB_2U(SCH_1):PAGE197
   A42 NC_CLK_CK440_MXCK5_DP @S9S_MB_2U_LIB.S9S_MB_2U(SCH_1):NC_CLK_CK440_MXCK5_DP   I180 @S9S_MB_2U_LIB.S9S_MB_2U(SCH_1):PAGE197
   A39 NC_CLK_CK440_MXCK6_DN @S9S_MB_2U_LIB.S9S_MB_2U(SCH_1):NC_CLK_CK440_MXCK6_DN   I180 @S9S_MB_2U_LIB.S9S_MB_2U(SCH_1):PAGE197
   A40 NC_CLK_CK440_MXCK6_DP @S9S_MB_2U_LIB.S9S_MB_2U(SCH_1):NC_CLK_CK440_MXCK6_DP   I180 @S9S_MB_2U_LIB.S9S_MB_2U(SCH_1):PAGE197
   A37 NC_CLK_CK440_MXCK7_DN @S9S_MB_2U_LIB.S9S_MB_2U(SCH_1):NC_CLK_CK440_MXCK7_DN   I180 @S9S_MB_2U_LIB.S9S_MB_2U(SCH_1):PAGE197
   A38 NC_CLK_CK440_MXCK7_DP @S9S_MB_2U_LIB.S9S_MB_2U(SCH_1):NC_CLK_CK440_MXCK7_DP   I180 @S9S_MB_2U_LIB.S9S_MB_2U(SCH_1):PAGE197
   A35 NC_CLK_CK440_MXCK8_DN @S9S_MB_2U_LIB.S9S_MB_2U(SCH_1):NC_CLK_CK440_MXCK8_DN   I180 @S9S_MB_2U_LIB.S9S_MB_2U(SCH_1):PAGE197
   A36 NC_CLK_CK440_MXCK8_DP @S9S_MB_2U_LIB.S9S_MB_2U(SCH_1):NC_CLK_CK440_MXCK8_DP   I180 @S9S_MB_2U_LIB.S9S_MB_2U(SCH_1):PAGE197
   B38 FM_CK440_MXCK_25M_100M @S9S_MB_2U_LIB.S9S_MB_2U(SCH_1):FM_CK440_MXCK_25M_100M   I180 @S9S_MB_2U_LIB.S9S_MB_2U(SCH_1):PAGE197
   B12    GND @S9S_MB_2U_LIB.S9S_MB_2U(SCH_1):GND   I180 @S9S_MB_2U_LIB.S9S_MB_2U(SCH_1):PAGE197
   B27 FM_CLK_GEN1_OE0_N @S9S_MB_2U_LIB.S9S_MB_2U(SCH_1):FM_CLK_GEN1_OE0_N   I180 @S9S_MB_2U_LIB.S9S_MB_2U(SCH_1):PAGE197
   B14 CK440Q_OE_6 @S9S_MB_2U_LIB.S9S_MB_2U(SCH_1):CK440Q_OE_6   I180 @S9S_MB_2U_LIB.S9S_MB_2U(SCH_1):PAGE197
    A9 TP_CLK_PFT_IN_DN @S9S_MB_2U_LIB.S9S_MB_2U(SCH_1):TP_CLK_PFT_IN_DN   I180 @S9S_MB_2U_LIB.S9S_MB_2U(SCH_1):PAGE197
    A8 TP_CLK_PFT_IN_DP @S9S_MB_2U_LIB.S9S_MB_2U(SCH_1):TP_CLK_PFT_IN_DP   I180 @S9S_MB_2U_LIB.S9S_MB_2U(SCH_1):PAGE197
    B4 PU_CLK_PFT_LOST_N @S9S_MB_2U_LIB.S9S_MB_2U(SCH_1):PU_CLK_PFT_LOST_N   I180 @S9S_MB_2U_LIB.S9S_MB_2U(SCH_1):PAGE197
    A7 TP_CLK_CK440_PFT_OUT_DN @S9S_MB_2U_LIB.S9S_MB_2U(SCH_1):TP_CLK_CK440_PFT_OUT_DN   I180 @S9S_MB_2U_LIB.S9S_MB_2U(SCH_1):PAGE197
    A6 TP_CLK_CK440_PFT_OUT_DP @S9S_MB_2U_LIB.S9S_MB_2U(SCH_1):TP_CLK_CK440_PFT_OUT_DP   I180 @S9S_MB_2U_LIB.S9S_MB_2U(SCH_1):PAGE197
   A17 FM_PLD_CLKS_DEV_EN @S9S_MB_2U_LIB.S9S_MB_2U(SCH_1):FM_PLD_CLKS_DEV_EN   I180 @S9S_MB_2U_LIB.S9S_MB_2U(SCH_1):PAGE197
   B43 PD_CK440_SBI_DATA_IN @S9S_MB_2U_LIB.S9S_MB_2U(SCH_1):PD_CK440_SBI_DATA_IN   I180 @S9S_MB_2U_LIB.S9S_MB_2U(SCH_1):PAGE197
   A53 TP_CK440_SBI_DATA_OUT @S9S_MB_2U_LIB.S9S_MB_2U(SCH_1):TP_CK440_SBI_DATA_OUT   I180 @S9S_MB_2U_LIB.S9S_MB_2U(SCH_1):PAGE197
   A10 SMB_HOST_CLK_3V3AUX_SCL @S9S_MB_2U_LIB.S9S_MB_2U(SCH_1):SMB_HOST_CLK_3V3AUX_SCL   I180 @S9S_MB_2U_LIB.S9S_MB_2U(SCH_1):PAGE197
    B8 SMB_HOST_CLK_3V3AUX_SDA @S9S_MB_2U_LIB.S9S_MB_2U(SCH_1):SMB_HOST_CLK_3V3AUX_SDA   I180 @S9S_MB_2U_LIB.S9S_MB_2U(SCH_1):PAGE197
   A11 CLK_CK440_SMB_ADDR0 @S9S_MB_2U_LIB.S9S_MB_2U(SCH_1):CLK_CK440_SMB_ADDR0   I180 @S9S_MB_2U_LIB.S9S_MB_2U(SCH_1):PAGE197
   A16 FM_CLK_CK440_SS_EN @S9S_MB_2U_LIB.S9S_MB_2U(SCH_1):FM_CLK_CK440_SS_EN   I180 @S9S_MB_2U_LIB.S9S_MB_2U(SCH_1):PAGE197
    B1 P3V3_AUX_CLK_GEN_VDDA25M_CK440 @S9S_MB_2U_LIB.S9S_MB_2U(SCH_1):P3V3_AUX_CLK_GEN_VDDA25M_CK440   I180 @S9S_MB_2U_LIB.S9S_MB_2U(SCH_1):PAGE197
   B17 P3V3_AUX_CLK_GEN_VDDA100M_CK440 @S9S_MB_2U_LIB.S9S_MB_2U(SCH_1):P3V3_AUX_CLK_GEN_VDDA100M_CK440   I180 @S9S_MB_2U_LIB.S9S_MB_2U(SCH_1):PAGE197
    B6 P3V3_AUX_CLK_GEN_VDDPT_CK440 @S9S_MB_2U_LIB.S9S_MB_2U(SCH_1):P3V3_AUX_CLK_GEN_VDDPT_CK440   I180 @S9S_MB_2U_LIB.S9S_MB_2U(SCH_1):PAGE197
   A12 P3V3_AUX_CLK_GEN_VDDXTAL_CK440 @S9S_MB_2U_LIB.S9S_MB_2U(SCH_1):P3V3_AUX_CLK_GEN_VDDXTAL_CK440   I180 @S9S_MB_2U_LIB.S9S_MB_2U(SCH_1):PAGE197
   A13 XTAL_CLK_GEN1_25M_X1 @S9S_MB_2U_LIB.S9S_MB_2U(SCH_1):XTAL_CLK_GEN1_25M_X1   I180 @S9S_MB_2U_LIB.S9S_MB_2U(SCH_1):PAGE197
   B11 XTAL_CLK_GEN1_25M_X2 @S9S_MB_2U_LIB.S9S_MB_2U(SCH_1):XTAL_CLK_GEN1_25M_X2   I180 @S9S_MB_2U_LIB.S9S_MB_2U(SCH_1):PAGE197
   B29 P3V3_AUX_CLK_GEN_VDDMXCK_CK440 @S9S_MB_2U_LIB.S9S_MB_2U(SCH_1):P3V3_AUX_CLK_GEN_VDDMXCK_CK440   I180 @S9S_MB_2U_LIB.S9S_MB_2U(SCH_1):PAGE197
   B32 P3V3_AUX_CLK_GEN_VDDMXCK_CK440 @S9S_MB_2U_LIB.S9S_MB_2U(SCH_1):P3V3_AUX_CLK_GEN_VDDMXCK_CK440   I180 @S9S_MB_2U_LIB.S9S_MB_2U(SCH_1):PAGE197
   B35 P3V3_AUX_CLK_GEN_VDDMXCK_CK440 @S9S_MB_2U_LIB.S9S_MB_2U(SCH_1):P3V3_AUX_CLK_GEN_VDDMXCK_CK440   I180 @S9S_MB_2U_LIB.S9S_MB_2U(SCH_1):PAGE197
   B40 P3V3_AUX_CLK_GEN_VDDMXCK_CK440 @S9S_MB_2U_LIB.S9S_MB_2U(SCH_1):P3V3_AUX_CLK_GEN_VDDMXCK_CK440   I180 @S9S_MB_2U_LIB.S9S_MB_2U(SCH_1):PAGE197
   B21 P3V3_AUX_CLK_GEN_VDD_CK440 @S9S_MB_2U_LIB.S9S_MB_2U(SCH_1):P3V3_AUX_CLK_GEN_VDD_CK440   I180 @S9S_MB_2U_LIB.S9S_MB_2U(SCH_1):PAGE197
   B23 P3V3_AUX_CLK_GEN_VDD_CK440 @S9S_MB_2U_LIB.S9S_MB_2U(SCH_1):P3V3_AUX_CLK_GEN_VDD_CK440   I180 @S9S_MB_2U_LIB.S9S_MB_2U(SCH_1):PAGE197
   B22 NC_CK440_B22 @S9S_MB_2U_LIB.S9S_MB_2U(SCH_1):NC_CK440_B22   I288 @S9S_MB_2U_LIB.S9S_MB_2U(SCH_1):PAGE197
   B20 NC_CK440_B20 @S9S_MB_2U_LIB.S9S_MB_2U(SCH_1):NC_CK440_B20   I288 @S9S_MB_2U_LIB.S9S_MB_2U(SCH_1):PAGE197
   B18 NC_CK440_B18 @S9S_MB_2U_LIB.S9S_MB_2U(SCH_1):NC_CK440_B18   I288 @S9S_MB_2U_LIB.S9S_MB_2U(SCH_1):PAGE197
   B16 NC_CK440_B16 @S9S_MB_2U_LIB.S9S_MB_2U(SCH_1):NC_CK440_B16   I288 @S9S_MB_2U_LIB.S9S_MB_2U(SCH_1):PAGE197
   B13 NC_CK440_B13 @S9S_MB_2U_LIB.S9S_MB_2U(SCH_1):NC_CK440_B13   I288 @S9S_MB_2U_LIB.S9S_MB_2U(SCH_1):PAGE197
    B7 NC_CK440_B7 @S9S_MB_2U_LIB.S9S_MB_2U(SCH_1):NC_CK440_B7   I288 @S9S_MB_2U_LIB.S9S_MB_2U(SCH_1):PAGE197
    B5 NC_CK440_B5 @S9S_MB_2U_LIB.S9S_MB_2U(SCH_1):NC_CK440_B5   I288 @S9S_MB_2U_LIB.S9S_MB_2U(SCH_1):PAGE197
    B3 NC_CK440_B3 @S9S_MB_2U_LIB.S9S_MB_2U(SCH_1):NC_CK440_B3   I288 @S9S_MB_2U_LIB.S9S_MB_2U(SCH_1):PAGE197
    B2 NC_CK440_B2 @S9S_MB_2U_LIB.S9S_MB_2U(SCH_1):NC_CK440_B2   I288 @S9S_MB_2U_LIB.S9S_MB_2U(SCH_1):PAGE197
   A15 NC_CK440_A15 @S9S_MB_2U_LIB.S9S_MB_2U(SCH_1):NC_CK440_A15   I288 @S9S_MB_2U_LIB.S9S_MB_2U(SCH_1):PAGE197
   B24 NC_CK440_B24 @S9S_MB_2U_LIB.S9S_MB_2U(SCH_1):NC_CK440_B24   I288 @S9S_MB_2U_LIB.S9S_MB_2U(SCH_1):PAGE197
   B25 NC_CK440_B25 @S9S_MB_2U_LIB.S9S_MB_2U(SCH_1):NC_CK440_B25   I288 @S9S_MB_2U_LIB.S9S_MB_2U(SCH_1):PAGE197
   B26 NC_CK440_B26 @S9S_MB_2U_LIB.S9S_MB_2U(SCH_1):NC_CK440_B26   I288 @S9S_MB_2U_LIB.S9S_MB_2U(SCH_1):PAGE197
   B28 NC_CK440_B28 @S9S_MB_2U_LIB.S9S_MB_2U(SCH_1):NC_CK440_B28   I288 @S9S_MB_2U_LIB.S9S_MB_2U(SCH_1):PAGE197
   B30 NC_CK440_B30 @S9S_MB_2U_LIB.S9S_MB_2U(SCH_1):NC_CK440_B30   I288 @S9S_MB_2U_LIB.S9S_MB_2U(SCH_1):PAGE197
   B31 NC_CK440_B31 @S9S_MB_2U_LIB.S9S_MB_2U(SCH_1):NC_CK440_B31   I288 @S9S_MB_2U_LIB.S9S_MB_2U(SCH_1):PAGE197
   B33 NC_CK440_B33 @S9S_MB_2U_LIB.S9S_MB_2U(SCH_1):NC_CK440_B33   I288 @S9S_MB_2U_LIB.S9S_MB_2U(SCH_1):PAGE197
   B34 NC_CK440_B34 @S9S_MB_2U_LIB.S9S_MB_2U(SCH_1):NC_CK440_B34   I288 @S9S_MB_2U_LIB.S9S_MB_2U(SCH_1):PAGE197
   B36 NC_CK440_B36 @S9S_MB_2U_LIB.S9S_MB_2U(SCH_1):NC_CK440_B36   I288 @S9S_MB_2U_LIB.S9S_MB_2U(SCH_1):PAGE197
   B37 NC_CK440_B37 @S9S_MB_2U_LIB.S9S_MB_2U(SCH_1):NC_CK440_B37   I288 @S9S_MB_2U_LIB.S9S_MB_2U(SCH_1):PAGE197
   B39 NC_CK440_B39 @S9S_MB_2U_LIB.S9S_MB_2U(SCH_1):NC_CK440_B39   I288 @S9S_MB_2U_LIB.S9S_MB_2U(SCH_1):PAGE197
   B41 NC_CK440_B41 @S9S_MB_2U_LIB.S9S_MB_2U(SCH_1):NC_CK440_B41   I288 @S9S_MB_2U_LIB.S9S_MB_2U(SCH_1):PAGE197
   B44 NC_CK440_B44 @S9S_MB_2U_LIB.S9S_MB_2U(SCH_1):NC_CK440_B44   I288 @S9S_MB_2U_LIB.S9S_MB_2U(SCH_1):PAGE197

 U14 QS3VH257QG8_SMLF-QS3VH257QG8,IA
     1 FM_SPD_REMOTE_EN @S9S_MB_2U_LIB.S9S_MB_2U(SCH_1):FM_SPD_REMOTE_EN    I12 @S9S_MB_2U_LIB.S9S_MB_2U(SCH_1):PAGE218
    15 PD_I3C_SPD_DDR_CPU1_OE_N @S9S_MB_2U_LIB.S9S_MB_2U(SCH_1):PD_I3C_SPD_DDR_CPU1_OE_N    I12 @S9S_MB_2U_LIB.S9S_MB_2U(SCH_1):PAGE218
     4 I3C_SPD_DDRABCD_CPU1_LVC1_R_SCL @S9S_MB_2U_LIB.S9S_MB_2U(SCH_1):I3C_SPD_DDRABCD_CPU1_LVC1_R_SCL    I12 @S9S_MB_2U_LIB.S9S_MB_2U(SCH_1):PAGE218
     2 I3C_SPD_DDRABCD_CPU1_R_SCL @S9S_MB_2U_LIB.S9S_MB_2U(SCH_1):I3C_SPD_DDRABCD_CPU1_R_SCL    I12 @S9S_MB_2U_LIB.S9S_MB_2U(SCH_1):PAGE218
     3 I3C_SPD_DDRABCD_CPU1_BMC_SCL @S9S_MB_2U_LIB.S9S_MB_2U(SCH_1):I3C_SPD_DDRABCD_CPU1_BMC_SCL    I12 @S9S_MB_2U_LIB.S9S_MB_2U(SCH_1):PAGE218
     5 I3C_SPD_DDRABCD_CPU1_R_SDA @S9S_MB_2U_LIB.S9S_MB_2U(SCH_1):I3C_SPD_DDRABCD_CPU1_R_SDA    I12 @S9S_MB_2U_LIB.S9S_MB_2U(SCH_1):PAGE218
     6 I3C_SPD_DDRABCD_CPU1_BMC_SDA @S9S_MB_2U_LIB.S9S_MB_2U(SCH_1):I3C_SPD_DDRABCD_CPU1_BMC_SDA    I12 @S9S_MB_2U_LIB.S9S_MB_2U(SCH_1):PAGE218
     7 I3C_SPD_DDRABCD_CPU1_LVC1_R_SDA @S9S_MB_2U_LIB.S9S_MB_2U(SCH_1):I3C_SPD_DDRABCD_CPU1_LVC1_R_SDA    I12 @S9S_MB_2U_LIB.S9S_MB_2U(SCH_1):PAGE218
    11 I3C_SPD_DDREFGH_CPU1_R_SCL @S9S_MB_2U_LIB.S9S_MB_2U(SCH_1):I3C_SPD_DDREFGH_CPU1_R_SCL    I12 @S9S_MB_2U_LIB.S9S_MB_2U(SCH_1):PAGE218
    10 I3C_SPD_DDREFGH_CPU1_BMC_SCL @S9S_MB_2U_LIB.S9S_MB_2U(SCH_1):I3C_SPD_DDREFGH_CPU1_BMC_SCL    I12 @S9S_MB_2U_LIB.S9S_MB_2U(SCH_1):PAGE218
     9 I3C_SPD_DDREFGH_CPU1_LVC1_R_SCL @S9S_MB_2U_LIB.S9S_MB_2U(SCH_1):I3C_SPD_DDREFGH_CPU1_LVC1_R_SCL    I12 @S9S_MB_2U_LIB.S9S_MB_2U(SCH_1):PAGE218
    12 I3C_SPD_DDREFGH_CPU1_LVC1_R_SDA @S9S_MB_2U_LIB.S9S_MB_2U(SCH_1):I3C_SPD_DDREFGH_CPU1_LVC1_R_SDA    I12 @S9S_MB_2U_LIB.S9S_MB_2U(SCH_1):PAGE218
    14 I3C_SPD_DDREFGH_CPU1_R_SDA @S9S_MB_2U_LIB.S9S_MB_2U(SCH_1):I3C_SPD_DDREFGH_CPU1_R_SDA    I12 @S9S_MB_2U_LIB.S9S_MB_2U(SCH_1):PAGE218
    13 I3C_SPD_DDREFGH_CPU1_BMC_SDA @S9S_MB_2U_LIB.S9S_MB_2U(SCH_1):I3C_SPD_DDREFGH_CPU1_BMC_SDA    I12 @S9S_MB_2U_LIB.S9S_MB_2U(SCH_1):PAGE218
     8    GND @S9S_MB_2U_LIB.S9S_MB_2U(SCH_1):GND    I12 @S9S_MB_2U_LIB.S9S_MB_2U(SCH_1):PAGE218
    16 P3V3_AUX @S9S_MB_2U_LIB.S9S_MB_2U(SCH_1):P3V3_AUX    I12 @S9S_MB_2U_LIB.S9S_MB_2U(SCH_1):PAGE218

 U15 QS3VH257QG8_SMLF-QS3VH257QG8,IA
     1 FM_SPD_REMOTE_EN @S9S_MB_2U_LIB.S9S_MB_2U(SCH_1):FM_SPD_REMOTE_EN    I19 @S9S_MB_2U_LIB.S9S_MB_2U(SCH_1):PAGE217
    15 PD_I3C_SPD_DDR_CPU0_OE_N @S9S_MB_2U_LIB.S9S_MB_2U(SCH_1):PD_I3C_SPD_DDR_CPU0_OE_N    I19 @S9S_MB_2U_LIB.S9S_MB_2U(SCH_1):PAGE217
     4 I3C_SPD_DDRABCD_CPU0_LVC1_R_SCL @S9S_MB_2U_LIB.S9S_MB_2U(SCH_1):I3C_SPD_DDRABCD_CPU0_LVC1_R_SCL    I19 @S9S_MB_2U_LIB.S9S_MB_2U(SCH_1):PAGE217
     2 I3C_SPD_DDRABCD_CPU0_R_SCL @S9S_MB_2U_LIB.S9S_MB_2U(SCH_1):I3C_SPD_DDRABCD_CPU0_R_SCL    I19 @S9S_MB_2U_LIB.S9S_MB_2U(SCH_1):PAGE217
     3 I3C_SPD_DDRABCD_CPU0_BMC_SCL @S9S_MB_2U_LIB.S9S_MB_2U(SCH_1):I3C_SPD_DDRABCD_CPU0_BMC_SCL    I19 @S9S_MB_2U_LIB.S9S_MB_2U(SCH_1):PAGE217
     5 I3C_SPD_DDRABCD_CPU0_R_SDA @S9S_MB_2U_LIB.S9S_MB_2U(SCH_1):I3C_SPD_DDRABCD_CPU0_R_SDA    I19 @S9S_MB_2U_LIB.S9S_MB_2U(SCH_1):PAGE217
     6 I3C_SPD_DDRABCD_CPU0_BMC_SDA @S9S_MB_2U_LIB.S9S_MB_2U(SCH_1):I3C_SPD_DDRABCD_CPU0_BMC_SDA    I19 @S9S_MB_2U_LIB.S9S_MB_2U(SCH_1):PAGE217
     7 I3C_SPD_DDRABCD_CPU0_LVC1_R_SDA @S9S_MB_2U_LIB.S9S_MB_2U(SCH_1):I3C_SPD_DDRABCD_CPU0_LVC1_R_SDA    I19 @S9S_MB_2U_LIB.S9S_MB_2U(SCH_1):PAGE217
    11 I3C_SPD_DDREFGH_CPU0_R_SCL @S9S_MB_2U_LIB.S9S_MB_2U(SCH_1):I3C_SPD_DDREFGH_CPU0_R_SCL    I19 @S9S_MB_2U_LIB.S9S_MB_2U(SCH_1):PAGE217
    10 I3C_SPD_DDREFGH_CPU0_BMC_SCL @S9S_MB_2U_LIB.S9S_MB_2U(SCH_1):I3C_SPD_DDREFGH_CPU0_BMC_SCL    I19 @S9S_MB_2U_LIB.S9S_MB_2U(SCH_1):PAGE217
     9 I3C_SPD_DDREFGH_CPU0_LVC1_R_SCL @S9S_MB_2U_LIB.S9S_MB_2U(SCH_1):I3C_SPD_DDREFGH_CPU0_LVC1_R_SCL    I19 @S9S_MB_2U_LIB.S9S_MB_2U(SCH_1):PAGE217
    12 I3C_SPD_DDREFGH_CPU0_LVC1_R_SDA @S9S_MB_2U_LIB.S9S_MB_2U(SCH_1):I3C_SPD_DDREFGH_CPU0_LVC1_R_SDA    I19 @S9S_MB_2U_LIB.S9S_MB_2U(SCH_1):PAGE217
    14 I3C_SPD_DDREFGH_CPU0_R_SDA @S9S_MB_2U_LIB.S9S_MB_2U(SCH_1):I3C_SPD_DDREFGH_CPU0_R_SDA    I19 @S9S_MB_2U_LIB.S9S_MB_2U(SCH_1):PAGE217
    13 I3C_SPD_DDREFGH_CPU0_BMC_SDA @S9S_MB_2U_LIB.S9S_MB_2U(SCH_1):I3C_SPD_DDREFGH_CPU0_BMC_SDA    I19 @S9S_MB_2U_LIB.S9S_MB_2U(SCH_1):PAGE217
     8    GND @S9S_MB_2U_LIB.S9S_MB_2U(SCH_1):GND    I19 @S9S_MB_2U_LIB.S9S_MB_2U(SCH_1):PAGE217
    16 P3V3_AUX @S9S_MB_2U_LIB.S9S_MB_2U(SCH_1):P3V3_AUX    I19 @S9S_MB_2U_LIB.S9S_MB_2U(SCH_1):PAGE217

 U16 74LVC1G66GV-74LVC1G66GV,SMLF,IA
     1 JTAG_CPU0_MUX_GTL_TDO @S9S_MB_2U_LIB.S9S_MB_2U(SCH_1):JTAG_CPU0_MUX_GTL_TDO   I115 @S9S_MB_2U_LIB.S9S_MB_2U(SCH_1):PAGE135
     2 JTAG_MUX_CPU1_GTL_TDI @S9S_MB_2U_LIB.S9S_MB_2U(SCH_1):JTAG_MUX_CPU1_GTL_TDI   I115 @S9S_MB_2U_LIB.S9S_MB_2U(SCH_1):PAGE135
     3    GND @S9S_MB_2U_LIB.S9S_MB_2U(SCH_1):GND   I115 @S9S_MB_2U_LIB.S9S_MB_2U(SCH_1):PAGE135
     4 FM_CPU_EN_R @S9S_MB_2U_LIB.S9S_MB_2U(SCH_1):FM_CPU_EN_R   I115 @S9S_MB_2U_LIB.S9S_MB_2U(SCH_1):PAGE135
     5 P3V3_AUX @S9S_MB_2U_LIB.S9S_MB_2U(SCH_1):P3V3_AUX   I115 @S9S_MB_2U_LIB.S9S_MB_2U(SCH_1):PAGE135

 U17 74CBTLV3126PW-74CBTLV3126PW,SMA
     5 JTAG_DBP_TDI @S9S_MB_2U_LIB.S9S_MB_2U(SCH_1):JTAG_DBP_TDI    I80 @S9S_MB_2U_LIB.S9S_MB_2U(SCH_1):PAGE134
     8 TP_74CB_B8 @S9S_MB_2U_LIB.S9S_MB_2U(SCH_1):TP_74CB_B8    I80 @S9S_MB_2U_LIB.S9S_MB_2U(SCH_1):PAGE134
     1 PWRGD_PVNN_MAIN_CPU0 @S9S_MB_2U_LIB.S9S_MB_2U(SCH_1):PWRGD_PVNN_MAIN_CPU0    I80 @S9S_MB_2U_LIB.S9S_MB_2U(SCH_1):PAGE134
     4 PWRGD_PVNN_MAIN_CPU0 @S9S_MB_2U_LIB.S9S_MB_2U(SCH_1):PWRGD_PVNN_MAIN_CPU0    I80 @S9S_MB_2U_LIB.S9S_MB_2U(SCH_1):PAGE134
     3 JTAG_DBP_CPU_QS_GTL_TMS @S9S_MB_2U_LIB.S9S_MB_2U(SCH_1):JTAG_DBP_CPU_QS_GTL_TMS    I80 @S9S_MB_2U_LIB.S9S_MB_2U(SCH_1):PAGE134
     6 JTAG_QS_MUX_GTL_TDI @S9S_MB_2U_LIB.S9S_MB_2U(SCH_1):JTAG_QS_MUX_GTL_TDI    I80 @S9S_MB_2U_LIB.S9S_MB_2U(SCH_1):PAGE134
     2 JTAG_DBP_TMS @S9S_MB_2U_LIB.S9S_MB_2U(SCH_1):JTAG_DBP_TMS    I80 @S9S_MB_2U_LIB.S9S_MB_2U(SCH_1):PAGE134
     7    GND @S9S_MB_2U_LIB.S9S_MB_2U(SCH_1):GND    I80 @S9S_MB_2U_LIB.S9S_MB_2U(SCH_1):PAGE134
     9 PD_74CB_A9 @S9S_MB_2U_LIB.S9S_MB_2U(SCH_1):PD_74CB_A9    I80 @S9S_MB_2U_LIB.S9S_MB_2U(SCH_1):PAGE134
    10 PWRGD_PVNN_MAIN_CPU0 @S9S_MB_2U_LIB.S9S_MB_2U(SCH_1):PWRGD_PVNN_MAIN_CPU0    I80 @S9S_MB_2U_LIB.S9S_MB_2U(SCH_1):PAGE134
    11 JTAG_MUX_QS_GTL_TDO @S9S_MB_2U_LIB.S9S_MB_2U(SCH_1):JTAG_MUX_QS_GTL_TDO    I80 @S9S_MB_2U_LIB.S9S_MB_2U(SCH_1):PAGE134
    12 JTAG_DBP_TDO @S9S_MB_2U_LIB.S9S_MB_2U(SCH_1):JTAG_DBP_TDO    I80 @S9S_MB_2U_LIB.S9S_MB_2U(SCH_1):PAGE134
    13 PWRGD_PVNN_MAIN_CPU0 @S9S_MB_2U_LIB.S9S_MB_2U(SCH_1):PWRGD_PVNN_MAIN_CPU0    I80 @S9S_MB_2U_LIB.S9S_MB_2U(SCH_1):PAGE134
    14 P3V3_AUX @S9S_MB_2U_LIB.S9S_MB_2U(SCH_1):P3V3_AUX    I80 @S9S_MB_2U_LIB.S9S_MB_2U(SCH_1):PAGE134

 U18 74CBTLV3126PW-74CBTLV3126PW,SMA
     5 JTAG_DBP_CPU_HOOK8_MBP2_GTL_N @S9S_MB_2U_LIB.S9S_MB_2U(SCH_1):JTAG_DBP_CPU_HOOK8_MBP2_GTL_N   I129 @S9S_MB_2U_LIB.S9S_MB_2U(SCH_1):PAGE134
     8 H_CPU_PRDY_QS_GTL_N @S9S_MB_2U_LIB.S9S_MB_2U(SCH_1):H_CPU_PRDY_QS_GTL_N   I129 @S9S_MB_2U_LIB.S9S_MB_2U(SCH_1):PAGE134
     1 PWRGD_PVNN_MAIN_CPU0 @S9S_MB_2U_LIB.S9S_MB_2U(SCH_1):PWRGD_PVNN_MAIN_CPU0   I129 @S9S_MB_2U_LIB.S9S_MB_2U(SCH_1):PAGE134
     4 PWRGD_PVNN_MAIN_CPU0 @S9S_MB_2U_LIB.S9S_MB_2U(SCH_1):PWRGD_PVNN_MAIN_CPU0   I129 @S9S_MB_2U_LIB.S9S_MB_2U(SCH_1):PAGE134
     3 DBP_CPU_HOOK9_MBP3_GTL_QS_N @S9S_MB_2U_LIB.S9S_MB_2U(SCH_1):DBP_CPU_HOOK9_MBP3_GTL_QS_N   I129 @S9S_MB_2U_LIB.S9S_MB_2U(SCH_1):PAGE134
     6 DBP_CPU_HOOK8_MBP2_GTL_QS_N @S9S_MB_2U_LIB.S9S_MB_2U(SCH_1):DBP_CPU_HOOK8_MBP2_GTL_QS_N   I129 @S9S_MB_2U_LIB.S9S_MB_2U(SCH_1):PAGE134
     2 JTAG_DBP_CPU_HOOK9_MBP3_GTL_N @S9S_MB_2U_LIB.S9S_MB_2U(SCH_1):JTAG_DBP_CPU_HOOK9_MBP3_GTL_N   I129 @S9S_MB_2U_LIB.S9S_MB_2U(SCH_1):PAGE134
     7    GND @S9S_MB_2U_LIB.S9S_MB_2U(SCH_1):GND   I129 @S9S_MB_2U_LIB.S9S_MB_2U(SCH_1):PAGE134
     9 JTAG_DBP_PRDY_N @S9S_MB_2U_LIB.S9S_MB_2U(SCH_1):JTAG_DBP_PRDY_N   I129 @S9S_MB_2U_LIB.S9S_MB_2U(SCH_1):PAGE134
    10 PWRGD_PVNN_MAIN_CPU0 @S9S_MB_2U_LIB.S9S_MB_2U(SCH_1):PWRGD_PVNN_MAIN_CPU0   I129 @S9S_MB_2U_LIB.S9S_MB_2U(SCH_1):PAGE134
    11 H_CPU_PREQ_QS_GTL_N @S9S_MB_2U_LIB.S9S_MB_2U(SCH_1):H_CPU_PREQ_QS_GTL_N   I129 @S9S_MB_2U_LIB.S9S_MB_2U(SCH_1):PAGE134
    12 JTAG_DBP_PREQ_N @S9S_MB_2U_LIB.S9S_MB_2U(SCH_1):JTAG_DBP_PREQ_N   I129 @S9S_MB_2U_LIB.S9S_MB_2U(SCH_1):PAGE134
    13 PWRGD_PVNN_MAIN_CPU0 @S9S_MB_2U_LIB.S9S_MB_2U(SCH_1):PWRGD_PVNN_MAIN_CPU0   I129 @S9S_MB_2U_LIB.S9S_MB_2U(SCH_1):PAGE134
    14 P3V3_AUX @S9S_MB_2U_LIB.S9S_MB_2U(SCH_1):P3V3_AUX   I129 @S9S_MB_2U_LIB.S9S_MB_2U(SCH_1):PAGE134

 U21 NC7SB3157_SMLF-NC7SB3157P6X,NCA
     1 JTAG_MUX_CPU1_GTL_TDI @S9S_MB_2U_LIB.S9S_MB_2U(SCH_1):JTAG_MUX_CPU1_GTL_TDI    I58 @S9S_MB_2U_LIB.S9S_MB_2U(SCH_1):PAGE135
     2    GND @S9S_MB_2U_LIB.S9S_MB_2U(SCH_1):GND    I58 @S9S_MB_2U_LIB.S9S_MB_2U(SCH_1):PAGE135
     3 JTAG_MUX_CPU0_GTL_TDI @S9S_MB_2U_LIB.S9S_MB_2U(SCH_1):JTAG_MUX_CPU0_GTL_TDI    I58 @S9S_MB_2U_LIB.S9S_MB_2U(SCH_1):PAGE135
     6 FM_CPU0_SKTOCC_N @S9S_MB_2U_LIB.S9S_MB_2U(SCH_1):FM_CPU0_SKTOCC_N    I58 @S9S_MB_2U_LIB.S9S_MB_2U(SCH_1):PAGE135
     5 P3V3_AUX @S9S_MB_2U_LIB.S9S_MB_2U(SCH_1):P3V3_AUX    I58 @S9S_MB_2U_LIB.S9S_MB_2U(SCH_1):PAGE135
     4 JTAG_QS_MUX_GTL_TDI @S9S_MB_2U_LIB.S9S_MB_2U(SCH_1):JTAG_QS_MUX_GTL_TDI    I58 @S9S_MB_2U_LIB.S9S_MB_2U(SCH_1):PAGE135

 U22 NC7SB3157_SMLF-NC7SB3157P6X,NCA
     1 JTAG_CPU0_MUX_GTL_TDO @S9S_MB_2U_LIB.S9S_MB_2U(SCH_1):JTAG_CPU0_MUX_GTL_TDO    I71 @S9S_MB_2U_LIB.S9S_MB_2U(SCH_1):PAGE135
     2    GND @S9S_MB_2U_LIB.S9S_MB_2U(SCH_1):GND    I71 @S9S_MB_2U_LIB.S9S_MB_2U(SCH_1):PAGE135
     3 JTAG_CPU1_MUX_GTL_TDO @S9S_MB_2U_LIB.S9S_MB_2U(SCH_1):JTAG_CPU1_MUX_GTL_TDO    I71 @S9S_MB_2U_LIB.S9S_MB_2U(SCH_1):PAGE135
     6 FM_CPU1_SKTOCC_N @S9S_MB_2U_LIB.S9S_MB_2U(SCH_1):FM_CPU1_SKTOCC_N    I71 @S9S_MB_2U_LIB.S9S_MB_2U(SCH_1):PAGE135
     5 P3V3_AUX @S9S_MB_2U_LIB.S9S_MB_2U(SCH_1):P3V3_AUX    I71 @S9S_MB_2U_LIB.S9S_MB_2U(SCH_1):PAGE135
     4 JTAG_MUX_QS_GTL_TDO @S9S_MB_2U_LIB.S9S_MB_2U(SCH_1):JTAG_MUX_QS_GTL_TDO    I71 @S9S_MB_2U_LIB.S9S_MB_2U(SCH_1):PAGE135

 U23 74LVC1G02GW_SMLF-74LVC1G02GW,IA
     1 FM_CPU1_SKTOCC_N @S9S_MB_2U_LIB.S9S_MB_2U(SCH_1):FM_CPU1_SKTOCC_N    I96 @S9S_MB_2U_LIB.S9S_MB_2U(SCH_1):PAGE135
     2 FM_CPU0_SKTOCC_N @S9S_MB_2U_LIB.S9S_MB_2U(SCH_1):FM_CPU0_SKTOCC_N    I96 @S9S_MB_2U_LIB.S9S_MB_2U(SCH_1):PAGE135
     4 FM_CPU_EN @S9S_MB_2U_LIB.S9S_MB_2U(SCH_1):FM_CPU_EN    I96 @S9S_MB_2U_LIB.S9S_MB_2U(SCH_1):PAGE135
     5 P3V3_AUX @S9S_MB_2U_LIB.S9S_MB_2U(SCH_1):P3V3_AUX    I96 @S9S_MB_2U_LIB.S9S_MB_2U(SCH_1):PAGE135
     3    GND @S9S_MB_2U_LIB.S9S_MB_2U(SCH_1):GND    I96 @S9S_MB_2U_LIB.S9S_MB_2U(SCH_1):PAGE135

 U28 PCA9617ADP-PCA9617ADP,SMLF,IC,A
     5 TP_SMB_PEHPCPU0_EN @S9S_MB_2U_LIB.S9S_MB_2U(SCH_1):TP_SMB_PEHPCPU0_EN    I39 @S9S_MB_2U_LIB.S9S_MB_2U(SCH_1):PAGE223
     1 PVNN_TERM_CPU0 @S9S_MB_2U_LIB.S9S_MB_2U(SCH_1):PVNN_TERM_CPU0    I39 @S9S_MB_2U_LIB.S9S_MB_2U(SCH_1):PAGE223
     8 P3V3_AUX @S9S_MB_2U_LIB.S9S_MB_2U(SCH_1):P3V3_AUX    I39 @S9S_MB_2U_LIB.S9S_MB_2U(SCH_1):PAGE223
     2 SMB_PEHPCPU0_GTL_R_SCL @S9S_MB_2U_LIB.S9S_MB_2U(SCH_1):SMB_PEHPCPU0_GTL_R_SCL    I39 @S9S_MB_2U_LIB.S9S_MB_2U(SCH_1):PAGE223
     3 SMB_PEHPCPU0_GTL_R_SDA @S9S_MB_2U_LIB.S9S_MB_2U(SCH_1):SMB_PEHPCPU0_GTL_R_SDA    I39 @S9S_MB_2U_LIB.S9S_MB_2U(SCH_1):PAGE223
     6 SMB_PEHPCPU0_LVC3_SDA_R0 @S9S_MB_2U_LIB.S9S_MB_2U(SCH_1):SMB_PEHPCPU0_LVC3_SDA_R0    I39 @S9S_MB_2U_LIB.S9S_MB_2U(SCH_1):PAGE223
     7 SMB_PEHPCPU0_LVC3_SCL_R0 @S9S_MB_2U_LIB.S9S_MB_2U(SCH_1):SMB_PEHPCPU0_LVC3_SCL_R0    I39 @S9S_MB_2U_LIB.S9S_MB_2U(SCH_1):PAGE223
     4    GND @S9S_MB_2U_LIB.S9S_MB_2U(SCH_1):GND    I39 @S9S_MB_2U_LIB.S9S_MB_2U(SCH_1):PAGE223

 U29 PCA9617ADP-PCA9617ADP,SMLF,IC,A
     5 TP_SMB_PEHPCPU1_EN @S9S_MB_2U_LIB.S9S_MB_2U(SCH_1):TP_SMB_PEHPCPU1_EN    I43 @S9S_MB_2U_LIB.S9S_MB_2U(SCH_1):PAGE223
     1 PVNN_TERM_CPU1 @S9S_MB_2U_LIB.S9S_MB_2U(SCH_1):PVNN_TERM_CPU1    I43 @S9S_MB_2U_LIB.S9S_MB_2U(SCH_1):PAGE223
     8 P3V3_AUX @S9S_MB_2U_LIB.S9S_MB_2U(SCH_1):P3V3_AUX    I43 @S9S_MB_2U_LIB.S9S_MB_2U(SCH_1):PAGE223
     2 SMB_PEHPCPU1_GTL_R_SCL @S9S_MB_2U_LIB.S9S_MB_2U(SCH_1):SMB_PEHPCPU1_GTL_R_SCL    I43 @S9S_MB_2U_LIB.S9S_MB_2U(SCH_1):PAGE223
     3 SMB_PEHPCPU1_GTL_R_SDA @S9S_MB_2U_LIB.S9S_MB_2U(SCH_1):SMB_PEHPCPU1_GTL_R_SDA    I43 @S9S_MB_2U_LIB.S9S_MB_2U(SCH_1):PAGE223
     6 SMB_PEHPCPU1_LVC3_SDA_R0 @S9S_MB_2U_LIB.S9S_MB_2U(SCH_1):SMB_PEHPCPU1_LVC3_SDA_R0    I43 @S9S_MB_2U_LIB.S9S_MB_2U(SCH_1):PAGE223
     7 SMB_PEHPCPU1_LVC3_SCL_R0 @S9S_MB_2U_LIB.S9S_MB_2U(SCH_1):SMB_PEHPCPU1_LVC3_SCL_R0    I43 @S9S_MB_2U_LIB.S9S_MB_2U(SCH_1):PAGE223
     4    GND @S9S_MB_2U_LIB.S9S_MB_2U(SCH_1):GND    I43 @S9S_MB_2U_LIB.S9S_MB_2U(SCH_1):PAGE223

 U30 PCA9517AD-PCA9517AD,SMLF,IC,ALA
     5 TP_SMB_S3M_CPU0_EN @S9S_MB_2U_LIB.S9S_MB_2U(SCH_1):TP_SMB_S3M_CPU0_EN    I28 @S9S_MB_2U_LIB.S9S_MB_2U(SCH_1):PAGE224
     1 PVNN_TERM_CPU0 @S9S_MB_2U_LIB.S9S_MB_2U(SCH_1):PVNN_TERM_CPU0    I28 @S9S_MB_2U_LIB.S9S_MB_2U(SCH_1):PAGE224
     8 P3V3_AUX @S9S_MB_2U_LIB.S9S_MB_2U(SCH_1):P3V3_AUX    I28 @S9S_MB_2U_LIB.S9S_MB_2U(SCH_1):PAGE224
     2 SMB_S3M_CPU0_R_SCL @S9S_MB_2U_LIB.S9S_MB_2U(SCH_1):SMB_S3M_CPU0_R_SCL    I28 @S9S_MB_2U_LIB.S9S_MB_2U(SCH_1):PAGE224
     3 SMB_S3M_CPU0_R_SDA @S9S_MB_2U_LIB.S9S_MB_2U(SCH_1):SMB_S3M_CPU0_R_SDA    I28 @S9S_MB_2U_LIB.S9S_MB_2U(SCH_1):PAGE224
     6 SMB_S3M_CPU0_3V3AUX_SDA @S9S_MB_2U_LIB.S9S_MB_2U(SCH_1):SMB_S3M_CPU0_3V3AUX_SDA    I28 @S9S_MB_2U_LIB.S9S_MB_2U(SCH_1):PAGE224
     7 SMB_S3M_CPU0_3V3AUX_SCL @S9S_MB_2U_LIB.S9S_MB_2U(SCH_1):SMB_S3M_CPU0_3V3AUX_SCL    I28 @S9S_MB_2U_LIB.S9S_MB_2U(SCH_1):PAGE224
     4    GND @S9S_MB_2U_LIB.S9S_MB_2U(SCH_1):GND    I28 @S9S_MB_2U_LIB.S9S_MB_2U(SCH_1):PAGE224

 U31 PCA9517AD-PCA9517AD,SMLF,IC,ALA
     5 TP_SMB_S3M_CPU1_EN @S9S_MB_2U_LIB.S9S_MB_2U(SCH_1):TP_SMB_S3M_CPU1_EN    I37 @S9S_MB_2U_LIB.S9S_MB_2U(SCH_1):PAGE224
     1 PVNN_TERM_CPU1 @S9S_MB_2U_LIB.S9S_MB_2U(SCH_1):PVNN_TERM_CPU1    I37 @S9S_MB_2U_LIB.S9S_MB_2U(SCH_1):PAGE224
     8 P3V3_AUX @S9S_MB_2U_LIB.S9S_MB_2U(SCH_1):P3V3_AUX    I37 @S9S_MB_2U_LIB.S9S_MB_2U(SCH_1):PAGE224
     2 SMB_S3M_CPU1_R_SCL @S9S_MB_2U_LIB.S9S_MB_2U(SCH_1):SMB_S3M_CPU1_R_SCL    I37 @S9S_MB_2U_LIB.S9S_MB_2U(SCH_1):PAGE224
     3 SMB_S3M_CPU1_R_SDA @S9S_MB_2U_LIB.S9S_MB_2U(SCH_1):SMB_S3M_CPU1_R_SDA    I37 @S9S_MB_2U_LIB.S9S_MB_2U(SCH_1):PAGE224
     6 SMB_S3M_CPU1_3V3AUX_SDA @S9S_MB_2U_LIB.S9S_MB_2U(SCH_1):SMB_S3M_CPU1_3V3AUX_SDA    I37 @S9S_MB_2U_LIB.S9S_MB_2U(SCH_1):PAGE224
     7 SMB_S3M_CPU1_3V3AUX_SCL @S9S_MB_2U_LIB.S9S_MB_2U(SCH_1):SMB_S3M_CPU1_3V3AUX_SCL    I37 @S9S_MB_2U_LIB.S9S_MB_2U(SCH_1):PAGE224
     4    GND @S9S_MB_2U_LIB.S9S_MB_2U(SCH_1):GND    I37 @S9S_MB_2U_LIB.S9S_MB_2U(SCH_1):PAGE224

 U36 TCA9548APWR-TCA9548APWR,SMLF,IA
     1 PCA9548_PCIE3_ADDR0 @S9S_MB_2U_LIB.S9S_MB_2U(SCH_1):PCA9548_PCIE3_ADDR0    I45 @S9S_MB_2U_LIB.S9S_MB_2U(SCH_1):PAGE219
     2 PCA9548_PCIE3_ADDR1 @S9S_MB_2U_LIB.S9S_MB_2U(SCH_1):PCA9548_PCIE3_ADDR1    I45 @S9S_MB_2U_LIB.S9S_MB_2U(SCH_1):PAGE219
     3 PU_RST_SMB_PCIE0_N @S9S_MB_2U_LIB.S9S_MB_2U(SCH_1):PU_RST_SMB_PCIE0_N    I45 @S9S_MB_2U_LIB.S9S_MB_2U(SCH_1):PAGE219
     4     NC     NC    I45 @S9S_MB_2U_LIB.S9S_MB_2U(SCH_1):PAGE219
     5     NC     NC    I45 @S9S_MB_2U_LIB.S9S_MB_2U(SCH_1):PAGE219
     6 SMB_IOEXP_3V3AUX_SDA_R @S9S_MB_2U_LIB.S9S_MB_2U(SCH_1):SMB_IOEXP_3V3AUX_SDA_R    I45 @S9S_MB_2U_LIB.S9S_MB_2U(SCH_1):PAGE219
     7 SMB_IOEXP_3V3AUX_SCL_R @S9S_MB_2U_LIB.S9S_MB_2U(SCH_1):SMB_IOEXP_3V3AUX_SCL_R    I45 @S9S_MB_2U_LIB.S9S_MB_2U(SCH_1):PAGE219
     8 SMB_PCIE0_3V3AUX_SDA_R3 @S9S_MB_2U_LIB.S9S_MB_2U(SCH_1):SMB_PCIE0_3V3AUX_SDA_R3    I45 @S9S_MB_2U_LIB.S9S_MB_2U(SCH_1):PAGE219
     9 SMB_PCIE0_3V3AUX_SCL_R3 @S9S_MB_2U_LIB.S9S_MB_2U(SCH_1):SMB_PCIE0_3V3AUX_SCL_R3    I45 @S9S_MB_2U_LIB.S9S_MB_2U(SCH_1):PAGE219
    10 SMB_PCIE0_3V3AUX_SDA_R5 @S9S_MB_2U_LIB.S9S_MB_2U(SCH_1):SMB_PCIE0_3V3AUX_SDA_R5    I45 @S9S_MB_2U_LIB.S9S_MB_2U(SCH_1):PAGE219
    11 SMB_PCIE0_3V3AUX_SCL_R5 @S9S_MB_2U_LIB.S9S_MB_2U(SCH_1):SMB_PCIE0_3V3AUX_SCL_R5    I45 @S9S_MB_2U_LIB.S9S_MB_2U(SCH_1):PAGE219
    12    GND @S9S_MB_2U_LIB.S9S_MB_2U(SCH_1):GND    I45 @S9S_MB_2U_LIB.S9S_MB_2U(SCH_1):PAGE219
    24 P3V3_AUX @S9S_MB_2U_LIB.S9S_MB_2U(SCH_1):P3V3_AUX    I45 @S9S_MB_2U_LIB.S9S_MB_2U(SCH_1):PAGE219
    23 SMB_PCIE0_3V3AUX_SDA_R @S9S_MB_2U_LIB.S9S_MB_2U(SCH_1):SMB_PCIE0_3V3AUX_SDA_R    I45 @S9S_MB_2U_LIB.S9S_MB_2U(SCH_1):PAGE219
    22 SMB_PCIE0_3V3AUX_SCL_R @S9S_MB_2U_LIB.S9S_MB_2U(SCH_1):SMB_PCIE0_3V3AUX_SCL_R    I45 @S9S_MB_2U_LIB.S9S_MB_2U(SCH_1):PAGE219
    21 PCA9548_PCIE3_ADDR2 @S9S_MB_2U_LIB.S9S_MB_2U(SCH_1):PCA9548_PCIE3_ADDR2    I45 @S9S_MB_2U_LIB.S9S_MB_2U(SCH_1):PAGE219
    20     NC     NC    I45 @S9S_MB_2U_LIB.S9S_MB_2U(SCH_1):PAGE219
    19     NC     NC    I45 @S9S_MB_2U_LIB.S9S_MB_2U(SCH_1):PAGE219
    18 SMB_INA230_3V3AUX_SCL_R @S9S_MB_2U_LIB.S9S_MB_2U(SCH_1):SMB_INA230_3V3AUX_SCL_R    I45 @S9S_MB_2U_LIB.S9S_MB_2U(SCH_1):PAGE219
    17 SMB_INA230_3V3AUX_SDA_R @S9S_MB_2U_LIB.S9S_MB_2U(SCH_1):SMB_INA230_3V3AUX_SDA_R    I45 @S9S_MB_2U_LIB.S9S_MB_2U(SCH_1):PAGE219
    16 SMB_FRU_3V3AUX_SCL_R @S9S_MB_2U_LIB.S9S_MB_2U(SCH_1):SMB_FRU_3V3AUX_SCL_R    I45 @S9S_MB_2U_LIB.S9S_MB_2U(SCH_1):PAGE219
    15 SMB_FRU_3V3AUX_SDA_R @S9S_MB_2U_LIB.S9S_MB_2U(SCH_1):SMB_FRU_3V3AUX_SDA_R    I45 @S9S_MB_2U_LIB.S9S_MB_2U(SCH_1):PAGE219
    14 SMB_BMC_SWB_SCL_R4 @S9S_MB_2U_LIB.S9S_MB_2U(SCH_1):SMB_BMC_SWB_SCL_R4    I45 @S9S_MB_2U_LIB.S9S_MB_2U(SCH_1):PAGE219
    13 SMB_BMC_SWB_SDA_R4 @S9S_MB_2U_LIB.S9S_MB_2U(SCH_1):SMB_BMC_SWB_SDA_R4    I45 @S9S_MB_2U_LIB.S9S_MB_2U(SCH_1):PAGE219

 U38 9QXL2001BNHGI8-9QXL2001BNHGI8,A
    H1 CLK_100M_DB2000_DN @S9S_MB_2U_LIB.S9S_MB_2U(SCH_1):CLK_100M_DB2000_DN   I119 @S9S_MB_2U_LIB.S9S_MB_2U(SCH_1):PAGE195
    J2 NC_CLK_100M_DB2000_NC12 @S9S_MB_2U_LIB.S9S_MB_2U(SCH_1):NC_CLK_100M_DB2000_NC12   I119 @S9S_MB_2U_LIB.S9S_MB_2U(SCH_1):PAGE195
    B3 NC_CLK_100M_DB2000_NC1 @S9S_MB_2U_LIB.S9S_MB_2U(SCH_1):NC_CLK_100M_DB2000_NC1   I119 @S9S_MB_2U_LIB.S9S_MB_2U(SCH_1):PAGE195
    G2 NC_CLK_100M_DB2000_NC10 @S9S_MB_2U_LIB.S9S_MB_2U(SCH_1):NC_CLK_100M_DB2000_NC10   I119 @S9S_MB_2U_LIB.S9S_MB_2U(SCH_1):PAGE195
    A5 CLK_100M_OCP_V3_2_B_R_DP @S9S_MB_2U_LIB.S9S_MB_2U(SCH_1):CLK_100M_OCP_V3_2_B_R_DP   I119 @S9S_MB_2U_LIB.S9S_MB_2U(SCH_1):PAGE195
    A1 CLK_100M_OCP_V3_2_D_R_DP @S9S_MB_2U_LIB.S9S_MB_2U(SCH_1):CLK_100M_OCP_V3_2_D_R_DP   I119 @S9S_MB_2U_LIB.S9S_MB_2U(SCH_1):PAGE195
    D1 TP_CLK_100M_DIF18_DN @S9S_MB_2U_LIB.S9S_MB_2U(SCH_1):TP_CLK_100M_DIF18_DN   I119 @S9S_MB_2U_LIB.S9S_MB_2U(SCH_1):PAGE195
    M6 FM_DB2000_DEV_EN @S9S_MB_2U_LIB.S9S_MB_2U(SCH_1):FM_DB2000_DEV_EN   I119 @S9S_MB_2U_LIB.S9S_MB_2U(SCH_1):PAGE195
    TH    GND @S9S_MB_2U_LIB.S9S_MB_2U(SCH_1):GND   I119 @S9S_MB_2U_LIB.S9S_MB_2U(SCH_1):PAGE195
    F2 NC_CLK_100M_DB2000_NC8 @S9S_MB_2U_LIB.S9S_MB_2U(SCH_1):NC_CLK_100M_DB2000_NC8   I119 @S9S_MB_2U_LIB.S9S_MB_2U(SCH_1):PAGE195
   G11 NC_CLK_100M_DB2000_NC11 @S9S_MB_2U_LIB.S9S_MB_2U(SCH_1):NC_CLK_100M_DB2000_NC11   I119 @S9S_MB_2U_LIB.S9S_MB_2U(SCH_1):PAGE195
    K2 NC_CLK_100M_DB2000_NC14 @S9S_MB_2U_LIB.S9S_MB_2U(SCH_1):NC_CLK_100M_DB2000_NC14   I119 @S9S_MB_2U_LIB.S9S_MB_2U(SCH_1):PAGE195
    L6 NC_CLK_100M_DB2000_NC15 @S9S_MB_2U_LIB.S9S_MB_2U(SCH_1):NC_CLK_100M_DB2000_NC15   I119 @S9S_MB_2U_LIB.S9S_MB_2U(SCH_1):PAGE195
   J11 NC_CLK_100M_DB2000_NC13 @S9S_MB_2U_LIB.S9S_MB_2U(SCH_1):NC_CLK_100M_DB2000_NC13   I119 @S9S_MB_2U_LIB.S9S_MB_2U(SCH_1):PAGE195
    J1 CLK_100M_DB2000_CPU0_BCLK0_DP @S9S_MB_2U_LIB.S9S_MB_2U(SCH_1):CLK_100M_DB2000_CPU0_BCLK0_DP   I119 @S9S_MB_2U_LIB.S9S_MB_2U(SCH_1):PAGE195
    K1 CLK_100M_DB2000_CPU0_BCLK0_DN @S9S_MB_2U_LIB.S9S_MB_2U(SCH_1):CLK_100M_DB2000_CPU0_BCLK0_DN   I119 @S9S_MB_2U_LIB.S9S_MB_2U(SCH_1):PAGE195
    L1 CLK_100M_DB2000_CPU0_BCLK1_DP @S9S_MB_2U_LIB.S9S_MB_2U(SCH_1):CLK_100M_DB2000_CPU0_BCLK1_DP   I119 @S9S_MB_2U_LIB.S9S_MB_2U(SCH_1):PAGE195
    M1 CLK_100M_DB2000_CPU0_BCLK1_DN @S9S_MB_2U_LIB.S9S_MB_2U(SCH_1):CLK_100M_DB2000_CPU0_BCLK1_DN   I119 @S9S_MB_2U_LIB.S9S_MB_2U(SCH_1):PAGE195
   D12 CLK_100M_OCP_SFF_1_R_DP @S9S_MB_2U_LIB.S9S_MB_2U(SCH_1):CLK_100M_OCP_SFF_1_R_DP   I119 @S9S_MB_2U_LIB.S9S_MB_2U(SCH_1):PAGE195
   C12 CLK_100M_OCP_SFF_1_R_DN @S9S_MB_2U_LIB.S9S_MB_2U(SCH_1):CLK_100M_OCP_SFF_1_R_DN   I119 @S9S_MB_2U_LIB.S9S_MB_2U(SCH_1):PAGE195
   B12 CLK_100M_OCP_SFF_2_R_DP @S9S_MB_2U_LIB.S9S_MB_2U(SCH_1):CLK_100M_OCP_SFF_2_R_DP   I119 @S9S_MB_2U_LIB.S9S_MB_2U(SCH_1):PAGE195
   A10 CLK_100M_OCP_SFF_3_R_DN @S9S_MB_2U_LIB.S9S_MB_2U(SCH_1):CLK_100M_OCP_SFF_3_R_DN   I119 @S9S_MB_2U_LIB.S9S_MB_2U(SCH_1):PAGE195
   A11 CLK_100M_OCP_SFF_3_R_DP @S9S_MB_2U_LIB.S9S_MB_2U(SCH_1):CLK_100M_OCP_SFF_3_R_DP   I119 @S9S_MB_2U_LIB.S9S_MB_2U(SCH_1):PAGE195
    A8 TP_CLK_100M_DIF13_DN @S9S_MB_2U_LIB.S9S_MB_2U(SCH_1):TP_CLK_100M_DIF13_DN   I119 @S9S_MB_2U_LIB.S9S_MB_2U(SCH_1):PAGE195
    A7 CLK_100M_OCP_V3_2_A_R_DP @S9S_MB_2U_LIB.S9S_MB_2U(SCH_1):CLK_100M_OCP_V3_2_A_R_DP   I119 @S9S_MB_2U_LIB.S9S_MB_2U(SCH_1):PAGE195
    A6 CLK_100M_OCP_V3_2_A_R_DN @S9S_MB_2U_LIB.S9S_MB_2U(SCH_1):CLK_100M_OCP_V3_2_A_R_DN   I119 @S9S_MB_2U_LIB.S9S_MB_2U(SCH_1):PAGE195
    A4 CLK_100M_OCP_V3_2_B_R_DN @S9S_MB_2U_LIB.S9S_MB_2U(SCH_1):CLK_100M_OCP_V3_2_B_R_DN   I119 @S9S_MB_2U_LIB.S9S_MB_2U(SCH_1):PAGE195
    A3 CLK_100M_OCP_V3_2_C_R_DP @S9S_MB_2U_LIB.S9S_MB_2U(SCH_1):CLK_100M_OCP_V3_2_C_R_DP   I119 @S9S_MB_2U_LIB.S9S_MB_2U(SCH_1):PAGE195
    A2 CLK_100M_OCP_V3_2_C_R_DN @S9S_MB_2U_LIB.S9S_MB_2U(SCH_1):CLK_100M_OCP_V3_2_C_R_DN   I119 @S9S_MB_2U_LIB.S9S_MB_2U(SCH_1):PAGE195
    C1 TP_CLK_100M_DIF18_DP @S9S_MB_2U_LIB.S9S_MB_2U(SCH_1):TP_CLK_100M_DIF18_DP   I119 @S9S_MB_2U_LIB.S9S_MB_2U(SCH_1):PAGE195
    G1 CLK_100M_DB2000_DP @S9S_MB_2U_LIB.S9S_MB_2U(SCH_1):CLK_100M_DB2000_DP   I119 @S9S_MB_2U_LIB.S9S_MB_2U(SCH_1):PAGE195
   A12 CLK_100M_OCP_SFF_2_R_DN @S9S_MB_2U_LIB.S9S_MB_2U(SCH_1):CLK_100M_OCP_SFF_2_R_DN   I119 @S9S_MB_2U_LIB.S9S_MB_2U(SCH_1):PAGE195
    A9 TP_CLK_100M_DIF13_DP @S9S_MB_2U_LIB.S9S_MB_2U(SCH_1):TP_CLK_100M_DIF13_DP   I119 @S9S_MB_2U_LIB.S9S_MB_2U(SCH_1):PAGE195
    B1 CLK_100M_OCP_V3_2_D_R_DN @S9S_MB_2U_LIB.S9S_MB_2U(SCH_1):CLK_100M_OCP_V3_2_D_R_DN   I119 @S9S_MB_2U_LIB.S9S_MB_2U(SCH_1):PAGE195
   F11 NC_CLK_100M_DB2000_NC9 @S9S_MB_2U_LIB.S9S_MB_2U(SCH_1):NC_CLK_100M_DB2000_NC9   I119 @S9S_MB_2U_LIB.S9S_MB_2U(SCH_1):PAGE195
   D11 NC_CLK_100M_DB2000_NC7 @S9S_MB_2U_LIB.S9S_MB_2U(SCH_1):NC_CLK_100M_DB2000_NC7   I119 @S9S_MB_2U_LIB.S9S_MB_2U(SCH_1):PAGE195
    L7 NC_CLK_100M_DB2000_NC16 @S9S_MB_2U_LIB.S9S_MB_2U(SCH_1):NC_CLK_100M_DB2000_NC16   I119 @S9S_MB_2U_LIB.S9S_MB_2U(SCH_1):PAGE195
    L3 NC_CLK_100M_DB2000_NC17 @S9S_MB_2U_LIB.S9S_MB_2U(SCH_1):NC_CLK_100M_DB2000_NC17   I119 @S9S_MB_2U_LIB.S9S_MB_2U(SCH_1):PAGE195
    L9 NC_CLK_100M_DB2000_NC18 @S9S_MB_2U_LIB.S9S_MB_2U(SCH_1):NC_CLK_100M_DB2000_NC18   I119 @S9S_MB_2U_LIB.S9S_MB_2U(SCH_1):PAGE195
    B5 NC_CLK_100M_DB2000_NC2 @S9S_MB_2U_LIB.S9S_MB_2U(SCH_1):NC_CLK_100M_DB2000_NC2   I119 @S9S_MB_2U_LIB.S9S_MB_2U(SCH_1):PAGE195
    B7 NC_CLK_100M_DB2000_NC3 @S9S_MB_2U_LIB.S9S_MB_2U(SCH_1):NC_CLK_100M_DB2000_NC3   I119 @S9S_MB_2U_LIB.S9S_MB_2U(SCH_1):PAGE195
    B9 NC_CLK_100M_DB2000_NC4 @S9S_MB_2U_LIB.S9S_MB_2U(SCH_1):NC_CLK_100M_DB2000_NC4   I119 @S9S_MB_2U_LIB.S9S_MB_2U(SCH_1):PAGE195
    C2 NC_CLK_100M_DB2000_NC5 @S9S_MB_2U_LIB.S9S_MB_2U(SCH_1):NC_CLK_100M_DB2000_NC5   I119 @S9S_MB_2U_LIB.S9S_MB_2U(SCH_1):PAGE195
    D2 NC_CLK_100M_DB2000_NC6 @S9S_MB_2U_LIB.S9S_MB_2U(SCH_1):NC_CLK_100M_DB2000_NC6   I119 @S9S_MB_2U_LIB.S9S_MB_2U(SCH_1):PAGE195
    M2 CLK_100M_DB2000_CPU0_BCLK2_DP @S9S_MB_2U_LIB.S9S_MB_2U(SCH_1):CLK_100M_DB2000_CPU0_BCLK2_DP   I119 @S9S_MB_2U_LIB.S9S_MB_2U(SCH_1):PAGE195
    M3 CLK_100M_DB2000_CPU0_BCLK2_DN @S9S_MB_2U_LIB.S9S_MB_2U(SCH_1):CLK_100M_DB2000_CPU0_BCLK2_DN   I119 @S9S_MB_2U_LIB.S9S_MB_2U(SCH_1):PAGE195
    M4 CLK_100M_DB2000_CPU0_BCLK3_DP @S9S_MB_2U_LIB.S9S_MB_2U(SCH_1):CLK_100M_DB2000_CPU0_BCLK3_DP   I119 @S9S_MB_2U_LIB.S9S_MB_2U(SCH_1):PAGE195
    M5 CLK_100M_DB2000_CPU0_BCLK3_DN @S9S_MB_2U_LIB.S9S_MB_2U(SCH_1):CLK_100M_DB2000_CPU0_BCLK3_DN   I119 @S9S_MB_2U_LIB.S9S_MB_2U(SCH_1):PAGE195
    M7 CLK_100M_DB2000_CPU1_BCLK0_DP @S9S_MB_2U_LIB.S9S_MB_2U(SCH_1):CLK_100M_DB2000_CPU1_BCLK0_DP   I119 @S9S_MB_2U_LIB.S9S_MB_2U(SCH_1):PAGE195
    M8 CLK_100M_DB2000_CPU1_BCLK0_DN @S9S_MB_2U_LIB.S9S_MB_2U(SCH_1):CLK_100M_DB2000_CPU1_BCLK0_DN   I119 @S9S_MB_2U_LIB.S9S_MB_2U(SCH_1):PAGE195
    M9 CLK_100M_DB2000_CPU1_BCLK1_DP @S9S_MB_2U_LIB.S9S_MB_2U(SCH_1):CLK_100M_DB2000_CPU1_BCLK1_DP   I119 @S9S_MB_2U_LIB.S9S_MB_2U(SCH_1):PAGE195
   M10 CLK_100M_DB2000_CPU1_BCLK1_DN @S9S_MB_2U_LIB.S9S_MB_2U(SCH_1):CLK_100M_DB2000_CPU1_BCLK1_DN   I119 @S9S_MB_2U_LIB.S9S_MB_2U(SCH_1):PAGE195
   M11 CLK_100M_DB2000_CPU1_BCLK2_DP @S9S_MB_2U_LIB.S9S_MB_2U(SCH_1):CLK_100M_DB2000_CPU1_BCLK2_DP   I119 @S9S_MB_2U_LIB.S9S_MB_2U(SCH_1):PAGE195
   M12 CLK_100M_DB2000_CPU1_BCLK2_DN @S9S_MB_2U_LIB.S9S_MB_2U(SCH_1):CLK_100M_DB2000_CPU1_BCLK2_DN   I119 @S9S_MB_2U_LIB.S9S_MB_2U(SCH_1):PAGE195
   L12 CLK_100M_DB2000_CPU1_BCLK3_DP @S9S_MB_2U_LIB.S9S_MB_2U(SCH_1):CLK_100M_DB2000_CPU1_BCLK3_DP   I119 @S9S_MB_2U_LIB.S9S_MB_2U(SCH_1):PAGE195
   K12 CLK_100M_DB2000_CPU1_BCLK3_DN @S9S_MB_2U_LIB.S9S_MB_2U(SCH_1):CLK_100M_DB2000_CPU1_BCLK3_DN   I119 @S9S_MB_2U_LIB.S9S_MB_2U(SCH_1):PAGE195
   J12 CLK_100M_GPU_SWB_REF_DP @S9S_MB_2U_LIB.S9S_MB_2U(SCH_1):CLK_100M_GPU_SWB_REF_DP   I119 @S9S_MB_2U_LIB.S9S_MB_2U(SCH_1):PAGE195
   H12 CLK_100M_GPU_SWB_REF_DN @S9S_MB_2U_LIB.S9S_MB_2U(SCH_1):CLK_100M_GPU_SWB_REF_DN   I119 @S9S_MB_2U_LIB.S9S_MB_2U(SCH_1):PAGE195
   G12 CLK_100M_OCP_SFF_0_R_DP @S9S_MB_2U_LIB.S9S_MB_2U(SCH_1):CLK_100M_OCP_SFF_0_R_DP   I119 @S9S_MB_2U_LIB.S9S_MB_2U(SCH_1):PAGE195
   F12 CLK_100M_OCP_SFF_0_R_DN @S9S_MB_2U_LIB.S9S_MB_2U(SCH_1):CLK_100M_OCP_SFF_0_R_DN   I119 @S9S_MB_2U_LIB.S9S_MB_2U(SCH_1):PAGE195
    E2 FM_DB2000_VSBEN @S9S_MB_2U_LIB.S9S_MB_2U(SCH_1):FM_DB2000_VSBEN   I119 @S9S_MB_2U_LIB.S9S_MB_2U(SCH_1):PAGE195
    L8 FM_DB2000_1_OE_N @S9S_MB_2U_LIB.S9S_MB_2U(SCH_1):FM_DB2000_1_OE_N   I119 @S9S_MB_2U_LIB.S9S_MB_2U(SCH_1):PAGE195
   L10 FM_DB2000_1_OE_N @S9S_MB_2U_LIB.S9S_MB_2U(SCH_1):FM_DB2000_1_OE_N   I119 @S9S_MB_2U_LIB.S9S_MB_2U(SCH_1):PAGE195
   K11 FM_DB2000_1_OE_N @S9S_MB_2U_LIB.S9S_MB_2U(SCH_1):FM_DB2000_1_OE_N   I119 @S9S_MB_2U_LIB.S9S_MB_2U(SCH_1):PAGE195
   H11 FM_DB2000_8_OE_N @S9S_MB_2U_LIB.S9S_MB_2U(SCH_1):FM_DB2000_8_OE_N   I119 @S9S_MB_2U_LIB.S9S_MB_2U(SCH_1):PAGE195
   E12 FM_DB2000_9_OE_N @S9S_MB_2U_LIB.S9S_MB_2U(SCH_1):FM_DB2000_9_OE_N   I119 @S9S_MB_2U_LIB.S9S_MB_2U(SCH_1):PAGE195
   E11 FM_DB2000_10_OE_N @S9S_MB_2U_LIB.S9S_MB_2U(SCH_1):FM_DB2000_10_OE_N   I119 @S9S_MB_2U_LIB.S9S_MB_2U(SCH_1):PAGE195
   C11 FM_DB2000_11_OE_N @S9S_MB_2U_LIB.S9S_MB_2U(SCH_1):FM_DB2000_11_OE_N   I119 @S9S_MB_2U_LIB.S9S_MB_2U(SCH_1):PAGE195
   B10 FM_DB2000_12_OE_N @S9S_MB_2U_LIB.S9S_MB_2U(SCH_1):FM_DB2000_12_OE_N   I119 @S9S_MB_2U_LIB.S9S_MB_2U(SCH_1):PAGE195
    L5 SMB_HOST_DB2000_3V3AUX_SCL @S9S_MB_2U_LIB.S9S_MB_2U(SCH_1):SMB_HOST_DB2000_3V3AUX_SCL   I119 @S9S_MB_2U_LIB.S9S_MB_2U(SCH_1):PAGE195
    L4 SMB_HOST_DB2000_3V3AUX_SDA @S9S_MB_2U_LIB.S9S_MB_2U(SCH_1):SMB_HOST_DB2000_3V3AUX_SDA   I119 @S9S_MB_2U_LIB.S9S_MB_2U(SCH_1):PAGE195
    B6 P3V3_DB2000_VDDA @S9S_MB_2U_LIB.S9S_MB_2U(SCH_1):P3V3_DB2000_VDDA   I119 @S9S_MB_2U_LIB.S9S_MB_2U(SCH_1):PAGE195
    B2 P3V3_DB2000_VDD @S9S_MB_2U_LIB.S9S_MB_2U(SCH_1):P3V3_DB2000_VDD   I119 @S9S_MB_2U_LIB.S9S_MB_2U(SCH_1):PAGE195
   B11 P3V3_DB2000_VDD @S9S_MB_2U_LIB.S9S_MB_2U(SCH_1):P3V3_DB2000_VDD   I119 @S9S_MB_2U_LIB.S9S_MB_2U(SCH_1):PAGE195
    L2 P3V3_DB2000_VDD @S9S_MB_2U_LIB.S9S_MB_2U(SCH_1):P3V3_DB2000_VDD   I119 @S9S_MB_2U_LIB.S9S_MB_2U(SCH_1):PAGE195
   L11 P3V3_DB2000_VDD @S9S_MB_2U_LIB.S9S_MB_2U(SCH_1):P3V3_DB2000_VDD   I119 @S9S_MB_2U_LIB.S9S_MB_2U(SCH_1):PAGE195
    H2 P3V3_DB2000_VDDR @S9S_MB_2U_LIB.S9S_MB_2U(SCH_1):P3V3_DB2000_VDDR   I119 @S9S_MB_2U_LIB.S9S_MB_2U(SCH_1):PAGE195
    B4 PD_DB2000_SMB_SA0 @S9S_MB_2U_LIB.S9S_MB_2U(SCH_1):PD_DB2000_SMB_SA0   I119 @S9S_MB_2U_LIB.S9S_MB_2U(SCH_1):PAGE195
    B8 PD_DB2000_SMB_SA1 @S9S_MB_2U_LIB.S9S_MB_2U(SCH_1):PD_DB2000_SMB_SA1   I119 @S9S_MB_2U_LIB.S9S_MB_2U(SCH_1):PAGE195
    E1 TP_CLK_100M_DIF19_DP @S9S_MB_2U_LIB.S9S_MB_2U(SCH_1):TP_CLK_100M_DIF19_DP   I119 @S9S_MB_2U_LIB.S9S_MB_2U(SCH_1):PAGE195
    F1 TP_CLK_100M_DIF19_DN @S9S_MB_2U_LIB.S9S_MB_2U(SCH_1):TP_CLK_100M_DIF19_DN   I119 @S9S_MB_2U_LIB.S9S_MB_2U(SCH_1):PAGE195

 U39 TCA9548APWR-TCA9548APWR,SMLF,IA
     1 PCA9548_PCIE0_ADDR0 @S9S_MB_2U_LIB.S9S_MB_2U(SCH_1):PCA9548_PCIE0_ADDR0   I103 @S9S_MB_2U_LIB.S9S_MB_2U(SCH_1):PAGE221
     2 PCA9548_PCIE0_ADDR1 @S9S_MB_2U_LIB.S9S_MB_2U(SCH_1):PCA9548_PCIE0_ADDR1   I103 @S9S_MB_2U_LIB.S9S_MB_2U(SCH_1):PAGE221
     3 PU_RST_SMB_PCIE2_N @S9S_MB_2U_LIB.S9S_MB_2U(SCH_1):PU_RST_SMB_PCIE2_N   I103 @S9S_MB_2U_LIB.S9S_MB_2U(SCH_1):PAGE221
     4 SMB_VR_3V3AUX_SDA_R6 @S9S_MB_2U_LIB.S9S_MB_2U(SCH_1):SMB_VR_3V3AUX_SDA_R6   I103 @S9S_MB_2U_LIB.S9S_MB_2U(SCH_1):PAGE221
     5 SMB_VR_3V3AUX_SCL_R6 @S9S_MB_2U_LIB.S9S_MB_2U(SCH_1):SMB_VR_3V3AUX_SCL_R6   I103 @S9S_MB_2U_LIB.S9S_MB_2U(SCH_1):PAGE221
     6 SMB_LM75_0_3V3AUX_SDA_R @S9S_MB_2U_LIB.S9S_MB_2U(SCH_1):SMB_LM75_0_3V3AUX_SDA_R   I103 @S9S_MB_2U_LIB.S9S_MB_2U(SCH_1):PAGE221
     7 SMB_LM75_0_3V3AUX_SCL_R @S9S_MB_2U_LIB.S9S_MB_2U(SCH_1):SMB_LM75_0_3V3AUX_SCL_R   I103 @S9S_MB_2U_LIB.S9S_MB_2U(SCH_1):PAGE221
     8 SMB_LM75_1_3V3AUX_SDA_R @S9S_MB_2U_LIB.S9S_MB_2U(SCH_1):SMB_LM75_1_3V3AUX_SDA_R   I103 @S9S_MB_2U_LIB.S9S_MB_2U(SCH_1):PAGE221
     9 SMB_LM75_1_3V3AUX_SCL_R @S9S_MB_2U_LIB.S9S_MB_2U(SCH_1):SMB_LM75_1_3V3AUX_SCL_R   I103 @S9S_MB_2U_LIB.S9S_MB_2U(SCH_1):PAGE221
    10 SMB_LM75_2_3V3AUX_SDA_R @S9S_MB_2U_LIB.S9S_MB_2U(SCH_1):SMB_LM75_2_3V3AUX_SDA_R   I103 @S9S_MB_2U_LIB.S9S_MB_2U(SCH_1):PAGE221
    11 SMB_LM75_2_3V3AUX_SCL_R @S9S_MB_2U_LIB.S9S_MB_2U(SCH_1):SMB_LM75_2_3V3AUX_SCL_R   I103 @S9S_MB_2U_LIB.S9S_MB_2U(SCH_1):PAGE221
    12    GND @S9S_MB_2U_LIB.S9S_MB_2U(SCH_1):GND   I103 @S9S_MB_2U_LIB.S9S_MB_2U(SCH_1):PAGE221
    24 P3V3_AUX @S9S_MB_2U_LIB.S9S_MB_2U(SCH_1):P3V3_AUX   I103 @S9S_MB_2U_LIB.S9S_MB_2U(SCH_1):PAGE221
    23 SMB_VR_SENSOR_3V3AUX_SDA_R @S9S_MB_2U_LIB.S9S_MB_2U(SCH_1):SMB_VR_SENSOR_3V3AUX_SDA_R   I103 @S9S_MB_2U_LIB.S9S_MB_2U(SCH_1):PAGE221
    22 SMB_VR_SENSOR_3V3AUX_SCL_R @S9S_MB_2U_LIB.S9S_MB_2U(SCH_1):SMB_VR_SENSOR_3V3AUX_SCL_R   I103 @S9S_MB_2U_LIB.S9S_MB_2U(SCH_1):PAGE221
    21 PCA9548_PCIE0_ADDR2 @S9S_MB_2U_LIB.S9S_MB_2U(SCH_1):PCA9548_PCIE0_ADDR2   I103 @S9S_MB_2U_LIB.S9S_MB_2U(SCH_1):PAGE221
    20     NC     NC   I103 @S9S_MB_2U_LIB.S9S_MB_2U(SCH_1):PAGE221
    19     NC     NC   I103 @S9S_MB_2U_LIB.S9S_MB_2U(SCH_1):PAGE221
    18     NC     NC   I103 @S9S_MB_2U_LIB.S9S_MB_2U(SCH_1):PAGE221
    17     NC     NC   I103 @S9S_MB_2U_LIB.S9S_MB_2U(SCH_1):PAGE221
    16     NC     NC   I103 @S9S_MB_2U_LIB.S9S_MB_2U(SCH_1):PAGE221
    15     NC     NC   I103 @S9S_MB_2U_LIB.S9S_MB_2U(SCH_1):PAGE221
    14 SMB_LM75_3_3V3AUX_SCL_R @S9S_MB_2U_LIB.S9S_MB_2U(SCH_1):SMB_LM75_3_3V3AUX_SCL_R   I103 @S9S_MB_2U_LIB.S9S_MB_2U(SCH_1):PAGE221
    13 SMB_LM75_3_3V3AUX_SDA_R @S9S_MB_2U_LIB.S9S_MB_2U(SCH_1):SMB_LM75_3_3V3AUX_SDA_R   I103 @S9S_MB_2U_LIB.S9S_MB_2U(SCH_1):PAGE221

 U49 MOSFET_N_SMLF-BSS138K,BSS138K,A
     G HP_LVC3_OCP_V3_1_PRSNT2_N @S9S_MB_2U_LIB.S9S_MB_2U(SCH_1):HP_LVC3_OCP_V3_1_PRSNT2_N   I177 @S9S_MB_2U_LIB.S9S_MB_2U(SCH_1):PAGE154
     D HP_LVC3_OCP_V3_1_PRSNT2 @S9S_MB_2U_LIB.S9S_MB_2U(SCH_1):HP_LVC3_OCP_V3_1_PRSNT2   I177 @S9S_MB_2U_LIB.S9S_MB_2U(SCH_1):PAGE154
     S    GND @S9S_MB_2U_LIB.S9S_MB_2U(SCH_1):GND   I177 @S9S_MB_2U_LIB.S9S_MB_2U(SCH_1):PAGE154

 U50 74LVC1G08W57-74LVC1G08W5-7,SMLA
     1 HP_OCP_V3_2_EN @S9S_MB_2U_LIB.S9S_MB_2U(SCH_1):HP_OCP_V3_2_EN     I9 @S9S_MB_2U_LIB.S9S_MB_2U(SCH_1):PAGE132
     2 HP_LVC3_OCP_V3_2_PRSNT2 @S9S_MB_2U_LIB.S9S_MB_2U(SCH_1):HP_LVC3_OCP_V3_2_PRSNT2     I9 @S9S_MB_2U_LIB.S9S_MB_2U(SCH_1):PAGE132
     3    GND @S9S_MB_2U_LIB.S9S_MB_2U(SCH_1):GND     I9 @S9S_MB_2U_LIB.S9S_MB_2U(SCH_1):PAGE132
     4 HP_LVC3_OCP_V3_2_EN @S9S_MB_2U_LIB.S9S_MB_2U(SCH_1):HP_LVC3_OCP_V3_2_EN     I9 @S9S_MB_2U_LIB.S9S_MB_2U(SCH_1):PAGE132
     5 P3V3_AUX @S9S_MB_2U_LIB.S9S_MB_2U(SCH_1):P3V3_AUX     I9 @S9S_MB_2U_LIB.S9S_MB_2U(SCH_1):PAGE132

 U51 PCA9555APW-PCA9555APW,SMLF,IC,A
    24 P3V3_AUX @S9S_MB_2U_LIB.S9S_MB_2U(SCH_1):P3V3_AUX    I66 @S9S_MB_2U_LIB.S9S_MB_2U(SCH_1):PAGE132
    12    GND @S9S_MB_2U_LIB.S9S_MB_2U(SCH_1):GND    I66 @S9S_MB_2U_LIB.S9S_MB_2U(SCH_1):PAGE132
     1 FM_SMB_CPU1_ALERT @S9S_MB_2U_LIB.S9S_MB_2U(SCH_1):FM_SMB_CPU1_ALERT    I66 @S9S_MB_2U_LIB.S9S_MB_2U(SCH_1):PAGE132
    23 SMB_PEHPCPU1_LVC3_R3_SDA @S9S_MB_2U_LIB.S9S_MB_2U(SCH_1):SMB_PEHPCPU1_LVC3_R3_SDA    I66 @S9S_MB_2U_LIB.S9S_MB_2U(SCH_1):PAGE132
    22 SMB_PEHPCPU1_LVC3_R3_SCL @S9S_MB_2U_LIB.S9S_MB_2U(SCH_1):SMB_PEHPCPU1_LVC3_R3_SCL    I66 @S9S_MB_2U_LIB.S9S_MB_2U(SCH_1):PAGE132
     4 TP_PCA9555_U51_P00 @S9S_MB_2U_LIB.S9S_MB_2U(SCH_1):TP_PCA9555_U51_P00    I66 @S9S_MB_2U_LIB.S9S_MB_2U(SCH_1):PAGE132
     5 TP_PCA9555_U51_P01 @S9S_MB_2U_LIB.S9S_MB_2U(SCH_1):TP_PCA9555_U51_P01    I66 @S9S_MB_2U_LIB.S9S_MB_2U(SCH_1):PAGE132
     6 HP_OCP_V3_2_EN @S9S_MB_2U_LIB.S9S_MB_2U(SCH_1):HP_OCP_V3_2_EN    I66 @S9S_MB_2U_LIB.S9S_MB_2U(SCH_1):PAGE132
     7 HP_LVC3_OCP_V3_2_ATTN_OUT_SW_N @S9S_MB_2U_LIB.S9S_MB_2U(SCH_1):HP_LVC3_OCP_V3_2_ATTN_OUT_SW_N    I66 @S9S_MB_2U_LIB.S9S_MB_2U(SCH_1):PAGE132
     8 HP_LVC3_OCP_V3_2_PRSNT2_N @S9S_MB_2U_LIB.S9S_MB_2U(SCH_1):HP_LVC3_OCP_V3_2_PRSNT2_N    I66 @S9S_MB_2U_LIB.S9S_MB_2U(SCH_1):PAGE132
     9 TP_PCA9555_U51_P05 @S9S_MB_2U_LIB.S9S_MB_2U(SCH_1):TP_PCA9555_U51_P05    I66 @S9S_MB_2U_LIB.S9S_MB_2U(SCH_1):PAGE132
    10 TP_PCA9555_U51_P06 @S9S_MB_2U_LIB.S9S_MB_2U(SCH_1):TP_PCA9555_U51_P06    I66 @S9S_MB_2U_LIB.S9S_MB_2U(SCH_1):PAGE132
    11 TP_PCA9555_U51_P07 @S9S_MB_2U_LIB.S9S_MB_2U(SCH_1):TP_PCA9555_U51_P07    I66 @S9S_MB_2U_LIB.S9S_MB_2U(SCH_1):PAGE132
    13 TP_PCA9555_U51_P10 @S9S_MB_2U_LIB.S9S_MB_2U(SCH_1):TP_PCA9555_U51_P10    I66 @S9S_MB_2U_LIB.S9S_MB_2U(SCH_1):PAGE132
    14 TP_PCA9555_U51_P11 @S9S_MB_2U_LIB.S9S_MB_2U(SCH_1):TP_PCA9555_U51_P11    I66 @S9S_MB_2U_LIB.S9S_MB_2U(SCH_1):PAGE132
    15 TP_PCA9555_U51_P12 @S9S_MB_2U_LIB.S9S_MB_2U(SCH_1):TP_PCA9555_U51_P12    I66 @S9S_MB_2U_LIB.S9S_MB_2U(SCH_1):PAGE132
    16 TP_PCA9555_U51_P13 @S9S_MB_2U_LIB.S9S_MB_2U(SCH_1):TP_PCA9555_U51_P13    I66 @S9S_MB_2U_LIB.S9S_MB_2U(SCH_1):PAGE132
    17 TP_PCA9555_U51_P14 @S9S_MB_2U_LIB.S9S_MB_2U(SCH_1):TP_PCA9555_U51_P14    I66 @S9S_MB_2U_LIB.S9S_MB_2U(SCH_1):PAGE132
    18 TP_PCA9555_U51_P15 @S9S_MB_2U_LIB.S9S_MB_2U(SCH_1):TP_PCA9555_U51_P15    I66 @S9S_MB_2U_LIB.S9S_MB_2U(SCH_1):PAGE132
    19 TP_PCA9555_U51_P16 @S9S_MB_2U_LIB.S9S_MB_2U(SCH_1):TP_PCA9555_U51_P16    I66 @S9S_MB_2U_LIB.S9S_MB_2U(SCH_1):PAGE132
    20 TP_PCA9555_U51_P17 @S9S_MB_2U_LIB.S9S_MB_2U(SCH_1):TP_PCA9555_U51_P17    I66 @S9S_MB_2U_LIB.S9S_MB_2U(SCH_1):PAGE132
    21 PD_SMB_OCP2_HP_ADD0 @S9S_MB_2U_LIB.S9S_MB_2U(SCH_1):PD_SMB_OCP2_HP_ADD0    I66 @S9S_MB_2U_LIB.S9S_MB_2U(SCH_1):PAGE132
     2 PD_SMB_OCP2_HP_ADD1 @S9S_MB_2U_LIB.S9S_MB_2U(SCH_1):PD_SMB_OCP2_HP_ADD1    I66 @S9S_MB_2U_LIB.S9S_MB_2U(SCH_1):PAGE132
     3 PD_SMB_OCP2_HP_ADD2 @S9S_MB_2U_LIB.S9S_MB_2U(SCH_1):PD_SMB_OCP2_HP_ADD2    I66 @S9S_MB_2U_LIB.S9S_MB_2U(SCH_1):PAGE132

 U52 APX80929SAG7-APX809-29SAG-7,SMA
     3 P3V3_OCP_SFF @S9S_MB_2U_LIB.S9S_MB_2U(SCH_1):P3V3_OCP_SFF   I228 @S9S_MB_2U_LIB.S9S_MB_2U(SCH_1):PAGE154
     2 HP_OCP_V3_1_RST @S9S_MB_2U_LIB.S9S_MB_2U(SCH_1):HP_OCP_V3_1_RST   I228 @S9S_MB_2U_LIB.S9S_MB_2U(SCH_1):PAGE154
     1    GND @S9S_MB_2U_LIB.S9S_MB_2U(SCH_1):GND   I228 @S9S_MB_2U_LIB.S9S_MB_2U(SCH_1):PAGE154

 U53 74LVC1G08W57-74LVC1G08W5-7,SMLA
     1 HP_LVC3_OCP_V3_2_PWRGD_R @S9S_MB_2U_LIB.S9S_MB_2U(SCH_1):HP_LVC3_OCP_V3_2_PWRGD_R    I56 @S9S_MB_2U_LIB.S9S_MB_2U(SCH_1):PAGE132
     2 RST_OCP_V3_2_N @S9S_MB_2U_LIB.S9S_MB_2U(SCH_1):RST_OCP_V3_2_N    I56 @S9S_MB_2U_LIB.S9S_MB_2U(SCH_1):PAGE132
     3    GND @S9S_MB_2U_LIB.S9S_MB_2U(SCH_1):GND    I56 @S9S_MB_2U_LIB.S9S_MB_2U(SCH_1):PAGE132
     4 RST_HP_OCP_V3_2_N @S9S_MB_2U_LIB.S9S_MB_2U(SCH_1):RST_HP_OCP_V3_2_N    I56 @S9S_MB_2U_LIB.S9S_MB_2U(SCH_1):PAGE132
     5 P3V3_AUX @S9S_MB_2U_LIB.S9S_MB_2U(SCH_1):P3V3_AUX    I56 @S9S_MB_2U_LIB.S9S_MB_2U(SCH_1):PAGE132

 U58 74LVC2G07DW7-74LVC2G07DW-7,SMLA
     1 OCP_V3_2_PRSNT0_R_N @S9S_MB_2U_LIB.S9S_MB_2U(SCH_1):OCP_V3_2_PRSNT0_R_N    I25 @S9S_MB_2U_LIB.S9S_MB_2U(SCH_1):PAGE131
     3 OCP_V3_2_PRSNT1_R_N @S9S_MB_2U_LIB.S9S_MB_2U(SCH_1):OCP_V3_2_PRSNT1_R_N    I25 @S9S_MB_2U_LIB.S9S_MB_2U(SCH_1):PAGE131
     6 HP_LVC3_OCP_V3_2_PRSNT2_N_R @S9S_MB_2U_LIB.S9S_MB_2U(SCH_1):HP_LVC3_OCP_V3_2_PRSNT2_N_R    I25 @S9S_MB_2U_LIB.S9S_MB_2U(SCH_1):PAGE131
     4 HP_LVC3_OCP_V3_2_PRSNT2_N_R @S9S_MB_2U_LIB.S9S_MB_2U(SCH_1):HP_LVC3_OCP_V3_2_PRSNT2_N_R    I25 @S9S_MB_2U_LIB.S9S_MB_2U(SCH_1):PAGE131
     2    GND @S9S_MB_2U_LIB.S9S_MB_2U(SCH_1):GND    I25 @S9S_MB_2U_LIB.S9S_MB_2U(SCH_1):PAGE131
     5 P3V3_AUX @S9S_MB_2U_LIB.S9S_MB_2U(SCH_1):P3V3_AUX    I25 @S9S_MB_2U_LIB.S9S_MB_2U(SCH_1):PAGE131

 U59 74LVC2G07DW7-74LVC2G07DW-7,SMLA
     1 OCP_V3_2_PRSNT2_R_N @S9S_MB_2U_LIB.S9S_MB_2U(SCH_1):OCP_V3_2_PRSNT2_R_N    I19 @S9S_MB_2U_LIB.S9S_MB_2U(SCH_1):PAGE131
     3 OCP_V3_2_PRSNT3_R_N @S9S_MB_2U_LIB.S9S_MB_2U(SCH_1):OCP_V3_2_PRSNT3_R_N    I19 @S9S_MB_2U_LIB.S9S_MB_2U(SCH_1):PAGE131
     6 HP_LVC3_OCP_V3_2_PRSNT2_N_R @S9S_MB_2U_LIB.S9S_MB_2U(SCH_1):HP_LVC3_OCP_V3_2_PRSNT2_N_R    I19 @S9S_MB_2U_LIB.S9S_MB_2U(SCH_1):PAGE131
     4 HP_LVC3_OCP_V3_2_PRSNT2_N_R @S9S_MB_2U_LIB.S9S_MB_2U(SCH_1):HP_LVC3_OCP_V3_2_PRSNT2_N_R    I19 @S9S_MB_2U_LIB.S9S_MB_2U(SCH_1):PAGE131
     2    GND @S9S_MB_2U_LIB.S9S_MB_2U(SCH_1):GND    I19 @S9S_MB_2U_LIB.S9S_MB_2U(SCH_1):PAGE131
     5 P3V3_AUX @S9S_MB_2U_LIB.S9S_MB_2U(SCH_1):P3V3_AUX    I19 @S9S_MB_2U_LIB.S9S_MB_2U(SCH_1):PAGE131

 U60 NC7SB3157_SMLF-NC7SB3157P6X,NCA
     1 IRQ_LPC_PIRQA_N_ESPI_ALERT0_R_N @S9S_MB_2U_LIB.S9S_MB_2U(SCH_1):IRQ_LPC_PIRQA_N_ESPI_ALERT0_R_N    I34 @S9S_MB_2U_LIB.S9S_MB_2U(SCH_1):PAGE190
     2    GND @S9S_MB_2U_LIB.S9S_MB_2U(SCH_1):GND    I34 @S9S_MB_2U_LIB.S9S_MB_2U(SCH_1):PAGE190
     3 IRQ_LPC_SERIRQ_ESPI_CS1_R_N @S9S_MB_2U_LIB.S9S_MB_2U(SCH_1):IRQ_LPC_SERIRQ_ESPI_CS1_R_N    I34 @S9S_MB_2U_LIB.S9S_MB_2U(SCH_1):PAGE190
     6 FM_ESPI_PLD_EN @S9S_MB_2U_LIB.S9S_MB_2U(SCH_1):FM_ESPI_PLD_EN    I34 @S9S_MB_2U_LIB.S9S_MB_2U(SCH_1):PAGE190
     5 PGPPA_AUX @S9S_MB_2U_LIB.S9S_MB_2U(SCH_1):PGPPA_AUX    I34 @S9S_MB_2U_LIB.S9S_MB_2U(SCH_1):PAGE190
     4 IRQ_ESPI_LPC_SERIRQ_ALERT_N @S9S_MB_2U_LIB.S9S_MB_2U(SCH_1):IRQ_ESPI_LPC_SERIRQ_ALERT_N    I34 @S9S_MB_2U_LIB.S9S_MB_2U(SCH_1):PAGE190

 U61 NC7SB3157_SMLF-NC7SB3157P6X,NCA
     1 RST_ESPI_RESET_N_R @S9S_MB_2U_LIB.S9S_MB_2U(SCH_1):RST_ESPI_RESET_N_R    I39 @S9S_MB_2U_LIB.S9S_MB_2U(SCH_1):PAGE190
     2    GND @S9S_MB_2U_LIB.S9S_MB_2U(SCH_1):GND    I39 @S9S_MB_2U_LIB.S9S_MB_2U(SCH_1):PAGE190
     3 RST_PLTRST_B_MUX_N @S9S_MB_2U_LIB.S9S_MB_2U(SCH_1):RST_PLTRST_B_MUX_N    I39 @S9S_MB_2U_LIB.S9S_MB_2U(SCH_1):PAGE190
     6 FM_ESPI_PLD_EN @S9S_MB_2U_LIB.S9S_MB_2U(SCH_1):FM_ESPI_PLD_EN    I39 @S9S_MB_2U_LIB.S9S_MB_2U(SCH_1):PAGE190
     5 PGPPA_AUX @S9S_MB_2U_LIB.S9S_MB_2U(SCH_1):PGPPA_AUX    I39 @S9S_MB_2U_LIB.S9S_MB_2U(SCH_1):PAGE190
     4 ESPI_BMC_LPC_RST_N @S9S_MB_2U_LIB.S9S_MB_2U(SCH_1):ESPI_BMC_LPC_RST_N    I39 @S9S_MB_2U_LIB.S9S_MB_2U(SCH_1):PAGE190

 U62 BAS70057F-BAS70-05-7-F,SMLF,ICA
     2 P3V3_AUX @S9S_MB_2U_LIB.S9S_MB_2U(SCH_1):P3V3_AUX    I64 @S9S_MB_2U_LIB.S9S_MB_2U(SCH_1):PAGE177
     1 P3V_BAT_R @S9S_MB_2U_LIB.S9S_MB_2U(SCH_1):P3V_BAT_R    I64 @S9S_MB_2U_LIB.S9S_MB_2U(SCH_1):PAGE177
     3 P3V3_RTC_AUX @S9S_MB_2U_LIB.S9S_MB_2U(SCH_1):P3V3_RTC_AUX    I64 @S9S_MB_2U_LIB.S9S_MB_2U(SCH_1):PAGE177

 U64 M24128BWMN6TP-M24128-BWMN6TP,SA
     8 P3V3_AUX @S9S_MB_2U_LIB.S9S_MB_2U(SCH_1):P3V3_AUX    I35 @S9S_MB_2U_LIB.S9S_MB_2U(SCH_1):PAGE231
     7 PD_MB_FRU_WP @S9S_MB_2U_LIB.S9S_MB_2U(SCH_1):PD_MB_FRU_WP    I35 @S9S_MB_2U_LIB.S9S_MB_2U(SCH_1):PAGE231
     6 SMB_FRU_3V3AUX_SCL @S9S_MB_2U_LIB.S9S_MB_2U(SCH_1):SMB_FRU_3V3AUX_SCL    I35 @S9S_MB_2U_LIB.S9S_MB_2U(SCH_1):PAGE231
     5 SMB_FRU_3V3AUX_SDA @S9S_MB_2U_LIB.S9S_MB_2U(SCH_1):SMB_FRU_3V3AUX_SDA    I35 @S9S_MB_2U_LIB.S9S_MB_2U(SCH_1):PAGE231
     4    GND @S9S_MB_2U_LIB.S9S_MB_2U(SCH_1):GND    I35 @S9S_MB_2U_LIB.S9S_MB_2U(SCH_1):PAGE231
     3 MB_FRU_ADDR2 @S9S_MB_2U_LIB.S9S_MB_2U(SCH_1):MB_FRU_ADDR2    I35 @S9S_MB_2U_LIB.S9S_MB_2U(SCH_1):PAGE231
     2 MB_FRU_ADDR1 @S9S_MB_2U_LIB.S9S_MB_2U(SCH_1):MB_FRU_ADDR1    I35 @S9S_MB_2U_LIB.S9S_MB_2U(SCH_1):PAGE231
     1 MB_FRU_ADDR0 @S9S_MB_2U_LIB.S9S_MB_2U(SCH_1):MB_FRU_ADDR0    I35 @S9S_MB_2U_LIB.S9S_MB_2U(SCH_1):PAGE231

 U66 74LVC1G126SE7-74LVC1G126SE-7,SA
     2 FM_OCP_SFF_PWR_GOOD @S9S_MB_2U_LIB.S9S_MB_2U(SCH_1):FM_OCP_SFF_PWR_GOOD    I15 @S9S_MB_2U_LIB.S9S_MB_2U(SCH_1):PAGE151
     4 FB_BMC_ISOLATE_R1 @S9S_MB_2U_LIB.S9S_MB_2U(SCH_1):FB_BMC_ISOLATE_R1    I15 @S9S_MB_2U_LIB.S9S_MB_2U(SCH_1):PAGE151
     5 P3V3_AUX @S9S_MB_2U_LIB.S9S_MB_2U(SCH_1):P3V3_AUX    I15 @S9S_MB_2U_LIB.S9S_MB_2U(SCH_1):PAGE151
     3    GND @S9S_MB_2U_LIB.S9S_MB_2U(SCH_1):GND    I15 @S9S_MB_2U_LIB.S9S_MB_2U(SCH_1):PAGE151
     1 OCP_SFF_AUX_PWR_EN_R1 @S9S_MB_2U_LIB.S9S_MB_2U(SCH_1):OCP_SFF_AUX_PWR_EN_R1    I15 @S9S_MB_2U_LIB.S9S_MB_2U(SCH_1):PAGE151

 U67 74CBTLV3126PW-74CBTLV3126PW,SMA
     5 NCSI_BMC_RXD0_R @S9S_MB_2U_LIB.S9S_MB_2U(SCH_1):NCSI_BMC_RXD0_R    I39 @S9S_MB_2U_LIB.S9S_MB_2U(SCH_1):PAGE151
     8 NCSI_OCP_SFF_CRS_DV @S9S_MB_2U_LIB.S9S_MB_2U(SCH_1):NCSI_OCP_SFF_CRS_DV    I39 @S9S_MB_2U_LIB.S9S_MB_2U(SCH_1):PAGE151
     1 FB_BMC_ISOLATE @S9S_MB_2U_LIB.S9S_MB_2U(SCH_1):FB_BMC_ISOLATE    I39 @S9S_MB_2U_LIB.S9S_MB_2U(SCH_1):PAGE151
     4 FB_BMC_ISOLATE @S9S_MB_2U_LIB.S9S_MB_2U(SCH_1):FB_BMC_ISOLATE    I39 @S9S_MB_2U_LIB.S9S_MB_2U(SCH_1):PAGE151
     3 NCSI_OCP_SFF_RXD1 @S9S_MB_2U_LIB.S9S_MB_2U(SCH_1):NCSI_OCP_SFF_RXD1    I39 @S9S_MB_2U_LIB.S9S_MB_2U(SCH_1):PAGE151
     6 NCSI_OCP_SFF_RXD0 @S9S_MB_2U_LIB.S9S_MB_2U(SCH_1):NCSI_OCP_SFF_RXD0    I39 @S9S_MB_2U_LIB.S9S_MB_2U(SCH_1):PAGE151
     2 NCSI_BMC_RXD1_R @S9S_MB_2U_LIB.S9S_MB_2U(SCH_1):NCSI_BMC_RXD1_R    I39 @S9S_MB_2U_LIB.S9S_MB_2U(SCH_1):PAGE151
     7    GND @S9S_MB_2U_LIB.S9S_MB_2U(SCH_1):GND    I39 @S9S_MB_2U_LIB.S9S_MB_2U(SCH_1):PAGE151
     9 NCSI_BMC_CRS_DV_R @S9S_MB_2U_LIB.S9S_MB_2U(SCH_1):NCSI_BMC_CRS_DV_R    I39 @S9S_MB_2U_LIB.S9S_MB_2U(SCH_1):PAGE151
    10 FB_BMC_ISOLATE @S9S_MB_2U_LIB.S9S_MB_2U(SCH_1):FB_BMC_ISOLATE    I39 @S9S_MB_2U_LIB.S9S_MB_2U(SCH_1):PAGE151
    11 OCP_SFF_ISO1_RBT_ARB_IN @S9S_MB_2U_LIB.S9S_MB_2U(SCH_1):OCP_SFF_ISO1_RBT_ARB_IN    I39 @S9S_MB_2U_LIB.S9S_MB_2U(SCH_1):PAGE151
    12 OCP_SFF_RBT_ARB_IN_R @S9S_MB_2U_LIB.S9S_MB_2U(SCH_1):OCP_SFF_RBT_ARB_IN_R    I39 @S9S_MB_2U_LIB.S9S_MB_2U(SCH_1):PAGE151
    13 FB_BMC_ISOLATE @S9S_MB_2U_LIB.S9S_MB_2U(SCH_1):FB_BMC_ISOLATE    I39 @S9S_MB_2U_LIB.S9S_MB_2U(SCH_1):PAGE151
    14 P3V3_AUX @S9S_MB_2U_LIB.S9S_MB_2U(SCH_1):P3V3_AUX    I39 @S9S_MB_2U_LIB.S9S_MB_2U(SCH_1):PAGE151

 U68 74CBTLV3126PW-74CBTLV3126PW,SMA
     5 NCSI_BMC_TXD0_R @S9S_MB_2U_LIB.S9S_MB_2U(SCH_1):NCSI_BMC_TXD0_R    I30 @S9S_MB_2U_LIB.S9S_MB_2U(SCH_1):PAGE151
     8 NCSI_OCP_SFF_TX_EN @S9S_MB_2U_LIB.S9S_MB_2U(SCH_1):NCSI_OCP_SFF_TX_EN    I30 @S9S_MB_2U_LIB.S9S_MB_2U(SCH_1):PAGE151
     1 FB_BMC_ISOLATE @S9S_MB_2U_LIB.S9S_MB_2U(SCH_1):FB_BMC_ISOLATE    I30 @S9S_MB_2U_LIB.S9S_MB_2U(SCH_1):PAGE151
     4 FB_BMC_ISOLATE @S9S_MB_2U_LIB.S9S_MB_2U(SCH_1):FB_BMC_ISOLATE    I30 @S9S_MB_2U_LIB.S9S_MB_2U(SCH_1):PAGE151
     3 NCSI_OCP_SFF_TXD1 @S9S_MB_2U_LIB.S9S_MB_2U(SCH_1):NCSI_OCP_SFF_TXD1    I30 @S9S_MB_2U_LIB.S9S_MB_2U(SCH_1):PAGE151
     6 NCSI_OCP_SFF_TXD0 @S9S_MB_2U_LIB.S9S_MB_2U(SCH_1):NCSI_OCP_SFF_TXD0    I30 @S9S_MB_2U_LIB.S9S_MB_2U(SCH_1):PAGE151
     2 NCSI_BMC_TXD1_R @S9S_MB_2U_LIB.S9S_MB_2U(SCH_1):NCSI_BMC_TXD1_R    I30 @S9S_MB_2U_LIB.S9S_MB_2U(SCH_1):PAGE151
     7    GND @S9S_MB_2U_LIB.S9S_MB_2U(SCH_1):GND    I30 @S9S_MB_2U_LIB.S9S_MB_2U(SCH_1):PAGE151
     9 NCSI_BMC_TX_EN_R @S9S_MB_2U_LIB.S9S_MB_2U(SCH_1):NCSI_BMC_TX_EN_R    I30 @S9S_MB_2U_LIB.S9S_MB_2U(SCH_1):PAGE151
    10 FB_BMC_ISOLATE @S9S_MB_2U_LIB.S9S_MB_2U(SCH_1):FB_BMC_ISOLATE    I30 @S9S_MB_2U_LIB.S9S_MB_2U(SCH_1):PAGE151
    11 OCP_SFF_ISO2_RBT_ARB_OUT @S9S_MB_2U_LIB.S9S_MB_2U(SCH_1):OCP_SFF_ISO2_RBT_ARB_OUT    I30 @S9S_MB_2U_LIB.S9S_MB_2U(SCH_1):PAGE151
    12 OCP_SFF_RBT_ARB_OUT @S9S_MB_2U_LIB.S9S_MB_2U(SCH_1):OCP_SFF_RBT_ARB_OUT    I30 @S9S_MB_2U_LIB.S9S_MB_2U(SCH_1):PAGE151
    13 FB_BMC_ISOLATE @S9S_MB_2U_LIB.S9S_MB_2U(SCH_1):FB_BMC_ISOLATE    I30 @S9S_MB_2U_LIB.S9S_MB_2U(SCH_1):PAGE151
    14 P3V3_AUX @S9S_MB_2U_LIB.S9S_MB_2U(SCH_1):P3V3_AUX    I30 @S9S_MB_2U_LIB.S9S_MB_2U(SCH_1):PAGE151

 U70 MOSFET_N_SMLF-BSS138K,BSS138K,A
     G FM_PLD_CLKS_DEV_EN @S9S_MB_2U_LIB.S9S_MB_2U(SCH_1):FM_PLD_CLKS_DEV_EN    I19 @S9S_MB_2U_LIB.S9S_MB_2U(SCH_1):PAGE212
     D FM_PLD_CLKS_OE_R_N @S9S_MB_2U_LIB.S9S_MB_2U(SCH_1):FM_PLD_CLKS_OE_R_N    I19 @S9S_MB_2U_LIB.S9S_MB_2U(SCH_1):PAGE212
     S    GND @S9S_MB_2U_LIB.S9S_MB_2U(SCH_1):GND    I19 @S9S_MB_2U_LIB.S9S_MB_2U(SCH_1):PAGE212

 U75 74LVC1G17GW-74LVC1G17GW,SMLF,IA
     5 P3V3_AUX @S9S_MB_2U_LIB.S9S_MB_2U(SCH_1):P3V3_AUX     I1 @S9S_MB_2U_LIB.S9S_MB_2U(SCH_1):PAGE152
     2 RST_HP_OCP_V3_1_N @S9S_MB_2U_LIB.S9S_MB_2U(SCH_1):RST_HP_OCP_V3_1_N     I1 @S9S_MB_2U_LIB.S9S_MB_2U(SCH_1):PAGE152
     3    GND @S9S_MB_2U_LIB.S9S_MB_2U(SCH_1):GND     I1 @S9S_MB_2U_LIB.S9S_MB_2U(SCH_1):PAGE152
     4 RST_OCP_V3_1_BUF_N @S9S_MB_2U_LIB.S9S_MB_2U(SCH_1):RST_OCP_V3_1_BUF_N     I1 @S9S_MB_2U_LIB.S9S_MB_2U(SCH_1):PAGE152
     1     NC     NC     I1 @S9S_MB_2U_LIB.S9S_MB_2U(SCH_1):PAGE152

 U82 74LVC1G126SE7-74LVC1G126SE-7,SA
     2 IRQ_LVC3_OCP_SFF_WAKE_N @S9S_MB_2U_LIB.S9S_MB_2U(SCH_1):IRQ_LVC3_OCP_SFF_WAKE_N    I79 @S9S_MB_2U_LIB.S9S_MB_2U(SCH_1):PAGE152
     4 OCP_SFF_WAKE_BUFF_N @S9S_MB_2U_LIB.S9S_MB_2U(SCH_1):OCP_SFF_WAKE_BUFF_N    I79 @S9S_MB_2U_LIB.S9S_MB_2U(SCH_1):PAGE152
     5 P3V3_AUX @S9S_MB_2U_LIB.S9S_MB_2U(SCH_1):P3V3_AUX    I79 @S9S_MB_2U_LIB.S9S_MB_2U(SCH_1):PAGE152
     3    GND @S9S_MB_2U_LIB.S9S_MB_2U(SCH_1):GND    I79 @S9S_MB_2U_LIB.S9S_MB_2U(SCH_1):PAGE152
     1 PU_OCP_SFF_WAKE_OE @S9S_MB_2U_LIB.S9S_MB_2U(SCH_1):PU_OCP_SFF_WAKE_OE    I79 @S9S_MB_2U_LIB.S9S_MB_2U(SCH_1):PAGE152

 U83 GTL2014PW-GTL2014PW,SMLF,IC,ALA
     2 PD_JTAG_DBP_B0 @S9S_MB_2U_LIB.S9S_MB_2U(SCH_1):PD_JTAG_DBP_B0    I45 @S9S_MB_2U_LIB.S9S_MB_2U(SCH_1):PAGE226
     3 JTAG_DBP_PRDY_R_N @S9S_MB_2U_LIB.S9S_MB_2U(SCH_1):JTAG_DBP_PRDY_R_N    I45 @S9S_MB_2U_LIB.S9S_MB_2U(SCH_1):PAGE226
     5 PD_JTAG_DBP_B2 @S9S_MB_2U_LIB.S9S_MB_2U(SCH_1):PD_JTAG_DBP_B2    I45 @S9S_MB_2U_LIB.S9S_MB_2U(SCH_1):PAGE226
     6 JTAG_DBP_FB_TDO @S9S_MB_2U_LIB.S9S_MB_2U(SCH_1):JTAG_DBP_FB_TDO    I45 @S9S_MB_2U_LIB.S9S_MB_2U(SCH_1):PAGE226
    11    GND @S9S_MB_2U_LIB.S9S_MB_2U(SCH_1):GND    I45 @S9S_MB_2U_LIB.S9S_MB_2U(SCH_1):PAGE226
     8    GND @S9S_MB_2U_LIB.S9S_MB_2U(SCH_1):GND    I45 @S9S_MB_2U_LIB.S9S_MB_2U(SCH_1):PAGE226
     7    GND @S9S_MB_2U_LIB.S9S_MB_2U(SCH_1):GND    I45 @S9S_MB_2U_LIB.S9S_MB_2U(SCH_1):PAGE226
     9 JTAG_BMC_DBP_TDO_R @S9S_MB_2U_LIB.S9S_MB_2U(SCH_1):JTAG_BMC_DBP_TDO_R    I45 @S9S_MB_2U_LIB.S9S_MB_2U(SCH_1):PAGE226
    10 TP_JTAG_BMC_A2 @S9S_MB_2U_LIB.S9S_MB_2U(SCH_1):TP_JTAG_BMC_A2    I45 @S9S_MB_2U_LIB.S9S_MB_2U(SCH_1):PAGE226
    12 JTAG_DBP_BMC_PRDY_R1_N @S9S_MB_2U_LIB.S9S_MB_2U(SCH_1):JTAG_DBP_BMC_PRDY_R1_N    I45 @S9S_MB_2U_LIB.S9S_MB_2U(SCH_1):PAGE226
    13 TP_JTAG_BMC_A0 @S9S_MB_2U_LIB.S9S_MB_2U(SCH_1):TP_JTAG_BMC_A0    I45 @S9S_MB_2U_LIB.S9S_MB_2U(SCH_1):PAGE226
     1 PD_GTL2014_BMC_JTAG_DIR_2 @S9S_MB_2U_LIB.S9S_MB_2U(SCH_1):PD_GTL2014_BMC_JTAG_DIR_2    I45 @S9S_MB_2U_LIB.S9S_MB_2U(SCH_1):PAGE226
     4 P0V7_JTAG_VREF_2 @S9S_MB_2U_LIB.S9S_MB_2U(SCH_1):P0V7_JTAG_VREF_2    I45 @S9S_MB_2U_LIB.S9S_MB_2U(SCH_1):PAGE226
    14 P3V3_AUX @S9S_MB_2U_LIB.S9S_MB_2U(SCH_1):P3V3_AUX    I45 @S9S_MB_2U_LIB.S9S_MB_2U(SCH_1):PAGE226

 U84 GTL2014PW-GTL2014PW,SMLF,IC,ALA
     2 JTAG_DBP_PREQ_R_N @S9S_MB_2U_LIB.S9S_MB_2U(SCH_1):JTAG_DBP_PREQ_R_N    I18 @S9S_MB_2U_LIB.S9S_MB_2U(SCH_1):PAGE226
     3 FM_CPU_FBRK_DEBUG_N @S9S_MB_2U_LIB.S9S_MB_2U(SCH_1):FM_CPU_FBRK_DEBUG_N    I18 @S9S_MB_2U_LIB.S9S_MB_2U(SCH_1):PAGE226
     5 JTAG_DBP_FB_TDI @S9S_MB_2U_LIB.S9S_MB_2U(SCH_1):JTAG_DBP_FB_TDI    I18 @S9S_MB_2U_LIB.S9S_MB_2U(SCH_1):PAGE226
     6 JTAG_DBP_FB_TMS @S9S_MB_2U_LIB.S9S_MB_2U(SCH_1):JTAG_DBP_FB_TMS    I18 @S9S_MB_2U_LIB.S9S_MB_2U(SCH_1):PAGE226
    11    GND @S9S_MB_2U_LIB.S9S_MB_2U(SCH_1):GND    I18 @S9S_MB_2U_LIB.S9S_MB_2U(SCH_1):PAGE226
     8    GND @S9S_MB_2U_LIB.S9S_MB_2U(SCH_1):GND    I18 @S9S_MB_2U_LIB.S9S_MB_2U(SCH_1):PAGE226
     7    GND @S9S_MB_2U_LIB.S9S_MB_2U(SCH_1):GND    I18 @S9S_MB_2U_LIB.S9S_MB_2U(SCH_1):PAGE226
     9 JTAG_BMC_DBP_TMS_R @S9S_MB_2U_LIB.S9S_MB_2U(SCH_1):JTAG_BMC_DBP_TMS_R    I18 @S9S_MB_2U_LIB.S9S_MB_2U(SCH_1):PAGE226
    10 JTAG_BMC_DBP_TDI_R @S9S_MB_2U_LIB.S9S_MB_2U(SCH_1):JTAG_BMC_DBP_TDI_R    I18 @S9S_MB_2U_LIB.S9S_MB_2U(SCH_1):PAGE226
    12 FM_BMC_CPU_FBRK_OUT_N @S9S_MB_2U_LIB.S9S_MB_2U(SCH_1):FM_BMC_CPU_FBRK_OUT_N    I18 @S9S_MB_2U_LIB.S9S_MB_2U(SCH_1):PAGE226
    13 JTAG_DBP_BMC_PREQ_R1_N @S9S_MB_2U_LIB.S9S_MB_2U(SCH_1):JTAG_DBP_BMC_PREQ_R1_N    I18 @S9S_MB_2U_LIB.S9S_MB_2U(SCH_1):PAGE226
     1 PU_GTL2014_BMC_JTAG_DIR_1 @S9S_MB_2U_LIB.S9S_MB_2U(SCH_1):PU_GTL2014_BMC_JTAG_DIR_1    I18 @S9S_MB_2U_LIB.S9S_MB_2U(SCH_1):PAGE226
     4 PD_GTL2014_BMC_JTAG_VREF_1 @S9S_MB_2U_LIB.S9S_MB_2U(SCH_1):PD_GTL2014_BMC_JTAG_VREF_1    I18 @S9S_MB_2U_LIB.S9S_MB_2U(SCH_1):PAGE226
    14 P3V3_AUX @S9S_MB_2U_LIB.S9S_MB_2U(SCH_1):P3V3_AUX    I18 @S9S_MB_2U_LIB.S9S_MB_2U(SCH_1):PAGE226

 U85 NC7SB3157_SMLF-NC7SB3157P6X,NCA
     1 JTAG_BMC_PCH_TCK @S9S_MB_2U_LIB.S9S_MB_2U(SCH_1):JTAG_BMC_PCH_TCK   I109 @S9S_MB_2U_LIB.S9S_MB_2U(SCH_1):PAGE137
     2    GND @S9S_MB_2U_LIB.S9S_MB_2U(SCH_1):GND   I109 @S9S_MB_2U_LIB.S9S_MB_2U(SCH_1):PAGE137
     3 JTAG_BMC_CPU_TCK @S9S_MB_2U_LIB.S9S_MB_2U(SCH_1):JTAG_BMC_CPU_TCK   I109 @S9S_MB_2U_LIB.S9S_MB_2U(SCH_1):PAGE137
     6 FM_JTAG_TCK_MUX_SEL @S9S_MB_2U_LIB.S9S_MB_2U(SCH_1):FM_JTAG_TCK_MUX_SEL   I109 @S9S_MB_2U_LIB.S9S_MB_2U(SCH_1):PAGE137
     5 P3V3_AUX @S9S_MB_2U_LIB.S9S_MB_2U(SCH_1):P3V3_AUX   I109 @S9S_MB_2U_LIB.S9S_MB_2U(SCH_1):PAGE137
     4 JTAG_BMC_DBP_TCK @S9S_MB_2U_LIB.S9S_MB_2U(SCH_1):JTAG_BMC_DBP_TCK   I109 @S9S_MB_2U_LIB.S9S_MB_2U(SCH_1):PAGE137

 U86 74CBTLV3126PW-74CBTLV3126PW,SMA
     5 FM_BMC_EN_DET @S9S_MB_2U_LIB.S9S_MB_2U(SCH_1):FM_BMC_EN_DET    I84 @S9S_MB_2U_LIB.S9S_MB_2U(SCH_1):PAGE137
     8 JTAG_DBP_TCK_PCH_R @S9S_MB_2U_LIB.S9S_MB_2U(SCH_1):JTAG_DBP_TCK_PCH_R    I84 @S9S_MB_2U_LIB.S9S_MB_2U(SCH_1):PAGE137
     1 PD_JTAG_BMC_NTRST_N @S9S_MB_2U_LIB.S9S_MB_2U(SCH_1):PD_JTAG_BMC_NTRST_N    I84 @S9S_MB_2U_LIB.S9S_MB_2U(SCH_1):PAGE137
     4 JTAG_BMC_CPU_TCK @S9S_MB_2U_LIB.S9S_MB_2U(SCH_1):JTAG_BMC_CPU_TCK    I84 @S9S_MB_2U_LIB.S9S_MB_2U(SCH_1):PAGE137
     3 TP_JTAG_BMC_1B @S9S_MB_2U_LIB.S9S_MB_2U(SCH_1):TP_JTAG_BMC_1B    I84 @S9S_MB_2U_LIB.S9S_MB_2U(SCH_1):PAGE137
     6 JTAG_DBP_CPU_GTL_TCK_R1 @S9S_MB_2U_LIB.S9S_MB_2U(SCH_1):JTAG_DBP_CPU_GTL_TCK_R1    I84 @S9S_MB_2U_LIB.S9S_MB_2U(SCH_1):PAGE137
     2 FM_BMC_EN_DET @S9S_MB_2U_LIB.S9S_MB_2U(SCH_1):FM_BMC_EN_DET    I84 @S9S_MB_2U_LIB.S9S_MB_2U(SCH_1):PAGE137
     7    GND @S9S_MB_2U_LIB.S9S_MB_2U(SCH_1):GND    I84 @S9S_MB_2U_LIB.S9S_MB_2U(SCH_1):PAGE137
     9 FM_BMC_EN_DET @S9S_MB_2U_LIB.S9S_MB_2U(SCH_1):FM_BMC_EN_DET    I84 @S9S_MB_2U_LIB.S9S_MB_2U(SCH_1):PAGE137
    10 JTAG_BMC_PCH_TCK @S9S_MB_2U_LIB.S9S_MB_2U(SCH_1):JTAG_BMC_PCH_TCK    I84 @S9S_MB_2U_LIB.S9S_MB_2U(SCH_1):PAGE137
    11 TP_JTAG_BMC_4B @S9S_MB_2U_LIB.S9S_MB_2U(SCH_1):TP_JTAG_BMC_4B    I84 @S9S_MB_2U_LIB.S9S_MB_2U(SCH_1):PAGE137
    12 FM_BMC_EN_DET @S9S_MB_2U_LIB.S9S_MB_2U(SCH_1):FM_BMC_EN_DET    I84 @S9S_MB_2U_LIB.S9S_MB_2U(SCH_1):PAGE137
    13 PD_JTAG_BMC_NTRST_N @S9S_MB_2U_LIB.S9S_MB_2U(SCH_1):PD_JTAG_BMC_NTRST_N    I84 @S9S_MB_2U_LIB.S9S_MB_2U(SCH_1):PAGE137
    14 P3V3_AUX @S9S_MB_2U_LIB.S9S_MB_2U(SCH_1):P3V3_AUX    I84 @S9S_MB_2U_LIB.S9S_MB_2U(SCH_1):PAGE137

 U87 MOSFET_N_SMLF-BSS138K,BSS138K,A
     G FM_REMOTE_DEBUG_DET_R @S9S_MB_2U_LIB.S9S_MB_2U(SCH_1):FM_REMOTE_DEBUG_DET_R    I96 @S9S_MB_2U_LIB.S9S_MB_2U(SCH_1):PAGE137
     D P1V05_PCH_AUX @S9S_MB_2U_LIB.S9S_MB_2U(SCH_1):P1V05_PCH_AUX    I96 @S9S_MB_2U_LIB.S9S_MB_2U(SCH_1):PAGE137
     S FM_BMC_EN_DET @S9S_MB_2U_LIB.S9S_MB_2U(SCH_1):FM_BMC_EN_DET    I96 @S9S_MB_2U_LIB.S9S_MB_2U(SCH_1):PAGE137

 U89 MOSFET_N_SMLF-BSS138K,BSS138K,A
     G FM_PLD_HEARTBEAT_LVC3 @S9S_MB_2U_LIB.S9S_MB_2U(SCH_1):FM_PLD_HEARTBEAT_LVC3   I236 @S9S_MB_2U_LIB.S9S_MB_2U(SCH_1):PAGE207
     D FM_PLD_HEARTBEAT_LVC3_D @S9S_MB_2U_LIB.S9S_MB_2U(SCH_1):FM_PLD_HEARTBEAT_LVC3_D   I236 @S9S_MB_2U_LIB.S9S_MB_2U(SCH_1):PAGE207
     S    GND @S9S_MB_2U_LIB.S9S_MB_2U(SCH_1):GND   I236 @S9S_MB_2U_LIB.S9S_MB_2U(SCH_1):PAGE207

 U90 PI6CV304LE-PI6CV304LE,SMLF,IC,A
     1 CLK_50M_RMII_R @S9S_MB_2U_LIB.S9S_MB_2U(SCH_1):CLK_50M_RMII_R    I46 @S9S_MB_2U_LIB.S9S_MB_2U(SCH_1):PAGE152
     2 CLK_50M_EN @S9S_MB_2U_LIB.S9S_MB_2U(SCH_1):CLK_50M_EN    I46 @S9S_MB_2U_LIB.S9S_MB_2U(SCH_1):PAGE152
     3 CLK_50M_BMC_MAC_R @S9S_MB_2U_LIB.S9S_MB_2U(SCH_1):CLK_50M_BMC_MAC_R    I46 @S9S_MB_2U_LIB.S9S_MB_2U(SCH_1):PAGE152
     5 CLK_50M_NCSI_OCP_1 @S9S_MB_2U_LIB.S9S_MB_2U(SCH_1):CLK_50M_NCSI_OCP_1    I46 @S9S_MB_2U_LIB.S9S_MB_2U(SCH_1):PAGE152
     7 CLK_50M_NCSI_OCP_2 @S9S_MB_2U_LIB.S9S_MB_2U(SCH_1):CLK_50M_NCSI_OCP_2    I46 @S9S_MB_2U_LIB.S9S_MB_2U(SCH_1):PAGE152
     8 TP_CLK_50M_PCH_LOM @S9S_MB_2U_LIB.S9S_MB_2U(SCH_1):TP_CLK_50M_PCH_LOM    I46 @S9S_MB_2U_LIB.S9S_MB_2U(SCH_1):PAGE152
     6 P3V3_AUX @S9S_MB_2U_LIB.S9S_MB_2U(SCH_1):P3V3_AUX    I46 @S9S_MB_2U_LIB.S9S_MB_2U(SCH_1):PAGE152
     4    GND @S9S_MB_2U_LIB.S9S_MB_2U(SCH_1):GND    I46 @S9S_MB_2U_LIB.S9S_MB_2U(SCH_1):PAGE152

 U94 ADM1086AKSZREEL7-ADM1086AKSZ-RA
     6 P3V3_AUX @S9S_MB_2U_LIB.S9S_MB_2U(SCH_1):P3V3_AUX    I27 @S9S_MB_2U_LIB.S9S_MB_2U(SCH_1):PAGE232
     3 FM_COMP_P3V3_AUX_VIN @S9S_MB_2U_LIB.S9S_MB_2U(SCH_1):FM_COMP_P3V3_AUX_VIN    I27 @S9S_MB_2U_LIB.S9S_MB_2U(SCH_1):PAGE232
     1 FM_COMP_P3V3_AUX_ENIN @S9S_MB_2U_LIB.S9S_MB_2U(SCH_1):FM_COMP_P3V3_AUX_ENIN    I27 @S9S_MB_2U_LIB.S9S_MB_2U(SCH_1):PAGE232
     4 PWRGD_DSW_PWROK_R1 @S9S_MB_2U_LIB.S9S_MB_2U(SCH_1):PWRGD_DSW_PWROK_R1    I27 @S9S_MB_2U_LIB.S9S_MB_2U(SCH_1):PAGE232
     5 FM_COMP_P3V3_STBY_CEXT @S9S_MB_2U_LIB.S9S_MB_2U(SCH_1):FM_COMP_P3V3_STBY_CEXT    I27 @S9S_MB_2U_LIB.S9S_MB_2U(SCH_1):PAGE232
     2    GND @S9S_MB_2U_LIB.S9S_MB_2U(SCH_1):GND    I27 @S9S_MB_2U_LIB.S9S_MB_2U(SCH_1):PAGE232

 U95 74LVC1G07SE7-74LVC1G07SE-7,SMLA
     5 P3V3_AUX @S9S_MB_2U_LIB.S9S_MB_2U(SCH_1):P3V3_AUX    I11 @S9S_MB_2U_LIB.S9S_MB_2U(SCH_1):PAGE232
     2 PWRGD_DSW_PWROK_R1 @S9S_MB_2U_LIB.S9S_MB_2U(SCH_1):PWRGD_DSW_PWROK_R1    I11 @S9S_MB_2U_LIB.S9S_MB_2U(SCH_1):PAGE232
     3    GND @S9S_MB_2U_LIB.S9S_MB_2U(SCH_1):GND    I11 @S9S_MB_2U_LIB.S9S_MB_2U(SCH_1):PAGE232
     4 PWRGD_DSW_PWROK_R2 @S9S_MB_2U_LIB.S9S_MB_2U(SCH_1):PWRGD_DSW_PWROK_R2    I11 @S9S_MB_2U_LIB.S9S_MB_2U(SCH_1):PAGE232
     1     NC     NC    I11 @S9S_MB_2U_LIB.S9S_MB_2U(SCH_1):PAGE232

 U96 NX3L2267GM-NX3L2267GM,SMLF,IC,A
    10 P3V3_AUX @S9S_MB_2U_LIB.S9S_MB_2U(SCH_1):P3V3_AUX    I68 @S9S_MB_2U_LIB.S9S_MB_2U(SCH_1):PAGE226
     6 JTAG_BMC_SW_TDO @S9S_MB_2U_LIB.S9S_MB_2U(SCH_1):JTAG_BMC_SW_TDO    I68 @S9S_MB_2U_LIB.S9S_MB_2U(SCH_1):PAGE226
     1 JTAG_BMC_PLD_TDI @S9S_MB_2U_LIB.S9S_MB_2U(SCH_1):JTAG_BMC_PLD_TDI    I68 @S9S_MB_2U_LIB.S9S_MB_2U(SCH_1):PAGE226
     5    GND @S9S_MB_2U_LIB.S9S_MB_2U(SCH_1):GND    I68 @S9S_MB_2U_LIB.S9S_MB_2U(SCH_1):PAGE226
     2 JTAG_BMC_DBP_TDI @S9S_MB_2U_LIB.S9S_MB_2U(SCH_1):JTAG_BMC_DBP_TDI    I68 @S9S_MB_2U_LIB.S9S_MB_2U(SCH_1):PAGE226
     7 FM_JTAG_BMC_MUX_SEL @S9S_MB_2U_LIB.S9S_MB_2U(SCH_1):FM_JTAG_BMC_MUX_SEL    I68 @S9S_MB_2U_LIB.S9S_MB_2U(SCH_1):PAGE226
     4 JTAG_BMC_DBP_TDO @S9S_MB_2U_LIB.S9S_MB_2U(SCH_1):JTAG_BMC_DBP_TDO    I68 @S9S_MB_2U_LIB.S9S_MB_2U(SCH_1):PAGE226
     9 JTAG_BMC_SW_TDI @S9S_MB_2U_LIB.S9S_MB_2U(SCH_1):JTAG_BMC_SW_TDI    I68 @S9S_MB_2U_LIB.S9S_MB_2U(SCH_1):PAGE226
     8 FM_JTAG_BMC_MUX_SEL @S9S_MB_2U_LIB.S9S_MB_2U(SCH_1):FM_JTAG_BMC_MUX_SEL    I68 @S9S_MB_2U_LIB.S9S_MB_2U(SCH_1):PAGE226
     3 JTAG_BMC_PLD_TDO @S9S_MB_2U_LIB.S9S_MB_2U(SCH_1):JTAG_BMC_PLD_TDO    I68 @S9S_MB_2U_LIB.S9S_MB_2U(SCH_1):PAGE226

 U97 NX3L2267GM-NX3L2267GM,SMLF,IC,A
    10 P3V3_AUX @S9S_MB_2U_LIB.S9S_MB_2U(SCH_1):P3V3_AUX    I38 @S9S_MB_2U_LIB.S9S_MB_2U(SCH_1):PAGE226
     6 JTAG_BMC_SW_TCK @S9S_MB_2U_LIB.S9S_MB_2U(SCH_1):JTAG_BMC_SW_TCK    I38 @S9S_MB_2U_LIB.S9S_MB_2U(SCH_1):PAGE226
     1 JTAG_BMC_PLD_TMS @S9S_MB_2U_LIB.S9S_MB_2U(SCH_1):JTAG_BMC_PLD_TMS    I38 @S9S_MB_2U_LIB.S9S_MB_2U(SCH_1):PAGE226
     5    GND @S9S_MB_2U_LIB.S9S_MB_2U(SCH_1):GND    I38 @S9S_MB_2U_LIB.S9S_MB_2U(SCH_1):PAGE226
     2 JTAG_BMC_DBP_TMS @S9S_MB_2U_LIB.S9S_MB_2U(SCH_1):JTAG_BMC_DBP_TMS    I38 @S9S_MB_2U_LIB.S9S_MB_2U(SCH_1):PAGE226
     7 FM_JTAG_BMC_MUX_SEL @S9S_MB_2U_LIB.S9S_MB_2U(SCH_1):FM_JTAG_BMC_MUX_SEL    I38 @S9S_MB_2U_LIB.S9S_MB_2U(SCH_1):PAGE226
     4 JTAG_BMC_DBP_TCK @S9S_MB_2U_LIB.S9S_MB_2U(SCH_1):JTAG_BMC_DBP_TCK    I38 @S9S_MB_2U_LIB.S9S_MB_2U(SCH_1):PAGE226
     9 JTAG_BMC_SW_TMS @S9S_MB_2U_LIB.S9S_MB_2U(SCH_1):JTAG_BMC_SW_TMS    I38 @S9S_MB_2U_LIB.S9S_MB_2U(SCH_1):PAGE226
     8 FM_JTAG_BMC_MUX_SEL @S9S_MB_2U_LIB.S9S_MB_2U(SCH_1):FM_JTAG_BMC_MUX_SEL    I38 @S9S_MB_2U_LIB.S9S_MB_2U(SCH_1):PAGE226
     3 JTAG_BMC_PLD_TCK @S9S_MB_2U_LIB.S9S_MB_2U(SCH_1):JTAG_BMC_PLD_TCK    I38 @S9S_MB_2U_LIB.S9S_MB_2U(SCH_1):PAGE226

 U98 PCA9306DP1-PCA9306DP1,SMLF,IC,A
     2 P1V8_PCH_AUX @S9S_MB_2U_LIB.S9S_MB_2U(SCH_1):P1V8_PCH_AUX    I27 @S9S_MB_2U_LIB.S9S_MB_2U(SCH_1):PAGE183
     3 SMB_M2_P0_1V8AUX_SCL_R @S9S_MB_2U_LIB.S9S_MB_2U(SCH_1):SMB_M2_P0_1V8AUX_SCL_R    I27 @S9S_MB_2U_LIB.S9S_MB_2U(SCH_1):PAGE183
     4 SMB_M2_P0_1V8AUX_SDA_R @S9S_MB_2U_LIB.S9S_MB_2U(SCH_1):SMB_M2_P0_1V8AUX_SDA_R    I27 @S9S_MB_2U_LIB.S9S_MB_2U(SCH_1):PAGE183
     5 SMB_SENSOR_M2_P0_3V3AUX_SDA @S9S_MB_2U_LIB.S9S_MB_2U(SCH_1):SMB_SENSOR_M2_P0_3V3AUX_SDA    I27 @S9S_MB_2U_LIB.S9S_MB_2U(SCH_1):PAGE183
     6 SMB_SENSOR_M2_P0_3V3AUX_SCL @S9S_MB_2U_LIB.S9S_MB_2U(SCH_1):SMB_SENSOR_M2_P0_3V3AUX_SCL    I27 @S9S_MB_2U_LIB.S9S_MB_2U(SCH_1):PAGE183
     7 SMB_PCIE_M2_0_EN @S9S_MB_2U_LIB.S9S_MB_2U(SCH_1):SMB_PCIE_M2_0_EN    I27 @S9S_MB_2U_LIB.S9S_MB_2U(SCH_1):PAGE183
     8 SMB_PCIE_M2_0_EN @S9S_MB_2U_LIB.S9S_MB_2U(SCH_1):SMB_PCIE_M2_0_EN    I27 @S9S_MB_2U_LIB.S9S_MB_2U(SCH_1):PAGE183
     1    GND @S9S_MB_2U_LIB.S9S_MB_2U(SCH_1):GND    I27 @S9S_MB_2U_LIB.S9S_MB_2U(SCH_1):PAGE183

 U99 RT9818C44GV-RT9818C-44GV,SMLF,A
     3    P5V @S9S_MB_2U_LIB.S9S_MB_2U(SCH_1):P5V     I4 @S9S_MB_2U_LIB.S9S_MB_2U(SCH_1):PAGE246
     1 PWRGD_P5V @S9S_MB_2U_LIB.S9S_MB_2U(SCH_1):PWRGD_P5V     I4 @S9S_MB_2U_LIB.S9S_MB_2U(SCH_1):PAGE246
     2    GND @S9S_MB_2U_LIB.S9S_MB_2U(SCH_1):GND     I4 @S9S_MB_2U_LIB.S9S_MB_2U(SCH_1):PAGE246

U102 INA183A1IDBVR-INA183A1IDBVR,SMA
     1    GND @S9S_MB_2U_LIB.S9S_MB_2U(SCH_1):GND    I29 @S9S_MB_2U_LIB.S9S_MB_2U(SCH_1):PAGE240
     2    GND @S9S_MB_2U_LIB.S9S_MB_2U(SCH_1):GND    I29 @S9S_MB_2U_LIB.S9S_MB_2U(SCH_1):PAGE240
     3 PVCCD_HV_CPU0_NVDIMM_ISENSE @S9S_MB_2U_LIB.S9S_MB_2U(SCH_1):PVCCD_HV_CPU0_NVDIMM_ISENSE    I29 @S9S_MB_2U_LIB.S9S_MB_2U(SCH_1):PAGE240
     4 P12V_AUX_CPU0_DIMM_ISEN_N @S9S_MB_2U_LIB.S9S_MB_2U(SCH_1):P12V_AUX_CPU0_DIMM_ISEN_N    I29 @S9S_MB_2U_LIB.S9S_MB_2U(SCH_1):PAGE240
     5 P12V_AUX_CPU0_DIMM_ISEN_P @S9S_MB_2U_LIB.S9S_MB_2U(SCH_1):P12V_AUX_CPU0_DIMM_ISEN_P    I29 @S9S_MB_2U_LIB.S9S_MB_2U(SCH_1):PAGE240

U103 INA183A1IDBVR-INA183A1IDBVR,SMA
     1    GND @S9S_MB_2U_LIB.S9S_MB_2U(SCH_1):GND    I22 @S9S_MB_2U_LIB.S9S_MB_2U(SCH_1):PAGE240
     2    GND @S9S_MB_2U_LIB.S9S_MB_2U(SCH_1):GND    I22 @S9S_MB_2U_LIB.S9S_MB_2U(SCH_1):PAGE240
     3 PVCCD_HV_CPU1_NVDIMM_ISENSE @S9S_MB_2U_LIB.S9S_MB_2U(SCH_1):PVCCD_HV_CPU1_NVDIMM_ISENSE    I22 @S9S_MB_2U_LIB.S9S_MB_2U(SCH_1):PAGE240
     4 P12V_AUX_CPU1_DIMM_ISEN_N @S9S_MB_2U_LIB.S9S_MB_2U(SCH_1):P12V_AUX_CPU1_DIMM_ISEN_N    I22 @S9S_MB_2U_LIB.S9S_MB_2U(SCH_1):PAGE240
     5 P12V_AUX_CPU1_DIMM_ISEN_P @S9S_MB_2U_LIB.S9S_MB_2U(SCH_1):P12V_AUX_CPU1_DIMM_ISEN_P    I22 @S9S_MB_2U_LIB.S9S_MB_2U(SCH_1):PAGE240

U104 74LVC1G07GV-74LVC1G07GV,SMLF,IA
     5 P3V3_AUX @S9S_MB_2U_LIB.S9S_MB_2U(SCH_1):P3V3_AUX    I63 @S9S_MB_2U_LIB.S9S_MB_2U(SCH_1):PAGE152
     2 FM_SYS_THROTTLE_R_N @S9S_MB_2U_LIB.S9S_MB_2U(SCH_1):FM_SYS_THROTTLE_R_N    I63 @S9S_MB_2U_LIB.S9S_MB_2U(SCH_1):PAGE152
     3    GND @S9S_MB_2U_LIB.S9S_MB_2U(SCH_1):GND    I63 @S9S_MB_2U_LIB.S9S_MB_2U(SCH_1):PAGE152
     4 OCP_SFF_PWRBRK_BUFF_N @S9S_MB_2U_LIB.S9S_MB_2U(SCH_1):OCP_SFF_PWRBRK_BUFF_N    I63 @S9S_MB_2U_LIB.S9S_MB_2U(SCH_1):PAGE152
     1 NC_U104_NC1 @S9S_MB_2U_LIB.S9S_MB_2U(SCH_1):NC_U104_NC1    I63 @S9S_MB_2U_LIB.S9S_MB_2U(SCH_1):PAGE152

U117 TPS3895ADRYR-TPS3895ADRYR,SMLFA
     1 FM_COMP_P3V3_AUX_ENIN @S9S_MB_2U_LIB.S9S_MB_2U(SCH_1):FM_COMP_P3V3_AUX_ENIN    I26 @S9S_MB_2U_LIB.S9S_MB_2U(SCH_1):PAGE232
     2    GND @S9S_MB_2U_LIB.S9S_MB_2U(SCH_1):GND    I26 @S9S_MB_2U_LIB.S9S_MB_2U(SCH_1):PAGE232
     3 FM_COMP_P3V3_AUX_VIN @S9S_MB_2U_LIB.S9S_MB_2U(SCH_1):FM_COMP_P3V3_AUX_VIN    I26 @S9S_MB_2U_LIB.S9S_MB_2U(SCH_1):PAGE232
     4 PWRGD_DSW_PWROK_R1 @S9S_MB_2U_LIB.S9S_MB_2U(SCH_1):PWRGD_DSW_PWROK_R1    I26 @S9S_MB_2U_LIB.S9S_MB_2U(SCH_1):PAGE232
     5 FM_COMP_P3V3_STBY_CEXT @S9S_MB_2U_LIB.S9S_MB_2U(SCH_1):FM_COMP_P3V3_STBY_CEXT    I26 @S9S_MB_2U_LIB.S9S_MB_2U(SCH_1):PAGE232
     6 P3V3_AUX @S9S_MB_2U_LIB.S9S_MB_2U(SCH_1):P3V3_AUX    I26 @S9S_MB_2U_LIB.S9S_MB_2U(SCH_1):PAGE232

U134 74LVC2G07DW7-74LVC2G07DW-7,SMLA
     1 RST_SMB_E1S_N @S9S_MB_2U_LIB.S9S_MB_2U(SCH_1):RST_SMB_E1S_N   I305 @S9S_MB_2U_LIB.S9S_MB_2U(SCH_1):PAGE297
     3 RST_SMB_E1S_N @S9S_MB_2U_LIB.S9S_MB_2U(SCH_1):RST_SMB_E1S_N   I305 @S9S_MB_2U_LIB.S9S_MB_2U(SCH_1):PAGE297
     6 RST_SMB_BUF_E1S_0_N @S9S_MB_2U_LIB.S9S_MB_2U(SCH_1):RST_SMB_BUF_E1S_0_N   I305 @S9S_MB_2U_LIB.S9S_MB_2U(SCH_1):PAGE297
     4 SMB_PCIE_E1S_ISO_EN_R2 @S9S_MB_2U_LIB.S9S_MB_2U(SCH_1):SMB_PCIE_E1S_ISO_EN_R2   I305 @S9S_MB_2U_LIB.S9S_MB_2U(SCH_1):PAGE297
     2    GND @S9S_MB_2U_LIB.S9S_MB_2U(SCH_1):GND   I305 @S9S_MB_2U_LIB.S9S_MB_2U(SCH_1):PAGE297
     5 P3V3_AUX @S9S_MB_2U_LIB.S9S_MB_2U(SCH_1):P3V3_AUX   I305 @S9S_MB_2U_LIB.S9S_MB_2U(SCH_1):PAGE297

U142 NC7SB3157_SMLF-NC7SB3157P6X,NCA
     1 PECI_BMC_B1 @S9S_MB_2U_LIB.S9S_MB_2U(SCH_1):PECI_BMC_B1    I35 @S9S_MB_2U_LIB.S9S_MB_2U(SCH_1):PAGE185
     2    GND @S9S_MB_2U_LIB.S9S_MB_2U(SCH_1):GND    I35 @S9S_MB_2U_LIB.S9S_MB_2U(SCH_1):PAGE185
     3 PECI_PCH_B1 @S9S_MB_2U_LIB.S9S_MB_2U(SCH_1):PECI_PCH_B1    I35 @S9S_MB_2U_LIB.S9S_MB_2U(SCH_1):PAGE185
     6 PECI_MUX_SEL_R @S9S_MB_2U_LIB.S9S_MB_2U(SCH_1):PECI_MUX_SEL_R    I35 @S9S_MB_2U_LIB.S9S_MB_2U(SCH_1):PAGE185
     5 P3V3_AUX @S9S_MB_2U_LIB.S9S_MB_2U(SCH_1):P3V3_AUX    I35 @S9S_MB_2U_LIB.S9S_MB_2U(SCH_1):PAGE185
     4 PECI_CPU_GTL @S9S_MB_2U_LIB.S9S_MB_2U(SCH_1):PECI_CPU_GTL    I35 @S9S_MB_2U_LIB.S9S_MB_2U(SCH_1):PAGE185

U143 PCA9545APW-PCA9545APW,SMLF,IC,A
     1 PCA9543_S3M_ADDR0 @S9S_MB_2U_LIB.S9S_MB_2U(SCH_1):PCA9543_S3M_ADDR0   I106 @S9S_MB_2U_LIB.S9S_MB_2U(SCH_1):PAGE224
     2 PCA9543_S3M_ADDR1 @S9S_MB_2U_LIB.S9S_MB_2U(SCH_1):PCA9543_S3M_ADDR1   I106 @S9S_MB_2U_LIB.S9S_MB_2U(SCH_1):PAGE224
     3 RST_SMB_S3M_N @S9S_MB_2U_LIB.S9S_MB_2U(SCH_1):RST_SMB_S3M_N   I106 @S9S_MB_2U_LIB.S9S_MB_2U(SCH_1):PAGE224
    17 PCA9545_S3M_INT_N @S9S_MB_2U_LIB.S9S_MB_2U(SCH_1):PCA9545_S3M_INT_N   I106 @S9S_MB_2U_LIB.S9S_MB_2U(SCH_1):PAGE224
    18 SMB_S3M_CPU_3V3AUX_SCL @S9S_MB_2U_LIB.S9S_MB_2U(SCH_1):SMB_S3M_CPU_3V3AUX_SCL   I106 @S9S_MB_2U_LIB.S9S_MB_2U(SCH_1):PAGE224
    19 SMB_S3M_CPU_3V3AUX_SDA @S9S_MB_2U_LIB.S9S_MB_2U(SCH_1):SMB_S3M_CPU_3V3AUX_SDA   I106 @S9S_MB_2U_LIB.S9S_MB_2U(SCH_1):PAGE224
    10    GND @S9S_MB_2U_LIB.S9S_MB_2U(SCH_1):GND   I106 @S9S_MB_2U_LIB.S9S_MB_2U(SCH_1):PAGE224
    20 P3V3_AUX @S9S_MB_2U_LIB.S9S_MB_2U(SCH_1):P3V3_AUX   I106 @S9S_MB_2U_LIB.S9S_MB_2U(SCH_1):PAGE224
     5 SMB_S3M_CPU0_3V3AUX_SDA_R @S9S_MB_2U_LIB.S9S_MB_2U(SCH_1):SMB_S3M_CPU0_3V3AUX_SDA_R   I106 @S9S_MB_2U_LIB.S9S_MB_2U(SCH_1):PAGE224
     6 SMB_S3M_CPU0_3V3AUX_SCL_R @S9S_MB_2U_LIB.S9S_MB_2U(SCH_1):SMB_S3M_CPU0_3V3AUX_SCL_R   I106 @S9S_MB_2U_LIB.S9S_MB_2U(SCH_1):PAGE224
     4 PCA9543_S3M_INT0_N @S9S_MB_2U_LIB.S9S_MB_2U(SCH_1):PCA9543_S3M_INT0_N   I106 @S9S_MB_2U_LIB.S9S_MB_2U(SCH_1):PAGE224
     8 SMB_S3M_CPU1_3V3AUX_SDA_R @S9S_MB_2U_LIB.S9S_MB_2U(SCH_1):SMB_S3M_CPU1_3V3AUX_SDA_R   I106 @S9S_MB_2U_LIB.S9S_MB_2U(SCH_1):PAGE224
     9 SMB_S3M_CPU1_3V3AUX_SCL_R @S9S_MB_2U_LIB.S9S_MB_2U(SCH_1):SMB_S3M_CPU1_3V3AUX_SCL_R   I106 @S9S_MB_2U_LIB.S9S_MB_2U(SCH_1):PAGE224
     7 PCA9543_S3M_INT1_N @S9S_MB_2U_LIB.S9S_MB_2U(SCH_1):PCA9543_S3M_INT1_N   I106 @S9S_MB_2U_LIB.S9S_MB_2U(SCH_1):PAGE224
    12 SMB_S3M_CPU0_PIROM_3V3AUX_SDA_R @S9S_MB_2U_LIB.S9S_MB_2U(SCH_1):SMB_S3M_CPU0_PIROM_3V3AUX_SDA_R   I106 @S9S_MB_2U_LIB.S9S_MB_2U(SCH_1):PAGE224
    13 SMB_S3M_CPU0_PIROM_3V3AUX_SCL_R @S9S_MB_2U_LIB.S9S_MB_2U(SCH_1):SMB_S3M_CPU0_PIROM_3V3AUX_SCL_R   I106 @S9S_MB_2U_LIB.S9S_MB_2U(SCH_1):PAGE224
    11 PCA9543_S3M_INT2_N @S9S_MB_2U_LIB.S9S_MB_2U(SCH_1):PCA9543_S3M_INT2_N   I106 @S9S_MB_2U_LIB.S9S_MB_2U(SCH_1):PAGE224
    15 SMB_S3M_CPU1_PIROM_3V3AUX_SDA_R @S9S_MB_2U_LIB.S9S_MB_2U(SCH_1):SMB_S3M_CPU1_PIROM_3V3AUX_SDA_R   I106 @S9S_MB_2U_LIB.S9S_MB_2U(SCH_1):PAGE224
    16 SMB_S3M_CPU1_PIROM_3V3AUX_SCL_R @S9S_MB_2U_LIB.S9S_MB_2U(SCH_1):SMB_S3M_CPU1_PIROM_3V3AUX_SCL_R   I106 @S9S_MB_2U_LIB.S9S_MB_2U(SCH_1):PAGE224
    14 PCA9543_S3M_INT3_N @S9S_MB_2U_LIB.S9S_MB_2U(SCH_1):PCA9543_S3M_INT3_N   I106 @S9S_MB_2U_LIB.S9S_MB_2U(SCH_1):PAGE224

U145 74LVC1G126SE7-74LVC1G126SE-7,SA
     2 E1S_0_PRSNT @S9S_MB_2U_LIB.S9S_MB_2U(SCH_1):E1S_0_PRSNT   I163 @S9S_MB_2U_LIB.S9S_MB_2U(SCH_1):PAGE297
     4 E1S_0_EN @S9S_MB_2U_LIB.S9S_MB_2U(SCH_1):E1S_0_EN   I163 @S9S_MB_2U_LIB.S9S_MB_2U(SCH_1):PAGE297
     5 P3V3_AUX @S9S_MB_2U_LIB.S9S_MB_2U(SCH_1):P3V3_AUX   I163 @S9S_MB_2U_LIB.S9S_MB_2U(SCH_1):PAGE297
     3    GND @S9S_MB_2U_LIB.S9S_MB_2U(SCH_1):GND   I163 @S9S_MB_2U_LIB.S9S_MB_2U(SCH_1):PAGE297
     1 FM_PS_EN_PLD_BUF1_R1 @S9S_MB_2U_LIB.S9S_MB_2U(SCH_1):FM_PS_EN_PLD_BUF1_R1   I163 @S9S_MB_2U_LIB.S9S_MB_2U(SCH_1):PAGE297

U150 74LVC2G17GW-74LVC2G17GW,SMLF,IA
     5 P3V3_AUX @S9S_MB_2U_LIB.S9S_MB_2U(SCH_1):P3V3_AUX     I2 @S9S_MB_2U_LIB.S9S_MB_2U(SCH_1):PAGE213
     4 NC_U150_B1 @S9S_MB_2U_LIB.S9S_MB_2U(SCH_1):NC_U150_B1     I2 @S9S_MB_2U_LIB.S9S_MB_2U(SCH_1):PAGE213
     2    GND @S9S_MB_2U_LIB.S9S_MB_2U(SCH_1):GND     I2 @S9S_MB_2U_LIB.S9S_MB_2U(SCH_1):PAGE213
     1 FM_PS_EN_PLD_R @S9S_MB_2U_LIB.S9S_MB_2U(SCH_1):FM_PS_EN_PLD_R     I2 @S9S_MB_2U_LIB.S9S_MB_2U(SCH_1):PAGE213
     3 NC_U150_A1 @S9S_MB_2U_LIB.S9S_MB_2U(SCH_1):NC_U150_A1     I2 @S9S_MB_2U_LIB.S9S_MB_2U(SCH_1):PAGE213
     6 FM_PS_EN_PLD_BUF1 @S9S_MB_2U_LIB.S9S_MB_2U(SCH_1):FM_PS_EN_PLD_BUF1     I2 @S9S_MB_2U_LIB.S9S_MB_2U(SCH_1):PAGE213

U154 74LVC1G07SE7-74LVC1G07SE-7,SMLA
     5 P3V3_AUX @S9S_MB_2U_LIB.S9S_MB_2U(SCH_1):P3V3_AUX    I95 @S9S_MB_2U_LIB.S9S_MB_2U(SCH_1):PAGE190
     2 FM_ESPI_PLD_R1_EN @S9S_MB_2U_LIB.S9S_MB_2U(SCH_1):FM_ESPI_PLD_R1_EN    I95 @S9S_MB_2U_LIB.S9S_MB_2U(SCH_1):PAGE190
     3    GND @S9S_MB_2U_LIB.S9S_MB_2U(SCH_1):GND    I95 @S9S_MB_2U_LIB.S9S_MB_2U(SCH_1):PAGE190
     4 FM_ESPI_PLD_R_EN_BUF @S9S_MB_2U_LIB.S9S_MB_2U(SCH_1):FM_ESPI_PLD_R_EN_BUF    I95 @S9S_MB_2U_LIB.S9S_MB_2U(SCH_1):PAGE190
     1 NC_ESPI_PLD_R_EN_BUF @S9S_MB_2U_LIB.S9S_MB_2U(SCH_1):NC_ESPI_PLD_R_EN_BUF    I95 @S9S_MB_2U_LIB.S9S_MB_2U(SCH_1):PAGE190

U157 74LVC1G07GV-74LVC1G07GV,SMLF,IA
     5 P3V3_AUX @S9S_MB_2U_LIB.S9S_MB_2U(SCH_1):P3V3_AUX    I65 @S9S_MB_2U_LIB.S9S_MB_2U(SCH_1):PAGE152
     2 OCP_SFF_WAKE_BUFF_R_N @S9S_MB_2U_LIB.S9S_MB_2U(SCH_1):OCP_SFF_WAKE_BUFF_R_N    I65 @S9S_MB_2U_LIB.S9S_MB_2U(SCH_1):PAGE152
     3    GND @S9S_MB_2U_LIB.S9S_MB_2U(SCH_1):GND    I65 @S9S_MB_2U_LIB.S9S_MB_2U(SCH_1):PAGE152
     4 IRQ_LVC3_WAKE_BUF_N @S9S_MB_2U_LIB.S9S_MB_2U(SCH_1):IRQ_LVC3_WAKE_BUF_N    I65 @S9S_MB_2U_LIB.S9S_MB_2U(SCH_1):PAGE152
     1 NC_U157_NC1 @S9S_MB_2U_LIB.S9S_MB_2U(SCH_1):NC_U157_NC1    I65 @S9S_MB_2U_LIB.S9S_MB_2U(SCH_1):PAGE152

U158 MOSFET_NCH_GDS_ESD_PROTECTED-2A
     D FM_P12V_HSC_EN_N @S9S_MB_2U_LIB.S9S_MB_2U(SCH_1):FM_P12V_HSC_EN_N     I6 @S9S_MB_2U_LIB.S9S_MB_2U(SCH_1):PAGE234
     G FM_P12V_HSC_EN_R @S9S_MB_2U_LIB.S9S_MB_2U(SCH_1):FM_P12V_HSC_EN_R     I6 @S9S_MB_2U_LIB.S9S_MB_2U(SCH_1):PAGE234
     S    GND @S9S_MB_2U_LIB.S9S_MB_2U(SCH_1):GND     I6 @S9S_MB_2U_LIB.S9S_MB_2U(SCH_1):PAGE234

U175 LTC4307CMS8-LTC4307CMS8,SMLF,IA
     1 SMB_BMC_SWB_EN_R @S9S_MB_2U_LIB.S9S_MB_2U(SCH_1):SMB_BMC_SWB_EN_R    I50 @S9S_MB_2U_LIB.S9S_MB_2U(SCH_1):PAGE222
     3 SMB_BMC_SWB_R_SCL @S9S_MB_2U_LIB.S9S_MB_2U(SCH_1):SMB_BMC_SWB_R_SCL    I50 @S9S_MB_2U_LIB.S9S_MB_2U(SCH_1):PAGE222
     6 SMB_BMC_SWB_R_SDA @S9S_MB_2U_LIB.S9S_MB_2U(SCH_1):SMB_BMC_SWB_R_SDA    I50 @S9S_MB_2U_LIB.S9S_MB_2U(SCH_1):PAGE222
     2 SMB_BMC_SWB_BUF_R_SCL @S9S_MB_2U_LIB.S9S_MB_2U(SCH_1):SMB_BMC_SWB_BUF_R_SCL    I50 @S9S_MB_2U_LIB.S9S_MB_2U(SCH_1):PAGE222
     7 SMB_BMC_SWB_BUF_R_SDA @S9S_MB_2U_LIB.S9S_MB_2U(SCH_1):SMB_BMC_SWB_BUF_R_SDA    I50 @S9S_MB_2U_LIB.S9S_MB_2U(SCH_1):PAGE222
     5     NC     NC    I50 @S9S_MB_2U_LIB.S9S_MB_2U(SCH_1):PAGE222
     4    GND @S9S_MB_2U_LIB.S9S_MB_2U(SCH_1):GND    I50 @S9S_MB_2U_LIB.S9S_MB_2U(SCH_1):PAGE222
     8 P3V3_AUX @S9S_MB_2U_LIB.S9S_MB_2U(SCH_1):P3V3_AUX    I50 @S9S_MB_2U_LIB.S9S_MB_2U(SCH_1):PAGE222

U176 LTC4307CMS8-LTC4307CMS8,SMLF,EA
     1 SMB_BMC_SWB_EN_R2 @S9S_MB_2U_LIB.S9S_MB_2U(SCH_1):SMB_BMC_SWB_EN_R2    I31 @S9S_MB_2U_LIB.S9S_MB_2U(SCH_1):PAGE222
     3 I3C_BMC_SWB_R_SCL @S9S_MB_2U_LIB.S9S_MB_2U(SCH_1):I3C_BMC_SWB_R_SCL    I31 @S9S_MB_2U_LIB.S9S_MB_2U(SCH_1):PAGE222
     6 I3C_BMC_SWB_R_SDA @S9S_MB_2U_LIB.S9S_MB_2U(SCH_1):I3C_BMC_SWB_R_SDA    I31 @S9S_MB_2U_LIB.S9S_MB_2U(SCH_1):PAGE222
     2 I3C_BMC_SWB_BUF_R_SCL @S9S_MB_2U_LIB.S9S_MB_2U(SCH_1):I3C_BMC_SWB_BUF_R_SCL    I31 @S9S_MB_2U_LIB.S9S_MB_2U(SCH_1):PAGE222
     7 I3C_BMC_SWB_BUF_R_SDA @S9S_MB_2U_LIB.S9S_MB_2U(SCH_1):I3C_BMC_SWB_BUF_R_SDA    I31 @S9S_MB_2U_LIB.S9S_MB_2U(SCH_1):PAGE222
     5     NC     NC    I31 @S9S_MB_2U_LIB.S9S_MB_2U(SCH_1):PAGE222
     4    GND @S9S_MB_2U_LIB.S9S_MB_2U(SCH_1):GND    I31 @S9S_MB_2U_LIB.S9S_MB_2U(SCH_1):PAGE222
     8 P3V3_AUX @S9S_MB_2U_LIB.S9S_MB_2U(SCH_1):P3V3_AUX    I31 @S9S_MB_2U_LIB.S9S_MB_2U(SCH_1):PAGE222

U181 PCA9539RPW-PCA9539RPW,SMLF,IC,A
     1 PU_U181_INT @S9S_MB_2U_LIB.S9S_MB_2U(SCH_1):PU_U181_INT    I66 @S9S_MB_2U_LIB.S9S_MB_2U(SCH_1):PAGE214
     2 TCA9539_0_ADD1 @S9S_MB_2U_LIB.S9S_MB_2U(SCH_1):TCA9539_0_ADD1    I66 @S9S_MB_2U_LIB.S9S_MB_2U(SCH_1):PAGE214
     3 PU_RST_SMB_U181_N @S9S_MB_2U_LIB.S9S_MB_2U(SCH_1):PU_RST_SMB_U181_N    I66 @S9S_MB_2U_LIB.S9S_MB_2U(SCH_1):PAGE214
     4 RST_USB_HUB_N @S9S_MB_2U_LIB.S9S_MB_2U(SCH_1):RST_USB_HUB_N    I66 @S9S_MB_2U_LIB.S9S_MB_2U(SCH_1):PAGE214
     5 RST_SWB_BIC_N @S9S_MB_2U_LIB.S9S_MB_2U(SCH_1):RST_SWB_BIC_N    I66 @S9S_MB_2U_LIB.S9S_MB_2U(SCH_1):PAGE214
     6 TP_TCA9539_0_P0_2 @S9S_MB_2U_LIB.S9S_MB_2U(SCH_1):TP_TCA9539_0_P0_2    I66 @S9S_MB_2U_LIB.S9S_MB_2U(SCH_1):PAGE214
     7 TP_TCA9539_0_P0_3 @S9S_MB_2U_LIB.S9S_MB_2U(SCH_1):TP_TCA9539_0_P0_3    I66 @S9S_MB_2U_LIB.S9S_MB_2U(SCH_1):PAGE214
     8 PRSNT_SWB_ISO_R1_N @S9S_MB_2U_LIB.S9S_MB_2U(SCH_1):PRSNT_SWB_ISO_R1_N    I66 @S9S_MB_2U_LIB.S9S_MB_2U(SCH_1):PAGE214
     9 GPU_PRSNT_N_ISO_R1 @S9S_MB_2U_LIB.S9S_MB_2U(SCH_1):GPU_PRSNT_N_ISO_R1    I66 @S9S_MB_2U_LIB.S9S_MB_2U(SCH_1):PAGE214
    10 PRSNT_CABLE_GPU_B3_ISO_R1_N @S9S_MB_2U_LIB.S9S_MB_2U(SCH_1):PRSNT_CABLE_GPU_B3_ISO_R1_N    I66 @S9S_MB_2U_LIB.S9S_MB_2U(SCH_1):PAGE214
    11 PRSNT_CABLE_SWB_B2_ISO_R_N @S9S_MB_2U_LIB.S9S_MB_2U(SCH_1):PRSNT_CABLE_SWB_B2_ISO_R_N    I66 @S9S_MB_2U_LIB.S9S_MB_2U(SCH_1):PAGE214
    12    GND @S9S_MB_2U_LIB.S9S_MB_2U(SCH_1):GND    I66 @S9S_MB_2U_LIB.S9S_MB_2U(SCH_1):PAGE214
    13 PRSNT_CABLE_GPU_A2_ISO_R1_N @S9S_MB_2U_LIB.S9S_MB_2U(SCH_1):PRSNT_CABLE_GPU_A2_ISO_R1_N    I66 @S9S_MB_2U_LIB.S9S_MB_2U(SCH_1):PAGE214
    14 PRSNT_CABLE_SWB_B1_ISO_R_N @S9S_MB_2U_LIB.S9S_MB_2U(SCH_1):PRSNT_CABLE_SWB_B1_ISO_R_N    I66 @S9S_MB_2U_LIB.S9S_MB_2U(SCH_1):PAGE214
    15 GPU_BASE_ID0_R @S9S_MB_2U_LIB.S9S_MB_2U(SCH_1):GPU_BASE_ID0_R    I66 @S9S_MB_2U_LIB.S9S_MB_2U(SCH_1):PAGE214
    16 GPU_BASE_ID1_R @S9S_MB_2U_LIB.S9S_MB_2U(SCH_1):GPU_BASE_ID1_R    I66 @S9S_MB_2U_LIB.S9S_MB_2U(SCH_1):PAGE214
    17 GPU_PEX_STRAP0_R @S9S_MB_2U_LIB.S9S_MB_2U(SCH_1):GPU_PEX_STRAP0_R    I66 @S9S_MB_2U_LIB.S9S_MB_2U(SCH_1):PAGE214
    18 GPU_PEX_STRAP1_R @S9S_MB_2U_LIB.S9S_MB_2U(SCH_1):GPU_PEX_STRAP1_R    I66 @S9S_MB_2U_LIB.S9S_MB_2U(SCH_1):PAGE214
    19 PRSNT_CABLE_GPU_A1_ISO_R1_N @S9S_MB_2U_LIB.S9S_MB_2U(SCH_1):PRSNT_CABLE_GPU_A1_ISO_R1_N    I66 @S9S_MB_2U_LIB.S9S_MB_2U(SCH_1):PAGE214
    20 PRSNT_CABLE_GPU_A3_ISO_R_N @S9S_MB_2U_LIB.S9S_MB_2U(SCH_1):PRSNT_CABLE_GPU_A3_ISO_R_N    I66 @S9S_MB_2U_LIB.S9S_MB_2U(SCH_1):PAGE214
    21 TCA9539_0_ADD0 @S9S_MB_2U_LIB.S9S_MB_2U(SCH_1):TCA9539_0_ADD0    I66 @S9S_MB_2U_LIB.S9S_MB_2U(SCH_1):PAGE214
    22 SMB_IOEXP_3V3AUX_SCL_R1 @S9S_MB_2U_LIB.S9S_MB_2U(SCH_1):SMB_IOEXP_3V3AUX_SCL_R1    I66 @S9S_MB_2U_LIB.S9S_MB_2U(SCH_1):PAGE214
    23 SMB_IOEXP_3V3AUX_SDA_R1 @S9S_MB_2U_LIB.S9S_MB_2U(SCH_1):SMB_IOEXP_3V3AUX_SDA_R1    I66 @S9S_MB_2U_LIB.S9S_MB_2U(SCH_1):PAGE214
    24 P3V3_AUX @S9S_MB_2U_LIB.S9S_MB_2U(SCH_1):P3V3_AUX    I66 @S9S_MB_2U_LIB.S9S_MB_2U(SCH_1):PAGE214

U192 LTC4307CMS8-LTC4307CMS8,SMLF,IA
     1 FM_MB_PDB_SMB9_R_EN @S9S_MB_2U_LIB.S9S_MB_2U(SCH_1):FM_MB_PDB_SMB9_R_EN    I16 @S9S_MB_2U_LIB.S9S_MB_2U(SCH_1):PAGE233
     3 SMB_FAN_3V3AUX_R_SCL @S9S_MB_2U_LIB.S9S_MB_2U(SCH_1):SMB_FAN_3V3AUX_R_SCL    I16 @S9S_MB_2U_LIB.S9S_MB_2U(SCH_1):PAGE233
     6 SMB_FAN_3V3AUX_R_SDA @S9S_MB_2U_LIB.S9S_MB_2U(SCH_1):SMB_FAN_3V3AUX_R_SDA    I16 @S9S_MB_2U_LIB.S9S_MB_2U(SCH_1):PAGE233
     2 SMB_FAN_3V3AUX_BUF_SCL @S9S_MB_2U_LIB.S9S_MB_2U(SCH_1):SMB_FAN_3V3AUX_BUF_SCL    I16 @S9S_MB_2U_LIB.S9S_MB_2U(SCH_1):PAGE233
     7 SMB_FAN_3V3AUX_BUF_SDA @S9S_MB_2U_LIB.S9S_MB_2U(SCH_1):SMB_FAN_3V3AUX_BUF_SDA    I16 @S9S_MB_2U_LIB.S9S_MB_2U(SCH_1):PAGE233
     5     NC     NC    I16 @S9S_MB_2U_LIB.S9S_MB_2U(SCH_1):PAGE233
     4    GND @S9S_MB_2U_LIB.S9S_MB_2U(SCH_1):GND    I16 @S9S_MB_2U_LIB.S9S_MB_2U(SCH_1):PAGE233
     8 P3V3_AUX @S9S_MB_2U_LIB.S9S_MB_2U(SCH_1):P3V3_AUX    I16 @S9S_MB_2U_LIB.S9S_MB_2U(SCH_1):PAGE233

U193 MAX11617EEET-MAX11617EEE+T,SMLA
     1 MAX11617_VREF_R @S9S_MB_2U_LIB.S9S_MB_2U(SCH_1):MAX11617_VREF_R    I57 @S9S_MB_2U_LIB.S9S_MB_2U(SCH_1):PAGE239
     2    GND @S9S_MB_2U_LIB.S9S_MB_2U(SCH_1):GND    I57 @S9S_MB_2U_LIB.S9S_MB_2U(SCH_1):PAGE239
     3    GND @S9S_MB_2U_LIB.S9S_MB_2U(SCH_1):GND    I57 @S9S_MB_2U_LIB.S9S_MB_2U(SCH_1):PAGE239
     4    GND @S9S_MB_2U_LIB.S9S_MB_2U(SCH_1):GND    I57 @S9S_MB_2U_LIB.S9S_MB_2U(SCH_1):PAGE239
     5 P12V_AUX_ADC_MAM @S9S_MB_2U_LIB.S9S_MB_2U(SCH_1):P12V_AUX_ADC_MAM    I57 @S9S_MB_2U_LIB.S9S_MB_2U(SCH_1):PAGE239
     6 P12V_OCP_SFF_ISENSE_MAM @S9S_MB_2U_LIB.S9S_MB_2U(SCH_1):P12V_OCP_SFF_ISENSE_MAM    I57 @S9S_MB_2U_LIB.S9S_MB_2U(SCH_1):PAGE239
     7 P12V_OCP_V3_2_ISENSE_MAM @S9S_MB_2U_LIB.S9S_MB_2U(SCH_1):P12V_OCP_V3_2_ISENSE_MAM    I57 @S9S_MB_2U_LIB.S9S_MB_2U(SCH_1):PAGE239
     8 P5V_ADC_MAM @S9S_MB_2U_LIB.S9S_MB_2U(SCH_1):P5V_ADC_MAM    I57 @S9S_MB_2U_LIB.S9S_MB_2U(SCH_1):PAGE239
     9 P3V3_ADC_MAM @S9S_MB_2U_LIB.S9S_MB_2U(SCH_1):P3V3_ADC_MAM    I57 @S9S_MB_2U_LIB.S9S_MB_2U(SCH_1):PAGE239
    10 P3V3_AUX_ADC_MAM @S9S_MB_2U_LIB.S9S_MB_2U(SCH_1):P3V3_AUX_ADC_MAM    I57 @S9S_MB_2U_LIB.S9S_MB_2U(SCH_1):PAGE239
    11 P3V3_PDB_AUX_ADC_MAM @S9S_MB_2U_LIB.S9S_MB_2U(SCH_1):P3V3_PDB_AUX_ADC_MAM    I57 @S9S_MB_2U_LIB.S9S_MB_2U(SCH_1):PAGE239
    12 P12V_E1S_0_ISENSE_MAM @S9S_MB_2U_LIB.S9S_MB_2U(SCH_1):P12V_E1S_0_ISENSE_MAM    I57 @S9S_MB_2U_LIB.S9S_MB_2U(SCH_1):PAGE239
    13 SMB_SEN_MAM_3V3AUX_SCL @S9S_MB_2U_LIB.S9S_MB_2U(SCH_1):SMB_SEN_MAM_3V3AUX_SCL    I57 @S9S_MB_2U_LIB.S9S_MB_2U(SCH_1):PAGE239
    14 SMB_SEN_MAM_3V3AUX_SDA @S9S_MB_2U_LIB.S9S_MB_2U(SCH_1):SMB_SEN_MAM_3V3AUX_SDA    I57 @S9S_MB_2U_LIB.S9S_MB_2U(SCH_1):PAGE239
    15    GND @S9S_MB_2U_LIB.S9S_MB_2U(SCH_1):GND    I57 @S9S_MB_2U_LIB.S9S_MB_2U(SCH_1):PAGE239
    16 P3V3_MAX11617_VDD @S9S_MB_2U_LIB.S9S_MB_2U(SCH_1):P3V3_MAX11617 _VDD    I57 @S9S_MB_2U_LIB.S9S_MB_2U(SCH_1):PAGE239

U194 LTC4307CMS8-LTC4307CMS8,SMLF,IA
     1 SMB_BMC_GPU_EN_R1 @S9S_MB_2U_LIB.S9S_MB_2U(SCH_1):SMB_BMC_GPU_EN_R1    I63 @S9S_MB_2U_LIB.S9S_MB_2U(SCH_1):PAGE222
     3 SMB_1_BMC_GPU_R_SCL @S9S_MB_2U_LIB.S9S_MB_2U(SCH_1):SMB_1_BMC_GPU_R_SCL    I63 @S9S_MB_2U_LIB.S9S_MB_2U(SCH_1):PAGE222
     6 SMB_1_BMC_GPU_R_SDA @S9S_MB_2U_LIB.S9S_MB_2U(SCH_1):SMB_1_BMC_GPU_R_SDA    I63 @S9S_MB_2U_LIB.S9S_MB_2U(SCH_1):PAGE222
     2 SMB_1_BMC_GPU_BUF_R_SCL @S9S_MB_2U_LIB.S9S_MB_2U(SCH_1):SMB_1_BMC_GPU_BUF_R_SCL    I63 @S9S_MB_2U_LIB.S9S_MB_2U(SCH_1):PAGE222
     7 SMB_1_BMC_GPU_BUF_R_SDA @S9S_MB_2U_LIB.S9S_MB_2U(SCH_1):SMB_1_BMC_GPU_BUF_R_SDA    I63 @S9S_MB_2U_LIB.S9S_MB_2U(SCH_1):PAGE222
     5     NC     NC    I63 @S9S_MB_2U_LIB.S9S_MB_2U(SCH_1):PAGE222
     4    GND @S9S_MB_2U_LIB.S9S_MB_2U(SCH_1):GND    I63 @S9S_MB_2U_LIB.S9S_MB_2U(SCH_1):PAGE222
     8 P3V3_AUX @S9S_MB_2U_LIB.S9S_MB_2U(SCH_1):P3V3_AUX    I63 @S9S_MB_2U_LIB.S9S_MB_2U(SCH_1):PAGE222

U195 74LVC2G17GW-74LVC2G17GW,SMLF,IA
     5 P3V3_AUX @S9S_MB_2U_LIB.S9S_MB_2U(SCH_1):P3V3_AUX    I65 @S9S_MB_2U_LIB.S9S_MB_2U(SCH_1):PAGE140
     4 RST_SWB_BIC_BUF_R_N @S9S_MB_2U_LIB.S9S_MB_2U(SCH_1):RST_SWB_BIC_BUF_R_N    I65 @S9S_MB_2U_LIB.S9S_MB_2U(SCH_1):PAGE140
     2    GND @S9S_MB_2U_LIB.S9S_MB_2U(SCH_1):GND    I65 @S9S_MB_2U_LIB.S9S_MB_2U(SCH_1):PAGE140
     1 BMC_MONITER_R @S9S_MB_2U_LIB.S9S_MB_2U(SCH_1):BMC_MONITER_R    I65 @S9S_MB_2U_LIB.S9S_MB_2U(SCH_1):PAGE140
     3 RST_SWB_BIC_R_N @S9S_MB_2U_LIB.S9S_MB_2U(SCH_1):RST_SWB_BIC_R_N    I65 @S9S_MB_2U_LIB.S9S_MB_2U(SCH_1):PAGE140
     6 BMC_MONITER_BUF_R @S9S_MB_2U_LIB.S9S_MB_2U(SCH_1):BMC_MONITER_BUF_R    I65 @S9S_MB_2U_LIB.S9S_MB_2U(SCH_1):PAGE140

U196 74LVC2G17GW-74LVC2G17GW,SMLF,IA
     5 P3V3_AUX @S9S_MB_2U_LIB.S9S_MB_2U(SCH_1):P3V3_AUX   I127 @S9S_MB_2U_LIB.S9S_MB_2U(SCH_1):PAGE140
     4 GPU_FPGA_RST_R1_BUF_N @S9S_MB_2U_LIB.S9S_MB_2U(SCH_1):GPU_FPGA_RST_R1_BUF_N   I127 @S9S_MB_2U_LIB.S9S_MB_2U(SCH_1):PAGE140
     2    GND @S9S_MB_2U_LIB.S9S_MB_2U(SCH_1):GND   I127 @S9S_MB_2U_LIB.S9S_MB_2U(SCH_1):PAGE140
     1 FM_GPU_PWR_EN_R @S9S_MB_2U_LIB.S9S_MB_2U(SCH_1):FM_GPU_PWR_EN_R   I127 @S9S_MB_2U_LIB.S9S_MB_2U(SCH_1):PAGE140
     3 GPU_FPGA_RST_R_N @S9S_MB_2U_LIB.S9S_MB_2U(SCH_1):GPU_FPGA_RST_R_N   I127 @S9S_MB_2U_LIB.S9S_MB_2U(SCH_1):PAGE140
     6 FM_GPU_PWR_EN_R1 @S9S_MB_2U_LIB.S9S_MB_2U(SCH_1):FM_GPU_PWR_EN_R1   I127 @S9S_MB_2U_LIB.S9S_MB_2U(SCH_1):PAGE140

U200 LTC4307CMS8-LTC4307CMS8,SMLF,IA
     1 SMB_BMC_GPU_EN_R3 @S9S_MB_2U_LIB.S9S_MB_2U(SCH_1):SMB_BMC_GPU_EN_R3    I11 @S9S_MB_2U_LIB.S9S_MB_2U(SCH_1):PAGE222
     3 SMB_2_BMC_GPU_R_SCL @S9S_MB_2U_LIB.S9S_MB_2U(SCH_1):SMB_2_BMC_GPU_R_SCL    I11 @S9S_MB_2U_LIB.S9S_MB_2U(SCH_1):PAGE222
     6 SMB_2_BMC_GPU_R_SDA @S9S_MB_2U_LIB.S9S_MB_2U(SCH_1):SMB_2_BMC_GPU_R_SDA    I11 @S9S_MB_2U_LIB.S9S_MB_2U(SCH_1):PAGE222
     2 SMB_2_BMC_GPU_BUF_R_SCL @S9S_MB_2U_LIB.S9S_MB_2U(SCH_1):SMB_2_BMC_GPU_BUF_R_SCL    I11 @S9S_MB_2U_LIB.S9S_MB_2U(SCH_1):PAGE222
     7 SMB_2_BMC_GPU_BUF_R_SDA @S9S_MB_2U_LIB.S9S_MB_2U(SCH_1):SMB_2_BMC_GPU_BUF_R_SDA    I11 @S9S_MB_2U_LIB.S9S_MB_2U(SCH_1):PAGE222
     5     NC     NC    I11 @S9S_MB_2U_LIB.S9S_MB_2U(SCH_1):PAGE222
     4    GND @S9S_MB_2U_LIB.S9S_MB_2U(SCH_1):GND    I11 @S9S_MB_2U_LIB.S9S_MB_2U(SCH_1):PAGE222
     8 P3V3_AUX @S9S_MB_2U_LIB.S9S_MB_2U(SCH_1):P3V3_AUX    I11 @S9S_MB_2U_LIB.S9S_MB_2U(SCH_1):PAGE222

U204 74LVC1G126SE7-74LVC1G126SE-7,SA
     2 UART_BMC_BIC_R_RX @S9S_MB_2U_LIB.S9S_MB_2U(SCH_1):UART_BMC_BIC_R_RX   I195 @S9S_MB_2U_LIB.S9S_MB_2U(SCH_1):PAGE140
     4 UART_BMC_BIC_R_BUF_RX @S9S_MB_2U_LIB.S9S_MB_2U(SCH_1):UART_BMC_BIC_R_BUF_RX   I195 @S9S_MB_2U_LIB.S9S_MB_2U(SCH_1):PAGE140
     5 P3V3_AUX @S9S_MB_2U_LIB.S9S_MB_2U(SCH_1):P3V3_AUX   I195 @S9S_MB_2U_LIB.S9S_MB_2U(SCH_1):PAGE140
     3    GND @S9S_MB_2U_LIB.S9S_MB_2U(SCH_1):GND   I195 @S9S_MB_2U_LIB.S9S_MB_2U(SCH_1):PAGE140
     1 FM_UART_EN @S9S_MB_2U_LIB.S9S_MB_2U(SCH_1):FM_UART_EN   I195 @S9S_MB_2U_LIB.S9S_MB_2U(SCH_1):PAGE140

U205 TPS3700DDCR-TPS3700DDCR,SMLF,EA
     5 U205_VDD @S9S_MB_2U_LIB.S9S_MB_2U(SCH_1):U205_VDD     I5 @S9S_MB_2U_LIB.S9S_MB_2U(SCH_1):PAGE326
     4 NC_U205_INB- @S9S_MB_2U_LIB.S9S_MB_2U(SCH_1):NC_U205_INB-     I5 @S9S_MB_2U_LIB.S9S_MB_2U(SCH_1):PAGE326
     2    GND @S9S_MB_2U_LIB.S9S_MB_2U(SCH_1):GND     I5 @S9S_MB_2U_LIB.S9S_MB_2U(SCH_1):PAGE326
     1 PWRGD_DSW_PWROK_R4 @S9S_MB_2U_LIB.S9S_MB_2U(SCH_1):PWRGD_DSW_PWROK_R4     I5 @S9S_MB_2U_LIB.S9S_MB_2U(SCH_1):PAGE326
     3 A_HSC_INAP @S9S_MB_2U_LIB.S9S_MB_2U(SCH_1):A_HSC_INAP     I5 @S9S_MB_2U_LIB.S9S_MB_2U(SCH_1):PAGE326
     6 NC_U205_OUTB @S9S_MB_2U_LIB.S9S_MB_2U(SCH_1):NC_U205_OUTB     I5 @S9S_MB_2U_LIB.S9S_MB_2U(SCH_1):PAGE326

U206 LT6700CS61TRPBF-LT6700CS6-1#TRA
     5 U206_VDD @S9S_MB_2U_LIB.S9S_MB_2U(SCH_1):U206_VDD   I102 @S9S_MB_2U_LIB.S9S_MB_2U(SCH_1):PAGE326
     4 A_P12V_STBY_FP_TRIGGER @S9S_MB_2U_LIB.S9S_MB_2U(SCH_1):A_P12V_STBY_FP_TRIGGER   I102 @S9S_MB_2U_LIB.S9S_MB_2U(SCH_1):PAGE326
     2    GND @S9S_MB_2U_LIB.S9S_MB_2U(SCH_1):GND   I102 @S9S_MB_2U_LIB.S9S_MB_2U(SCH_1):PAGE326
     1 FM_UV_ADR_TRIGGER_N @S9S_MB_2U_LIB.S9S_MB_2U(SCH_1):FM_UV_ADR_TRIGGER_N   I102 @S9S_MB_2U_LIB.S9S_MB_2U(SCH_1):PAGE326
     3 A_P12V_STBY_ADR_TRIGGER @S9S_MB_2U_LIB.S9S_MB_2U(SCH_1):A_P12V_STBY_ADR_TRIGGER   I102 @S9S_MB_2U_LIB.S9S_MB_2U(SCH_1):PAGE326
     6 A_P12V_STBY_FPH_GATE @S9S_MB_2U_LIB.S9S_MB_2U(SCH_1):A_P12V_STBY_FPH_GATE   I102 @S9S_MB_2U_LIB.S9S_MB_2U(SCH_1):PAGE326

U207 74LVC1G17GW-74LVC1G17GW,SMLF,IA
     5 P3V3_AUX @S9S_MB_2U_LIB.S9S_MB_2U(SCH_1):P3V3_AUX    I35 @S9S_MB_2U_LIB.S9S_MB_2U(SCH_1):PAGE156
     2 RST_HP_OCP_V3_2_N @S9S_MB_2U_LIB.S9S_MB_2U(SCH_1):RST_HP_OCP_V3_2_N    I35 @S9S_MB_2U_LIB.S9S_MB_2U(SCH_1):PAGE156
     3    GND @S9S_MB_2U_LIB.S9S_MB_2U(SCH_1):GND    I35 @S9S_MB_2U_LIB.S9S_MB_2U(SCH_1):PAGE156
     4 RST_OCP_V3_2_BUF_N @S9S_MB_2U_LIB.S9S_MB_2U(SCH_1):RST_OCP_V3_2_BUF_N    I35 @S9S_MB_2U_LIB.S9S_MB_2U(SCH_1):PAGE156
     1     NC     NC    I35 @S9S_MB_2U_LIB.S9S_MB_2U(SCH_1):PAGE156

U208 74LVC1G08W57-74LVC1G08W5-7,SMLA
     1 HP_OCP_V3_1_EN @S9S_MB_2U_LIB.S9S_MB_2U(SCH_1):HP_OCP_V3_1_EN   I190 @S9S_MB_2U_LIB.S9S_MB_2U(SCH_1):PAGE154
     2 HP_LVC3_OCP_V3_1_PRSNT2 @S9S_MB_2U_LIB.S9S_MB_2U(SCH_1):HP_LVC3_OCP_V3_1_PRSNT2   I190 @S9S_MB_2U_LIB.S9S_MB_2U(SCH_1):PAGE154
     3    GND @S9S_MB_2U_LIB.S9S_MB_2U(SCH_1):GND   I190 @S9S_MB_2U_LIB.S9S_MB_2U(SCH_1):PAGE154
     4 HP_LVC3_OCP_V3_1_EN @S9S_MB_2U_LIB.S9S_MB_2U(SCH_1):HP_LVC3_OCP_V3_1_EN   I190 @S9S_MB_2U_LIB.S9S_MB_2U(SCH_1):PAGE154
     5 P3V3_AUX @S9S_MB_2U_LIB.S9S_MB_2U(SCH_1):P3V3_AUX   I190 @S9S_MB_2U_LIB.S9S_MB_2U(SCH_1):PAGE154

U209 PCA9555APW-PCA9555APW,SMLF,IC,A
    24 P3V3_AUX @S9S_MB_2U_LIB.S9S_MB_2U(SCH_1):P3V3_AUX   I206 @S9S_MB_2U_LIB.S9S_MB_2U(SCH_1):PAGE154
    12    GND @S9S_MB_2U_LIB.S9S_MB_2U(SCH_1):GND   I206 @S9S_MB_2U_LIB.S9S_MB_2U(SCH_1):PAGE154
     1 FM_SMB_CPU0_ALERT @S9S_MB_2U_LIB.S9S_MB_2U(SCH_1):FM_SMB_CPU0_ALERT   I206 @S9S_MB_2U_LIB.S9S_MB_2U(SCH_1):PAGE154
    23 SMB_PEHPCPU0_LVC3_R_SDA @S9S_MB_2U_LIB.S9S_MB_2U(SCH_1):SMB_PEHPCPU0_LVC3_R_SDA   I206 @S9S_MB_2U_LIB.S9S_MB_2U(SCH_1):PAGE154
    22 SMB_PEHPCPU0_LVC3_R_SCL @S9S_MB_2U_LIB.S9S_MB_2U(SCH_1):SMB_PEHPCPU0_LVC3_R_SCL   I206 @S9S_MB_2U_LIB.S9S_MB_2U(SCH_1):PAGE154
     4 TP_PCA9555_0_P00 @S9S_MB_2U_LIB.S9S_MB_2U(SCH_1):TP_PCA9555_0_P00   I206 @S9S_MB_2U_LIB.S9S_MB_2U(SCH_1):PAGE154
     5 TP_PCA9555_0_P01 @S9S_MB_2U_LIB.S9S_MB_2U(SCH_1):TP_PCA9555_0_P01   I206 @S9S_MB_2U_LIB.S9S_MB_2U(SCH_1):PAGE154
     6 HP_OCP_V3_1_EN @S9S_MB_2U_LIB.S9S_MB_2U(SCH_1):HP_OCP_V3_1_EN   I206 @S9S_MB_2U_LIB.S9S_MB_2U(SCH_1):PAGE154
     7 HP_LVC3_OCP_V3_1_ATTN_OUT_SW_N @S9S_MB_2U_LIB.S9S_MB_2U(SCH_1):HP_LVC3_OCP_V3_1_ATTN_OUT_SW_N   I206 @S9S_MB_2U_LIB.S9S_MB_2U(SCH_1):PAGE154
     8 HP_LVC3_OCP_V3_1_PRSNT2_N @S9S_MB_2U_LIB.S9S_MB_2U(SCH_1):HP_LVC3_OCP_V3_1_PRSNT2_N   I206 @S9S_MB_2U_LIB.S9S_MB_2U(SCH_1):PAGE154
     9 TP_PCA9555_0_P5 @S9S_MB_2U_LIB.S9S_MB_2U(SCH_1):TP_PCA9555_0_P5   I206 @S9S_MB_2U_LIB.S9S_MB_2U(SCH_1):PAGE154
    10 TP_PCA9555_0_P6 @S9S_MB_2U_LIB.S9S_MB_2U(SCH_1):TP_PCA9555_0_P6   I206 @S9S_MB_2U_LIB.S9S_MB_2U(SCH_1):PAGE154
    11 TP_PCA9555_0_P7 @S9S_MB_2U_LIB.S9S_MB_2U(SCH_1):TP_PCA9555_0_P7   I206 @S9S_MB_2U_LIB.S9S_MB_2U(SCH_1):PAGE154
    13 TP_PCA9555_0_P10 @S9S_MB_2U_LIB.S9S_MB_2U(SCH_1):TP_PCA9555_0_P10   I206 @S9S_MB_2U_LIB.S9S_MB_2U(SCH_1):PAGE154
    14 TP_PCA9555_0_P11 @S9S_MB_2U_LIB.S9S_MB_2U(SCH_1):TP_PCA9555_0_P11   I206 @S9S_MB_2U_LIB.S9S_MB_2U(SCH_1):PAGE154
    15 TP_PCA9555_0_P12 @S9S_MB_2U_LIB.S9S_MB_2U(SCH_1):TP_PCA9555_0_P12   I206 @S9S_MB_2U_LIB.S9S_MB_2U(SCH_1):PAGE154
    16 TP_PCA9555_0_P13 @S9S_MB_2U_LIB.S9S_MB_2U(SCH_1):TP_PCA9555_0_P13   I206 @S9S_MB_2U_LIB.S9S_MB_2U(SCH_1):PAGE154
    17 TP_PCA9555_0_P14 @S9S_MB_2U_LIB.S9S_MB_2U(SCH_1):TP_PCA9555_0_P14   I206 @S9S_MB_2U_LIB.S9S_MB_2U(SCH_1):PAGE154
    18 TP_PCA9555_0_P15 @S9S_MB_2U_LIB.S9S_MB_2U(SCH_1):TP_PCA9555_0_P15   I206 @S9S_MB_2U_LIB.S9S_MB_2U(SCH_1):PAGE154
    19 TP_PCA9555_0_P16 @S9S_MB_2U_LIB.S9S_MB_2U(SCH_1):TP_PCA9555_0_P16   I206 @S9S_MB_2U_LIB.S9S_MB_2U(SCH_1):PAGE154
    20 TP_PCA9555_0_P17 @S9S_MB_2U_LIB.S9S_MB_2U(SCH_1):TP_PCA9555_0_P17   I206 @S9S_MB_2U_LIB.S9S_MB_2U(SCH_1):PAGE154
    21 PD_SMB_OCP1_HP_ADD0 @S9S_MB_2U_LIB.S9S_MB_2U(SCH_1):PD_SMB_OCP1_HP_ADD0   I206 @S9S_MB_2U_LIB.S9S_MB_2U(SCH_1):PAGE154
     2 PD_SMB_OCP1_HP_ADD1 @S9S_MB_2U_LIB.S9S_MB_2U(SCH_1):PD_SMB_OCP1_HP_ADD1   I206 @S9S_MB_2U_LIB.S9S_MB_2U(SCH_1):PAGE154
     3 PD_SMB_OCP1_HP_ADD2 @S9S_MB_2U_LIB.S9S_MB_2U(SCH_1):PD_SMB_OCP1_HP_ADD2   I206 @S9S_MB_2U_LIB.S9S_MB_2U(SCH_1):PAGE154

U210 74LVC1G08W57-74LVC1G08W5-7,SMLA
     1 HP_LVC3_OCP_V3_1_PWRGD_R @S9S_MB_2U_LIB.S9S_MB_2U(SCH_1):HP_LVC3_OCP_V3_1_PWRGD_R   I189 @S9S_MB_2U_LIB.S9S_MB_2U(SCH_1):PAGE154
     2 RST_OCP_V3_1_N @S9S_MB_2U_LIB.S9S_MB_2U(SCH_1):RST_OCP_V3_1_N   I189 @S9S_MB_2U_LIB.S9S_MB_2U(SCH_1):PAGE154
     3    GND @S9S_MB_2U_LIB.S9S_MB_2U(SCH_1):GND   I189 @S9S_MB_2U_LIB.S9S_MB_2U(SCH_1):PAGE154
     4 RST_HP_OCP_V3_1_N @S9S_MB_2U_LIB.S9S_MB_2U(SCH_1):RST_HP_OCP_V3_1_N   I189 @S9S_MB_2U_LIB.S9S_MB_2U(SCH_1):PAGE154
     5 P3V3_AUX @S9S_MB_2U_LIB.S9S_MB_2U(SCH_1):P3V3_AUX   I189 @S9S_MB_2U_LIB.S9S_MB_2U(SCH_1):PAGE154

U211 74LVC2G07DW7-74LVC2G07DW-7,SMLA
     1 OCP_SFF_PRSNT0_R_N @S9S_MB_2U_LIB.S9S_MB_2U(SCH_1):OCP_SFF_PRSNT0_R_N    I26 @S9S_MB_2U_LIB.S9S_MB_2U(SCH_1):PAGE153
     3 OCP_SFF_PRSNT1_R_N @S9S_MB_2U_LIB.S9S_MB_2U(SCH_1):OCP_SFF_PRSNT1_R_N    I26 @S9S_MB_2U_LIB.S9S_MB_2U(SCH_1):PAGE153
     6 HP_LVC3_OCP_V3_1_PRSNT2_N_R @S9S_MB_2U_LIB.S9S_MB_2U(SCH_1):HP_LVC3_OCP_V3_1_PRSNT2_N_R    I26 @S9S_MB_2U_LIB.S9S_MB_2U(SCH_1):PAGE153
     4 HP_LVC3_OCP_V3_1_PRSNT2_N_R @S9S_MB_2U_LIB.S9S_MB_2U(SCH_1):HP_LVC3_OCP_V3_1_PRSNT2_N_R    I26 @S9S_MB_2U_LIB.S9S_MB_2U(SCH_1):PAGE153
     2    GND @S9S_MB_2U_LIB.S9S_MB_2U(SCH_1):GND    I26 @S9S_MB_2U_LIB.S9S_MB_2U(SCH_1):PAGE153
     5 P3V3_AUX @S9S_MB_2U_LIB.S9S_MB_2U(SCH_1):P3V3_AUX    I26 @S9S_MB_2U_LIB.S9S_MB_2U(SCH_1):PAGE153

U212 74LVC2G07DW7-74LVC2G07DW-7,SMLA
     1 OCP_SFF_PRSNT2_R_N @S9S_MB_2U_LIB.S9S_MB_2U(SCH_1):OCP_SFF_PRSNT2_R_N    I23 @S9S_MB_2U_LIB.S9S_MB_2U(SCH_1):PAGE153
     3 OCP_SFF_PRSNT3_R_N @S9S_MB_2U_LIB.S9S_MB_2U(SCH_1):OCP_SFF_PRSNT3_R_N    I23 @S9S_MB_2U_LIB.S9S_MB_2U(SCH_1):PAGE153
     6 HP_LVC3_OCP_V3_1_PRSNT2_N_R @S9S_MB_2U_LIB.S9S_MB_2U(SCH_1):HP_LVC3_OCP_V3_1_PRSNT2_N_R    I23 @S9S_MB_2U_LIB.S9S_MB_2U(SCH_1):PAGE153
     4 HP_LVC3_OCP_V3_1_PRSNT2_N_R @S9S_MB_2U_LIB.S9S_MB_2U(SCH_1):HP_LVC3_OCP_V3_1_PRSNT2_N_R    I23 @S9S_MB_2U_LIB.S9S_MB_2U(SCH_1):PAGE153
     2    GND @S9S_MB_2U_LIB.S9S_MB_2U(SCH_1):GND    I23 @S9S_MB_2U_LIB.S9S_MB_2U(SCH_1):PAGE153
     5 P3V3_AUX @S9S_MB_2U_LIB.S9S_MB_2U(SCH_1):P3V3_AUX    I23 @S9S_MB_2U_LIB.S9S_MB_2U(SCH_1):PAGE153

U215 MOSFET_N_SMLF-BSS138K,BSS138K,A
     G HP_LVC3_OCP_V3_2_PRSNT2_N @S9S_MB_2U_LIB.S9S_MB_2U(SCH_1):HP_LVC3_OCP_V3_2_PRSNT2_N     I3 @S9S_MB_2U_LIB.S9S_MB_2U(SCH_1):PAGE132
     D HP_LVC3_OCP_V3_2_PRSNT2 @S9S_MB_2U_LIB.S9S_MB_2U(SCH_1):HP_LVC3_OCP_V3_2_PRSNT2     I3 @S9S_MB_2U_LIB.S9S_MB_2U(SCH_1):PAGE132
     S    GND @S9S_MB_2U_LIB.S9S_MB_2U(SCH_1):GND     I3 @S9S_MB_2U_LIB.S9S_MB_2U(SCH_1):PAGE132

U216 APX80929SAG7-APX809-29SAG-7,SMA
     3 P3V3_OCP_V3_2 @S9S_MB_2U_LIB.S9S_MB_2U(SCH_1):P3V3_OCP_V3_2    I85 @S9S_MB_2U_LIB.S9S_MB_2U(SCH_1):PAGE132
     2 HP_OCP_V3_2_RST @S9S_MB_2U_LIB.S9S_MB_2U(SCH_1):HP_OCP_V3_2_RST    I85 @S9S_MB_2U_LIB.S9S_MB_2U(SCH_1):PAGE132
     1    GND @S9S_MB_2U_LIB.S9S_MB_2U(SCH_1):GND    I85 @S9S_MB_2U_LIB.S9S_MB_2U(SCH_1):PAGE132

U217 74LVC1G126SE7-74LVC1G126SE-7,SA
     2 IRQ_LVC3_OCP_V3_2_WAKE_N @S9S_MB_2U_LIB.S9S_MB_2U(SCH_1):IRQ_LVC3_OCP_V3_2_WAKE_N    I79 @S9S_MB_2U_LIB.S9S_MB_2U(SCH_1):PAGE156
     4 OCP_V3_2_WAKE_BUFF_N @S9S_MB_2U_LIB.S9S_MB_2U(SCH_1):OCP_V3_2_WAKE_BUFF_N    I79 @S9S_MB_2U_LIB.S9S_MB_2U(SCH_1):PAGE156
     5 P3V3_AUX @S9S_MB_2U_LIB.S9S_MB_2U(SCH_1):P3V3_AUX    I79 @S9S_MB_2U_LIB.S9S_MB_2U(SCH_1):PAGE156
     3    GND @S9S_MB_2U_LIB.S9S_MB_2U(SCH_1):GND    I79 @S9S_MB_2U_LIB.S9S_MB_2U(SCH_1):PAGE156
     1 PU_OCP_V3_2_WAKE_OE @S9S_MB_2U_LIB.S9S_MB_2U(SCH_1):PU_OCP_V3_2_WAKE_OE    I79 @S9S_MB_2U_LIB.S9S_MB_2U(SCH_1):PAGE156

U218 74LVC1G07GV-74LVC1G07GV,SMLF,IA
     5 P3V3_AUX @S9S_MB_2U_LIB.S9S_MB_2U(SCH_1):P3V3_AUX    I31 @S9S_MB_2U_LIB.S9S_MB_2U(SCH_1):PAGE156
     2 FM_SYS_THROTTLE_R_N @S9S_MB_2U_LIB.S9S_MB_2U(SCH_1):FM_SYS_THROTTLE_R_N    I31 @S9S_MB_2U_LIB.S9S_MB_2U(SCH_1):PAGE156
     3    GND @S9S_MB_2U_LIB.S9S_MB_2U(SCH_1):GND    I31 @S9S_MB_2U_LIB.S9S_MB_2U(SCH_1):PAGE156
     4 OCP_V3_2_PWRBRK_BUFF_N @S9S_MB_2U_LIB.S9S_MB_2U(SCH_1):OCP_V3_2_PWRBRK_BUFF_N    I31 @S9S_MB_2U_LIB.S9S_MB_2U(SCH_1):PAGE156
     1 NC_U218_NC1 @S9S_MB_2U_LIB.S9S_MB_2U(SCH_1):NC_U218_NC1    I31 @S9S_MB_2U_LIB.S9S_MB_2U(SCH_1):PAGE156

U219 74LVC1G07GV-74LVC1G07GV,SMLF,IA
     5 P3V3_AUX @S9S_MB_2U_LIB.S9S_MB_2U(SCH_1):P3V3_AUX    I61 @S9S_MB_2U_LIB.S9S_MB_2U(SCH_1):PAGE156
     2 OCP_V3_2_WAKE_BUFF_R_N @S9S_MB_2U_LIB.S9S_MB_2U(SCH_1):OCP_V3_2_WAKE_BUFF_R_N    I61 @S9S_MB_2U_LIB.S9S_MB_2U(SCH_1):PAGE156
     3    GND @S9S_MB_2U_LIB.S9S_MB_2U(SCH_1):GND    I61 @S9S_MB_2U_LIB.S9S_MB_2U(SCH_1):PAGE156
     4 IRQ_LVC3_V3_2_WAKE_BUF_N @S9S_MB_2U_LIB.S9S_MB_2U(SCH_1):IRQ_LVC3_V3_2_WAKE_BUF_N    I61 @S9S_MB_2U_LIB.S9S_MB_2U(SCH_1):PAGE156
     1 NC_U219_NC1 @S9S_MB_2U_LIB.S9S_MB_2U(SCH_1):NC_U219_NC1    I61 @S9S_MB_2U_LIB.S9S_MB_2U(SCH_1):PAGE156

U222 74CBTLV3126PW-74CBTLV3126PW,SMA
     5 NCSI_BMC_RXD0_R1 @S9S_MB_2U_LIB.S9S_MB_2U(SCH_1):NCSI_BMC_RXD0_R1    I32 @S9S_MB_2U_LIB.S9S_MB_2U(SCH_1):PAGE307
     8 NCSI_OCP_V3_2_CRS_DV @S9S_MB_2U_LIB.S9S_MB_2U(SCH_1):NCSI_OCP_V3_2_CRS_DV    I32 @S9S_MB_2U_LIB.S9S_MB_2U(SCH_1):PAGE307
     1 FB_BMC_ISOLATE1 @S9S_MB_2U_LIB.S9S_MB_2U(SCH_1):FB_BMC_ISOLATE1    I32 @S9S_MB_2U_LIB.S9S_MB_2U(SCH_1):PAGE307
     4 FB_BMC_ISOLATE1 @S9S_MB_2U_LIB.S9S_MB_2U(SCH_1):FB_BMC_ISOLATE1    I32 @S9S_MB_2U_LIB.S9S_MB_2U(SCH_1):PAGE307
     3 NCSI_OCP_V3_2_RXD1 @S9S_MB_2U_LIB.S9S_MB_2U(SCH_1):NCSI_OCP_V3_2_RXD1    I32 @S9S_MB_2U_LIB.S9S_MB_2U(SCH_1):PAGE307
     6 NCSI_OCP_V3_2_RXD0 @S9S_MB_2U_LIB.S9S_MB_2U(SCH_1):NCSI_OCP_V3_2_RXD0    I32 @S9S_MB_2U_LIB.S9S_MB_2U(SCH_1):PAGE307
     2 NCSI_BMC_RXD1_R1 @S9S_MB_2U_LIB.S9S_MB_2U(SCH_1):NCSI_BMC_RXD1_R1    I32 @S9S_MB_2U_LIB.S9S_MB_2U(SCH_1):PAGE307
     7    GND @S9S_MB_2U_LIB.S9S_MB_2U(SCH_1):GND    I32 @S9S_MB_2U_LIB.S9S_MB_2U(SCH_1):PAGE307
     9 NCSI_BMC_CRS_DV_R1 @S9S_MB_2U_LIB.S9S_MB_2U(SCH_1):NCSI_BMC_CRS_DV_R1    I32 @S9S_MB_2U_LIB.S9S_MB_2U(SCH_1):PAGE307
    10 FB_BMC_ISOLATE1 @S9S_MB_2U_LIB.S9S_MB_2U(SCH_1):FB_BMC_ISOLATE1    I32 @S9S_MB_2U_LIB.S9S_MB_2U(SCH_1):PAGE307
    11 OCP_V3_2_ISO1_RBT_ARB_IN @S9S_MB_2U_LIB.S9S_MB_2U(SCH_1):OCP_V3_2_ISO1_RBT_ARB_IN    I32 @S9S_MB_2U_LIB.S9S_MB_2U(SCH_1):PAGE307
    12 OCP_V3_2_RBT_ARB_IN_R @S9S_MB_2U_LIB.S9S_MB_2U(SCH_1):OCP_V3_2_RBT_ARB_IN_R    I32 @S9S_MB_2U_LIB.S9S_MB_2U(SCH_1):PAGE307
    13 FB_BMC_ISOLATE1 @S9S_MB_2U_LIB.S9S_MB_2U(SCH_1):FB_BMC_ISOLATE1    I32 @S9S_MB_2U_LIB.S9S_MB_2U(SCH_1):PAGE307
    14 P3V3_AUX @S9S_MB_2U_LIB.S9S_MB_2U(SCH_1):P3V3_AUX    I32 @S9S_MB_2U_LIB.S9S_MB_2U(SCH_1):PAGE307

U223 74CBTLV3126PW-74CBTLV3126PW,SMA
     5 NCSI_BMC_TXD0_R1 @S9S_MB_2U_LIB.S9S_MB_2U(SCH_1):NCSI_BMC_TXD0_R1    I78 @S9S_MB_2U_LIB.S9S_MB_2U(SCH_1):PAGE307
     8 NCSI_OCP_V3_2_TX_EN @S9S_MB_2U_LIB.S9S_MB_2U(SCH_1):NCSI_OCP_V3_2_TX_EN    I78 @S9S_MB_2U_LIB.S9S_MB_2U(SCH_1):PAGE307
     1 FB_BMC_ISOLATE1 @S9S_MB_2U_LIB.S9S_MB_2U(SCH_1):FB_BMC_ISOLATE1    I78 @S9S_MB_2U_LIB.S9S_MB_2U(SCH_1):PAGE307
     4 FB_BMC_ISOLATE1 @S9S_MB_2U_LIB.S9S_MB_2U(SCH_1):FB_BMC_ISOLATE1    I78 @S9S_MB_2U_LIB.S9S_MB_2U(SCH_1):PAGE307
     3 NCSI_OCP_V3_2_TXD1 @S9S_MB_2U_LIB.S9S_MB_2U(SCH_1):NCSI_OCP_V3_2_TXD1    I78 @S9S_MB_2U_LIB.S9S_MB_2U(SCH_1):PAGE307
     6 NCSI_OCP_V3_2_TXD0 @S9S_MB_2U_LIB.S9S_MB_2U(SCH_1):NCSI_OCP_V3_2_TXD0    I78 @S9S_MB_2U_LIB.S9S_MB_2U(SCH_1):PAGE307
     2 NCSI_BMC_TXD1_R1 @S9S_MB_2U_LIB.S9S_MB_2U(SCH_1):NCSI_BMC_TXD1_R1    I78 @S9S_MB_2U_LIB.S9S_MB_2U(SCH_1):PAGE307
     7    GND @S9S_MB_2U_LIB.S9S_MB_2U(SCH_1):GND    I78 @S9S_MB_2U_LIB.S9S_MB_2U(SCH_1):PAGE307
     9 NCSI_BMC_TX_EN_R1 @S9S_MB_2U_LIB.S9S_MB_2U(SCH_1):NCSI_BMC_TX_EN_R1    I78 @S9S_MB_2U_LIB.S9S_MB_2U(SCH_1):PAGE307
    10 FB_BMC_ISOLATE1 @S9S_MB_2U_LIB.S9S_MB_2U(SCH_1):FB_BMC_ISOLATE1    I78 @S9S_MB_2U_LIB.S9S_MB_2U(SCH_1):PAGE307
    11 OCP_V3_2_ISO2_RBT_ARB_OUT @S9S_MB_2U_LIB.S9S_MB_2U(SCH_1):OCP_V3_2_ISO2_RBT_ARB_OUT    I78 @S9S_MB_2U_LIB.S9S_MB_2U(SCH_1):PAGE307
    12 OCP_V3_2_RBT_ARB_OUT @S9S_MB_2U_LIB.S9S_MB_2U(SCH_1):OCP_V3_2_RBT_ARB_OUT    I78 @S9S_MB_2U_LIB.S9S_MB_2U(SCH_1):PAGE307
    13 FB_BMC_ISOLATE1 @S9S_MB_2U_LIB.S9S_MB_2U(SCH_1):FB_BMC_ISOLATE1    I78 @S9S_MB_2U_LIB.S9S_MB_2U(SCH_1):PAGE307
    14 P3V3_AUX @S9S_MB_2U_LIB.S9S_MB_2U(SCH_1):P3V3_AUX    I78 @S9S_MB_2U_LIB.S9S_MB_2U(SCH_1):PAGE307

U224 74LVC1G126SE7-74LVC1G126SE-7,SA
     2 RST_SMB_SWITCH_N @S9S_MB_2U_LIB.S9S_MB_2U(SCH_1):RST_SMB_SWITCH_N     I7 @S9S_MB_2U_LIB.S9S_MB_2U(SCH_1):PAGE151
     4 RST_HP_OCP_SFF_R_N @S9S_MB_2U_LIB.S9S_MB_2U(SCH_1):RST_HP_OCP_SFF_R_N     I7 @S9S_MB_2U_LIB.S9S_MB_2U(SCH_1):PAGE151
     5 P3V3_AUX @S9S_MB_2U_LIB.S9S_MB_2U(SCH_1):P3V3_AUX     I7 @S9S_MB_2U_LIB.S9S_MB_2U(SCH_1):PAGE151
     3    GND @S9S_MB_2U_LIB.S9S_MB_2U(SCH_1):GND     I7 @S9S_MB_2U_LIB.S9S_MB_2U(SCH_1):PAGE151
     1 OCP_SFF_AUX_PWR_EN_R4 @S9S_MB_2U_LIB.S9S_MB_2U(SCH_1):OCP_SFF_AUX_PWR_EN_R4     I7 @S9S_MB_2U_LIB.S9S_MB_2U(SCH_1):PAGE151

U225 74LVC1G126SE7-74LVC1G126SE-7,SA
     2 RST_SMB_SWITCH_N @S9S_MB_2U_LIB.S9S_MB_2U(SCH_1):RST_SMB_SWITCH_N    I74 @S9S_MB_2U_LIB.S9S_MB_2U(SCH_1):PAGE156
     4 RST_HP_OCP_V3_2_R_N @S9S_MB_2U_LIB.S9S_MB_2U(SCH_1):RST_HP_OCP_V3_2_R_N    I74 @S9S_MB_2U_LIB.S9S_MB_2U(SCH_1):PAGE156
     5 P3V3_AUX @S9S_MB_2U_LIB.S9S_MB_2U(SCH_1):P3V3_AUX    I74 @S9S_MB_2U_LIB.S9S_MB_2U(SCH_1):PAGE156
     3    GND @S9S_MB_2U_LIB.S9S_MB_2U(SCH_1):GND    I74 @S9S_MB_2U_LIB.S9S_MB_2U(SCH_1):PAGE156
     1 OCP_V3_2_AUX_PWR_EN_R3 @S9S_MB_2U_LIB.S9S_MB_2U(SCH_1):OCP_V3_2_AUX_PWR_EN_R3    I74 @S9S_MB_2U_LIB.S9S_MB_2U(SCH_1):PAGE156

U235 PCA9617ADP-PCA9617ADP,SMLF,IC,A
     5 HP_LVC3_OCP_V3_2_R_EN @S9S_MB_2U_LIB.S9S_MB_2U(SCH_1):HP_LVC3_OCP_V3_2_R_EN     I5 @S9S_MB_2U_LIB.S9S_MB_2U(SCH_1):PAGE216
     1 P3V3_AUX @S9S_MB_2U_LIB.S9S_MB_2U(SCH_1):P3V3_AUX     I5 @S9S_MB_2U_LIB.S9S_MB_2U(SCH_1):PAGE216
     8 P3V3_OCP_V3_2 @S9S_MB_2U_LIB.S9S_MB_2U(SCH_1):P3V3_OCP_V3_2     I5 @S9S_MB_2U_LIB.S9S_MB_2U(SCH_1):PAGE216
     2 SMB_OCP_V3_2_3V3AUX_SCL @S9S_MB_2U_LIB.S9S_MB_2U(SCH_1):SMB_OCP_V3_2_3V3AUX_SCL     I5 @S9S_MB_2U_LIB.S9S_MB_2U(SCH_1):PAGE216
     3 SMB_OCP_V3_2_3V3AUX_SDA @S9S_MB_2U_LIB.S9S_MB_2U(SCH_1):SMB_OCP_V3_2_3V3AUX_SDA     I5 @S9S_MB_2U_LIB.S9S_MB_2U(SCH_1):PAGE216
     6 SMB_OCP_V3_2_3V3AUX_BUF_SDA @S9S_MB_2U_LIB.S9S_MB_2U(SCH_1):SMB_OCP_V3_2_3V3AUX_BUF_SDA     I5 @S9S_MB_2U_LIB.S9S_MB_2U(SCH_1):PAGE216
     7 SMB_OCP_V3_2_3V3AUX_BUF_SCL @S9S_MB_2U_LIB.S9S_MB_2U(SCH_1):SMB_OCP_V3_2_3V3AUX_BUF_SCL     I5 @S9S_MB_2U_LIB.S9S_MB_2U(SCH_1):PAGE216
     4    GND @S9S_MB_2U_LIB.S9S_MB_2U(SCH_1):GND     I5 @S9S_MB_2U_LIB.S9S_MB_2U(SCH_1):PAGE216

U236 PCA9617ADP-PCA9617ADP,SMLF,IC,A
     5 HP_LVC3_OCP_V3_1_R_EN @S9S_MB_2U_LIB.S9S_MB_2U(SCH_1):HP_LVC3_OCP_V3_1_R_EN    I28 @S9S_MB_2U_LIB.S9S_MB_2U(SCH_1):PAGE216
     1 P3V3_AUX @S9S_MB_2U_LIB.S9S_MB_2U(SCH_1):P3V3_AUX    I28 @S9S_MB_2U_LIB.S9S_MB_2U(SCH_1):PAGE216
     8 P3V3_OCP_SFF @S9S_MB_2U_LIB.S9S_MB_2U(SCH_1):P3V3_OCP_SFF    I28 @S9S_MB_2U_LIB.S9S_MB_2U(SCH_1):PAGE216
     2 SMB_OCP_SFF_3V3AUX_SCL @S9S_MB_2U_LIB.S9S_MB_2U(SCH_1):SMB_OCP_SFF_3V3AUX_SCL    I28 @S9S_MB_2U_LIB.S9S_MB_2U(SCH_1):PAGE216
     3 SMB_OCP_SFF_3V3AUX_SDA @S9S_MB_2U_LIB.S9S_MB_2U(SCH_1):SMB_OCP_SFF_3V3AUX_SDA    I28 @S9S_MB_2U_LIB.S9S_MB_2U(SCH_1):PAGE216
     6 SMB_OCP_SFF_3V3AUX_BUF_SDA @S9S_MB_2U_LIB.S9S_MB_2U(SCH_1):SMB_OCP_SFF_3V3AUX_BUF_SDA    I28 @S9S_MB_2U_LIB.S9S_MB_2U(SCH_1):PAGE216
     7 SMB_OCP_SFF_3V3AUX_BUF_SCL @S9S_MB_2U_LIB.S9S_MB_2U(SCH_1):SMB_OCP_SFF_3V3AUX_BUF_SCL    I28 @S9S_MB_2U_LIB.S9S_MB_2U(SCH_1):PAGE216
     4    GND @S9S_MB_2U_LIB.S9S_MB_2U(SCH_1):GND    I28 @S9S_MB_2U_LIB.S9S_MB_2U(SCH_1):PAGE216

U237 PI3EQX12902AZLEX-PI3EQX12902AZA
     1 P3V3_AUX @S9S_MB_2U_LIB.S9S_MB_2U(SCH_1):P3V3_AUX    I50 @S9S_MB_2U_LIB.S9S_MB_2U(SCH_1):PAGE136
     2 P2E_MB_BMC_TX_C_R1_DP<0> @S9S_MB_2U_LIB.S9S_MB_2U(SCH_1):P2E_MB_BMC_TX_C_R1_DP(0)    I50 @S9S_MB_2U_LIB.S9S_MB_2U(SCH_1):PAGE136
     3 P2E_MB_BMC_TX_C_R1_DN<0> @S9S_MB_2U_LIB.S9S_MB_2U(SCH_1):P2E_MB_BMC_TX_C_R1_DN(0)    I50 @S9S_MB_2U_LIB.S9S_MB_2U(SCH_1):PAGE136
     4    GND @S9S_MB_2U_LIB.S9S_MB_2U(SCH_1):GND    I50 @S9S_MB_2U_LIB.S9S_MB_2U(SCH_1):PAGE136
     5 PU_TEST @S9S_MB_2U_LIB.S9S_MB_2U(SCH_1):PU_TEST    I50 @S9S_MB_2U_LIB.S9S_MB_2U(SCH_1):PAGE136
     6    GND @S9S_MB_2U_LIB.S9S_MB_2U(SCH_1):GND    I50 @S9S_MB_2U_LIB.S9S_MB_2U(SCH_1):PAGE136
     7    GND @S9S_MB_2U_LIB.S9S_MB_2U(SCH_1):GND    I50 @S9S_MB_2U_LIB.S9S_MB_2U(SCH_1):PAGE136
     8 P2E_MB_BMC_RX_BUF_C_DN<0> @S9S_MB_2U_LIB.S9S_MB_2U(SCH_1):P2E_MB_BMC_RX_BUF_C_DN(0)    I50 @S9S_MB_2U_LIB.S9S_MB_2U(SCH_1):PAGE136
     9 P2E_MB_BMC_RX_BUF_C_DP<0> @S9S_MB_2U_LIB.S9S_MB_2U(SCH_1):P2E_MB_BMC_RX_BUF_C_DP(0)    I50 @S9S_MB_2U_LIB.S9S_MB_2U(SCH_1):PAGE136
    10 P3V3_AUX @S9S_MB_2U_LIB.S9S_MB_2U(SCH_1):P3V3_AUX    I50 @S9S_MB_2U_LIB.S9S_MB_2U(SCH_1):PAGE136
    11 FM_P2E_EN_N @S9S_MB_2U_LIB.S9S_MB_2U(SCH_1):FM_P2E_EN_N    I50 @S9S_MB_2U_LIB.S9S_MB_2U(SCH_1):PAGE136
    12 FM_P2E_SWB @S9S_MB_2U_LIB.S9S_MB_2U(SCH_1):FM_P2E_SWB    I50 @S9S_MB_2U_LIB.S9S_MB_2U(SCH_1):PAGE136
    13    GND @S9S_MB_2U_LIB.S9S_MB_2U(SCH_1):GND    I50 @S9S_MB_2U_LIB.S9S_MB_2U(SCH_1):PAGE136
    14 FM_P2E_FGB @S9S_MB_2U_LIB.S9S_MB_2U(SCH_1):FM_P2E_FGB    I50 @S9S_MB_2U_LIB.S9S_MB_2U(SCH_1):PAGE136
    15 FM_P2E_EQB1 @S9S_MB_2U_LIB.S9S_MB_2U(SCH_1):FM_P2E_EQB1    I50 @S9S_MB_2U_LIB.S9S_MB_2U(SCH_1):PAGE136
    16 P3V3_AUX @S9S_MB_2U_LIB.S9S_MB_2U(SCH_1):P3V3_AUX    I50 @S9S_MB_2U_LIB.S9S_MB_2U(SCH_1):PAGE136
    17 P2E_MB_BMC_RX_R1_DP<0> @S9S_MB_2U_LIB.S9S_MB_2U(SCH_1):P2E_MB_BMC_RX_R1_DP(0)    I50 @S9S_MB_2U_LIB.S9S_MB_2U(SCH_1):PAGE136
    18 P2E_MB_BMC_RX_R1_DN<0> @S9S_MB_2U_LIB.S9S_MB_2U(SCH_1):P2E_MB_BMC_RX_R1_DN(0)    I50 @S9S_MB_2U_LIB.S9S_MB_2U(SCH_1):PAGE136
    19    GND @S9S_MB_2U_LIB.S9S_MB_2U(SCH_1):GND    I50 @S9S_MB_2U_LIB.S9S_MB_2U(SCH_1):PAGE136
    20 FM_P2E_EQB0 @S9S_MB_2U_LIB.S9S_MB_2U(SCH_1):FM_P2E_EQB0    I50 @S9S_MB_2U_LIB.S9S_MB_2U(SCH_1):PAGE136
    21 FM_P2E_EQA0 @S9S_MB_2U_LIB.S9S_MB_2U(SCH_1):FM_P2E_EQA0    I50 @S9S_MB_2U_LIB.S9S_MB_2U(SCH_1):PAGE136
    22    GND @S9S_MB_2U_LIB.S9S_MB_2U(SCH_1):GND    I50 @S9S_MB_2U_LIB.S9S_MB_2U(SCH_1):PAGE136
    23 P2E_MB_BMC_TX_BUF_DN<0> @S9S_MB_2U_LIB.S9S_MB_2U(SCH_1):P2E_MB_BMC_TX_BUF_DN(0)    I50 @S9S_MB_2U_LIB.S9S_MB_2U(SCH_1):PAGE136
    24 P2E_MB_BMC_TX_BUF_DP<0> @S9S_MB_2U_LIB.S9S_MB_2U(SCH_1):P2E_MB_BMC_TX_BUF_DP(0)    I50 @S9S_MB_2U_LIB.S9S_MB_2U(SCH_1):PAGE136
    25 P3V3_AUX @S9S_MB_2U_LIB.S9S_MB_2U(SCH_1):P3V3_AUX    I50 @S9S_MB_2U_LIB.S9S_MB_2U(SCH_1):PAGE136
    26 FM_P2E_EQA1 @S9S_MB_2U_LIB.S9S_MB_2U(SCH_1):FM_P2E_EQA1    I50 @S9S_MB_2U_LIB.S9S_MB_2U(SCH_1):PAGE136
    27 FM_P2E_FGA @S9S_MB_2U_LIB.S9S_MB_2U(SCH_1):FM_P2E_FGA    I50 @S9S_MB_2U_LIB.S9S_MB_2U(SCH_1):PAGE136
    28    GND @S9S_MB_2U_LIB.S9S_MB_2U(SCH_1):GND    I50 @S9S_MB_2U_LIB.S9S_MB_2U(SCH_1):PAGE136
    29 FM_P2E_SWA @S9S_MB_2U_LIB.S9S_MB_2U(SCH_1):FM_P2E_SWA    I50 @S9S_MB_2U_LIB.S9S_MB_2U(SCH_1):PAGE136
    30 FM_P2E_MODE @S9S_MB_2U_LIB.S9S_MB_2U(SCH_1):FM_P2E_MODE    I50 @S9S_MB_2U_LIB.S9S_MB_2U(SCH_1):PAGE136
    TH    GND @S9S_MB_2U_LIB.S9S_MB_2U(SCH_1):GND    I50 @S9S_MB_2U_LIB.S9S_MB_2U(SCH_1):PAGE136

U239 74LVC1G126SE7-74LVC1G126SE-7,SA
     2 LED_HDD_ACTIVITY_N @S9S_MB_2U_LIB.S9S_MB_2U(SCH_1):LED_HDD_ACTIVITY_N   I315 @S9S_MB_2U_LIB.S9S_MB_2U(SCH_1):PAGE182
     4 LED_HDD_ACTIVITY_B_N @S9S_MB_2U_LIB.S9S_MB_2U(SCH_1):LED_HDD_ACTIVITY_B_N   I315 @S9S_MB_2U_LIB.S9S_MB_2U(SCH_1):PAGE182
     5 P3V3_AUX @S9S_MB_2U_LIB.S9S_MB_2U(SCH_1):P3V3_AUX   I315 @S9S_MB_2U_LIB.S9S_MB_2U(SCH_1):PAGE182
     3    GND @S9S_MB_2U_LIB.S9S_MB_2U(SCH_1):GND   I315 @S9S_MB_2U_LIB.S9S_MB_2U(SCH_1):PAGE182
     1 PU_BUFFER_HDD_ACTIVITY @S9S_MB_2U_LIB.S9S_MB_2U(SCH_1):PU_BUFFER_HDD_ACTIVITY   I315 @S9S_MB_2U_LIB.S9S_MB_2U(SCH_1):PAGE182

U240 74LVC2G08DP-74LVC2G08DP,SMLF,IA
     8 P3V3_AUX @S9S_MB_2U_LIB.S9S_MB_2U(SCH_1):P3V3_AUX    I11 @S9S_MB_2U_LIB.S9S_MB_2U(SCH_1):PAGE170
     4    GND @S9S_MB_2U_LIB.S9S_MB_2U(SCH_1):GND    I11 @S9S_MB_2U_LIB.S9S_MB_2U(SCH_1):PAGE170
     1 OCP_SFF_PRSNT0_R_N @S9S_MB_2U_LIB.S9S_MB_2U(SCH_1):OCP_SFF_PRSNT0_R_N    I11 @S9S_MB_2U_LIB.S9S_MB_2U(SCH_1):PAGE170
     2 OCP_SFF_PRSNT1_R_N @S9S_MB_2U_LIB.S9S_MB_2U(SCH_1):OCP_SFF_PRSNT1_R_N    I11 @S9S_MB_2U_LIB.S9S_MB_2U(SCH_1):PAGE170
     7 OCP_SFF_PRSNT01_R_N @S9S_MB_2U_LIB.S9S_MB_2U(SCH_1):OCP_SFF_PRSNT01_R_N    I11 @S9S_MB_2U_LIB.S9S_MB_2U(SCH_1):PAGE170
     5 OCP_SFF_PRSNT2_R_N @S9S_MB_2U_LIB.S9S_MB_2U(SCH_1):OCP_SFF_PRSNT2_R_N    I12 @S9S_MB_2U_LIB.S9S_MB_2U(SCH_1):PAGE170
     6 OCP_SFF_PRSNT3_R_N @S9S_MB_2U_LIB.S9S_MB_2U(SCH_1):OCP_SFF_PRSNT3_R_N    I12 @S9S_MB_2U_LIB.S9S_MB_2U(SCH_1):PAGE170
     3 OCP_SFF_PRSNT23_R_N @S9S_MB_2U_LIB.S9S_MB_2U(SCH_1):OCP_SFF_PRSNT23_R_N    I12 @S9S_MB_2U_LIB.S9S_MB_2U(SCH_1):PAGE170

U241 74LVC2G08DP-74LVC2G08DP,SMLF,IA
     8 P3V3_AUX @S9S_MB_2U_LIB.S9S_MB_2U(SCH_1):P3V3_AUX     I1 @S9S_MB_2U_LIB.S9S_MB_2U(SCH_1):PAGE170
     4    GND @S9S_MB_2U_LIB.S9S_MB_2U(SCH_1):GND     I1 @S9S_MB_2U_LIB.S9S_MB_2U(SCH_1):PAGE170
     1 OCP_V3_2_PRSNT0_R_N @S9S_MB_2U_LIB.S9S_MB_2U(SCH_1):OCP_V3_2_PRSNT0_R_N     I1 @S9S_MB_2U_LIB.S9S_MB_2U(SCH_1):PAGE170
     2 OCP_V3_2_PRSNT1_R_N @S9S_MB_2U_LIB.S9S_MB_2U(SCH_1):OCP_V3_2_PRSNT1_R_N     I1 @S9S_MB_2U_LIB.S9S_MB_2U(SCH_1):PAGE170
     7 OCP_V3_2_PRSNT01_R_N @S9S_MB_2U_LIB.S9S_MB_2U(SCH_1):OCP_V3_2_PRSNT01_R_N     I1 @S9S_MB_2U_LIB.S9S_MB_2U(SCH_1):PAGE170
     5 OCP_V3_2_PRSNT2_R_N @S9S_MB_2U_LIB.S9S_MB_2U(SCH_1):OCP_V3_2_PRSNT2_R_N     I2 @S9S_MB_2U_LIB.S9S_MB_2U(SCH_1):PAGE170
     6 OCP_V3_2_PRSNT3_R_N @S9S_MB_2U_LIB.S9S_MB_2U(SCH_1):OCP_V3_2_PRSNT3_R_N     I2 @S9S_MB_2U_LIB.S9S_MB_2U(SCH_1):PAGE170
     3 OCP_V3_2_PRSNT23_R_N @S9S_MB_2U_LIB.S9S_MB_2U(SCH_1):OCP_V3_2_PRSNT23_R_N     I2 @S9S_MB_2U_LIB.S9S_MB_2U(SCH_1):PAGE170

U242 74LVC2G08DP-74LVC2G08DP,SMLF,IA
     8 P3V3_AUX @S9S_MB_2U_LIB.S9S_MB_2U(SCH_1):P3V3_AUX    I13 @S9S_MB_2U_LIB.S9S_MB_2U(SCH_1):PAGE170
     4    GND @S9S_MB_2U_LIB.S9S_MB_2U(SCH_1):GND    I13 @S9S_MB_2U_LIB.S9S_MB_2U(SCH_1):PAGE170
     1 OCP_SFF_PRSNT01_R_N @S9S_MB_2U_LIB.S9S_MB_2U(SCH_1):OCP_SFF_PRSNT01_R_N    I13 @S9S_MB_2U_LIB.S9S_MB_2U(SCH_1):PAGE170
     2 OCP_SFF_PRSNT23_R_N @S9S_MB_2U_LIB.S9S_MB_2U(SCH_1):OCP_SFF_PRSNT23_R_N    I13 @S9S_MB_2U_LIB.S9S_MB_2U(SCH_1):PAGE170
     7 OCP_SFF_PRSNT_ALL_R_N @S9S_MB_2U_LIB.S9S_MB_2U(SCH_1):OCP_SFF_PRSNT_ALL_R_N    I13 @S9S_MB_2U_LIB.S9S_MB_2U(SCH_1):PAGE170
     5 OCP_V3_2_PRSNT01_R_N @S9S_MB_2U_LIB.S9S_MB_2U(SCH_1):OCP_V3_2_PRSNT01_R_N    I14 @S9S_MB_2U_LIB.S9S_MB_2U(SCH_1):PAGE170
     6 OCP_V3_2_PRSNT23_R_N @S9S_MB_2U_LIB.S9S_MB_2U(SCH_1):OCP_V3_2_PRSNT23_R_N    I14 @S9S_MB_2U_LIB.S9S_MB_2U(SCH_1):PAGE170
     3 OCP_V3_2_PRSNT_ALL_R_N @S9S_MB_2U_LIB.S9S_MB_2U(SCH_1):OCP_V3_2_PRSNT_ALL_R_N    I14 @S9S_MB_2U_LIB.S9S_MB_2U(SCH_1):PAGE170

U243 NC7SB3157_SMLF-NC7SB3157P6X,NCB
     1 OCP_SFF_NOT_PRSNT_RBT_ARB_IN @S9S_MB_2U_LIB.S9S_MB_2U(SCH_1):OCP_SFF_NOT_PRSNT_RBT_ARB_IN    I15 @S9S_MB_2U_LIB.S9S_MB_2U(SCH_1):PAGE170
     2    GND @S9S_MB_2U_LIB.S9S_MB_2U(SCH_1):GND    I15 @S9S_MB_2U_LIB.S9S_MB_2U(SCH_1):PAGE170
     3 OCP_SFF_RBT_ARB_OUT @S9S_MB_2U_LIB.S9S_MB_2U(SCH_1):OCP_SFF_RBT_ARB_OUT    I15 @S9S_MB_2U_LIB.S9S_MB_2U(SCH_1):PAGE170
     6 OCP_SFF_PRSNT_ALL_R1_N @S9S_MB_2U_LIB.S9S_MB_2U(SCH_1):OCP_SFF_PRSNT_ALL_R1_N    I15 @S9S_MB_2U_LIB.S9S_MB_2U(SCH_1):PAGE170
     5 P3V3_AUX @S9S_MB_2U_LIB.S9S_MB_2U(SCH_1):P3V3_AUX    I15 @S9S_MB_2U_LIB.S9S_MB_2U(SCH_1):PAGE170
     4 OCP_SFF_RBT_ARB_IN_MUX2 @S9S_MB_2U_LIB.S9S_MB_2U(SCH_1):OCP_SFF_RBT_ARB_IN_MUX2    I15 @S9S_MB_2U_LIB.S9S_MB_2U(SCH_1):PAGE170

U244 NC7SB3157_SMLF-NC7SB3157P6X,NCB
     1 OCP_SFF_NOT_PRSNT_RBT_ARB_IN @S9S_MB_2U_LIB.S9S_MB_2U(SCH_1):OCP_SFF_NOT_PRSNT_RBT_ARB_IN    I16 @S9S_MB_2U_LIB.S9S_MB_2U(SCH_1):PAGE170
     2    GND @S9S_MB_2U_LIB.S9S_MB_2U(SCH_1):GND    I16 @S9S_MB_2U_LIB.S9S_MB_2U(SCH_1):PAGE170
     3 OCP_SFF_RBT_ARB_IN @S9S_MB_2U_LIB.S9S_MB_2U(SCH_1):OCP_SFF_RBT_ARB_IN    I16 @S9S_MB_2U_LIB.S9S_MB_2U(SCH_1):PAGE170
     6 OCP_SFF_PRSNT_ALL_R3_N @S9S_MB_2U_LIB.S9S_MB_2U(SCH_1):OCP_SFF_PRSNT_ALL_R3_N    I16 @S9S_MB_2U_LIB.S9S_MB_2U(SCH_1):PAGE170
     5 P3V3_AUX @S9S_MB_2U_LIB.S9S_MB_2U(SCH_1):P3V3_AUX    I16 @S9S_MB_2U_LIB.S9S_MB_2U(SCH_1):PAGE170
     4 OCP_SFF_RBT_ARB_IN_MUX1_R @S9S_MB_2U_LIB.S9S_MB_2U(SCH_1):OCP_SFF_RBT_ARB_IN_MUX1_R    I16 @S9S_MB_2U_LIB.S9S_MB_2U(SCH_1):PAGE170

U245 NC7SB3157_SMLF-NC7SB3157P6X,NCB
     1 OCP_V3_2_NOT_PRSNT_RBT_ARB_IN @S9S_MB_2U_LIB.S9S_MB_2U(SCH_1):OCP_V3_2_NOT_PRSNT_RBT_ARB_IN    I18 @S9S_MB_2U_LIB.S9S_MB_2U(SCH_1):PAGE170
     2    GND @S9S_MB_2U_LIB.S9S_MB_2U(SCH_1):GND    I18 @S9S_MB_2U_LIB.S9S_MB_2U(SCH_1):PAGE170
     3 OCP_V3_2_RBT_ARB_IN @S9S_MB_2U_LIB.S9S_MB_2U(SCH_1):OCP_V3_2_RBT_ARB_IN    I18 @S9S_MB_2U_LIB.S9S_MB_2U(SCH_1):PAGE170
     6 OCP_V3_2_PRSNT_ALL_R3_N @S9S_MB_2U_LIB.S9S_MB_2U(SCH_1):OCP_V3_2_PRSNT_ALL_R3_N    I18 @S9S_MB_2U_LIB.S9S_MB_2U(SCH_1):PAGE170
     5 P3V3_AUX @S9S_MB_2U_LIB.S9S_MB_2U(SCH_1):P3V3_AUX    I18 @S9S_MB_2U_LIB.S9S_MB_2U(SCH_1):PAGE170
     4 OCP_SFF_RBT_ARB_IN_MUX2_R @S9S_MB_2U_LIB.S9S_MB_2U(SCH_1):OCP_SFF_RBT_ARB_IN_MUX2_R    I18 @S9S_MB_2U_LIB.S9S_MB_2U(SCH_1):PAGE170

U246 NC7SB3157_SMLF-NC7SB3157P6X,NCB
     1 OCP_V3_2_NOT_PRSNT_RBT_ARB_IN @S9S_MB_2U_LIB.S9S_MB_2U(SCH_1):OCP_V3_2_NOT_PRSNT_RBT_ARB_IN    I17 @S9S_MB_2U_LIB.S9S_MB_2U(SCH_1):PAGE170
     2    GND @S9S_MB_2U_LIB.S9S_MB_2U(SCH_1):GND    I17 @S9S_MB_2U_LIB.S9S_MB_2U(SCH_1):PAGE170
     3 OCP_V3_2_RBT_ARB_OUT @S9S_MB_2U_LIB.S9S_MB_2U(SCH_1):OCP_V3_2_RBT_ARB_OUT    I17 @S9S_MB_2U_LIB.S9S_MB_2U(SCH_1):PAGE170
     6 OCP_V3_2_PRSNT_ALL_R1_N @S9S_MB_2U_LIB.S9S_MB_2U(SCH_1):OCP_V3_2_PRSNT_ALL_R1_N    I17 @S9S_MB_2U_LIB.S9S_MB_2U(SCH_1):PAGE170
     5 P3V3_AUX @S9S_MB_2U_LIB.S9S_MB_2U(SCH_1):P3V3_AUX    I17 @S9S_MB_2U_LIB.S9S_MB_2U(SCH_1):PAGE170
     4 OCP_SFF_RBT_ARB_IN_MUX1 @S9S_MB_2U_LIB.S9S_MB_2U(SCH_1):OCP_SFF_RBT_ARB_IN_MUX1    I17 @S9S_MB_2U_LIB.S9S_MB_2U(SCH_1):PAGE170

U247 9FGL0251DKILFT-9FGL0251DKILFT,A
     1 CLK_GEN2_XTAL_IN @S9S_MB_2U_LIB.S9S_MB_2U(SCH_1):CLK_GEN2_XTAL_IN   I167 @S9S_MB_2U_LIB.S9S_MB_2U(SCH_1):PAGE201
     2 CLK_GEN2_XTAL_OUT @S9S_MB_2U_LIB.S9S_MB_2U(SCH_1):CLK_GEN2_XTAL_OUT   I167 @S9S_MB_2U_LIB.S9S_MB_2U(SCH_1):PAGE201
     3 VFG3P3_CLK_GEN @S9S_MB_2U_LIB.S9S_MB_2U(SCH_1):VFG3P3_CLK_GEN   I167 @S9S_MB_2U_LIB.S9S_MB_2U(SCH_1):PAGE201
     4 CLK_GEN2_SMB_SADR @S9S_MB_2U_LIB.S9S_MB_2U(SCH_1):CLK_GEN2_SMB_SADR   I167 @S9S_MB_2U_LIB.S9S_MB_2U(SCH_1):PAGE201
     5    GND @S9S_MB_2U_LIB.S9S_MB_2U(SCH_1):GND   I167 @S9S_MB_2U_LIB.S9S_MB_2U(SCH_1):PAGE201
     6    GND @S9S_MB_2U_LIB.S9S_MB_2U(SCH_1):GND   I167 @S9S_MB_2U_LIB.S9S_MB_2U(SCH_1):PAGE201
     7 VFG3P3_CLK_GEN @S9S_MB_2U_LIB.S9S_MB_2U(SCH_1):VFG3P3_CLK_GEN   I167 @S9S_MB_2U_LIB.S9S_MB_2U(SCH_1):PAGE201
     8 SMB_HOST_CLK_GEN2_3V3AUX_SCL @S9S_MB_2U_LIB.S9S_MB_2U(SCH_1):SMB_HOST_CLK_GEN2_3V3AUX_SCL   I167 @S9S_MB_2U_LIB.S9S_MB_2U(SCH_1):PAGE201
     9 SMB_HOST_CLK_GEN2_3V3AUX_SDA @S9S_MB_2U_LIB.S9S_MB_2U(SCH_1):SMB_HOST_CLK_GEN2_3V3AUX_SDA   I167 @S9S_MB_2U_LIB.S9S_MB_2U(SCH_1):PAGE201
    10    GND @S9S_MB_2U_LIB.S9S_MB_2U(SCH_1):GND   I167 @S9S_MB_2U_LIB.S9S_MB_2U(SCH_1):PAGE201
    11 VFG3P3_CLK_GEN @S9S_MB_2U_LIB.S9S_MB_2U(SCH_1):VFG3P3_CLK_GEN   I167 @S9S_MB_2U_LIB.S9S_MB_2U(SCH_1):PAGE201
    12 CLK_GEN2_BMC_RC_OE_R3_N @S9S_MB_2U_LIB.S9S_MB_2U(SCH_1):CLK_GEN2_BMC_RC_OE_R3_N   I167 @S9S_MB_2U_LIB.S9S_MB_2U(SCH_1):PAGE201
    13 CLK_100M_BMC_RC_DP_R @S9S_MB_2U_LIB.S9S_MB_2U(SCH_1):CLK_100M_BMC_RC_DP_R   I167 @S9S_MB_2U_LIB.S9S_MB_2U(SCH_1):PAGE201
    14 CLK_100M_BMC_RC_DN_R @S9S_MB_2U_LIB.S9S_MB_2U(SCH_1):CLK_100M_BMC_RC_DN_R   I167 @S9S_MB_2U_LIB.S9S_MB_2U(SCH_1):PAGE201
    15    GND @S9S_MB_2U_LIB.S9S_MB_2U(SCH_1):GND   I167 @S9S_MB_2U_LIB.S9S_MB_2U(SCH_1):PAGE201
    16 VFG_3P3A_CLK_GEN @S9S_MB_2U_LIB.S9S_MB_2U(SCH_1):VFG_3P3A_CLK_GEN   I167 @S9S_MB_2U_LIB.S9S_MB_2U(SCH_1):PAGE201
    17 CLK_100M_GPU_FPGA_DP_R @S9S_MB_2U_LIB.S9S_MB_2U(SCH_1):CLK_100M_GPU_FPGA_DP_R   I167 @S9S_MB_2U_LIB.S9S_MB_2U(SCH_1):PAGE201
    18 CLK_100M_GPU_FPGA_DN_R @S9S_MB_2U_LIB.S9S_MB_2U(SCH_1):CLK_100M_GPU_FPGA_DN_R   I167 @S9S_MB_2U_LIB.S9S_MB_2U(SCH_1):PAGE201
    19 CLK_GEN2_GPU_OE_N @S9S_MB_2U_LIB.S9S_MB_2U(SCH_1):CLK_GEN2_GPU_OE_N   I167 @S9S_MB_2U_LIB.S9S_MB_2U(SCH_1):PAGE201
    20 VFG3P3_CLK_GEN @S9S_MB_2U_LIB.S9S_MB_2U(SCH_1):VFG3P3_CLK_GEN   I167 @S9S_MB_2U_LIB.S9S_MB_2U(SCH_1):PAGE201
    21    GND @S9S_MB_2U_LIB.S9S_MB_2U(SCH_1):GND   I167 @S9S_MB_2U_LIB.S9S_MB_2U(SCH_1):PAGE201
    22 P3V3_PWRGD_CLKGEN @S9S_MB_2U_LIB.S9S_MB_2U(SCH_1):P3V3_PWRGD_CLKGEN   I167 @S9S_MB_2U_LIB.S9S_MB_2U(SCH_1):PAGE201
    23 FG_SS_EN @S9S_MB_2U_LIB.S9S_MB_2U(SCH_1):FG_SS_EN   I167 @S9S_MB_2U_LIB.S9S_MB_2U(SCH_1):PAGE201
    24    GND @S9S_MB_2U_LIB.S9S_MB_2U(SCH_1):GND   I167 @S9S_MB_2U_LIB.S9S_MB_2U(SCH_1):PAGE201
    25    GND @S9S_MB_2U_LIB.S9S_MB_2U(SCH_1):GND   I167 @S9S_MB_2U_LIB.S9S_MB_2U(SCH_1):PAGE201

U248 74LVC1G32GW_SMLF-74LVC1G32GW,IA
     1 GPU_FPGA_READY_R_N @S9S_MB_2U_LIB.S9S_MB_2U(SCH_1):GPU_FPGA_READY_R_N   I158 @S9S_MB_2U_LIB.S9S_MB_2U(SCH_1):PAGE201
     2 CLK_GEN2_GPU_FPGA_OE_R2_N @S9S_MB_2U_LIB.S9S_MB_2U(SCH_1):CLK_GEN2_GPU_FPGA_OE_R2_N   I158 @S9S_MB_2U_LIB.S9S_MB_2U(SCH_1):PAGE201
     4 CLK_GEN2_GPU_FPGA_OE_OR_N @S9S_MB_2U_LIB.S9S_MB_2U(SCH_1):CLK_GEN2_GPU_FPGA_OE_OR_N   I158 @S9S_MB_2U_LIB.S9S_MB_2U(SCH_1):PAGE201
     5 P3V3_AUX @S9S_MB_2U_LIB.S9S_MB_2U(SCH_1):P3V3_AUX   I158 @S9S_MB_2U_LIB.S9S_MB_2U(SCH_1):PAGE201
     3    GND @S9S_MB_2U_LIB.S9S_MB_2U(SCH_1):GND   I158 @S9S_MB_2U_LIB.S9S_MB_2U(SCH_1):PAGE201

U249 LCMXO3LF9400C5BG484C-LCMXO3LF-A
    D3 RST_CPU0_DRAM_AB_PLD_LVT3_N @S9S_MB_2U_LIB.S9S_MB_2U(SCH_1):RST_CPU0_DRAM_AB_PLD_LVT3_N    I33 @S9S_MB_2U_LIB.S9S_MB_2U(SCH_1):PAGE311
    D4 RST_CPU0_DRAM_CD_PLD_LVT3_N @S9S_MB_2U_LIB.S9S_MB_2U(SCH_1):RST_CPU0_DRAM_CD_PLD_LVT3_N    I33 @S9S_MB_2U_LIB.S9S_MB_2U(SCH_1):PAGE311
    F6 RST_CPU0_DRAM_EF_PLD_LVT3_N @S9S_MB_2U_LIB.S9S_MB_2U(SCH_1):RST_CPU0_DRAM_EF_PLD_LVT3_N    I33 @S9S_MB_2U_LIB.S9S_MB_2U(SCH_1):PAGE311
    G7 RST_CPU0_DRAM_GH_PLD_LVT3_N @S9S_MB_2U_LIB.S9S_MB_2U(SCH_1):RST_CPU0_DRAM_GH_PLD_LVT3_N    I33 @S9S_MB_2U_LIB.S9S_MB_2U(SCH_1):PAGE311
    E4 RST_CPU1_DRAM_AB_PLD_LVT3_N @S9S_MB_2U_LIB.S9S_MB_2U(SCH_1):RST_CPU1_DRAM_AB_PLD_LVT3_N    I33 @S9S_MB_2U_LIB.S9S_MB_2U(SCH_1):PAGE311
    F5 RST_CPU1_DRAM_CD_PLD_LVT3_N @S9S_MB_2U_LIB.S9S_MB_2U(SCH_1):RST_CPU1_DRAM_CD_PLD_LVT3_N    I33 @S9S_MB_2U_LIB.S9S_MB_2U(SCH_1):PAGE311
    G6 RST_CPU1_DRAM_EF_PLD_LVT3_N @S9S_MB_2U_LIB.S9S_MB_2U(SCH_1):RST_CPU1_DRAM_EF_PLD_LVT3_N    I33 @S9S_MB_2U_LIB.S9S_MB_2U(SCH_1):PAGE311
    H7 RST_CPU1_DRAM_GH_PLD_LVT3_N @S9S_MB_2U_LIB.S9S_MB_2U(SCH_1):RST_CPU1_DRAM_GH_PLD_LVT3_N    I33 @S9S_MB_2U_LIB.S9S_MB_2U(SCH_1):PAGE311
    C1 RST_PLD_CPU0_DRAM_AB_N @S9S_MB_2U_LIB.S9S_MB_2U(SCH_1):RST_PLD_CPU0_DRAM_AB_N    I33 @S9S_MB_2U_LIB.S9S_MB_2U(SCH_1):PAGE311
    D2 RST_PLD_CPU0_DRAM_CD_N @S9S_MB_2U_LIB.S9S_MB_2U(SCH_1):RST_PLD_CPU0_DRAM_CD_N    I33 @S9S_MB_2U_LIB.S9S_MB_2U(SCH_1):PAGE311
    G5 RST_PLD_CPU0_DRAM_EF_N @S9S_MB_2U_LIB.S9S_MB_2U(SCH_1):RST_PLD_CPU0_DRAM_EF_N    I33 @S9S_MB_2U_LIB.S9S_MB_2U(SCH_1):PAGE311
    H6 RST_PLD_CPU0_DRAM_GH_N @S9S_MB_2U_LIB.S9S_MB_2U(SCH_1):RST_PLD_CPU0_DRAM_GH_N    I33 @S9S_MB_2U_LIB.S9S_MB_2U(SCH_1):PAGE311
    D1 RST_PLD_CPU1_DRAM_AB_N @S9S_MB_2U_LIB.S9S_MB_2U(SCH_1):RST_PLD_CPU1_DRAM_AB_N    I33 @S9S_MB_2U_LIB.S9S_MB_2U(SCH_1):PAGE311
    E2 RST_PLD_CPU1_DRAM_CD_N @S9S_MB_2U_LIB.S9S_MB_2U(SCH_1):RST_PLD_CPU1_DRAM_CD_N    I33 @S9S_MB_2U_LIB.S9S_MB_2U(SCH_1):PAGE311
    E3 RST_PLD_CPU1_DRAM_EF_N @S9S_MB_2U_LIB.S9S_MB_2U(SCH_1):RST_PLD_CPU1_DRAM_EF_N    I33 @S9S_MB_2U_LIB.S9S_MB_2U(SCH_1):PAGE311
    F4 RST_PLD_CPU1_DRAM_GH_N @S9S_MB_2U_LIB.S9S_MB_2U(SCH_1):RST_PLD_CPU1_DRAM_GH_N    I33 @S9S_MB_2U_LIB.S9S_MB_2U(SCH_1):PAGE311
    L7 HP_LVC3_OCP_V3_1_FUSE_PWRGD @S9S_MB_2U_LIB.S9S_MB_2U(SCH_1):HP_LVC3_OCP_V3_1_FUSE_PWRGD    I33 @S9S_MB_2U_LIB.S9S_MB_2U(SCH_1):PAGE311
    K5 HP_LVC3_OCP_V3_2_FUSE_PWRGD @S9S_MB_2U_LIB.S9S_MB_2U(SCH_1):HP_LVC3_OCP_V3_2_FUSE_PWRGD    I33 @S9S_MB_2U_LIB.S9S_MB_2U(SCH_1):PAGE311
    K4 HP_LVC3_OCP_V3_1_PRSNT2_PLD_N @S9S_MB_2U_LIB.S9S_MB_2U(SCH_1):HP_LVC3_OCP_V3_1_PRSNT2_PLD_N    I33 @S9S_MB_2U_LIB.S9S_MB_2U(SCH_1):PAGE311
    K3 HP_LVC3_OCP_V3_2_PRSNT2_PLD_N @S9S_MB_2U_LIB.S9S_MB_2U(SCH_1):HP_LVC3_OCP_V3_2_PRSNT2_PLD_N    I33 @S9S_MB_2U_LIB.S9S_MB_2U(SCH_1):PAGE311
    K2 HP_LVC3_E1S_0_HSC_PWRGD_PLD @S9S_MB_2U_LIB.S9S_MB_2U(SCH_1):HP_LVC3_E1S_0_HSC_PWRGD_PLD    I33 @S9S_MB_2U_LIB.S9S_MB_2U(SCH_1):PAGE311
    K1 HP_E1S_0_P3V3_PWRGD_PLD @S9S_MB_2U_LIB.S9S_MB_2U(SCH_1):HP_E1S_0_P3V3_PWRGD_PLD    I33 @S9S_MB_2U_LIB.S9S_MB_2U(SCH_1):PAGE311
    L1     NC     NC    I33 @S9S_MB_2U_LIB.S9S_MB_2U(SCH_1):PAGE311
    M2     NC     NC    I33 @S9S_MB_2U_LIB.S9S_MB_2U(SCH_1):PAGE311
    P4     NC     NC    I33 @S9S_MB_2U_LIB.S9S_MB_2U(SCH_1):PAGE311
    N5     NC     NC    I33 @S9S_MB_2U_LIB.S9S_MB_2U(SCH_1):PAGE311
    N6     NC     NC    I33 @S9S_MB_2U_LIB.S9S_MB_2U(SCH_1):PAGE311
    N7     NC     NC    I33 @S9S_MB_2U_LIB.S9S_MB_2U(SCH_1):PAGE311
    R2     NC     NC    I33 @S9S_MB_2U_LIB.S9S_MB_2U(SCH_1):PAGE311
    T1     NC     NC    I33 @S9S_MB_2U_LIB.S9S_MB_2U(SCH_1):PAGE311
    P5 PWRGD_CPUPWRGD_LVC2_R1 @S9S_MB_2U_LIB.S9S_MB_2U(SCH_1):PWRGD_CPUPWRGD_LVC2_R1    I33 @S9S_MB_2U_LIB.S9S_MB_2U(SCH_1):PAGE311
    P6     NC     NC    I33 @S9S_MB_2U_LIB.S9S_MB_2U(SCH_1):PAGE311
    T5 H_CPU_ERR1_LVC2_N @S9S_MB_2U_LIB.S9S_MB_2U(SCH_1):H_CPU_ERR1_LVC2_N    I33 @S9S_MB_2U_LIB.S9S_MB_2U(SCH_1):PAGE311
    T6 H_CPU_ERR0_LVC2_N @S9S_MB_2U_LIB.S9S_MB_2U(SCH_1):H_CPU_ERR0_LVC2_N    I33 @S9S_MB_2U_LIB.S9S_MB_2U(SCH_1):PAGE311
    L6 E1S_0_CLK_OE_N @S9S_MB_2U_LIB.S9S_MB_2U(SCH_1):E1S_0_CLK_OE_N    I33 @S9S_MB_2U_LIB.S9S_MB_2U(SCH_1):PAGE311
    L5 HP_LVC3_SCM_HSC_PWRGD_PLD @S9S_MB_2U_LIB.S9S_MB_2U(SCH_1):HP_LVC3_SCM_HSC_PWRGD_PLD    I33 @S9S_MB_2U_LIB.S9S_MB_2U(SCH_1):PAGE311
    L3     NC     NC    I33 @S9S_MB_2U_LIB.S9S_MB_2U(SCH_1):PAGE311
    L4     NC     NC    I33 @S9S_MB_2U_LIB.S9S_MB_2U(SCH_1):PAGE311
    G3     NC     NC    I33 @S9S_MB_2U_LIB.S9S_MB_2U(SCH_1):PAGE311
    G4     NC     NC    I33 @S9S_MB_2U_LIB.S9S_MB_2U(SCH_1):PAGE311
    E1     NC     NC    I33 @S9S_MB_2U_LIB.S9S_MB_2U(SCH_1):PAGE311
    F1     NC     NC    I33 @S9S_MB_2U_LIB.S9S_MB_2U(SCH_1):PAGE311
    T2 H_CPU0_THERMTRIP_LVC1_N @S9S_MB_2U_LIB.S9S_MB_2U(SCH_1):H_CPU0_THERMTRIP_LVC1_N    I33 @S9S_MB_2U_LIB.S9S_MB_2U(SCH_1):PAGE311
    U1 H_CPU1_MEMTRIP_LVC1_N @S9S_MB_2U_LIB.S9S_MB_2U(SCH_1):H_CPU1_MEMTRIP_LVC1_N    I33 @S9S_MB_2U_LIB.S9S_MB_2U(SCH_1):PAGE311
    R3     NC     NC    I33 @S9S_MB_2U_LIB.S9S_MB_2U(SCH_1):PAGE311
    R4     NC     NC    I33 @S9S_MB_2U_LIB.S9S_MB_2U(SCH_1):PAGE311
    R5     NC     NC    I33 @S9S_MB_2U_LIB.S9S_MB_2U(SCH_1):PAGE311
    P7 H_CPU1_THERMTRIP_LVC1_N @S9S_MB_2U_LIB.S9S_MB_2U(SCH_1):H_CPU1_THERMTRIP_LVC1_N    I33 @S9S_MB_2U_LIB.S9S_MB_2U(SCH_1):PAGE311
    R6 H_CPU0_MEMTRIP_LVC1_N @S9S_MB_2U_LIB.S9S_MB_2U(SCH_1):H_CPU0_MEMTRIP_LVC1_N    I33 @S9S_MB_2U_LIB.S9S_MB_2U(SCH_1):PAGE311
    R7 H_CPU1_MEMHOT_OUT_LVC1_N @S9S_MB_2U_LIB.S9S_MB_2U(SCH_1):H_CPU1_MEMHOT_OUT_LVC1_N    I33 @S9S_MB_2U_LIB.S9S_MB_2U(SCH_1):PAGE311
    T3 H_CPU0_MEMHOT_OUT_LVC1_N @S9S_MB_2U_LIB.S9S_MB_2U(SCH_1):H_CPU0_MEMHOT_OUT_LVC1_N    I33 @S9S_MB_2U_LIB.S9S_MB_2U(SCH_1):PAGE311
    T4 H_CPU_ERR2_LVC2_N @S9S_MB_2U_LIB.S9S_MB_2U(SCH_1):H_CPU_ERR2_LVC2_N    I33 @S9S_MB_2U_LIB.S9S_MB_2U(SCH_1):PAGE311
    M1     NC     NC    I33 @S9S_MB_2U_LIB.S9S_MB_2U(SCH_1):PAGE311
    N1     NC     NC    I33 @S9S_MB_2U_LIB.S9S_MB_2U(SCH_1):PAGE311
    M6     NC     NC    I33 @S9S_MB_2U_LIB.S9S_MB_2U(SCH_1):PAGE311
    M5     NC     NC    I33 @S9S_MB_2U_LIB.S9S_MB_2U(SCH_1):PAGE311
    N2     NC     NC    I33 @S9S_MB_2U_LIB.S9S_MB_2U(SCH_1):PAGE311
    P1     NC     NC    I33 @S9S_MB_2U_LIB.S9S_MB_2U(SCH_1):PAGE311
    N3     NC     NC    I33 @S9S_MB_2U_LIB.S9S_MB_2U(SCH_1):PAGE311
    N4     NC     NC    I33 @S9S_MB_2U_LIB.S9S_MB_2U(SCH_1):PAGE311
    P2     NC     NC    I33 @S9S_MB_2U_LIB.S9S_MB_2U(SCH_1):PAGE311
    R1     NC     NC    I33 @S9S_MB_2U_LIB.S9S_MB_2U(SCH_1):PAGE311
    P3     NC     NC    I33 @S9S_MB_2U_LIB.S9S_MB_2U(SCH_1):PAGE311
    M7     NC     NC    I33 @S9S_MB_2U_LIB.S9S_MB_2U(SCH_1):PAGE311
    U2     NC     NC    I33 @S9S_MB_2U_LIB.S9S_MB_2U(SCH_1):PAGE311
    V1     NC     NC    I33 @S9S_MB_2U_LIB.S9S_MB_2U(SCH_1):PAGE311
    U3     NC     NC    I33 @S9S_MB_2U_LIB.S9S_MB_2U(SCH_1):PAGE311
    U4     NC     NC    I33 @S9S_MB_2U_LIB.S9S_MB_2U(SCH_1):PAGE311
    W1 PWRGD_CPU1_LVC1_R @S9S_MB_2U_LIB.S9S_MB_2U(SCH_1):PWRGD_CPU1_LVC1_R    I33 @S9S_MB_2U_LIB.S9S_MB_2U(SCH_1):PAGE311
    W2 PWRGD_CPU0_LVC1_R @S9S_MB_2U_LIB.S9S_MB_2U(SCH_1):PWRGD_CPU0_LVC1_R    I33 @S9S_MB_2U_LIB.S9S_MB_2U(SCH_1):PAGE311
    V4 RST_CPU1_LVC1_R_N @S9S_MB_2U_LIB.S9S_MB_2U(SCH_1):RST_CPU1_LVC1_R_N    I33 @S9S_MB_2U_LIB.S9S_MB_2U(SCH_1):PAGE311
    U5 RST_CPU0_LVC1_R_N @S9S_MB_2U_LIB.S9S_MB_2U(SCH_1):RST_CPU0_LVC1_R_N    I33 @S9S_MB_2U_LIB.S9S_MB_2U(SCH_1):PAGE311
    Y1 H_CPU_RMCA_LVC2_R2_N @S9S_MB_2U_LIB.S9S_MB_2U(SCH_1):H_CPU_RMCA_LVC2_R2_N    I33 @S9S_MB_2U_LIB.S9S_MB_2U(SCH_1):PAGE311
   AA1 H_CPU_NMI_LVC1_R_N @S9S_MB_2U_LIB.S9S_MB_2U(SCH_1):H_CPU_NMI_LVC1_R_N    I33 @S9S_MB_2U_LIB.S9S_MB_2U(SCH_1):PAGE311
    W3 FM_THERMTRIP_DLY_LVC1_R_N @S9S_MB_2U_LIB.S9S_MB_2U(SCH_1):FM_THERMTRIP_DLY_LVC1_R_N    I33 @S9S_MB_2U_LIB.S9S_MB_2U(SCH_1):PAGE311
    Y2 H_CPU_CATERR_LVC2_R2_N @S9S_MB_2U_LIB.S9S_MB_2U(SCH_1):H_CPU_CATERR_LVC2_R2_N    I33 @S9S_MB_2U_LIB.S9S_MB_2U(SCH_1):PAGE311
    Y3 H_CPU1_PROCHOT_LVC1_R_N @S9S_MB_2U_LIB.S9S_MB_2U(SCH_1):H_CPU1_PROCHOT_LVC1_R_N    I33 @S9S_MB_2U_LIB.S9S_MB_2U(SCH_1):PAGE311
    W4 H_CPU0_PROCHOT_LVC1_R_N @S9S_MB_2U_LIB.S9S_MB_2U(SCH_1):H_CPU0_PROCHOT_LVC1_R_N    I33 @S9S_MB_2U_LIB.S9S_MB_2U(SCH_1):PAGE311
    V5 H_CPU1_MEMHOT_IN_LVC1_R_N @S9S_MB_2U_LIB.S9S_MB_2U(SCH_1):H_CPU1_MEMHOT_IN_LVC1_R_N    I33 @S9S_MB_2U_LIB.S9S_MB_2U(SCH_1):PAGE311
    T7 H_CPU0_MEMHOT_IN_LVC1_R_N @S9S_MB_2U_LIB.S9S_MB_2U(SCH_1):H_CPU0_MEMHOT_IN_LVC1_R_N    I33 @S9S_MB_2U_LIB.S9S_MB_2U(SCH_1):PAGE311
    G2 PWRGD_DRAMPWRGD_CPU0_AB_R_LVC1 @S9S_MB_2U_LIB.S9S_MB_2U(SCH_1):PWRGD_DRAMPWRGD_CPU0_AB_R_LVC1    I33 @S9S_MB_2U_LIB.S9S_MB_2U(SCH_1):PAGE311
    G1 PWRGD_DRAMPWRGD_CPU0_CD_R_LVC1 @S9S_MB_2U_LIB.S9S_MB_2U(SCH_1):PWRGD_DRAMPWRGD_CPU0_CD_R_LVC1    I33 @S9S_MB_2U_LIB.S9S_MB_2U(SCH_1):PAGE311
    H4 PWRGD_DRAMPWRGD_CPU0_EF_R_LVC1 @S9S_MB_2U_LIB.S9S_MB_2U(SCH_1):PWRGD_DRAMPWRGD_CPU0_EF_R_LVC1    I33 @S9S_MB_2U_LIB.S9S_MB_2U(SCH_1):PAGE311
    H3 PWRGD_DRAMPWRGD_CPU0_GH_R_LVC1 @S9S_MB_2U_LIB.S9S_MB_2U(SCH_1):PWRGD_DRAMPWRGD_CPU0_GH_R_LVC1    I33 @S9S_MB_2U_LIB.S9S_MB_2U(SCH_1):PAGE311
    H2 PWRGD_DRAMPWRGD_CPU1_AB_R_LVC1 @S9S_MB_2U_LIB.S9S_MB_2U(SCH_1):PWRGD_DRAMPWRGD_CPU1_AB_R_LVC1    I33 @S9S_MB_2U_LIB.S9S_MB_2U(SCH_1):PAGE311
    H1 PWRGD_DRAMPWRGD_CPU1_CD_R_LVC1 @S9S_MB_2U_LIB.S9S_MB_2U(SCH_1):PWRGD_DRAMPWRGD_CPU1_CD_R_LVC1    I33 @S9S_MB_2U_LIB.S9S_MB_2U(SCH_1):PAGE311
    J7 PWRGD_DRAMPWRGD_CPU1_EF_R_LVC1 @S9S_MB_2U_LIB.S9S_MB_2U(SCH_1):PWRGD_DRAMPWRGD_CPU1_EF_R_LVC1    I33 @S9S_MB_2U_LIB.S9S_MB_2U(SCH_1):PAGE311
    J6 PWRGD_DRAMPWRGD_CPU1_GH_R_LVC1 @S9S_MB_2U_LIB.S9S_MB_2U(SCH_1):PWRGD_DRAMPWRGD_CPU1_GH_R_LVC1    I33 @S9S_MB_2U_LIB.S9S_MB_2U(SCH_1):PAGE311
    H5 FM_BOARD_BMC_SKU_ID4 @S9S_MB_2U_LIB.S9S_MB_2U(SCH_1):FM_BOARD_BMC_SKU_ID4    I33 @S9S_MB_2U_LIB.S9S_MB_2U(SCH_1):PAGE311
    J5 FM_BOARD_BMC_SKU_ID3 @S9S_MB_2U_LIB.S9S_MB_2U(SCH_1):FM_BOARD_BMC_SKU_ID3    I33 @S9S_MB_2U_LIB.S9S_MB_2U(SCH_1):PAGE311
    J4 FM_BOARD_BMC_SKU_ID2 @S9S_MB_2U_LIB.S9S_MB_2U(SCH_1):FM_BOARD_BMC_SKU_ID2    I33 @S9S_MB_2U_LIB.S9S_MB_2U(SCH_1):PAGE311
    J3 FM_BOARD_BMC_SKU_ID1 @S9S_MB_2U_LIB.S9S_MB_2U(SCH_1):FM_BOARD_BMC_SKU_ID1    I33 @S9S_MB_2U_LIB.S9S_MB_2U(SCH_1):PAGE311
    J2 FM_BOARD_BMC_SKU_ID0 @S9S_MB_2U_LIB.S9S_MB_2U(SCH_1):FM_BOARD_BMC_SKU_ID0    I33 @S9S_MB_2U_LIB.S9S_MB_2U(SCH_1):PAGE311
    J1 FAB_BMC_REV_ID2 @S9S_MB_2U_LIB.S9S_MB_2U(SCH_1):FAB_BMC_REV_ID2    I33 @S9S_MB_2U_LIB.S9S_MB_2U(SCH_1):PAGE311
    K7 FAB_BMC_REV_ID1 @S9S_MB_2U_LIB.S9S_MB_2U(SCH_1):FAB_BMC_REV_ID1    I33 @S9S_MB_2U_LIB.S9S_MB_2U(SCH_1):PAGE311
    K6 FAB_BMC_REV_ID0 @S9S_MB_2U_LIB.S9S_MB_2U(SCH_1):FAB_BMC_REV_ID0    I33 @S9S_MB_2U_LIB.S9S_MB_2U(SCH_1):PAGE311
   AA2 FM_ADR_ACK_R @S9S_MB_2U_LIB.S9S_MB_2U(SCH_1):FM_ADR_ACK_R     I1 @S9S_MB_2U_LIB.S9S_MB_2U(SCH_1):PAGE312
   AB2 FM_UV_ADR_TRIGGER_R_N @S9S_MB_2U_LIB.S9S_MB_2U(SCH_1):FM_UV_ADR_TRIGGER_R_N     I1 @S9S_MB_2U_LIB.S9S_MB_2U(SCH_1):PAGE312
    V6 FM_ADR_TRIGGER_N @S9S_MB_2U_LIB.S9S_MB_2U(SCH_1):FM_ADR_TRIGGER_N     I1 @S9S_MB_2U_LIB.S9S_MB_2U(SCH_1):PAGE312
    U6 FM_ADR_COMPLETE @S9S_MB_2U_LIB.S9S_MB_2U(SCH_1):FM_ADR_COMPLETE     I1 @S9S_MB_2U_LIB.S9S_MB_2U(SCH_1):PAGE312
   AA3 FM_ADR_MODE0_R @S9S_MB_2U_LIB.S9S_MB_2U(SCH_1):FM_ADR_MODE0_R     I1 @S9S_MB_2U_LIB.S9S_MB_2U(SCH_1):PAGE312
   AB3 FM_ADR_MODE1_R @S9S_MB_2U_LIB.S9S_MB_2U(SCH_1):FM_ADR_MODE1_R     I1 @S9S_MB_2U_LIB.S9S_MB_2U(SCH_1):PAGE312
    Y4 IRQ_UV_DETECT_R_N @S9S_MB_2U_LIB.S9S_MB_2U(SCH_1):IRQ_UV_DETECT_R_N     I1 @S9S_MB_2U_LIB.S9S_MB_2U(SCH_1):PAGE312
    W5 NC_FPGA_PB7D @S9S_MB_2U_LIB.S9S_MB_2U(SCH_1):NC_FPGA_PB7D     I1 @S9S_MB_2U_LIB.S9S_MB_2U(SCH_1):PAGE312
    U7 FM_PLD_CLKS_DEV_R_EN @S9S_MB_2U_LIB.S9S_MB_2U(SCH_1):FM_PLD_CLKS_DEV_R_EN     I1 @S9S_MB_2U_LIB.S9S_MB_2U(SCH_1):PAGE312
    T8 FM_PLD_CLK_25M_R_EN @S9S_MB_2U_LIB.S9S_MB_2U(SCH_1):FM_PLD_CLK_25M_R_EN     I1 @S9S_MB_2U_LIB.S9S_MB_2U(SCH_1):PAGE312
   AA4 IRQ_PVCCD_CPU0_VRHOT_LVC3_N @S9S_MB_2U_LIB.S9S_MB_2U(SCH_1):IRQ_PVCCD_CPU0_VRHOT_LVC3_N     I1 @S9S_MB_2U_LIB.S9S_MB_2U(SCH_1):PAGE312
   AB4 IRQ_BMC_PCH_NMI_R @S9S_MB_2U_LIB.S9S_MB_2U(SCH_1):IRQ_BMC_PCH_NMI_R     I1 @S9S_MB_2U_LIB.S9S_MB_2U(SCH_1):PAGE312
   AA5 PWRGD_PLT_AUX_CPU0_LVT3_R @S9S_MB_2U_LIB.S9S_MB_2U(SCH_1):PWRGD_PLT_AUX_CPU0_LVT3_R     I1 @S9S_MB_2U_LIB.S9S_MB_2U(SCH_1):PAGE312
   AB5 PWRGD_PLT_AUX_CPU1_LVT3_R @S9S_MB_2U_LIB.S9S_MB_2U(SCH_1):PWRGD_PLT_AUX_CPU1_LVT3_R     I1 @S9S_MB_2U_LIB.S9S_MB_2U(SCH_1):PAGE312
    Y5 PCIE_M2_SSD0_PRSNT_N @S9S_MB_2U_LIB.S9S_MB_2U(SCH_1):PCIE_M2_SSD0_PRSNT_N     I1 @S9S_MB_2U_LIB.S9S_MB_2U(SCH_1):PAGE312
    Y6 FM_HBM2_HBM3_VPP_SEL @S9S_MB_2U_LIB.S9S_MB_2U(SCH_1):FM_HBM2_HBM3_VPP_SEL     I1 @S9S_MB_2U_LIB.S9S_MB_2U(SCH_1):PAGE312
    V8 FM_REMOTE_DEBUG_DET @S9S_MB_2U_LIB.S9S_MB_2U(SCH_1):FM_REMOTE_DEBUG_DET     I1 @S9S_MB_2U_LIB.S9S_MB_2U(SCH_1):PAGE312
    U8 FM_BMC_DBP_PRESENT_R_N @S9S_MB_2U_LIB.S9S_MB_2U(SCH_1):FM_BMC_DBP_PRESENT_R_N     I1 @S9S_MB_2U_LIB.S9S_MB_2U(SCH_1):PAGE312
    T9 FM_BIOS_POST_CMPLT_BMC_N @S9S_MB_2U_LIB.S9S_MB_2U(SCH_1):FM_BIOS_POST_CMPLT_BMC_N     I1 @S9S_MB_2U_LIB.S9S_MB_2U(SCH_1):PAGE312
    U9 FM_BMC_RSTBTN_OUT_N @S9S_MB_2U_LIB.S9S_MB_2U(SCH_1):FM_BMC_RSTBTN_OUT_N     I1 @S9S_MB_2U_LIB.S9S_MB_2U(SCH_1):PAGE312
   AA8 FM_CPU_RMCA_CATERR_LVT3_R_N @S9S_MB_2U_LIB.S9S_MB_2U(SCH_1):FM_CPU_RMCA_CATERR_LVT3_R_N     I1 @S9S_MB_2U_LIB.S9S_MB_2U(SCH_1):PAGE312
   AB8 FM_PCH_BMC_THERMTRIP_N @S9S_MB_2U_LIB.S9S_MB_2U(SCH_1):FM_PCH_BMC_THERMTRIP_N     I1 @S9S_MB_2U_LIB.S9S_MB_2U(SCH_1):PAGE312
   V10 E1S_0_PRSNT_N @S9S_MB_2U_LIB.S9S_MB_2U(SCH_1):E1S_0_PRSNT_N     I1 @S9S_MB_2U_LIB.S9S_MB_2U(SCH_1):PAGE312
   W10 HSC_D_OC_R1 @S9S_MB_2U_LIB.S9S_MB_2U(SCH_1):HSC_D_OC_R1     I1 @S9S_MB_2U_LIB.S9S_MB_2U(SCH_1):PAGE312
  AA10 CLK_25M_OSC_MAIN_FPGA @S9S_MB_2U_LIB.S9S_MB_2U(SCH_1):CLK_25M_OSC_MAIN_FPGA     I1 @S9S_MB_2U_LIB.S9S_MB_2U(SCH_1):PAGE312
  AB10 NC_FPGA_PB22B @S9S_MB_2U_LIB.S9S_MB_2U(SCH_1):NC_FPGA_PB22B     I1 @S9S_MB_2U_LIB.S9S_MB_2U(SCH_1):PAGE312
  AA11 PRSNT_CABLE_GPU_B3_ISO_R_N @S9S_MB_2U_LIB.S9S_MB_2U(SCH_1):PRSNT_CABLE_GPU_B3_ISO_R_N     I1 @S9S_MB_2U_LIB.S9S_MB_2U(SCH_1):PAGE312
  AB11 GPU_3V3IO_RSVD3_FFU_ISO_R @S9S_MB_2U_LIB.S9S_MB_2U(SCH_1):GPU_3V3IO_RSVD3_FFU_ISO_R     I1 @S9S_MB_2U_LIB.S9S_MB_2U(SCH_1):PAGE312
   V11 PRSNT_CABLE_GPU_A2_ISO_R_N @S9S_MB_2U_LIB.S9S_MB_2U(SCH_1):PRSNT_CABLE_GPU_A2_ISO_R_N     I1 @S9S_MB_2U_LIB.S9S_MB_2U(SCH_1):PAGE312
   Y11 GPU_3V3IO_RSVD5_FFU_ISO_R @S9S_MB_2U_LIB.S9S_MB_2U(SCH_1):GPU_3V3IO_RSVD5_FFU_ISO_R     I1 @S9S_MB_2U_LIB.S9S_MB_2U(SCH_1):PAGE312
  AB12 IRQ_SGPIO_INTR_N_R @S9S_MB_2U_LIB.S9S_MB_2U(SCH_1):IRQ_SGPIO_INTR_N_R     I1 @S9S_MB_2U_LIB.S9S_MB_2U(SCH_1):PAGE312
  AA12 IRQ_PSYS_CRIT_N @S9S_MB_2U_LIB.S9S_MB_2U(SCH_1):IRQ_PSYS_CRIT_N     I1 @S9S_MB_2U_LIB.S9S_MB_2U(SCH_1):PAGE312
  AB13 IRQ_TPM_SPI_N @S9S_MB_2U_LIB.S9S_MB_2U(SCH_1):IRQ_TPM_SPI_N     I1 @S9S_MB_2U_LIB.S9S_MB_2U(SCH_1):PAGE312
  AA13 IRQ_PVCCD_CPU1_VRHOT_LVC3_N @S9S_MB_2U_LIB.S9S_MB_2U(SCH_1):IRQ_PVCCD_CPU1_VRHOT_LVC3_N     I1 @S9S_MB_2U_LIB.S9S_MB_2U(SCH_1):PAGE312
  AB14 RST_PLTRST_PLD_B_N @S9S_MB_2U_LIB.S9S_MB_2U(SCH_1):RST_PLTRST_PLD_B_N     I1 @S9S_MB_2U_LIB.S9S_MB_2U(SCH_1):PAGE312
  AA14 FM_SYS_THROTTLE_R_N @S9S_MB_2U_LIB.S9S_MB_2U(SCH_1):FM_SYS_THROTTLE_R_N     I1 @S9S_MB_2U_LIB.S9S_MB_2U(SCH_1):PAGE312
  AB19 CLK_GEN2_BMC_RC_OE_N @S9S_MB_2U_LIB.S9S_MB_2U(SCH_1):CLK_GEN2_BMC_RC_OE_N     I1 @S9S_MB_2U_LIB.S9S_MB_2U(SCH_1):PAGE312
  AA19 FM_PLD_REV_N @S9S_MB_2U_LIB.S9S_MB_2U(SCH_1):FM_PLD_REV_N     I1 @S9S_MB_2U_LIB.S9S_MB_2U(SCH_1):PAGE312
  AB20 HGX_DETECT_N_R @S9S_MB_2U_LIB.S9S_MB_2U(SCH_1):HGX_DETECT_N_R     I1 @S9S_MB_2U_LIB.S9S_MB_2U(SCH_1):PAGE312
  AA20 HPDB_HSC_PWRGD_ISO_R @S9S_MB_2U_LIB.S9S_MB_2U(SCH_1):HPDB_HSC_PWRGD_ISO_R     I1 @S9S_MB_2U_LIB.S9S_MB_2U(SCH_1):PAGE312
  AB21 PULL_FPGA_PB46A @S9S_MB_2U_LIB.S9S_MB_2U(SCH_1):PULL_FPGA_PB46A     I1 @S9S_MB_2U_LIB.S9S_MB_2U(SCH_1):PAGE312
  AA21 NC_FPGA_PB46B @S9S_MB_2U_LIB.S9S_MB_2U(SCH_1):NC_FPGA_PB46B     I1 @S9S_MB_2U_LIB.S9S_MB_2U(SCH_1):PAGE312
  AB15 FM_SPD_REMOTE_EN_R @S9S_MB_2U_LIB.S9S_MB_2U(SCH_1):FM_SPD_REMOTE_EN_R     I1 @S9S_MB_2U_LIB.S9S_MB_2U(SCH_1):PAGE312
  AA15 NC_FPGA_PB35B @S9S_MB_2U_LIB.S9S_MB_2U(SCH_1):NC_FPGA_PB35B     I1 @S9S_MB_2U_LIB.S9S_MB_2U(SCH_1):PAGE312
   AA6 RST_MB_STBY_R_N @S9S_MB_2U_LIB.S9S_MB_2U(SCH_1):RST_MB_STBY_R_N     I1 @S9S_MB_2U_LIB.S9S_MB_2U(SCH_1):PAGE312
   AB6 RST_SMB_SWITCH_N @S9S_MB_2U_LIB.S9S_MB_2U(SCH_1):RST_SMB_SWITCH_N     I1 @S9S_MB_2U_LIB.S9S_MB_2U(SCH_1):PAGE312
    W6 RST_PFR_OVR_RTC_R @S9S_MB_2U_LIB.S9S_MB_2U(SCH_1):RST_PFR_OVR_RTC_R     I1 @S9S_MB_2U_LIB.S9S_MB_2U(SCH_1):PAGE312
    V7 RST_PFR_OVR_SRTC_R @S9S_MB_2U_LIB.S9S_MB_2U(SCH_1):RST_PFR_OVR_SRTC_R     I1 @S9S_MB_2U_LIB.S9S_MB_2U(SCH_1):PAGE312
   AA7 FM_DIS_PS_PWROK_DLY @S9S_MB_2U_LIB.S9S_MB_2U(SCH_1):FM_DIS_PS_PWROK_DLY     I1 @S9S_MB_2U_LIB.S9S_MB_2U(SCH_1):PAGE312
   AB7 FM_PCH_CRASHLOG_TRIG_R_N @S9S_MB_2U_LIB.S9S_MB_2U(SCH_1):FM_PCH_CRASHLOG_TRIG_R_N     I1 @S9S_MB_2U_LIB.S9S_MB_2U(SCH_1):PAGE312
    V9 FM_PS_PWROK_DLY_SEL @S9S_MB_2U_LIB.S9S_MB_2U(SCH_1):FM_PS_PWROK_DLY_SEL     I1 @S9S_MB_2U_LIB.S9S_MB_2U(SCH_1):PAGE312
    W8 FM_RST_PERST_BIT2 @S9S_MB_2U_LIB.S9S_MB_2U(SCH_1):FM_RST_PERST_BIT2     I1 @S9S_MB_2U_LIB.S9S_MB_2U(SCH_1):PAGE312
    Y8 FM_ME_AUTHN_FAIL @S9S_MB_2U_LIB.S9S_MB_2U(SCH_1):FM_ME_AUTHN_FAIL     I1 @S9S_MB_2U_LIB.S9S_MB_2U(SCH_1):PAGE312
    W9 USB_OC1_REAR_N @S9S_MB_2U_LIB.S9S_MB_2U(SCH_1):USB_OC1_REAR_N     I1 @S9S_MB_2U_LIB.S9S_MB_2U(SCH_1):PAGE312
   AA9 JTAG_DBP_BMC_PRDY_R_N @S9S_MB_2U_LIB.S9S_MB_2U(SCH_1):JTAG_DBP_BMC_PRDY_R_N     I1 @S9S_MB_2U_LIB.S9S_MB_2U(SCH_1):PAGE312
   AB9 FM_DEBUG_PORT_PRSNT_N @S9S_MB_2U_LIB.S9S_MB_2U(SCH_1):FM_DEBUG_PORT_PRSNT_N     I1 @S9S_MB_2U_LIB.S9S_MB_2U(SCH_1):PAGE312
   T10 FM_PLD_HEARTBEAT_LVC3 @S9S_MB_2U_LIB.S9S_MB_2U(SCH_1):FM_PLD_HEARTBEAT_LVC3     I1 @S9S_MB_2U_LIB.S9S_MB_2U(SCH_1):PAGE312
   U10 FM_FORCE_PWRON_LVC3 @S9S_MB_2U_LIB.S9S_MB_2U(SCH_1):FM_FORCE_PWRON_LVC3     I1 @S9S_MB_2U_LIB.S9S_MB_2U(SCH_1):PAGE312
   T11 GPU_3V3IO_RSVD0_FFU_ISO_R @S9S_MB_2U_LIB.S9S_MB_2U(SCH_1):GPU_3V3IO_RSVD0_FFU_ISO_R     I1 @S9S_MB_2U_LIB.S9S_MB_2U(SCH_1):PAGE312
   U11 GPU_3V3IO_RSVD1_FFU_ISO_R @S9S_MB_2U_LIB.S9S_MB_2U(SCH_1):GPU_3V3IO_RSVD1_FFU_ISO_R     I1 @S9S_MB_2U_LIB.S9S_MB_2U(SCH_1):PAGE312
   Y12 PRSNT_CABLE_GPU_A1_ISO_R_N @S9S_MB_2U_LIB.S9S_MB_2U(SCH_1):PRSNT_CABLE_GPU_A1_ISO_R_N     I1 @S9S_MB_2U_LIB.S9S_MB_2U(SCH_1):PAGE312
   T12 GPU_3V3IO_RSVD1_ISO_R @S9S_MB_2U_LIB.S9S_MB_2U(SCH_1):GPU_3V3IO_RSVD1_ISO_R     I1 @S9S_MB_2U_LIB.S9S_MB_2U(SCH_1):PAGE312
   U12 GPU_3V3IO_RSVD3_ISO_R @S9S_MB_2U_LIB.S9S_MB_2U(SCH_1):GPU_3V3IO_RSVD3_ISO_R     I1 @S9S_MB_2U_LIB.S9S_MB_2U(SCH_1):PAGE312
   V12 GPU_3V3IO_RSVD4_ISO_R @S9S_MB_2U_LIB.S9S_MB_2U(SCH_1):GPU_3V3IO_RSVD4_ISO_R     I1 @S9S_MB_2U_LIB.S9S_MB_2U(SCH_1):PAGE312
   V13 IRQ_PCH_CPU_NMI_EVENT_N @S9S_MB_2U_LIB.S9S_MB_2U(SCH_1):IRQ_PCH_CPU_NMI_EVENT_N     I1 @S9S_MB_2U_LIB.S9S_MB_2U(SCH_1):PAGE312
   U13 IRQ_BMC_CPU_NMI_R1 @S9S_MB_2U_LIB.S9S_MB_2U(SCH_1):IRQ_BMC_CPU_NMI_R1     I1 @S9S_MB_2U_LIB.S9S_MB_2U(SCH_1):PAGE312
   Y13 IRQ_PSU_ALERT_R_N @S9S_MB_2U_LIB.S9S_MB_2U(SCH_1):IRQ_PSU_ALERT_R_N     I1 @S9S_MB_2U_LIB.S9S_MB_2U(SCH_1):PAGE312
   W13 IRQ_PCH_SCI_WHEA_R_N @S9S_MB_2U_LIB.S9S_MB_2U(SCH_1):IRQ_PCH_SCI_WHEA_R_N     I1 @S9S_MB_2U_LIB.S9S_MB_2U(SCH_1):PAGE312
   Y14 FM_NCSI_OCP_V3_1_R_OE @S9S_MB_2U_LIB.S9S_MB_2U(SCH_1):FM_NCSI_OCP_V3_1_R_OE     I1 @S9S_MB_2U_LIB.S9S_MB_2U(SCH_1):PAGE312
   W14 FM_BIOS_DEBUG_EN_N @S9S_MB_2U_LIB.S9S_MB_2U(SCH_1):FM_BIOS_DEBUG_EN_N     I1 @S9S_MB_2U_LIB.S9S_MB_2U(SCH_1):PAGE312
   T13 RST_SGPIO_RESET_N_R @S9S_MB_2U_LIB.S9S_MB_2U(SCH_1):RST_SGPIO_RESET_N_R     I1 @S9S_MB_2U_LIB.S9S_MB_2U(SCH_1):PAGE312
   T14 FM_ME_BT_DONE @S9S_MB_2U_LIB.S9S_MB_2U(SCH_1):FM_ME_BT_DONE     I1 @S9S_MB_2U_LIB.S9S_MB_2U(SCH_1):PAGE312
   U14 RST_PCIE_PCH_DEV_PERST_N @S9S_MB_2U_LIB.S9S_MB_2U(SCH_1):RST_PCIE_PCH_DEV_PERST_N     I1 @S9S_MB_2U_LIB.S9S_MB_2U(SCH_1):PAGE312
   V14 NC_FPGA_PB32D @S9S_MB_2U_LIB.S9S_MB_2U(SCH_1):NC_FPGA_PB32D     I1 @S9S_MB_2U_LIB.S9S_MB_2U(SCH_1):PAGE312
   Y15 FM_THROTTLE_R_N @S9S_MB_2U_LIB.S9S_MB_2U(SCH_1):FM_THROTTLE_R_N     I1 @S9S_MB_2U_LIB.S9S_MB_2U(SCH_1):PAGE312
   W15 FM_DIMM_12V_CPS_SX_N @S9S_MB_2U_LIB.S9S_MB_2U(SCH_1):FM_DIMM_12V_CPS_SX_N     I1 @S9S_MB_2U_LIB.S9S_MB_2U(SCH_1):PAGE312
  AB16 VIRTUAL_RESEAT @S9S_MB_2U_LIB.S9S_MB_2U(SCH_1):VIRTUAL_RESEAT     I1 @S9S_MB_2U_LIB.S9S_MB_2U(SCH_1):PAGE312
  AA16 FM_PCH_PLD_GLB_RST_WARN_N @S9S_MB_2U_LIB.S9S_MB_2U(SCH_1):FM_PCH_PLD_GLB_RST_WARN_N     I1 @S9S_MB_2U_LIB.S9S_MB_2U(SCH_1):PAGE312
   V15 ROT_P1_RST_IND_N_R @S9S_MB_2U_LIB.S9S_MB_2U(SCH_1):ROT_P1_RST_IND_N_R     I1 @S9S_MB_2U_LIB.S9S_MB_2U(SCH_1):PAGE312
   U15 FM_SLPS3_PLD_N @S9S_MB_2U_LIB.S9S_MB_2U(SCH_1):FM_SLPS3_PLD_N     I1 @S9S_MB_2U_LIB.S9S_MB_2U(SCH_1):PAGE312
  AB17 FM_PCHHOT_R_N @S9S_MB_2U_LIB.S9S_MB_2U(SCH_1):FM_PCHHOT_R_N     I1 @S9S_MB_2U_LIB.S9S_MB_2U(SCH_1):PAGE312
  AA17 FM_BMC_READY_R_PLD_N @S9S_MB_2U_LIB.S9S_MB_2U(SCH_1):FM_BMC_READY_R_PLD_N     I1 @S9S_MB_2U_LIB.S9S_MB_2U(SCH_1):PAGE312
   Y17 RST_PLTRST_PLD_N @S9S_MB_2U_LIB.S9S_MB_2U(SCH_1):RST_PLTRST_PLD_N     I1 @S9S_MB_2U_LIB.S9S_MB_2U(SCH_1):PAGE312
   V16 RST_RSMRST_PLD_R_N @S9S_MB_2U_LIB.S9S_MB_2U(SCH_1):RST_RSMRST_PLD_R_N     I1 @S9S_MB_2U_LIB.S9S_MB_2U(SCH_1):PAGE312
  AB18 JTAG_DBP_BMC_PREQ_R_N @S9S_MB_2U_LIB.S9S_MB_2U(SCH_1):JTAG_DBP_BMC_PREQ_R_N     I1 @S9S_MB_2U_LIB.S9S_MB_2U(SCH_1):PAGE312
  AA18 CLK_GPU_1_OE_N @S9S_MB_2U_LIB.S9S_MB_2U(SCH_1):CLK_GPU_1_OE_N     I1 @S9S_MB_2U_LIB.S9S_MB_2U(SCH_1):PAGE312
   Y18 CLK_GPU_2_OE_N @S9S_MB_2U_LIB.S9S_MB_2U(SCH_1):CLK_GPU_2_OE_N     I1 @S9S_MB_2U_LIB.S9S_MB_2U(SCH_1):PAGE312
   W17 CLK_SWB_OE_N @S9S_MB_2U_LIB.S9S_MB_2U(SCH_1):CLK_SWB_OE_N     I1 @S9S_MB_2U_LIB.S9S_MB_2U(SCH_1):PAGE312
   T15 CLK_SWB_BUF2_OE_N @S9S_MB_2U_LIB.S9S_MB_2U(SCH_1):CLK_SWB_BUF2_OE_N     I1 @S9S_MB_2U_LIB.S9S_MB_2U(SCH_1):PAGE312
   U16 NC_FPGA_PB43D @S9S_MB_2U_LIB.S9S_MB_2U(SCH_1):NC_FPGA_PB43D     I1 @S9S_MB_2U_LIB.S9S_MB_2U(SCH_1):PAGE312
   Y19 SWB_HSC_EN_R @S9S_MB_2U_LIB.S9S_MB_2U(SCH_1):SWB_HSC_EN_R     I1 @S9S_MB_2U_LIB.S9S_MB_2U(SCH_1):PAGE312
   W18 SWB_HSC_PWRGD_ISO_R @S9S_MB_2U_LIB.S9S_MB_2U(SCH_1):SWB_HSC_PWRGD_ISO_R     I1 @S9S_MB_2U_LIB.S9S_MB_2U(SCH_1):PAGE312
   V17 FM_PDB_BUF_EN @S9S_MB_2U_LIB.S9S_MB_2U(SCH_1):FM_PDB_BUF_EN     I1 @S9S_MB_2U_LIB.S9S_MB_2U(SCH_1):PAGE312
   T16 FM_AC_PWR_BTN_PLD_ISO_N @S9S_MB_2U_LIB.S9S_MB_2U(SCH_1):FM_AC_PWR_BTN_PLD_ISO_N     I1 @S9S_MB_2U_LIB.S9S_MB_2U(SCH_1):PAGE312
    Y9 PRSNT_SWB_ISO_R_N @S9S_MB_2U_LIB.S9S_MB_2U(SCH_1):PRSNT_SWB_ISO_R_N     I1 @S9S_MB_2U_LIB.S9S_MB_2U(SCH_1):PAGE312
   Y10 FM_PCH_BMC_RST_N @S9S_MB_2U_LIB.S9S_MB_2U(SCH_1):FM_PCH_BMC_RST_N     I1 @S9S_MB_2U_LIB.S9S_MB_2U(SCH_1):PAGE312
   B21 NC_FPGA_PT43B @S9S_MB_2U_LIB.S9S_MB_2U(SCH_1):NC_FPGA_PT43B   I188 @S9S_MB_2U_LIB.S9S_MB_2U(SCH_1):PAGE314
   A20 NC_FPGA_PT43A @S9S_MB_2U_LIB.S9S_MB_2U(SCH_1):NC_FPGA_PT43A   I188 @S9S_MB_2U_LIB.S9S_MB_2U(SCH_1):PAGE314
   B19 PU_MAIN_FPGA_CONFIG_DONE @S9S_MB_2U_LIB.S9S_MB_2U(SCH_1):PU_MAIN_FPGA_CONFIG_DONE   I188 @S9S_MB_2U_LIB.S9S_MB_2U(SCH_1):PAGE314
   A18 GPU_FPGA_READY_ISO_R @S9S_MB_2U_LIB.S9S_MB_2U(SCH_1):GPU_FPGA_READY_ISO_R   I188 @S9S_MB_2U_LIB.S9S_MB_2U(SCH_1):PAGE314
   F14 SGPIO_BMC_LD_N @S9S_MB_2U_LIB.S9S_MB_2U(SCH_1):SGPIO_BMC_LD_N   I188 @S9S_MB_2U_LIB.S9S_MB_2U(SCH_1):PAGE314
   G14 SGPIO_BMC_DIN_R @S9S_MB_2U_LIB.S9S_MB_2U(SCH_1):SGPIO_BMC_DIN_R   I188 @S9S_MB_2U_LIB.S9S_MB_2U(SCH_1):PAGE314
   F12 PWRGD_PVCCD_HV_CPU0 @S9S_MB_2U_LIB.S9S_MB_2U(SCH_1):PWRGD_PVCCD_HV_CPU0   I188 @S9S_MB_2U_LIB.S9S_MB_2U(SCH_1):PAGE314
   G12 PWRGD_P3V3_AUX_PLD @S9S_MB_2U_LIB.S9S_MB_2U(SCH_1):PWRGD_P3V3_AUX_PLD   I188 @S9S_MB_2U_LIB.S9S_MB_2U(SCH_1):PAGE314
   A12 SMB_1_PLD_3V3AUX_SDA_R1 @S9S_MB_2U_LIB.S9S_MB_2U(SCH_1):SMB_1_PLD_3V3AUX_SDA_R1   I188 @S9S_MB_2U_LIB.S9S_MB_2U(SCH_1):PAGE314
   B12 SMB_1_PLD_3V3AUX_SCL_R1 @S9S_MB_2U_LIB.S9S_MB_2U(SCH_1):SMB_1_PLD_3V3AUX_SCL_R1   I188 @S9S_MB_2U_LIB.S9S_MB_2U(SCH_1):PAGE314
   B22 NC_FPGA_PT44B @S9S_MB_2U_LIB.S9S_MB_2U(SCH_1):NC_FPGA_PT44B   I188 @S9S_MB_2U_LIB.S9S_MB_2U(SCH_1):PAGE314
   A21 NC_FPGA_PT44A @S9S_MB_2U_LIB.S9S_MB_2U(SCH_1):NC_FPGA_PT44A   I188 @S9S_MB_2U_LIB.S9S_MB_2U(SCH_1):PAGE314
   A10 SMB_HOST_3V3AUX_PLD_SCL @S9S_MB_2U_LIB.S9S_MB_2U(SCH_1):SMB_HOST_3V3AUX_PLD_SCL   I188 @S9S_MB_2U_LIB.S9S_MB_2U(SCH_1):PAGE314
   B10 SMB_HOST_3V3AUX_PLD_SDA @S9S_MB_2U_LIB.S9S_MB_2U(SCH_1):SMB_HOST_3V3AUX_PLD_SDA   I188 @S9S_MB_2U_LIB.S9S_MB_2U(SCH_1):PAGE314
    D8 IRQ_SML1_PMBUS_BMC_ALERT_N @S9S_MB_2U_LIB.S9S_MB_2U(SCH_1):IRQ_SML1_PMBUS_BMC_ALERT_N   I188 @S9S_MB_2U_LIB.S9S_MB_2U(SCH_1):PAGE314
    F7 FM_GPU_PWRGD_ISO_R @S9S_MB_2U_LIB.S9S_MB_2U(SCH_1):FM_GPU_PWRGD_ISO_R   I188 @S9S_MB_2U_LIB.S9S_MB_2U(SCH_1):PAGE314
    A2 FM_GPU_PWR_EN @S9S_MB_2U_LIB.S9S_MB_2U(SCH_1):FM_GPU_PWR_EN   I188 @S9S_MB_2U_LIB.S9S_MB_2U(SCH_1):PAGE314
    E6 FM_SWB_PWRGD_ISO_R @S9S_MB_2U_LIB.S9S_MB_2U(SCH_1):FM_SWB_PWRGD_ISO_R   I188 @S9S_MB_2U_LIB.S9S_MB_2U(SCH_1):PAGE314
    B1 FM_SWB_PWR_EN @S9S_MB_2U_LIB.S9S_MB_2U(SCH_1):FM_SWB_PWR_EN   I188 @S9S_MB_2U_LIB.S9S_MB_2U(SCH_1):PAGE314
    C8 OCP_SFF_CLK_OE_R_N @S9S_MB_2U_LIB.S9S_MB_2U(SCH_1):OCP_SFF_CLK_OE_R_N   I188 @S9S_MB_2U_LIB.S9S_MB_2U(SCH_1):PAGE314
    B3 FM_SWB_BIC_READY_ISO_R_N @S9S_MB_2U_LIB.S9S_MB_2U(SCH_1):FM_SWB_BIC_READY_ISO_R_N   I188 @S9S_MB_2U_LIB.S9S_MB_2U(SCH_1):PAGE314
    A4 SMB_BMC_SWB_EN @S9S_MB_2U_LIB.S9S_MB_2U(SCH_1):SMB_BMC_SWB_EN   I188 @S9S_MB_2U_LIB.S9S_MB_2U(SCH_1):PAGE314
   F10 GPU_BASE_HMC_READY_ISO_R @S9S_MB_2U_LIB.S9S_MB_2U(SCH_1):GPU_BASE_HMC_READY_ISO_R   I188 @S9S_MB_2U_LIB.S9S_MB_2U(SCH_1):PAGE314
   E10 GPU_HMC_PRSNT_ISO_R_N @S9S_MB_2U_LIB.S9S_MB_2U(SCH_1):GPU_HMC_PRSNT_ISO_R_N   I188 @S9S_MB_2U_LIB.S9S_MB_2U(SCH_1):PAGE314
    F8 RST_BMC_FROM_SWB_ISO_R_N @S9S_MB_2U_LIB.S9S_MB_2U(SCH_1):RST_BMC_FROM_SWB_ISO_R_N   I188 @S9S_MB_2U_LIB.S9S_MB_2U(SCH_1):PAGE314
    G8 SMB_BMC_GPU_EN @S9S_MB_2U_LIB.S9S_MB_2U(SCH_1):SMB_BMC_GPU_EN   I188 @S9S_MB_2U_LIB.S9S_MB_2U(SCH_1):PAGE314
    B2 FM_FAN_PWR_EN @S9S_MB_2U_LIB.S9S_MB_2U(SCH_1):FM_FAN_PWR_EN   I188 @S9S_MB_2U_LIB.S9S_MB_2U(SCH_1):PAGE314
    A3 FM_GPU_HSC_EN_R @S9S_MB_2U_LIB.S9S_MB_2U(SCH_1):FM_GPU_HSC_EN_R   I188 @S9S_MB_2U_LIB.S9S_MB_2U(SCH_1):PAGE314
    C3 BIC_MONITER_ISO_R @S9S_MB_2U_LIB.S9S_MB_2U(SCH_1):BIC_MONITER_ISO_R   I188 @S9S_MB_2U_LIB.S9S_MB_2U(SCH_1):PAGE314
    C4 BMC_MONITER @S9S_MB_2U_LIB.S9S_MB_2U(SCH_1):BMC_MONITER   I188 @S9S_MB_2U_LIB.S9S_MB_2U(SCH_1):PAGE314
    B4 FM_PCH_PRSNT_N @S9S_MB_2U_LIB.S9S_MB_2U(SCH_1):FM_PCH_PRSNT_N   I188 @S9S_MB_2U_LIB.S9S_MB_2U(SCH_1):PAGE314
    A5 FM_TPM_PRSNT_R_N @S9S_MB_2U_LIB.S9S_MB_2U(SCH_1):FM_TPM_PRSNT_R_N   I188 @S9S_MB_2U_LIB.S9S_MB_2U(SCH_1):PAGE314
    D5 VIRTUAL_RESEAT_FPGA_R_N @S9S_MB_2U_LIB.S9S_MB_2U(SCH_1):VIRTUAL_RESEAT_FPGA_R_N   I188 @S9S_MB_2U_LIB.S9S_MB_2U(SCH_1):PAGE314
    C5 FM_BMC_SUSACK_R_N @S9S_MB_2U_LIB.S9S_MB_2U(SCH_1):FM_BMC_SUSACK_R_N   I188 @S9S_MB_2U_LIB.S9S_MB_2U(SCH_1):PAGE314
    B5 IRQ_HSC_FAULT_R1_N @S9S_MB_2U_LIB.S9S_MB_2U(SCH_1):IRQ_HSC_FAULT_R1_N   I188 @S9S_MB_2U_LIB.S9S_MB_2U(SCH_1):PAGE314
    A6 FM_PECI_MUX_SEL_N @S9S_MB_2U_LIB.S9S_MB_2U(SCH_1):FM_PECI_MUX_SEL_N   I188 @S9S_MB_2U_LIB.S9S_MB_2U(SCH_1):PAGE314
    D6 OCP_V3_2_AUX_PWR_PLD_EN @S9S_MB_2U_LIB.S9S_MB_2U(SCH_1):OCP_V3_2_AUX_PWR_PLD_EN   I188 @S9S_MB_2U_LIB.S9S_MB_2U(SCH_1):PAGE314
    E7 OCP_SFF_AUX_PWR_PLD_EN @S9S_MB_2U_LIB.S9S_MB_2U(SCH_1):OCP_SFF_AUX_PWR_PLD_EN   I188 @S9S_MB_2U_LIB.S9S_MB_2U(SCH_1):PAGE314
    B6 FM_OCP_V3_2_PWR_GOOD_R @S9S_MB_2U_LIB.S9S_MB_2U(SCH_1):FM_OCP_V3_2_PWR_GOOD_R   I188 @S9S_MB_2U_LIB.S9S_MB_2U(SCH_1):PAGE314
    A7 FM_OCP_SFF_PWR_GOOD_R @S9S_MB_2U_LIB.S9S_MB_2U(SCH_1):FM_OCP_SFF_PWR_GOOD_R   I188 @S9S_MB_2U_LIB.S9S_MB_2U(SCH_1):PAGE314
    C6 FM_S3M_CPU0_CPLD_CRC_ERROR @S9S_MB_2U_LIB.S9S_MB_2U(SCH_1):FM_S3M_CPU0_CPLD_CRC_ERROR   I188 @S9S_MB_2U_LIB.S9S_MB_2U(SCH_1):PAGE314
    D7 FM_S3M_CPU1_CPLD_CRC_ERROR @S9S_MB_2U_LIB.S9S_MB_2U(SCH_1):FM_S3M_CPU1_CPLD_CRC_ERROR   I188 @S9S_MB_2U_LIB.S9S_MB_2U(SCH_1):PAGE314
    B8 IRQ_SML0_ALERT_R_N @S9S_MB_2U_LIB.S9S_MB_2U(SCH_1):IRQ_SML0_ALERT_R_N   I188 @S9S_MB_2U_LIB.S9S_MB_2U(SCH_1):PAGE314
    A8 IRQ_SML1_PMBUS_PLD_ALERT_N @S9S_MB_2U_LIB.S9S_MB_2U(SCH_1):IRQ_SML1_PMBUS_PLD_ALERT_N   I188 @S9S_MB_2U_LIB.S9S_MB_2U(SCH_1):PAGE314
    C9 FM_SLP_SUS_RSM_RST_N @S9S_MB_2U_LIB.S9S_MB_2U(SCH_1):FM_SLP_SUS_RSM_RST_N   I188 @S9S_MB_2U_LIB.S9S_MB_2U(SCH_1):PAGE314
    D9 PU_RST_DEDI_BUSY_PLD_N @S9S_MB_2U_LIB.S9S_MB_2U(SCH_1):PU_RST_DEDI_BUSY_PLD_N   I188 @S9S_MB_2U_LIB.S9S_MB_2U(SCH_1):PAGE314
    B9 GPU_FPGA_THERM_OVERT_ISO_R_N @S9S_MB_2U_LIB.S9S_MB_2U(SCH_1):GPU_FPGA_THERM_OVERT_ISO_R_N   I188 @S9S_MB_2U_LIB.S9S_MB_2U(SCH_1):PAGE314
    A9 GPU_NVS_PWR_BRAKE_R_N @S9S_MB_2U_LIB.S9S_MB_2U(SCH_1):GPU_NVS_PWR_BRAKE_R_N   I188 @S9S_MB_2U_LIB.S9S_MB_2U(SCH_1):PAGE314
    F9 GPU_FPGA_EROT_RST_R_N @S9S_MB_2U_LIB.S9S_MB_2U(SCH_1):GPU_FPGA_EROT_RST_R_N   I188 @S9S_MB_2U_LIB.S9S_MB_2U(SCH_1):PAGE314
    G9 GPU_BASE_STBY_EN_R @S9S_MB_2U_LIB.S9S_MB_2U(SCH_1):GPU_BASE_STBY_EN_R   I188 @S9S_MB_2U_LIB.S9S_MB_2U(SCH_1):PAGE314
   G11 GPU_FPGA_BOOT_EN_R @S9S_MB_2U_LIB.S9S_MB_2U(SCH_1):GPU_FPGA_BOOT_EN_R   I188 @S9S_MB_2U_LIB.S9S_MB_2U(SCH_1):PAGE314
   F11 GPU_FPGA_EROT_RECOV_R_N @S9S_MB_2U_LIB.S9S_MB_2U(SCH_1):GPU_FPGA_EROT_RECOV_R_N   I188 @S9S_MB_2U_LIB.S9S_MB_2U(SCH_1):PAGE314
   B11 GPU_FPGA_OVERT_ISO_R_N @S9S_MB_2U_LIB.S9S_MB_2U(SCH_1):GPU_FPGA_OVERT_ISO_R_N   I188 @S9S_MB_2U_LIB.S9S_MB_2U(SCH_1):PAGE314
   A11 GPU_WP_HW_CTRL_R_N @S9S_MB_2U_LIB.S9S_MB_2U(SCH_1):GPU_WP_HW_CTRL_R_N   I188 @S9S_MB_2U_LIB.S9S_MB_2U(SCH_1):PAGE314
   E11 GPU_PRSNT_N_ISO_R @S9S_MB_2U_LIB.S9S_MB_2U(SCH_1):GPU_PRSNT_N_ISO_R   I188 @S9S_MB_2U_LIB.S9S_MB_2U(SCH_1):PAGE314
   D11 GPU_FPGA_EROT_FATALERR_ISO_R_N @S9S_MB_2U_LIB.S9S_MB_2U(SCH_1):GPU_FPGA_EROT_FATALERR_ISO_R_N   I188 @S9S_MB_2U_LIB.S9S_MB_2U(SCH_1):PAGE314
   D12 PWRGD_P5V_AUX_R2 @S9S_MB_2U_LIB.S9S_MB_2U(SCH_1):PWRGD_P5V_AUX_R2   I188 @S9S_MB_2U_LIB.S9S_MB_2U(SCH_1):PAGE314
   E12 PWRGD_P3V3 @S9S_MB_2U_LIB.S9S_MB_2U(SCH_1):PWRGD_P3V3   I188 @S9S_MB_2U_LIB.S9S_MB_2U(SCH_1):PAGE314
   E13 PWRGD_PVCCFA_EHV_FIVRA_CPU0 @S9S_MB_2U_LIB.S9S_MB_2U(SCH_1):PWRGD_PVCCFA_EHV_FIVRA_CPU0   I188 @S9S_MB_2U_LIB.S9S_MB_2U(SCH_1):PAGE314
   F13 PWRGD_PVCCIN_CPU0 @S9S_MB_2U_LIB.S9S_MB_2U(SCH_1):PWRGD_PVCCIN_CPU0   I188 @S9S_MB_2U_LIB.S9S_MB_2U(SCH_1):PAGE314
   A13 PWRGD_PVNN_MAIN_CPU0 @S9S_MB_2U_LIB.S9S_MB_2U(SCH_1):PWRGD_PVNN_MAIN_CPU0   I188 @S9S_MB_2U_LIB.S9S_MB_2U(SCH_1):PAGE314
   B13 PWRGD_PVNN_PCH_AUX @S9S_MB_2U_LIB.S9S_MB_2U(SCH_1):PWRGD_PVNN_PCH_AUX   I188 @S9S_MB_2U_LIB.S9S_MB_2U(SCH_1):PAGE314
   C13 PWRGD_PVNN_MAIN_CPU1 @S9S_MB_2U_LIB.S9S_MB_2U(SCH_1):PWRGD_PVNN_MAIN_CPU1   I188 @S9S_MB_2U_LIB.S9S_MB_2U(SCH_1):PAGE314
   D13 PWRGD_PVPP_HBM_CPU0 @S9S_MB_2U_LIB.S9S_MB_2U(SCH_1):PWRGD_PVPP_HBM_CPU0   I188 @S9S_MB_2U_LIB.S9S_MB_2U(SCH_1):PAGE314
   A14 PWRGD_PVPP_HBM_CPU1 @S9S_MB_2U_LIB.S9S_MB_2U(SCH_1):PWRGD_PVPP_HBM_CPU1   I188 @S9S_MB_2U_LIB.S9S_MB_2U(SCH_1):PAGE314
   B14 FM_NCSI_OCP_V3_2_R_OE @S9S_MB_2U_LIB.S9S_MB_2U(SCH_1):FM_NCSI_OCP_V3_2_R_OE   I188 @S9S_MB_2U_LIB.S9S_MB_2U(SCH_1):PAGE314
   C14 SGPIO_BMC_DOUT @S9S_MB_2U_LIB.S9S_MB_2U(SCH_1):SGPIO_BMC_DOUT   I188 @S9S_MB_2U_LIB.S9S_MB_2U(SCH_1):PAGE314
   D14 SGPIO_BMC_CLK @S9S_MB_2U_LIB.S9S_MB_2U(SCH_1):SGPIO_BMC_CLK   I188 @S9S_MB_2U_LIB.S9S_MB_2U(SCH_1):PAGE314
   A15 SGPIO_DEBUG_PLD_DOUT @S9S_MB_2U_LIB.S9S_MB_2U(SCH_1):SGPIO_DEBUG_PLD_DOUT   I188 @S9S_MB_2U_LIB.S9S_MB_2U(SCH_1):PAGE314
   B15 SGPIO_DEBUG_PLD_CLK @S9S_MB_2U_LIB.S9S_MB_2U(SCH_1):SGPIO_DEBUG_PLD_CLK   I188 @S9S_MB_2U_LIB.S9S_MB_2U(SCH_1):PAGE314
   C15 SGPIO_DEBUG_PLD_DIN @S9S_MB_2U_LIB.S9S_MB_2U(SCH_1):SGPIO_DEBUG_PLD_DIN   I188 @S9S_MB_2U_LIB.S9S_MB_2U(SCH_1):PAGE314
   D15 SGPIO_DEBUG_PLD_LD_N @S9S_MB_2U_LIB.S9S_MB_2U(SCH_1):SGPIO_DEBUG_PLD_LD_N   I188 @S9S_MB_2U_LIB.S9S_MB_2U(SCH_1):PAGE314
   A16 SGPIO_OCP_SFF_DATAOUT @S9S_MB_2U_LIB.S9S_MB_2U(SCH_1):SGPIO_OCP_SFF_DATAOUT   I188 @S9S_MB_2U_LIB.S9S_MB_2U(SCH_1):PAGE314
   B17 SGPIO_OCP_SFF_CLK @S9S_MB_2U_LIB.S9S_MB_2U(SCH_1):SGPIO_OCP_SFF_CLK   I188 @S9S_MB_2U_LIB.S9S_MB_2U(SCH_1):PAGE314
   C17 SGPIO_OCP_SFF_DATAIN @S9S_MB_2U_LIB.S9S_MB_2U(SCH_1):SGPIO_OCP_SFF_DATAIN   I188 @S9S_MB_2U_LIB.S9S_MB_2U(SCH_1):PAGE314
   D16 SGPIO_OCP_SFF_LD_N @S9S_MB_2U_LIB.S9S_MB_2U(SCH_1):SGPIO_OCP_SFF_LD_N   I188 @S9S_MB_2U_LIB.S9S_MB_2U(SCH_1):PAGE314
   A17 SGPIO_OCP_V3_2_DATAOUT @S9S_MB_2U_LIB.S9S_MB_2U(SCH_1):SGPIO_OCP_V3_2_DATAOUT   I188 @S9S_MB_2U_LIB.S9S_MB_2U(SCH_1):PAGE314
   B18 SGPIO_OCP_V3_2_CLK @S9S_MB_2U_LIB.S9S_MB_2U(SCH_1):SGPIO_OCP_V3_2_CLK   I188 @S9S_MB_2U_LIB.S9S_MB_2U(SCH_1):PAGE314
   E16 SGPIO_OCP_V3_2_DATAIN @S9S_MB_2U_LIB.S9S_MB_2U(SCH_1):SGPIO_OCP_V3_2_DATAIN   I188 @S9S_MB_2U_LIB.S9S_MB_2U(SCH_1):PAGE314
   D17 SGPIO_OCP_V3_2_LD_N @S9S_MB_2U_LIB.S9S_MB_2U(SCH_1):SGPIO_OCP_V3_2_LD_N   I188 @S9S_MB_2U_LIB.S9S_MB_2U(SCH_1):PAGE314
   C18 JTAG_BMC_SW_PLD_OE @S9S_MB_2U_LIB.S9S_MB_2U(SCH_1):JTAG_BMC_SW_PLD_OE   I188 @S9S_MB_2U_LIB.S9S_MB_2U(SCH_1):PAGE314
   D18 NC_FPGA_PT41D @S9S_MB_2U_LIB.S9S_MB_2U(SCH_1):NC_FPGA_PT41D   I188 @S9S_MB_2U_LIB.S9S_MB_2U(SCH_1):PAGE314
   A19 P12V_HSC_TEMP_ALERT_R_N @S9S_MB_2U_LIB.S9S_MB_2U(SCH_1):P12V_HSC_TEMP_ALERT_R_N   I188 @S9S_MB_2U_LIB.S9S_MB_2U(SCH_1):PAGE314
   B20 P12V_HSC_T_CRIT_R_N @S9S_MB_2U_LIB.S9S_MB_2U(SCH_1):P12V_HSC_T_CRIT_R_N   I188 @S9S_MB_2U_LIB.S9S_MB_2U(SCH_1):PAGE314
   F15 RST_SRST_PLD_BMC_R_N @S9S_MB_2U_LIB.S9S_MB_2U(SCH_1):RST_SRST_PLD_BMC_R_N   I188 @S9S_MB_2U_LIB.S9S_MB_2U(SCH_1):PAGE314
   G15 NC_FPGA_PT42D @S9S_MB_2U_LIB.S9S_MB_2U(SCH_1):NC_FPGA_PT42D   I188 @S9S_MB_2U_LIB.S9S_MB_2U(SCH_1):PAGE314
   C19 NC_FPGA_PT43C @S9S_MB_2U_LIB.S9S_MB_2U(SCH_1):NC_FPGA_PT43C   I188 @S9S_MB_2U_LIB.S9S_MB_2U(SCH_1):PAGE314
   C20 NC_FPGA_PT43D @S9S_MB_2U_LIB.S9S_MB_2U(SCH_1):NC_FPGA_PT43D   I188 @S9S_MB_2U_LIB.S9S_MB_2U(SCH_1):PAGE314
    E8 JTAG_PLD_TDO_R @S9S_MB_2U_LIB.S9S_MB_2U(SCH_1):JTAG_PLD_TDO_R    I70 @S9S_MB_2U_LIB.S9S_MB_2U(SCH_1):PAGE311
    E9 JTAG_PLD_TDI_R @S9S_MB_2U_LIB.S9S_MB_2U(SCH_1):JTAG_PLD_TDI_R    I70 @S9S_MB_2U_LIB.S9S_MB_2U(SCH_1):PAGE311
   D10 JTAG_PLD_TCK_R @S9S_MB_2U_LIB.S9S_MB_2U(SCH_1):JTAG_PLD_TCK_R    I70 @S9S_MB_2U_LIB.S9S_MB_2U(SCH_1):PAGE311
   C10 JTAG_PLD_TMS_R @S9S_MB_2U_LIB.S9S_MB_2U(SCH_1):JTAG_PLD_TMS_R    I70 @S9S_MB_2U_LIB.S9S_MB_2U(SCH_1):PAGE311
   E15 PU_FPGA_D12_PROGRAMN @S9S_MB_2U_LIB.S9S_MB_2U(SCH_1):PU_FPGA_D12_PROGRAMN    I70 @S9S_MB_2U_LIB.S9S_MB_2U(SCH_1):PAGE311
   F16 NC_FPGA_PT44C @S9S_MB_2U_LIB.S9S_MB_2U(SCH_1):NC_FPGA_PT44C    I70 @S9S_MB_2U_LIB.S9S_MB_2U(SCH_1):PAGE311
   E17 NC_FPGA_PT44D @S9S_MB_2U_LIB.S9S_MB_2U(SCH_1):NC_FPGA_PT44D    I70 @S9S_MB_2U_LIB.S9S_MB_2U(SCH_1):PAGE311
   E14 JTAG_PLD_JTAGEN @S9S_MB_2U_LIB.S9S_MB_2U(SCH_1):JTAG_PLD_JTAGEN    I70 @S9S_MB_2U_LIB.S9S_MB_2U(SCH_1):PAGE311
   K10 VCC_PLD_CORE @S9S_MB_2U_LIB.S9S_MB_2U(SCH_1):VCC_PLD_CORE   I102 @S9S_MB_2U_LIB.S9S_MB_2U(SCH_1):PAGE202
   K11 VCC_PLD_CORE @S9S_MB_2U_LIB.S9S_MB_2U(SCH_1):VCC_PLD_CORE   I102 @S9S_MB_2U_LIB.S9S_MB_2U(SCH_1):PAGE202
   K12 VCC_PLD_CORE @S9S_MB_2U_LIB.S9S_MB_2U(SCH_1):VCC_PLD_CORE   I102 @S9S_MB_2U_LIB.S9S_MB_2U(SCH_1):PAGE202
   K13 VCC_PLD_CORE @S9S_MB_2U_LIB.S9S_MB_2U(SCH_1):VCC_PLD_CORE   I102 @S9S_MB_2U_LIB.S9S_MB_2U(SCH_1):PAGE202
   L11 VCC_PLD_CORE @S9S_MB_2U_LIB.S9S_MB_2U(SCH_1):VCC_PLD_CORE   I102 @S9S_MB_2U_LIB.S9S_MB_2U(SCH_1):PAGE202
   L12 VCC_PLD_CORE @S9S_MB_2U_LIB.S9S_MB_2U(SCH_1):VCC_PLD_CORE   I102 @S9S_MB_2U_LIB.S9S_MB_2U(SCH_1):PAGE202
   M11 VCC_PLD_CORE @S9S_MB_2U_LIB.S9S_MB_2U(SCH_1):VCC_PLD_CORE   I102 @S9S_MB_2U_LIB.S9S_MB_2U(SCH_1):PAGE202
   M12 VCC_PLD_CORE @S9S_MB_2U_LIB.S9S_MB_2U(SCH_1):VCC_PLD_CORE   I102 @S9S_MB_2U_LIB.S9S_MB_2U(SCH_1):PAGE202
   N10 VCC_PLD_CORE @S9S_MB_2U_LIB.S9S_MB_2U(SCH_1):VCC_PLD_CORE   I102 @S9S_MB_2U_LIB.S9S_MB_2U(SCH_1):PAGE202
   N11 VCC_PLD_CORE @S9S_MB_2U_LIB.S9S_MB_2U(SCH_1):VCC_PLD_CORE   I102 @S9S_MB_2U_LIB.S9S_MB_2U(SCH_1):PAGE202
   N12 VCC_PLD_CORE @S9S_MB_2U_LIB.S9S_MB_2U(SCH_1):VCC_PLD_CORE   I102 @S9S_MB_2U_LIB.S9S_MB_2U(SCH_1):PAGE202
   N13 VCC_PLD_CORE @S9S_MB_2U_LIB.S9S_MB_2U(SCH_1):VCC_PLD_CORE   I102 @S9S_MB_2U_LIB.S9S_MB_2U(SCH_1):PAGE202
    F3 P3V3_AUX_FPGA_VCCIO5 @S9S_MB_2U_LIB.S9S_MB_2U(SCH_1):P3V3_AUX_FPGA_VCCIO5   I102 @S9S_MB_2U_LIB.S9S_MB_2U(SCH_1):PAGE202
    J8 P3V3_AUX_FPGA_VCCIO5 @S9S_MB_2U_LIB.S9S_MB_2U(SCH_1):P3V3_AUX_FPGA_VCCIO5   I102 @S9S_MB_2U_LIB.S9S_MB_2U(SCH_1):PAGE202
    K8 P3V3_AUX_FPGA_VCCIO5 @S9S_MB_2U_LIB.S9S_MB_2U(SCH_1):P3V3_AUX_FPGA_VCCIO5   I102 @S9S_MB_2U_LIB.S9S_MB_2U(SCH_1):PAGE202
    L8 P3V3_AUX_FPGA_VCCIO4 @S9S_MB_2U_LIB.S9S_MB_2U(SCH_1):P3V3_AUX_FPGA_VCCIO4   I102 @S9S_MB_2U_LIB.S9S_MB_2U(SCH_1):PAGE202
    M8 P3V3_AUX_FPGA_VCCIO4 @S9S_MB_2U_LIB.S9S_MB_2U(SCH_1):P3V3_AUX_FPGA_VCCIO4   I102 @S9S_MB_2U_LIB.S9S_MB_2U(SCH_1):PAGE202
    M3 P3V3_AUX_FPGA_VCCIO4 @S9S_MB_2U_LIB.S9S_MB_2U(SCH_1):P3V3_AUX_FPGA_VCCIO4   I102 @S9S_MB_2U_LIB.S9S_MB_2U(SCH_1):PAGE202
    N8 P3V3_AUX_FPGA_VCCIO3 @S9S_MB_2U_LIB.S9S_MB_2U(SCH_1):P3V3_AUX_FPGA_VCCIO3   I102 @S9S_MB_2U_LIB.S9S_MB_2U(SCH_1):PAGE202
    P8 P3V3_AUX_FPGA_VCCIO3 @S9S_MB_2U_LIB.S9S_MB_2U(SCH_1):P3V3_AUX_FPGA_VCCIO3   I102 @S9S_MB_2U_LIB.S9S_MB_2U(SCH_1):PAGE202
    V3 P3V3_AUX_FPGA_VCCIO3 @S9S_MB_2U_LIB.S9S_MB_2U(SCH_1):P3V3_AUX_FPGA_VCCIO3   I102 @S9S_MB_2U_LIB.S9S_MB_2U(SCH_1):PAGE202
    R9 P3V3_AUX_FPGA_VCCIO2 @S9S_MB_2U_LIB.S9S_MB_2U(SCH_1):P3V3_AUX_FPGA_VCCIO2   I102 @S9S_MB_2U_LIB.S9S_MB_2U(SCH_1):PAGE202
   R10 P3V3_AUX_FPGA_VCCIO2 @S9S_MB_2U_LIB.S9S_MB_2U(SCH_1):P3V3_AUX_FPGA_VCCIO2   I102 @S9S_MB_2U_LIB.S9S_MB_2U(SCH_1):PAGE202
   R11 P3V3_AUX_FPGA_VCCIO2 @S9S_MB_2U_LIB.S9S_MB_2U(SCH_1):P3V3_AUX_FPGA_VCCIO2   I102 @S9S_MB_2U_LIB.S9S_MB_2U(SCH_1):PAGE202
   R12 P3V3_AUX_FPGA_VCCIO2 @S9S_MB_2U_LIB.S9S_MB_2U(SCH_1):P3V3_AUX_FPGA_VCCIO2   I102 @S9S_MB_2U_LIB.S9S_MB_2U(SCH_1):PAGE202
   R13 P3V3_AUX_FPGA_VCCIO2 @S9S_MB_2U_LIB.S9S_MB_2U(SCH_1):P3V3_AUX_FPGA_VCCIO2   I102 @S9S_MB_2U_LIB.S9S_MB_2U(SCH_1):PAGE202
   R14 P3V3_AUX_FPGA_VCCIO2 @S9S_MB_2U_LIB.S9S_MB_2U(SCH_1):P3V3_AUX_FPGA_VCCIO2   I102 @S9S_MB_2U_LIB.S9S_MB_2U(SCH_1):PAGE202
    W7 P3V3_AUX_FPGA_VCCIO2 @S9S_MB_2U_LIB.S9S_MB_2U(SCH_1):P3V3_AUX_FPGA_VCCIO2   I102 @S9S_MB_2U_LIB.S9S_MB_2U(SCH_1):PAGE202
   W11 P3V3_AUX_FPGA_VCCIO2 @S9S_MB_2U_LIB.S9S_MB_2U(SCH_1):P3V3_AUX_FPGA_VCCIO2   I102 @S9S_MB_2U_LIB.S9S_MB_2U(SCH_1):PAGE202
   W16 P3V3_AUX_FPGA_VCCIO2 @S9S_MB_2U_LIB.S9S_MB_2U(SCH_1):P3V3_AUX_FPGA_VCCIO2   I102 @S9S_MB_2U_LIB.S9S_MB_2U(SCH_1):PAGE202
   F20 P3V3_AUX_FPGA_VCCIO1 @S9S_MB_2U_LIB.S9S_MB_2U(SCH_1):P3V3_AUX_FPGA_VCCIO1   I102 @S9S_MB_2U_LIB.S9S_MB_2U(SCH_1):PAGE202
   J15 P3V3_AUX_FPGA_VCCIO1 @S9S_MB_2U_LIB.S9S_MB_2U(SCH_1):P3V3_AUX_FPGA_VCCIO1   I102 @S9S_MB_2U_LIB.S9S_MB_2U(SCH_1):PAGE202
   K15 P3V3_AUX_FPGA_VCCIO1 @S9S_MB_2U_LIB.S9S_MB_2U(SCH_1):P3V3_AUX_FPGA_VCCIO1   I102 @S9S_MB_2U_LIB.S9S_MB_2U(SCH_1):PAGE202
   L15 P3V3_AUX_FPGA_VCCIO1 @S9S_MB_2U_LIB.S9S_MB_2U(SCH_1):P3V3_AUX_FPGA_VCCIO1   I102 @S9S_MB_2U_LIB.S9S_MB_2U(SCH_1):PAGE202
   M15 P3V3_AUX_FPGA_VCCIO1 @S9S_MB_2U_LIB.S9S_MB_2U(SCH_1):P3V3_AUX_FPGA_VCCIO1   I102 @S9S_MB_2U_LIB.S9S_MB_2U(SCH_1):PAGE202
   M18 P3V3_AUX_FPGA_VCCIO1 @S9S_MB_2U_LIB.S9S_MB_2U(SCH_1):P3V3_AUX_FPGA_VCCIO1   I102 @S9S_MB_2U_LIB.S9S_MB_2U(SCH_1):PAGE202
   N15 P3V3_AUX_FPGA_VCCIO1 @S9S_MB_2U_LIB.S9S_MB_2U(SCH_1):P3V3_AUX_FPGA_VCCIO1   I102 @S9S_MB_2U_LIB.S9S_MB_2U(SCH_1):PAGE202
   P15 P3V3_AUX_FPGA_VCCIO1 @S9S_MB_2U_LIB.S9S_MB_2U(SCH_1):P3V3_AUX_FPGA_VCCIO1   I102 @S9S_MB_2U_LIB.S9S_MB_2U(SCH_1):PAGE202
   V20 P3V3_AUX_FPGA_VCCIO1 @S9S_MB_2U_LIB.S9S_MB_2U(SCH_1):P3V3_AUX_FPGA_VCCIO1   I102 @S9S_MB_2U_LIB.S9S_MB_2U(SCH_1):PAGE202
    C7 P3V3_AUX_FPGA_VCCIO0 @S9S_MB_2U_LIB.S9S_MB_2U(SCH_1):P3V3_AUX_FPGA_VCCIO0   I102 @S9S_MB_2U_LIB.S9S_MB_2U(SCH_1):PAGE202
   C12 P3V3_AUX_FPGA_VCCIO0 @S9S_MB_2U_LIB.S9S_MB_2U(SCH_1):P3V3_AUX_FPGA_VCCIO0   I102 @S9S_MB_2U_LIB.S9S_MB_2U(SCH_1):PAGE202
   C16 P3V3_AUX_FPGA_VCCIO0 @S9S_MB_2U_LIB.S9S_MB_2U(SCH_1):P3V3_AUX_FPGA_VCCIO0   I102 @S9S_MB_2U_LIB.S9S_MB_2U(SCH_1):PAGE202
   G10 P3V3_AUX_FPGA_VCCIO0 @S9S_MB_2U_LIB.S9S_MB_2U(SCH_1):P3V3_AUX_FPGA_VCCIO0   I102 @S9S_MB_2U_LIB.S9S_MB_2U(SCH_1):PAGE202
   H11 P3V3_AUX_FPGA_VCCIO0 @S9S_MB_2U_LIB.S9S_MB_2U(SCH_1):P3V3_AUX_FPGA_VCCIO0   I102 @S9S_MB_2U_LIB.S9S_MB_2U(SCH_1):PAGE202
   H12 P3V3_AUX_FPGA_VCCIO0 @S9S_MB_2U_LIB.S9S_MB_2U(SCH_1):P3V3_AUX_FPGA_VCCIO0   I102 @S9S_MB_2U_LIB.S9S_MB_2U(SCH_1):PAGE202
   H14 P3V3_AUX_FPGA_VCCIO0 @S9S_MB_2U_LIB.S9S_MB_2U(SCH_1):P3V3_AUX_FPGA_VCCIO0   I102 @S9S_MB_2U_LIB.S9S_MB_2U(SCH_1):PAGE202
    H9 P3V3_AUX_FPGA_VCCIO0 @S9S_MB_2U_LIB.S9S_MB_2U(SCH_1):P3V3_AUX_FPGA_VCCIO0   I102 @S9S_MB_2U_LIB.S9S_MB_2U(SCH_1):PAGE202
   G13 P3V3_AUX_FPGA_VCCIO0 @S9S_MB_2U_LIB.S9S_MB_2U(SCH_1):P3V3_AUX_FPGA_VCCIO0   I102 @S9S_MB_2U_LIB.S9S_MB_2U(SCH_1):PAGE202
    A1    GND @S9S_MB_2U_LIB.S9S_MB_2U(SCH_1):GND     I1 @S9S_MB_2U_LIB.S9S_MB_2U(SCH_1):PAGE202
   A22    GND @S9S_MB_2U_LIB.S9S_MB_2U(SCH_1):GND     I1 @S9S_MB_2U_LIB.S9S_MB_2U(SCH_1):PAGE202
    B7    GND @S9S_MB_2U_LIB.S9S_MB_2U(SCH_1):GND     I1 @S9S_MB_2U_LIB.S9S_MB_2U(SCH_1):PAGE202
   B16    GND @S9S_MB_2U_LIB.S9S_MB_2U(SCH_1):GND     I1 @S9S_MB_2U_LIB.S9S_MB_2U(SCH_1):PAGE202
    C2    GND @S9S_MB_2U_LIB.S9S_MB_2U(SCH_1):GND     I1 @S9S_MB_2U_LIB.S9S_MB_2U(SCH_1):PAGE202
   C11    GND @S9S_MB_2U_LIB.S9S_MB_2U(SCH_1):GND     I1 @S9S_MB_2U_LIB.S9S_MB_2U(SCH_1):PAGE202
    E5    GND @S9S_MB_2U_LIB.S9S_MB_2U(SCH_1):GND     I1 @S9S_MB_2U_LIB.S9S_MB_2U(SCH_1):PAGE202
   E18    GND @S9S_MB_2U_LIB.S9S_MB_2U(SCH_1):GND     I1 @S9S_MB_2U_LIB.S9S_MB_2U(SCH_1):PAGE202
    F2    GND @S9S_MB_2U_LIB.S9S_MB_2U(SCH_1):GND     I1 @S9S_MB_2U_LIB.S9S_MB_2U(SCH_1):PAGE202
   F21    GND @S9S_MB_2U_LIB.S9S_MB_2U(SCH_1):GND     I1 @S9S_MB_2U_LIB.S9S_MB_2U(SCH_1):PAGE202
    H8    GND @S9S_MB_2U_LIB.S9S_MB_2U(SCH_1):GND     I1 @S9S_MB_2U_LIB.S9S_MB_2U(SCH_1):PAGE202
   H10    GND @S9S_MB_2U_LIB.S9S_MB_2U(SCH_1):GND     I1 @S9S_MB_2U_LIB.S9S_MB_2U(SCH_1):PAGE202
   H13    GND @S9S_MB_2U_LIB.S9S_MB_2U(SCH_1):GND     I1 @S9S_MB_2U_LIB.S9S_MB_2U(SCH_1):PAGE202
   H15    GND @S9S_MB_2U_LIB.S9S_MB_2U(SCH_1):GND     I1 @S9S_MB_2U_LIB.S9S_MB_2U(SCH_1):PAGE202
    J9    GND @S9S_MB_2U_LIB.S9S_MB_2U(SCH_1):GND     I1 @S9S_MB_2U_LIB.S9S_MB_2U(SCH_1):PAGE202
   J10    GND @S9S_MB_2U_LIB.S9S_MB_2U(SCH_1):GND     I1 @S9S_MB_2U_LIB.S9S_MB_2U(SCH_1):PAGE202
   J11    GND @S9S_MB_2U_LIB.S9S_MB_2U(SCH_1):GND     I1 @S9S_MB_2U_LIB.S9S_MB_2U(SCH_1):PAGE202
   J12    GND @S9S_MB_2U_LIB.S9S_MB_2U(SCH_1):GND     I1 @S9S_MB_2U_LIB.S9S_MB_2U(SCH_1):PAGE202
   J13    GND @S9S_MB_2U_LIB.S9S_MB_2U(SCH_1):GND     I1 @S9S_MB_2U_LIB.S9S_MB_2U(SCH_1):PAGE202
   J14    GND @S9S_MB_2U_LIB.S9S_MB_2U(SCH_1):GND     I1 @S9S_MB_2U_LIB.S9S_MB_2U(SCH_1):PAGE202
    K9    GND @S9S_MB_2U_LIB.S9S_MB_2U(SCH_1):GND     I1 @S9S_MB_2U_LIB.S9S_MB_2U(SCH_1):PAGE202
   K14    GND @S9S_MB_2U_LIB.S9S_MB_2U(SCH_1):GND     I1 @S9S_MB_2U_LIB.S9S_MB_2U(SCH_1):PAGE202
   K21    GND @S9S_MB_2U_LIB.S9S_MB_2U(SCH_1):GND     I1 @S9S_MB_2U_LIB.S9S_MB_2U(SCH_1):PAGE202
    L2    GND @S9S_MB_2U_LIB.S9S_MB_2U(SCH_1):GND     I1 @S9S_MB_2U_LIB.S9S_MB_2U(SCH_1):PAGE202
    L9    GND @S9S_MB_2U_LIB.S9S_MB_2U(SCH_1):GND     I1 @S9S_MB_2U_LIB.S9S_MB_2U(SCH_1):PAGE202
   L10    GND @S9S_MB_2U_LIB.S9S_MB_2U(SCH_1):GND     I1 @S9S_MB_2U_LIB.S9S_MB_2U(SCH_1):PAGE202
   L13    GND @S9S_MB_2U_LIB.S9S_MB_2U(SCH_1):GND     I1 @S9S_MB_2U_LIB.S9S_MB_2U(SCH_1):PAGE202
   L14    GND @S9S_MB_2U_LIB.S9S_MB_2U(SCH_1):GND     I1 @S9S_MB_2U_LIB.S9S_MB_2U(SCH_1):PAGE202
   L18    GND @S9S_MB_2U_LIB.S9S_MB_2U(SCH_1):GND     I1 @S9S_MB_2U_LIB.S9S_MB_2U(SCH_1):PAGE202
    M4    GND @S9S_MB_2U_LIB.S9S_MB_2U(SCH_1):GND     I1 @S9S_MB_2U_LIB.S9S_MB_2U(SCH_1):PAGE202
    M9    GND @S9S_MB_2U_LIB.S9S_MB_2U(SCH_1):GND     I1 @S9S_MB_2U_LIB.S9S_MB_2U(SCH_1):PAGE202
   M10    GND @S9S_MB_2U_LIB.S9S_MB_2U(SCH_1):GND     I1 @S9S_MB_2U_LIB.S9S_MB_2U(SCH_1):PAGE202
   M13    GND @S9S_MB_2U_LIB.S9S_MB_2U(SCH_1):GND     I1 @S9S_MB_2U_LIB.S9S_MB_2U(SCH_1):PAGE202
   M14    GND @S9S_MB_2U_LIB.S9S_MB_2U(SCH_1):GND     I1 @S9S_MB_2U_LIB.S9S_MB_2U(SCH_1):PAGE202
    N9    GND @S9S_MB_2U_LIB.S9S_MB_2U(SCH_1):GND     I1 @S9S_MB_2U_LIB.S9S_MB_2U(SCH_1):PAGE202
   N14    GND @S9S_MB_2U_LIB.S9S_MB_2U(SCH_1):GND     I1 @S9S_MB_2U_LIB.S9S_MB_2U(SCH_1):PAGE202
   N21    GND @S9S_MB_2U_LIB.S9S_MB_2U(SCH_1):GND     I1 @S9S_MB_2U_LIB.S9S_MB_2U(SCH_1):PAGE202
    P9    GND @S9S_MB_2U_LIB.S9S_MB_2U(SCH_1):GND     I1 @S9S_MB_2U_LIB.S9S_MB_2U(SCH_1):PAGE202
   P10    GND @S9S_MB_2U_LIB.S9S_MB_2U(SCH_1):GND     I1 @S9S_MB_2U_LIB.S9S_MB_2U(SCH_1):PAGE202
   P11    GND @S9S_MB_2U_LIB.S9S_MB_2U(SCH_1):GND     I1 @S9S_MB_2U_LIB.S9S_MB_2U(SCH_1):PAGE202
   P12    GND @S9S_MB_2U_LIB.S9S_MB_2U(SCH_1):GND     I1 @S9S_MB_2U_LIB.S9S_MB_2U(SCH_1):PAGE202
   P13    GND @S9S_MB_2U_LIB.S9S_MB_2U(SCH_1):GND     I1 @S9S_MB_2U_LIB.S9S_MB_2U(SCH_1):PAGE202
   P14    GND @S9S_MB_2U_LIB.S9S_MB_2U(SCH_1):GND     I1 @S9S_MB_2U_LIB.S9S_MB_2U(SCH_1):PAGE202
    R8    GND @S9S_MB_2U_LIB.S9S_MB_2U(SCH_1):GND     I1 @S9S_MB_2U_LIB.S9S_MB_2U(SCH_1):PAGE202
   R15    GND @S9S_MB_2U_LIB.S9S_MB_2U(SCH_1):GND     I1 @S9S_MB_2U_LIB.S9S_MB_2U(SCH_1):PAGE202
    V2    GND @S9S_MB_2U_LIB.S9S_MB_2U(SCH_1):GND     I1 @S9S_MB_2U_LIB.S9S_MB_2U(SCH_1):PAGE202
   V21    GND @S9S_MB_2U_LIB.S9S_MB_2U(SCH_1):GND     I1 @S9S_MB_2U_LIB.S9S_MB_2U(SCH_1):PAGE202
   W12    GND @S9S_MB_2U_LIB.S9S_MB_2U(SCH_1):GND     I1 @S9S_MB_2U_LIB.S9S_MB_2U(SCH_1):PAGE202
   Y16    GND @S9S_MB_2U_LIB.S9S_MB_2U(SCH_1):GND     I1 @S9S_MB_2U_LIB.S9S_MB_2U(SCH_1):PAGE202
    Y7    GND @S9S_MB_2U_LIB.S9S_MB_2U(SCH_1):GND     I1 @S9S_MB_2U_LIB.S9S_MB_2U(SCH_1):PAGE202
   AB1    GND @S9S_MB_2U_LIB.S9S_MB_2U(SCH_1):GND     I1 @S9S_MB_2U_LIB.S9S_MB_2U(SCH_1):PAGE202
  AB22    GND @S9S_MB_2U_LIB.S9S_MB_2U(SCH_1):GND     I1 @S9S_MB_2U_LIB.S9S_MB_2U(SCH_1):PAGE202
   W20 FM_PCH_SPKR_R @S9S_MB_2U_LIB.S9S_MB_2U(SCH_1):FM_PCH_SPKR_R     I1 @S9S_MB_2U_LIB.S9S_MB_2U(SCH_1):PAGE313
   V18 FM_BMC_CPU_FBRK_OUT_R_N @S9S_MB_2U_LIB.S9S_MB_2U(SCH_1):FM_BMC_CPU_FBRK_OUT_R_N     I1 @S9S_MB_2U_LIB.S9S_MB_2U(SCH_1):PAGE313
   V19 CLK_GEN2_GPU_FPGA_OE_R_N @S9S_MB_2U_LIB.S9S_MB_2U(SCH_1):CLK_GEN2_GPU_FPGA_OE_R_N     I1 @S9S_MB_2U_LIB.S9S_MB_2U(SCH_1):PAGE313
   Y21 GPU_FPGA_RST_N @S9S_MB_2U_LIB.S9S_MB_2U(SCH_1):GPU_FPGA_RST_N     I1 @S9S_MB_2U_LIB.S9S_MB_2U(SCH_1):PAGE313
   U17 FM_JTAG_TCK_MUX_SEL_R @S9S_MB_2U_LIB.S9S_MB_2U(SCH_1):FM_JTAG_TCK_MUX_SEL_R     I1 @S9S_MB_2U_LIB.S9S_MB_2U(SCH_1):PAGE313
  AA22 LED_HDD_ACTIVITY_B_PLD_N @S9S_MB_2U_LIB.S9S_MB_2U(SCH_1):LED_HDD_ACTIVITY_B_PLD_N     I1 @S9S_MB_2U_LIB.S9S_MB_2U(SCH_1):PAGE313
   W22 PWRGD_FAIL_CPU0_AB_R @S9S_MB_2U_LIB.S9S_MB_2U(SCH_1):PWRGD_FAIL_CPU0_AB_R     I1 @S9S_MB_2U_LIB.S9S_MB_2U(SCH_1):PAGE313
   V22 FM_PS_EN_PLD_R @S9S_MB_2U_LIB.S9S_MB_2U(SCH_1):FM_PS_EN_PLD_R     I1 @S9S_MB_2U_LIB.S9S_MB_2U(SCH_1):PAGE313
   R21 FM_CPU1_PKGID0 @S9S_MB_2U_LIB.S9S_MB_2U(SCH_1):FM_CPU1_PKGID0     I1 @S9S_MB_2U_LIB.S9S_MB_2U(SCH_1):PAGE313
   R22 FM_CPU0_PKGID2 @S9S_MB_2U_LIB.S9S_MB_2U(SCH_1):FM_CPU0_PKGID2     I1 @S9S_MB_2U_LIB.S9S_MB_2U(SCH_1):PAGE313
   P21 FM_CPU1_PROC_ID1 @S9S_MB_2U_LIB.S9S_MB_2U(SCH_1):FM_CPU1_PROC_ID1     I1 @S9S_MB_2U_LIB.S9S_MB_2U(SCH_1):PAGE313
   N22 FM_CPU1_PROC_ID0 @S9S_MB_2U_LIB.S9S_MB_2U(SCH_1):FM_CPU1_PROC_ID0     I1 @S9S_MB_2U_LIB.S9S_MB_2U(SCH_1):PAGE313
   M21 SMB_2_PLD_3V3AUX_SDA_R1 @S9S_MB_2U_LIB.S9S_MB_2U(SCH_1):SMB_2_PLD_3V3AUX_SDA_R1     I1 @S9S_MB_2U_LIB.S9S_MB_2U(SCH_1):PAGE313
   M22 SMB_2_PLD_3V3AUX_SCL_R1 @S9S_MB_2U_LIB.S9S_MB_2U(SCH_1):SMB_2_PLD_3V3AUX_SCL_R1     I1 @S9S_MB_2U_LIB.S9S_MB_2U(SCH_1):PAGE313
   L21 FM_THERMAL_ALERT_R_N @S9S_MB_2U_LIB.S9S_MB_2U(SCH_1):FM_THERMAL_ALERT_R_N     I1 @S9S_MB_2U_LIB.S9S_MB_2U(SCH_1):PAGE313
   K22 FM_SOL_UART_CH_SEL @S9S_MB_2U_LIB.S9S_MB_2U(SCH_1):FM_SOL_UART_CH_SEL     I1 @S9S_MB_2U_LIB.S9S_MB_2U(SCH_1):PAGE313
   L16 NC_FPGA_PR14B @S9S_MB_2U_LIB.S9S_MB_2U(SCH_1):NC_FPGA_PR14B     I1 @S9S_MB_2U_LIB.S9S_MB_2U(SCH_1):PAGE313
   L17 NC_FPGA_PR14A @S9S_MB_2U_LIB.S9S_MB_2U(SCH_1):NC_FPGA_PR14A     I1 @S9S_MB_2U_LIB.S9S_MB_2U(SCH_1):PAGE313
   H21 PWRGD_PVCCFA_EHV_CPU1 @S9S_MB_2U_LIB.S9S_MB_2U(SCH_1):PWRGD_PVCCFA_EHV_CPU1     I1 @S9S_MB_2U_LIB.S9S_MB_2U(SCH_1):PAGE313
   H22 PWRGD_PVCCFA_EHV_CPU0 @S9S_MB_2U_LIB.S9S_MB_2U(SCH_1):PWRGD_PVCCFA_EHV_CPU0     I1 @S9S_MB_2U_LIB.S9S_MB_2U(SCH_1):PAGE313
   D21 FM_PVCCFA_EHV_FIVRA_CPU1_R_EN @S9S_MB_2U_LIB.S9S_MB_2U(SCH_1):FM_PVCCFA_EHV_FIVRA_CPU1_R_EN     I1 @S9S_MB_2U_LIB.S9S_MB_2U(SCH_1):PAGE313
   D22 FM_PVCCFA_EHV_FIVRA_CPU0_R_EN @S9S_MB_2U_LIB.S9S_MB_2U(SCH_1):FM_PVCCFA_EHV_FIVRA_CPU0_R_EN     I1 @S9S_MB_2U_LIB.S9S_MB_2U(SCH_1):PAGE313
   C22 FM_PVCCD_HV_CPU1_EN @S9S_MB_2U_LIB.S9S_MB_2U(SCH_1):FM_PVCCD_HV_CPU1_EN     I1 @S9S_MB_2U_LIB.S9S_MB_2U(SCH_1):PAGE313
   C21 FM_PVCCD_HV_CPU0_EN @S9S_MB_2U_LIB.S9S_MB_2U(SCH_1):FM_PVCCD_HV_CPU0_EN     I1 @S9S_MB_2U_LIB.S9S_MB_2U(SCH_1):PAGE313
   F17 FM_PVCCFA_EHV_CPU0_R_EN @S9S_MB_2U_LIB.S9S_MB_2U(SCH_1):FM_PVCCFA_EHV_CPU0_R_EN     I1 @S9S_MB_2U_LIB.S9S_MB_2U(SCH_1):PAGE313
   G16 FM_PVCCFA_EHV_CPU1_R_EN @S9S_MB_2U_LIB.S9S_MB_2U(SCH_1):FM_PVCCFA_EHV_CPU1_R_EN     I1 @S9S_MB_2U_LIB.S9S_MB_2U(SCH_1):PAGE313
   D19 FM_PVCCINFAON_CPU0_R_EN @S9S_MB_2U_LIB.S9S_MB_2U(SCH_1):FM_PVCCINFAON_CPU0_R_EN     I1 @S9S_MB_2U_LIB.S9S_MB_2U(SCH_1):PAGE313
   D20 FM_PVCCINFAON_CPU1_R_EN @S9S_MB_2U_LIB.S9S_MB_2U(SCH_1):FM_PVCCINFAON_CPU1_R_EN     I1 @S9S_MB_2U_LIB.S9S_MB_2U(SCH_1):PAGE313
   E19 FM_PVCCIN_CPU0_R_EN @S9S_MB_2U_LIB.S9S_MB_2U(SCH_1):FM_PVCCIN_CPU0_R_EN     I1 @S9S_MB_2U_LIB.S9S_MB_2U(SCH_1):PAGE313
   E20 FM_PVCCIN_CPU1_R_EN @S9S_MB_2U_LIB.S9S_MB_2U(SCH_1):FM_PVCCIN_CPU1_R_EN     I1 @S9S_MB_2U_LIB.S9S_MB_2U(SCH_1):PAGE313
   E22 FM_PVNN_MAIN_CPU0_EN @S9S_MB_2U_LIB.S9S_MB_2U(SCH_1):FM_PVNN_MAIN_CPU0_EN     I1 @S9S_MB_2U_LIB.S9S_MB_2U(SCH_1):PAGE313
   E21 FM_PVNN_MAIN_CPU1_EN @S9S_MB_2U_LIB.S9S_MB_2U(SCH_1):FM_PVNN_MAIN_CPU1_EN     I1 @S9S_MB_2U_LIB.S9S_MB_2U(SCH_1):PAGE313
   F22 FM_PVPP_HBM_CPU1_EN @S9S_MB_2U_LIB.S9S_MB_2U(SCH_1):FM_PVPP_HBM_CPU1_EN     I1 @S9S_MB_2U_LIB.S9S_MB_2U(SCH_1):PAGE313
   G22 FM_PVPP_HBM_CPU0_EN @S9S_MB_2U_LIB.S9S_MB_2U(SCH_1):FM_PVPP_HBM_CPU0_EN     I1 @S9S_MB_2U_LIB.S9S_MB_2U(SCH_1):PAGE313
   F18 FM_AUX_SW_EN @S9S_MB_2U_LIB.S9S_MB_2U(SCH_1):FM_AUX_SW_EN     I1 @S9S_MB_2U_LIB.S9S_MB_2U(SCH_1):PAGE313
   F19 FM_PCH_P1V8_AUX_EN @S9S_MB_2U_LIB.S9S_MB_2U(SCH_1):FM_PCH_P1V8_AUX_EN     I1 @S9S_MB_2U_LIB.S9S_MB_2U(SCH_1):PAGE313
   G21 FM_P5V_EN @S9S_MB_2U_LIB.S9S_MB_2U(SCH_1):FM_P5V_EN     I1 @S9S_MB_2U_LIB.S9S_MB_2U(SCH_1):PAGE313
   G20 FM_P1V05_PCH_AUX_EN @S9S_MB_2U_LIB.S9S_MB_2U(SCH_1):FM_P1V05_PCH_AUX_EN     I1 @S9S_MB_2U_LIB.S9S_MB_2U(SCH_1):PAGE313
   G19 FM_ESPI_PLD_R_EN @S9S_MB_2U_LIB.S9S_MB_2U(SCH_1):FM_ESPI_PLD_R_EN     I1 @S9S_MB_2U_LIB.S9S_MB_2U(SCH_1):PAGE313
   G18 PWRGD_PVCCIN_CPU1 @S9S_MB_2U_LIB.S9S_MB_2U(SCH_1):PWRGD_PVCCIN_CPU1     I1 @S9S_MB_2U_LIB.S9S_MB_2U(SCH_1):PAGE313
   G17 PWRGD_PVCCINFAON_CPU0 @S9S_MB_2U_LIB.S9S_MB_2U(SCH_1):PWRGD_PVCCINFAON_CPU0     I1 @S9S_MB_2U_LIB.S9S_MB_2U(SCH_1):PAGE313
   H20 PWRGD_PVCCINFAON_CPU1 @S9S_MB_2U_LIB.S9S_MB_2U(SCH_1):PWRGD_PVCCINFAON_CPU1     I1 @S9S_MB_2U_LIB.S9S_MB_2U(SCH_1):PAGE313
   H19 PWRGD_PVCCFA_EHV_FIVRA_CPU1 @S9S_MB_2U_LIB.S9S_MB_2U(SCH_1):PWRGD_PVCCFA_EHV_FIVRA_CPU1     I1 @S9S_MB_2U_LIB.S9S_MB_2U(SCH_1):PAGE313
   H18 PWRGD_PVCCD_HV_CPU1 @S9S_MB_2U_LIB.S9S_MB_2U(SCH_1):PWRGD_PVCCD_HV_CPU1     I1 @S9S_MB_2U_LIB.S9S_MB_2U(SCH_1):PAGE313
   H17 FM_PFR_DSW_PWROK_N @S9S_MB_2U_LIB.S9S_MB_2U(SCH_1):FM_PFR_DSW_PWROK_N     I1 @S9S_MB_2U_LIB.S9S_MB_2U(SCH_1):PAGE313
   H16 PWRGD_PS_PWROK_PLD_ISO_R @S9S_MB_2U_LIB.S9S_MB_2U(SCH_1):PWRGD_PS_PWROK_PLD_ISO_R     I1 @S9S_MB_2U_LIB.S9S_MB_2U(SCH_1):PAGE313
   J16 PWRGD_P1V05_PCH_AUX @S9S_MB_2U_LIB.S9S_MB_2U(SCH_1):PWRGD_P1V05_PCH_AUX     I1 @S9S_MB_2U_LIB.S9S_MB_2U(SCH_1):PAGE313
   J17 PWRGD_P1V8_PCH_AUX_PLD @S9S_MB_2U_LIB.S9S_MB_2U(SCH_1):PWRGD_P1V8_PCH_AUX_PLD     I1 @S9S_MB_2U_LIB.S9S_MB_2U(SCH_1):PAGE313
   J18 PWRGD_SYS_PWROK_R @S9S_MB_2U_LIB.S9S_MB_2U(SCH_1):PWRGD_SYS_PWROK_R     I1 @S9S_MB_2U_LIB.S9S_MB_2U(SCH_1):PAGE313
   J19 PWRGD_PCH_PWROK_R @S9S_MB_2U_LIB.S9S_MB_2U(SCH_1):PWRGD_PCH_PWROK_R     I1 @S9S_MB_2U_LIB.S9S_MB_2U(SCH_1):PAGE313
   J21 IRQ_PVCCFA_CPU0_VRHOT_R_N @S9S_MB_2U_LIB.S9S_MB_2U(SCH_1):IRQ_PVCCFA_CPU0_VRHOT_R_N     I1 @S9S_MB_2U_LIB.S9S_MB_2U(SCH_1):PAGE313
   J22 IRQ_PVCCFA_CPU1_VRHOT_R_N @S9S_MB_2U_LIB.S9S_MB_2U(SCH_1):IRQ_PVCCFA_CPU1_VRHOT_R_N     I1 @S9S_MB_2U_LIB.S9S_MB_2U(SCH_1):PAGE313
   J20 E1S_0_P3V3_ADC_ALERT @S9S_MB_2U_LIB.S9S_MB_2U(SCH_1):E1S_0_P3V3_ADC_ALERT     I1 @S9S_MB_2U_LIB.S9S_MB_2U(SCH_1):PAGE313
   K20 OCP_SFF_P3V3_ADC_ALERT @S9S_MB_2U_LIB.S9S_MB_2U(SCH_1):OCP_SFF_P3V3_ADC_ALERT     I1 @S9S_MB_2U_LIB.S9S_MB_2U(SCH_1):PAGE313
   K19 NC_FPGA_PR13A @S9S_MB_2U_LIB.S9S_MB_2U(SCH_1):NC_FPGA_PR13A     I1 @S9S_MB_2U_LIB.S9S_MB_2U(SCH_1):PAGE313
   K18 OCP_V3_2_P3V3_ADC_ALERT @S9S_MB_2U_LIB.S9S_MB_2U(SCH_1):OCP_V3_2_P3V3_ADC_ALERT     I1 @S9S_MB_2U_LIB.S9S_MB_2U(SCH_1):PAGE313
   K17 M2_0_P3V3_ADC_ALERT @S9S_MB_2U_LIB.S9S_MB_2U(SCH_1):M2_0_P3V3_ADC_ALERT     I1 @S9S_MB_2U_LIB.S9S_MB_2U(SCH_1):PAGE313
   K16 P12V_SCM_ADC_ALERT @S9S_MB_2U_LIB.S9S_MB_2U(SCH_1):P12V_SCM_ADC_ALERT     I1 @S9S_MB_2U_LIB.S9S_MB_2U(SCH_1):PAGE313
   L19 FM_UARTSW_LSB_N @S9S_MB_2U_LIB.S9S_MB_2U(SCH_1):FM_UARTSW_LSB_N     I1 @S9S_MB_2U_LIB.S9S_MB_2U(SCH_1):PAGE313
   L20 FM_UARTSW_MSB_N @S9S_MB_2U_LIB.S9S_MB_2U(SCH_1):FM_UARTSW_MSB_N     I1 @S9S_MB_2U_LIB.S9S_MB_2U(SCH_1):PAGE313
   L22 NC_FPGA_PR16C @S9S_MB_2U_LIB.S9S_MB_2U(SCH_1):NC_FPGA_PR16C     I1 @S9S_MB_2U_LIB.S9S_MB_2U(SCH_1):PAGE313
   M17 NC_FPGA_PR16D @S9S_MB_2U_LIB.S9S_MB_2U(SCH_1):NC_FPGA_PR16D     I1 @S9S_MB_2U_LIB.S9S_MB_2U(SCH_1):PAGE313
   M20 RST_PCIE_CPU0_DEV_PERST_N @S9S_MB_2U_LIB.S9S_MB_2U(SCH_1):RST_PCIE_CPU0_DEV_PERST_N     I1 @S9S_MB_2U_LIB.S9S_MB_2U(SCH_1):PAGE313
   M19 RST_PCIE_CPU1_DEV_PERST_N @S9S_MB_2U_LIB.S9S_MB_2U(SCH_1):RST_PCIE_CPU1_DEV_PERST_N     I1 @S9S_MB_2U_LIB.S9S_MB_2U(SCH_1):PAGE313
   M16 FM_CPU0_SKTOCC_LVT3_PLD_N @S9S_MB_2U_LIB.S9S_MB_2U(SCH_1):FM_CPU0_SKTOCC_LVT3_PLD_N     I1 @S9S_MB_2U_LIB.S9S_MB_2U(SCH_1):PAGE313
   N16 FM_CPU1_SKTOCC_LVT3_PLD_N @S9S_MB_2U_LIB.S9S_MB_2U(SCH_1):FM_CPU1_SKTOCC_LVT3_PLD_N     I1 @S9S_MB_2U_LIB.S9S_MB_2U(SCH_1):PAGE313
   N17 FM_CPU0_PROC_ID0 @S9S_MB_2U_LIB.S9S_MB_2U(SCH_1):FM_CPU0_PROC_ID0     I1 @S9S_MB_2U_LIB.S9S_MB_2U(SCH_1):PAGE313
   N18 FM_CPU0_PROC_ID1 @S9S_MB_2U_LIB.S9S_MB_2U(SCH_1):FM_CPU0_PROC_ID1     I1 @S9S_MB_2U_LIB.S9S_MB_2U(SCH_1):PAGE313
   N20 FM_CPU0_PKGID0 @S9S_MB_2U_LIB.S9S_MB_2U(SCH_1):FM_CPU0_PKGID0     I1 @S9S_MB_2U_LIB.S9S_MB_2U(SCH_1):PAGE313
   N19 FM_CPU0_PKGID1 @S9S_MB_2U_LIB.S9S_MB_2U(SCH_1):FM_CPU0_PKGID1     I1 @S9S_MB_2U_LIB.S9S_MB_2U(SCH_1):PAGE313
   P22 FM_CPU1_PKGID1 @S9S_MB_2U_LIB.S9S_MB_2U(SCH_1):FM_CPU1_PKGID1     I1 @S9S_MB_2U_LIB.S9S_MB_2U(SCH_1):PAGE313
   P20 FM_CPU1_PKGID2 @S9S_MB_2U_LIB.S9S_MB_2U(SCH_1):FM_CPU1_PKGID2     I1 @S9S_MB_2U_LIB.S9S_MB_2U(SCH_1):PAGE313
   T22 PWRGD_DSW_PWROK_R3 @S9S_MB_2U_LIB.S9S_MB_2U(SCH_1):PWRGD_DSW_PWROK_R3     I1 @S9S_MB_2U_LIB.S9S_MB_2U(SCH_1):PAGE313
   T21 IRQ_PVCCIN_CPU0_VRHOT_R_N @S9S_MB_2U_LIB.S9S_MB_2U(SCH_1):IRQ_PVCCIN_CPU0_VRHOT_R_N     I1 @S9S_MB_2U_LIB.S9S_MB_2U(SCH_1):PAGE313
   P19 IRQ_PVCCIN_CPU1_VRHOT_R_N @S9S_MB_2U_LIB.S9S_MB_2U(SCH_1):IRQ_PVCCIN_CPU1_VRHOT_R_N     I1 @S9S_MB_2U_LIB.S9S_MB_2U(SCH_1):PAGE313
   P18 FM_RST_PERST_BIT0 @S9S_MB_2U_LIB.S9S_MB_2U(SCH_1):FM_RST_PERST_BIT0     I1 @S9S_MB_2U_LIB.S9S_MB_2U(SCH_1):PAGE313
   P17 FM_RST_PERST_BIT1 @S9S_MB_2U_LIB.S9S_MB_2U(SCH_1):FM_RST_PERST_BIT1     I1 @S9S_MB_2U_LIB.S9S_MB_2U(SCH_1):PAGE313
   P16 FM_CPU_RMCA_CATERR_DLY_LVT3_R_N @S9S_MB_2U_LIB.S9S_MB_2U(SCH_1):FM_CPU_RMCA_CATERR_DLY_LVT3_R_N     I1 @S9S_MB_2U_LIB.S9S_MB_2U(SCH_1):PAGE313
   U22 FM_JTAG_BMC_MUX_SEL_R @S9S_MB_2U_LIB.S9S_MB_2U(SCH_1):FM_JTAG_BMC_MUX_SEL_R     I1 @S9S_MB_2U_LIB.S9S_MB_2U(SCH_1):PAGE313
   U21 FM_SLPS4_PLD_N @S9S_MB_2U_LIB.S9S_MB_2U(SCH_1):FM_SLPS4_PLD_N     I1 @S9S_MB_2U_LIB.S9S_MB_2U(SCH_1):PAGE313
   R20 PWRGD_FAIL_CPU0_CD_R @S9S_MB_2U_LIB.S9S_MB_2U(SCH_1):PWRGD_FAIL_CPU0_CD_R     I1 @S9S_MB_2U_LIB.S9S_MB_2U(SCH_1):PAGE313
   R19 PWRGD_FAIL_CPU0_EF_R @S9S_MB_2U_LIB.S9S_MB_2U(SCH_1):PWRGD_FAIL_CPU0_EF_R     I1 @S9S_MB_2U_LIB.S9S_MB_2U(SCH_1):PAGE313
   R18 PWRGD_FAIL_CPU0_GH_R @S9S_MB_2U_LIB.S9S_MB_2U(SCH_1):PWRGD_FAIL_CPU0_GH_R     I1 @S9S_MB_2U_LIB.S9S_MB_2U(SCH_1):PAGE313
   R17 PWRGD_FAIL_CPU1_AB_R @S9S_MB_2U_LIB.S9S_MB_2U(SCH_1):PWRGD_FAIL_CPU1_AB_R     I1 @S9S_MB_2U_LIB.S9S_MB_2U(SCH_1):PAGE313
   R16 PWRGD_FAIL_CPU1_CD_R @S9S_MB_2U_LIB.S9S_MB_2U(SCH_1):PWRGD_FAIL_CPU1_CD_R     I1 @S9S_MB_2U_LIB.S9S_MB_2U(SCH_1):PAGE313
   T20 PWRGD_FAIL_CPU1_EF_R @S9S_MB_2U_LIB.S9S_MB_2U(SCH_1):PWRGD_FAIL_CPU1_EF_R     I1 @S9S_MB_2U_LIB.S9S_MB_2U(SCH_1):PAGE313
   T19 PWRGD_FAIL_CPU1_GH_R @S9S_MB_2U_LIB.S9S_MB_2U(SCH_1):PWRGD_FAIL_CPU1_GH_R     I1 @S9S_MB_2U_LIB.S9S_MB_2U(SCH_1):PAGE313
   T18 OCP_SFF_MAIN_PWR_EN @S9S_MB_2U_LIB.S9S_MB_2U(SCH_1):OCP_SFF_MAIN_PWR_EN     I1 @S9S_MB_2U_LIB.S9S_MB_2U(SCH_1):PAGE313
   T17 OCP_V3_2_MAIN_PWR_EN @S9S_MB_2U_LIB.S9S_MB_2U(SCH_1):OCP_V3_2_MAIN_PWR_EN     I1 @S9S_MB_2U_LIB.S9S_MB_2U(SCH_1):PAGE313
   U20 HP_LVC3_OCP_V3_2_HSC_PWRGD_PLD_ @S9S_MB_2U_LIB.S9S_MB_2U(SCH_1):HP_LVC3_OCP_V3_2_HSC_PWRGD_PLD_R     I1 @S9S_MB_2U_LIB.S9S_MB_2U(SCH_1):PAGE313
   Y22 HP_LVC3_OCP_V3_1_HSC_PWRGD_PLD_ @S9S_MB_2U_LIB.S9S_MB_2U(SCH_1):HP_LVC3_OCP_V3_1_HSC_PWRGD_PLD_R     I1 @S9S_MB_2U_LIB.S9S_MB_2U(SCH_1):PAGE313
   W21 FM_SMB_1_ALERT_GPU_ISO_R_N @S9S_MB_2U_LIB.S9S_MB_2U(SCH_1):FM_SMB_1_ALERT_GPU_ISO_R_N     I1 @S9S_MB_2U_LIB.S9S_MB_2U(SCH_1):PAGE313
   U19 FM_SMB_2_ALERT_GPU_ISO_R_N @S9S_MB_2U_LIB.S9S_MB_2U(SCH_1):FM_SMB_2_ALERT_GPU_ISO_R_N     I1 @S9S_MB_2U_LIB.S9S_MB_2U(SCH_1):PAGE313
   U18 E1S_0_LED_ACT_R_N @S9S_MB_2U_LIB.S9S_MB_2U(SCH_1):E1S_0_LED_ACT_R_N     I1 @S9S_MB_2U_LIB.S9S_MB_2U(SCH_1):PAGE313
   W19 RST_PERST_SWB_N @S9S_MB_2U_LIB.S9S_MB_2U(SCH_1):RST_PERST_SWB_N     I1 @S9S_MB_2U_LIB.S9S_MB_2U(SCH_1):PAGE313
   Y20 NC_FPGA_PR30D @S9S_MB_2U_LIB.S9S_MB_2U(SCH_1):NC_FPGA_PR30D     I1 @S9S_MB_2U_LIB.S9S_MB_2U(SCH_1):PAGE313

U252 74LVC2G17GW-74LVC2G17GW,SMLF,IA
     5 P3V3_AUX @S9S_MB_2U_LIB.S9S_MB_2U(SCH_1):P3V3_AUX   I153 @S9S_MB_2U_LIB.S9S_MB_2U(SCH_1):PAGE160
     4 RST_PERST_1_SWB_BUF_R_N @S9S_MB_2U_LIB.S9S_MB_2U(SCH_1):RST_PERST_1_SWB_BUF_R_N   I153 @S9S_MB_2U_LIB.S9S_MB_2U(SCH_1):PAGE160
     2    GND @S9S_MB_2U_LIB.S9S_MB_2U(SCH_1):GND   I153 @S9S_MB_2U_LIB.S9S_MB_2U(SCH_1):PAGE160
     1 RST_PERST_SWB_R_N @S9S_MB_2U_LIB.S9S_MB_2U(SCH_1):RST_PERST_SWB_R_N   I153 @S9S_MB_2U_LIB.S9S_MB_2U(SCH_1):PAGE160
     3 RST_PERST_SWB_R_N @S9S_MB_2U_LIB.S9S_MB_2U(SCH_1):RST_PERST_SWB_R_N   I153 @S9S_MB_2U_LIB.S9S_MB_2U(SCH_1):PAGE160
     6 RST_PERST_0_SWB_BUF_R_N @S9S_MB_2U_LIB.S9S_MB_2U(SCH_1):RST_PERST_0_SWB_BUF_R_N   I153 @S9S_MB_2U_LIB.S9S_MB_2U(SCH_1):PAGE160

U253 74LVC2G17GW-74LVC2G17GW,SMLF,IA
     5 P3V3_AUX @S9S_MB_2U_LIB.S9S_MB_2U(SCH_1):P3V3_AUX    I26 @S9S_MB_2U_LIB.S9S_MB_2U(SCH_1):PAGE160
     4 GPU_BASE_STBY_EN_BUF_R @S9S_MB_2U_LIB.S9S_MB_2U(SCH_1):GPU_BASE_STBY_EN_BUF_R    I26 @S9S_MB_2U_LIB.S9S_MB_2U(SCH_1):PAGE160
     2    GND @S9S_MB_2U_LIB.S9S_MB_2U(SCH_1):GND    I26 @S9S_MB_2U_LIB.S9S_MB_2U(SCH_1):PAGE160
     1 GPU_FPGA_BOOT_EN @S9S_MB_2U_LIB.S9S_MB_2U(SCH_1):GPU_FPGA_BOOT_EN    I26 @S9S_MB_2U_LIB.S9S_MB_2U(SCH_1):PAGE160
     3 GPU_BASE_STBY_EN @S9S_MB_2U_LIB.S9S_MB_2U(SCH_1):GPU_BASE_STBY_EN    I26 @S9S_MB_2U_LIB.S9S_MB_2U(SCH_1):PAGE160
     6 GPU_FPGA_BOOT_EN_BUF_R @S9S_MB_2U_LIB.S9S_MB_2U(SCH_1):GPU_FPGA_BOOT_EN_BUF_R    I26 @S9S_MB_2U_LIB.S9S_MB_2U(SCH_1):PAGE160

U255 74LVC2G07DW7-74LVC2G07DW-7,SMLA
     1 GPU_NVS_PWR_BRAKE_N @S9S_MB_2U_LIB.S9S_MB_2U(SCH_1):GPU_NVS_PWR_BRAKE_N    I16 @S9S_MB_2U_LIB.S9S_MB_2U(SCH_1):PAGE296
     3 GPU_FPGA_EROT_RST_N @S9S_MB_2U_LIB.S9S_MB_2U(SCH_1):GPU_FPGA_EROT_RST_N    I16 @S9S_MB_2U_LIB.S9S_MB_2U(SCH_1):PAGE296
     6 GPU_NVS_PWR_BRAKE_N_R @S9S_MB_2U_LIB.S9S_MB_2U(SCH_1):GPU_NVS_PWR_BRAKE_N_R    I16 @S9S_MB_2U_LIB.S9S_MB_2U(SCH_1):PAGE296
     4 GPU_FPGA_EROT_RST_BUF_R_N @S9S_MB_2U_LIB.S9S_MB_2U(SCH_1):GPU_FPGA_EROT_RST_BUF_R_N    I16 @S9S_MB_2U_LIB.S9S_MB_2U(SCH_1):PAGE296
     2    GND @S9S_MB_2U_LIB.S9S_MB_2U(SCH_1):GND    I16 @S9S_MB_2U_LIB.S9S_MB_2U(SCH_1):PAGE296
     5 P3V3_AUX @S9S_MB_2U_LIB.S9S_MB_2U(SCH_1):P3V3_AUX    I16 @S9S_MB_2U_LIB.S9S_MB_2U(SCH_1):PAGE296

U256 74LVC2G17GW-74LVC2G17GW,SMLF,IA
     5 P3V3_AUX @S9S_MB_2U_LIB.S9S_MB_2U(SCH_1):P3V3_AUX   I173 @S9S_MB_2U_LIB.S9S_MB_2U(SCH_1):PAGE160
     4 FM_SWB_PWR_EN_R1_BUF @S9S_MB_2U_LIB.S9S_MB_2U(SCH_1):FM_SWB_PWR_EN_R1_BUF   I173 @S9S_MB_2U_LIB.S9S_MB_2U(SCH_1):PAGE160
     2    GND @S9S_MB_2U_LIB.S9S_MB_2U(SCH_1):GND   I173 @S9S_MB_2U_LIB.S9S_MB_2U(SCH_1):PAGE160
     1 RST_PERST_SWB_R_N @S9S_MB_2U_LIB.S9S_MB_2U(SCH_1):RST_PERST_SWB_R_N   I173 @S9S_MB_2U_LIB.S9S_MB_2U(SCH_1):PAGE160
     3 FM_SWB_PWR_EN_R @S9S_MB_2U_LIB.S9S_MB_2U(SCH_1):FM_SWB_PWR_EN_R   I173 @S9S_MB_2U_LIB.S9S_MB_2U(SCH_1):PAGE160
     6 RST_PERST_2_SWB_BUF_R_N @S9S_MB_2U_LIB.S9S_MB_2U(SCH_1):RST_PERST_2_SWB_BUF_R_N   I173 @S9S_MB_2U_LIB.S9S_MB_2U(SCH_1):PAGE160

U257 74LVC2G07DW7-74LVC2G07DW-7,SMLA
     1 GPU_FPGA_EROT_RECOV_N @S9S_MB_2U_LIB.S9S_MB_2U(SCH_1):GPU_FPGA_EROT_RECOV_N    I50 @S9S_MB_2U_LIB.S9S_MB_2U(SCH_1):PAGE296
     3    GND @S9S_MB_2U_LIB.S9S_MB_2U(SCH_1):GND    I50 @S9S_MB_2U_LIB.S9S_MB_2U(SCH_1):PAGE296
     6 GPU_FPGA_EROT_RECOV_BUF_R_N @S9S_MB_2U_LIB.S9S_MB_2U(SCH_1):GPU_FPGA_EROT_RECOV_BUF_R_N    I50 @S9S_MB_2U_LIB.S9S_MB_2U(SCH_1):PAGE296
     4 NC_U257_2Y @S9S_MB_2U_LIB.S9S_MB_2U(SCH_1):NC_U257_2Y    I50 @S9S_MB_2U_LIB.S9S_MB_2U(SCH_1):PAGE296
     2    GND @S9S_MB_2U_LIB.S9S_MB_2U(SCH_1):GND    I50 @S9S_MB_2U_LIB.S9S_MB_2U(SCH_1):PAGE296
     5 P3V3_AUX @S9S_MB_2U_LIB.S9S_MB_2U(SCH_1):P3V3_AUX    I50 @S9S_MB_2U_LIB.S9S_MB_2U(SCH_1):PAGE296

U259 SN74LVC2G07DCKR_SMLF-SN74LVC2GA
     1 M2_SSD0_CLKREQ_EN_N @S9S_MB_2U_LIB.S9S_MB_2U(SCH_1):M2_SSD0_CLKREQ_EN_N   I327 @S9S_MB_2U_LIB.S9S_MB_2U(SCH_1):PAGE182
     3 RST_PCIE_PCH_DEV_PERST_M2_R_N @S9S_MB_2U_LIB.S9S_MB_2U(SCH_1):RST_PCIE_PCH_DEV_PERST_M2_R_N   I327 @S9S_MB_2U_LIB.S9S_MB_2U(SCH_1):PAGE182
     6 HDD_ACTIVITY_BUF @S9S_MB_2U_LIB.S9S_MB_2U(SCH_1):HDD_ACTIVITY_BUF   I327 @S9S_MB_2U_LIB.S9S_MB_2U(SCH_1):PAGE182
     4 RST_PCIE_PCH_DEV_BUF_M2_0_PERST @S9S_MB_2U_LIB.S9S_MB_2U(SCH_1):RST_PCIE_PCH_DEV_BUF_M2_0_PERST_N   I327 @S9S_MB_2U_LIB.S9S_MB_2U(SCH_1):PAGE182
     2    GND @S9S_MB_2U_LIB.S9S_MB_2U(SCH_1):GND   I327 @S9S_MB_2U_LIB.S9S_MB_2U(SCH_1):PAGE182
     5 P3V3_AUX @S9S_MB_2U_LIB.S9S_MB_2U(SCH_1):P3V3_AUX   I327 @S9S_MB_2U_LIB.S9S_MB_2U(SCH_1):PAGE182

U263 INA230AIRGTR-INA230AIRGTR,SMLFB
     9 P3V3_AUX @S9S_MB_2U_LIB.S9S_MB_2U(SCH_1):P3V3_AUX    I94 @S9S_MB_2U_LIB.S9S_MB_2U(SCH_1):PAGE163
     1 INA230_3_A1 @S9S_MB_2U_LIB.S9S_MB_2U(SCH_1):INA230_3_A1    I94 @S9S_MB_2U_LIB.S9S_MB_2U(SCH_1):PAGE163
     2 INA230_3_A0 @S9S_MB_2U_LIB.S9S_MB_2U(SCH_1):INA230_3_A0    I94 @S9S_MB_2U_LIB.S9S_MB_2U(SCH_1):PAGE163
     5 SMB_INA230_3_3V3AUX_SCL_R1 @S9S_MB_2U_LIB.S9S_MB_2U(SCH_1):SMB_INA230_3_3V3AUX_SCL_R1    I94 @S9S_MB_2U_LIB.S9S_MB_2U(SCH_1):PAGE163
     4 SMB_INA230_3_3V3AUX_SDA_R1 @S9S_MB_2U_LIB.S9S_MB_2U(SCH_1):SMB_INA230_3_3V3AUX_SDA_R1    I94 @S9S_MB_2U_LIB.S9S_MB_2U(SCH_1):PAGE163
    11 P3V3_OCP_V3_2_R @S9S_MB_2U_LIB.S9S_MB_2U(SCH_1):P3V3_OCP_V3_2_R    I94 @S9S_MB_2U_LIB.S9S_MB_2U(SCH_1):PAGE163
    13 VSENSE_P12V_INA230_3_INP @S9S_MB_2U_LIB.S9S_MB_2U(SCH_1):VSENSE_P12V_INA230_3_INP    I94 @S9S_MB_2U_LIB.S9S_MB_2U(SCH_1):PAGE163
    12 VSENSE_P12V_INA230_3_INN @S9S_MB_2U_LIB.S9S_MB_2U(SCH_1):VSENSE_P12V_INA230_3_INN    I94 @S9S_MB_2U_LIB.S9S_MB_2U(SCH_1):PAGE163
     3 OCP_V3_2_P3V3_ADC_ALERT_R @S9S_MB_2U_LIB.S9S_MB_2U(SCH_1):OCP_V3_2_P3V3_ADC_ALERT_R    I94 @S9S_MB_2U_LIB.S9S_MB_2U(SCH_1):PAGE163
     6 NC_INA230_3_NC0 @S9S_MB_2U_LIB.S9S_MB_2U(SCH_1):NC_INA230_3_NC0    I94 @S9S_MB_2U_LIB.S9S_MB_2U(SCH_1):PAGE163
     7 NC_INA230_3_NC1 @S9S_MB_2U_LIB.S9S_MB_2U(SCH_1):NC_INA230_3_NC1    I94 @S9S_MB_2U_LIB.S9S_MB_2U(SCH_1):PAGE163
     8 NC_INA230_3_NC2 @S9S_MB_2U_LIB.S9S_MB_2U(SCH_1):NC_INA230_3_NC2    I94 @S9S_MB_2U_LIB.S9S_MB_2U(SCH_1):PAGE163
    14 NC_INA230_3_NC3 @S9S_MB_2U_LIB.S9S_MB_2U(SCH_1):NC_INA230_3_NC3    I94 @S9S_MB_2U_LIB.S9S_MB_2U(SCH_1):PAGE163
    15 NC_INA230_3_NC4 @S9S_MB_2U_LIB.S9S_MB_2U(SCH_1):NC_INA230_3_NC4    I94 @S9S_MB_2U_LIB.S9S_MB_2U(SCH_1):PAGE163
    16 NC_INA230_3_NC5 @S9S_MB_2U_LIB.S9S_MB_2U(SCH_1):NC_INA230_3_NC5    I94 @S9S_MB_2U_LIB.S9S_MB_2U(SCH_1):PAGE163
    10    GND @S9S_MB_2U_LIB.S9S_MB_2U(SCH_1):GND    I94 @S9S_MB_2U_LIB.S9S_MB_2U(SCH_1):PAGE163
    TH    GND @S9S_MB_2U_LIB.S9S_MB_2U(SCH_1):GND    I94 @S9S_MB_2U_LIB.S9S_MB_2U(SCH_1):PAGE163

U264 INA230AIRGTR-INA230AIRGTR,SMLFB
     9 P3V3_AUX @S9S_MB_2U_LIB.S9S_MB_2U(SCH_1):P3V3_AUX    I46 @S9S_MB_2U_LIB.S9S_MB_2U(SCH_1):PAGE163
     1 INA230_4_A1 @S9S_MB_2U_LIB.S9S_MB_2U(SCH_1):INA230_4_A1    I46 @S9S_MB_2U_LIB.S9S_MB_2U(SCH_1):PAGE163
     2 INA230_4_A0 @S9S_MB_2U_LIB.S9S_MB_2U(SCH_1):INA230_4_A0    I46 @S9S_MB_2U_LIB.S9S_MB_2U(SCH_1):PAGE163
     5 SMB_INA230_4_3V3AUX_SCL_R1 @S9S_MB_2U_LIB.S9S_MB_2U(SCH_1):SMB_INA230_4_3V3AUX_SCL_R1    I46 @S9S_MB_2U_LIB.S9S_MB_2U(SCH_1):PAGE163
     4 SMB_INA230_4_3V3AUX_SDA_R1 @S9S_MB_2U_LIB.S9S_MB_2U(SCH_1):SMB_INA230_4_3V3AUX_SDA_R1    I46 @S9S_MB_2U_LIB.S9S_MB_2U(SCH_1):PAGE163
    11   P3V3 @S9S_MB_2U_LIB.S9S_MB_2U(SCH_1):P3V3    I46 @S9S_MB_2U_LIB.S9S_MB_2U(SCH_1):PAGE163
    13 VSENSE_P12V_INA230_4_INP @S9S_MB_2U_LIB.S9S_MB_2U(SCH_1):VSENSE_P12V_INA230_4_INP    I46 @S9S_MB_2U_LIB.S9S_MB_2U(SCH_1):PAGE163
    12 VSENSE_P12V_INA230_4_INN @S9S_MB_2U_LIB.S9S_MB_2U(SCH_1):VSENSE_P12V_INA230_4_INN    I46 @S9S_MB_2U_LIB.S9S_MB_2U(SCH_1):PAGE163
     3 M2_0_P3V3_ADC_ALERT_R @S9S_MB_2U_LIB.S9S_MB_2U(SCH_1):M2_0_P3V3_ADC_ALERT_R    I46 @S9S_MB_2U_LIB.S9S_MB_2U(SCH_1):PAGE163
     6 NC_INA230_4_NC0 @S9S_MB_2U_LIB.S9S_MB_2U(SCH_1):NC_INA230_4_NC0    I46 @S9S_MB_2U_LIB.S9S_MB_2U(SCH_1):PAGE163
     7 NC_INA230_4_NC1 @S9S_MB_2U_LIB.S9S_MB_2U(SCH_1):NC_INA230_4_NC1    I46 @S9S_MB_2U_LIB.S9S_MB_2U(SCH_1):PAGE163
     8 NC_INA230_4_NC2 @S9S_MB_2U_LIB.S9S_MB_2U(SCH_1):NC_INA230_4_NC2    I46 @S9S_MB_2U_LIB.S9S_MB_2U(SCH_1):PAGE163
    14 NC_INA230_4_NC3 @S9S_MB_2U_LIB.S9S_MB_2U(SCH_1):NC_INA230_4_NC3    I46 @S9S_MB_2U_LIB.S9S_MB_2U(SCH_1):PAGE163
    15 NC_INA230_4_NC4 @S9S_MB_2U_LIB.S9S_MB_2U(SCH_1):NC_INA230_4_NC4    I46 @S9S_MB_2U_LIB.S9S_MB_2U(SCH_1):PAGE163
    16 NC_INA230_4_NC5 @S9S_MB_2U_LIB.S9S_MB_2U(SCH_1):NC_INA230_4_NC5    I46 @S9S_MB_2U_LIB.S9S_MB_2U(SCH_1):PAGE163
    10    GND @S9S_MB_2U_LIB.S9S_MB_2U(SCH_1):GND    I46 @S9S_MB_2U_LIB.S9S_MB_2U(SCH_1):PAGE163
    TH    GND @S9S_MB_2U_LIB.S9S_MB_2U(SCH_1):GND    I46 @S9S_MB_2U_LIB.S9S_MB_2U(SCH_1):PAGE163

U265 INA230AIRGTR-INA230AIRGTR,SMLFB
     9 P3V3_AUX @S9S_MB_2U_LIB.S9S_MB_2U(SCH_1):P3V3_AUX    I69 @S9S_MB_2U_LIB.S9S_MB_2U(SCH_1):PAGE163
     1 INA230_5_A1 @S9S_MB_2U_LIB.S9S_MB_2U(SCH_1):INA230_5_A1    I69 @S9S_MB_2U_LIB.S9S_MB_2U(SCH_1):PAGE163
     2 INA230_5_A0 @S9S_MB_2U_LIB.S9S_MB_2U(SCH_1):INA230_5_A0    I69 @S9S_MB_2U_LIB.S9S_MB_2U(SCH_1):PAGE163
     5 SMB_INA230_5_3V3AUX_SCL_R1 @S9S_MB_2U_LIB.S9S_MB_2U(SCH_1):SMB_INA230_5_3V3AUX_SCL_R1    I69 @S9S_MB_2U_LIB.S9S_MB_2U(SCH_1):PAGE163
     4 SMB_INA230_5_3V3AUX_SDA_R1 @S9S_MB_2U_LIB.S9S_MB_2U(SCH_1):SMB_INA230_5_3V3AUX_SDA_R1    I69 @S9S_MB_2U_LIB.S9S_MB_2U(SCH_1):PAGE163
    11 P12V_SCM_R @S9S_MB_2U_LIB.S9S_MB_2U(SCH_1):P12V_SCM_R    I69 @S9S_MB_2U_LIB.S9S_MB_2U(SCH_1):PAGE163
    13 VSENSE_P12V_INA230_5_INP @S9S_MB_2U_LIB.S9S_MB_2U(SCH_1):VSENSE_P12V_INA230_5_INP    I69 @S9S_MB_2U_LIB.S9S_MB_2U(SCH_1):PAGE163
    12 VSENSE_P12V_INA230_5_INN @S9S_MB_2U_LIB.S9S_MB_2U(SCH_1):VSENSE_P12V_INA230_5_INN    I69 @S9S_MB_2U_LIB.S9S_MB_2U(SCH_1):PAGE163
     3 P12V_SCM_ADC_ALERT_R @S9S_MB_2U_LIB.S9S_MB_2U(SCH_1):P12V_SCM_ADC_ALERT_R    I69 @S9S_MB_2U_LIB.S9S_MB_2U(SCH_1):PAGE163
     6 NC_INA230_5_NC0 @S9S_MB_2U_LIB.S9S_MB_2U(SCH_1):NC_INA230_5_NC0    I69 @S9S_MB_2U_LIB.S9S_MB_2U(SCH_1):PAGE163
     7 NC_INA230_5_NC1 @S9S_MB_2U_LIB.S9S_MB_2U(SCH_1):NC_INA230_5_NC1    I69 @S9S_MB_2U_LIB.S9S_MB_2U(SCH_1):PAGE163
     8 NC_INA230_5_NC2 @S9S_MB_2U_LIB.S9S_MB_2U(SCH_1):NC_INA230_5_NC2    I69 @S9S_MB_2U_LIB.S9S_MB_2U(SCH_1):PAGE163
    14 NC_INA230_5_NC3 @S9S_MB_2U_LIB.S9S_MB_2U(SCH_1):NC_INA230_5_NC3    I69 @S9S_MB_2U_LIB.S9S_MB_2U(SCH_1):PAGE163
    15 NC_INA230_5_NC4 @S9S_MB_2U_LIB.S9S_MB_2U(SCH_1):NC_INA230_5_NC4    I69 @S9S_MB_2U_LIB.S9S_MB_2U(SCH_1):PAGE163
    16 NC_INA230_5_NC5 @S9S_MB_2U_LIB.S9S_MB_2U(SCH_1):NC_INA230_5_NC5    I69 @S9S_MB_2U_LIB.S9S_MB_2U(SCH_1):PAGE163
    10    GND @S9S_MB_2U_LIB.S9S_MB_2U(SCH_1):GND    I69 @S9S_MB_2U_LIB.S9S_MB_2U(SCH_1):PAGE163
    TH    GND @S9S_MB_2U_LIB.S9S_MB_2U(SCH_1):GND    I69 @S9S_MB_2U_LIB.S9S_MB_2U(SCH_1):PAGE163

U266 INA230AIRGTR-INA230AIRGTR,SMLFB
     9 P3V3_AUX @S9S_MB_2U_LIB.S9S_MB_2U(SCH_1):P3V3_AUX    I30 @S9S_MB_2U_LIB.S9S_MB_2U(SCH_1):PAGE295
     1 INA230_1_A1 @S9S_MB_2U_LIB.S9S_MB_2U(SCH_1):INA230_1_A1    I30 @S9S_MB_2U_LIB.S9S_MB_2U(SCH_1):PAGE295
     2 INA230_1_A0 @S9S_MB_2U_LIB.S9S_MB_2U(SCH_1):INA230_1_A0    I30 @S9S_MB_2U_LIB.S9S_MB_2U(SCH_1):PAGE295
     5 SMB_INA230_1_3V3AUX_SCL_R1 @S9S_MB_2U_LIB.S9S_MB_2U(SCH_1):SMB_INA230_1_3V3AUX_SCL_R1    I30 @S9S_MB_2U_LIB.S9S_MB_2U(SCH_1):PAGE295
     4 SMB_INA230_1_3V3AUX_SDA_R1 @S9S_MB_2U_LIB.S9S_MB_2U(SCH_1):SMB_INA230_1_3V3AUX_SDA_R1    I30 @S9S_MB_2U_LIB.S9S_MB_2U(SCH_1):PAGE295
    11 P3V3_OCP_SFF_R @S9S_MB_2U_LIB.S9S_MB_2U(SCH_1):P3V3_OCP_SFF_R    I30 @S9S_MB_2U_LIB.S9S_MB_2U(SCH_1):PAGE295
    13 VSENSE_P3V3_INA230_1_INP @S9S_MB_2U_LIB.S9S_MB_2U(SCH_1):VSENSE_P3V3_INA230_1_INP    I30 @S9S_MB_2U_LIB.S9S_MB_2U(SCH_1):PAGE295
    12 VSENSE_P3V3_INA230_1_INN @S9S_MB_2U_LIB.S9S_MB_2U(SCH_1):VSENSE_P3V3_INA230_1_INN    I30 @S9S_MB_2U_LIB.S9S_MB_2U(SCH_1):PAGE295
     3 OCP_SFF_P3V3_ADC_ALERT_R @S9S_MB_2U_LIB.S9S_MB_2U(SCH_1):OCP_SFF_P3V3_ADC_ALERT_R    I30 @S9S_MB_2U_LIB.S9S_MB_2U(SCH_1):PAGE295
     6 NC_INA230_1_NC0 @S9S_MB_2U_LIB.S9S_MB_2U(SCH_1):NC_INA230_1_NC0    I30 @S9S_MB_2U_LIB.S9S_MB_2U(SCH_1):PAGE295
     7 NC_INA230_1_NC1 @S9S_MB_2U_LIB.S9S_MB_2U(SCH_1):NC_INA230_1_NC1    I30 @S9S_MB_2U_LIB.S9S_MB_2U(SCH_1):PAGE295
     8 NC_INA230_1_NC2 @S9S_MB_2U_LIB.S9S_MB_2U(SCH_1):NC_INA230_1_NC2    I30 @S9S_MB_2U_LIB.S9S_MB_2U(SCH_1):PAGE295
    14 NC_INA230_1_NC3 @S9S_MB_2U_LIB.S9S_MB_2U(SCH_1):NC_INA230_1_NC3    I30 @S9S_MB_2U_LIB.S9S_MB_2U(SCH_1):PAGE295
    15 NC_INA230_1_NC4 @S9S_MB_2U_LIB.S9S_MB_2U(SCH_1):NC_INA230_1_NC4    I30 @S9S_MB_2U_LIB.S9S_MB_2U(SCH_1):PAGE295
    16 NC_INA230_1_NC5 @S9S_MB_2U_LIB.S9S_MB_2U(SCH_1):NC_INA230_1_NC5    I30 @S9S_MB_2U_LIB.S9S_MB_2U(SCH_1):PAGE295
    10    GND @S9S_MB_2U_LIB.S9S_MB_2U(SCH_1):GND    I30 @S9S_MB_2U_LIB.S9S_MB_2U(SCH_1):PAGE295
    TH    GND @S9S_MB_2U_LIB.S9S_MB_2U(SCH_1):GND    I30 @S9S_MB_2U_LIB.S9S_MB_2U(SCH_1):PAGE295

U268 GL852GOHY60-GL852G-OHY60,SMLF,A
    10 USB_HUB_XTAL_IN @S9S_MB_2U_LIB.S9S_MB_2U(SCH_1):USB_HUB_XTAL_IN   I100 @S9S_MB_2U_LIB.S9S_MB_2U(SCH_1):PAGE155
    11 USB_HUB_XTAL_OUT @S9S_MB_2U_LIB.S9S_MB_2U(SCH_1):USB_HUB_XTAL_OUT   I100 @S9S_MB_2U_LIB.S9S_MB_2U(SCH_1):PAGE155
    18 USB_HUB_TEST @S9S_MB_2U_LIB.S9S_MB_2U(SCH_1):USB_HUB_TEST   I100 @S9S_MB_2U_LIB.S9S_MB_2U(SCH_1):PAGE155
    26 NC_USB_HUB_SDA @S9S_MB_2U_LIB.S9S_MB_2U(SCH_1):NC_USB_HUB_SDA   I100 @S9S_MB_2U_LIB.S9S_MB_2U(SCH_1):PAGE155
    27 P3V3_AUX_USB_HUB @S9S_MB_2U_LIB.S9S_MB_2U(SCH_1):P3V3_AUX_USB_HUB   I100 @S9S_MB_2U_LIB.S9S_MB_2U(SCH_1):PAGE155
    28 P3V3_AUX_USB_HUB @S9S_MB_2U_LIB.S9S_MB_2U(SCH_1):P3V3_AUX_USB_HUB   I100 @S9S_MB_2U_LIB.S9S_MB_2U(SCH_1):PAGE155
     5 P3V3_AUX_USB_HUB @S9S_MB_2U_LIB.S9S_MB_2U(SCH_1):P3V3_AUX_USB_HUB   I100 @S9S_MB_2U_LIB.S9S_MB_2U(SCH_1):PAGE155
     9 P3V3_AUX_USB_HUB @S9S_MB_2U_LIB.S9S_MB_2U(SCH_1):P3V3_AUX_USB_HUB   I100 @S9S_MB_2U_LIB.S9S_MB_2U(SCH_1):PAGE155
    14 P3V3_AUX_USB_HUB @S9S_MB_2U_LIB.S9S_MB_2U(SCH_1):P3V3_AUX_USB_HUB   I100 @S9S_MB_2U_LIB.S9S_MB_2U(SCH_1):PAGE155
    21 USB_HUB_DVDD @S9S_MB_2U_LIB.S9S_MB_2U(SCH_1):USB_HUB_DVDD   I100 @S9S_MB_2U_LIB.S9S_MB_2U(SCH_1):PAGE155
    TH    GND @S9S_MB_2U_LIB.S9S_MB_2U(SCH_1):GND   I100 @S9S_MB_2U_LIB.S9S_MB_2U(SCH_1):PAGE155
    25 USB_HUB_OVCUR1 @S9S_MB_2U_LIB.S9S_MB_2U(SCH_1):USB_HUB_OVCUR1   I100 @S9S_MB_2U_LIB.S9S_MB_2U(SCH_1):PAGE155
    24 USB_HUB_OVCUR2 @S9S_MB_2U_LIB.S9S_MB_2U(SCH_1):USB_HUB_OVCUR2   I100 @S9S_MB_2U_LIB.S9S_MB_2U(SCH_1):PAGE155
    20 USB_HUB_OVCUR3 @S9S_MB_2U_LIB.S9S_MB_2U(SCH_1):USB_HUB_OVCUR3   I100 @S9S_MB_2U_LIB.S9S_MB_2U(SCH_1):PAGE155
    19 USB_HUB_OVCUR4 @S9S_MB_2U_LIB.S9S_MB_2U(SCH_1):USB_HUB_OVCUR4   I100 @S9S_MB_2U_LIB.S9S_MB_2U(SCH_1):PAGE155
    17 RST_USB_HUB_R_N @S9S_MB_2U_LIB.S9S_MB_2U(SCH_1):RST_USB_HUB_R_N   I100 @S9S_MB_2U_LIB.S9S_MB_2U(SCH_1):PAGE155
    23 USB_HUB_PGANG @S9S_MB_2U_LIB.S9S_MB_2U(SCH_1):USB_HUB_PGANG   I100 @S9S_MB_2U_LIB.S9S_MB_2U(SCH_1):PAGE155
    22 USB_HUB_PSELF @S9S_MB_2U_LIB.S9S_MB_2U(SCH_1):USB_HUB_PSELF   I100 @S9S_MB_2U_LIB.S9S_MB_2U(SCH_1):PAGE155
     8 USB_HUB_RREF @S9S_MB_2U_LIB.S9S_MB_2U(SCH_1):USB_HUB_RREF   I100 @S9S_MB_2U_LIB.S9S_MB_2U(SCH_1):PAGE155
     2 USB2_P0_R_DP @S9S_MB_2U_LIB.S9S_MB_2U(SCH_1):USB2_P0_R_DP   I100 @S9S_MB_2U_LIB.S9S_MB_2U(SCH_1):PAGE155
     1 USB2_P0_R_DN @S9S_MB_2U_LIB.S9S_MB_2U(SCH_1):USB2_P0_R_DN   I100 @S9S_MB_2U_LIB.S9S_MB_2U(SCH_1):PAGE155
     4 USB2_HUB_SWB_DP @S9S_MB_2U_LIB.S9S_MB_2U(SCH_1):USB2_HUB_SWB_DP   I100 @S9S_MB_2U_LIB.S9S_MB_2U(SCH_1):PAGE155
     3 USB2_HUB_SWB_DN @S9S_MB_2U_LIB.S9S_MB_2U(SCH_1):USB2_HUB_SWB_DN   I100 @S9S_MB_2U_LIB.S9S_MB_2U(SCH_1):PAGE155
     7 NC_USB_HUB_DP2 @S9S_MB_2U_LIB.S9S_MB_2U(SCH_1):NC_USB_HUB_DP2   I100 @S9S_MB_2U_LIB.S9S_MB_2U(SCH_1):PAGE155
     6 NC_USB_HUB_DM2 @S9S_MB_2U_LIB.S9S_MB_2U(SCH_1):NC_USB_HUB_DM2   I100 @S9S_MB_2U_LIB.S9S_MB_2U(SCH_1):PAGE155
    13 NC_USB_HUB_DP3 @S9S_MB_2U_LIB.S9S_MB_2U(SCH_1):NC_USB_HUB_DP3   I100 @S9S_MB_2U_LIB.S9S_MB_2U(SCH_1):PAGE155
    12 NC_USB_HUB_DM3 @S9S_MB_2U_LIB.S9S_MB_2U(SCH_1):NC_USB_HUB_DM3   I100 @S9S_MB_2U_LIB.S9S_MB_2U(SCH_1):PAGE155
    16 NC_USB_HUB_DP4 @S9S_MB_2U_LIB.S9S_MB_2U(SCH_1):NC_USB_HUB_DP4   I100 @S9S_MB_2U_LIB.S9S_MB_2U(SCH_1):PAGE155
    15 NC_USB_HUB_DM4 @S9S_MB_2U_LIB.S9S_MB_2U(SCH_1):NC_USB_HUB_DM4   I100 @S9S_MB_2U_LIB.S9S_MB_2U(SCH_1):PAGE155

U269 ADC128D818CIMTXNOPB-ADC128D818A
     1 ADC128_VREF @S9S_MB_2U_LIB.S9S_MB_2U(SCH_1):ADC128_VREF   I103 @S9S_MB_2U_LIB.S9S_MB_2U(SCH_1):PAGE239
     5 P3V3_ADC128_VCC @S9S_MB_2U_LIB.S9S_MB_2U(SCH_1):P3V3_ADC128_VCC   I103 @S9S_MB_2U_LIB.S9S_MB_2U(SCH_1):PAGE239
     7 ADC128_A0 @S9S_MB_2U_LIB.S9S_MB_2U(SCH_1):ADC128_A0   I103 @S9S_MB_2U_LIB.S9S_MB_2U(SCH_1):PAGE239
     8 ADC128_A1 @S9S_MB_2U_LIB.S9S_MB_2U(SCH_1):ADC128_A1   I103 @S9S_MB_2U_LIB.S9S_MB_2U(SCH_1):PAGE239
     9 P12V_E1S_0_ISENSE_TIC @S9S_MB_2U_LIB.S9S_MB_2U(SCH_1):P12V_E1S_0_ISENSE_TIC   I103 @S9S_MB_2U_LIB.S9S_MB_2U(SCH_1):PAGE239
    10 P3V3_PDB_AUX_ADC_TIC @S9S_MB_2U_LIB.S9S_MB_2U(SCH_1):P3V3_PDB_AUX_ADC_TIC   I103 @S9S_MB_2U_LIB.S9S_MB_2U(SCH_1):PAGE239
    11 P3V3_AUX_ADC_TIC @S9S_MB_2U_LIB.S9S_MB_2U(SCH_1):P3V3_AUX_ADC_TIC   I103 @S9S_MB_2U_LIB.S9S_MB_2U(SCH_1):PAGE239
    12 P3V3_ADC_TIC @S9S_MB_2U_LIB.S9S_MB_2U(SCH_1):P3V3_ADC_TIC   I103 @S9S_MB_2U_LIB.S9S_MB_2U(SCH_1):PAGE239
    13 P5V_ADC_TIC @S9S_MB_2U_LIB.S9S_MB_2U(SCH_1):P5V_ADC_TIC   I103 @S9S_MB_2U_LIB.S9S_MB_2U(SCH_1):PAGE239
    14 P12V_OCP_V3_2_ISENSE_TIC @S9S_MB_2U_LIB.S9S_MB_2U(SCH_1):P12V_OCP_V3_2_ISENSE_TIC   I103 @S9S_MB_2U_LIB.S9S_MB_2U(SCH_1):PAGE239
    15 P12V_OCP_SFF_ISENSE_TIC @S9S_MB_2U_LIB.S9S_MB_2U(SCH_1):P12V_OCP_SFF_ISENSE_TIC   I103 @S9S_MB_2U_LIB.S9S_MB_2U(SCH_1):PAGE239
    16 P12V_AUX_ADC_TIC @S9S_MB_2U_LIB.S9S_MB_2U(SCH_1):P12V_AUX_ADC_TIC   I103 @S9S_MB_2U_LIB.S9S_MB_2U(SCH_1):PAGE239
     2 SMB_SEN_TIC_3V3AUX_SDA @S9S_MB_2U_LIB.S9S_MB_2U(SCH_1):SMB_SEN_TIC_3V3AUX_SDA   I103 @S9S_MB_2U_LIB.S9S_MB_2U(SCH_1):PAGE239
     3 SMB_SEN_TIC_3V3AUX_SCL @S9S_MB_2U_LIB.S9S_MB_2U(SCH_1):SMB_SEN_TIC_3V3AUX_SCL   I103 @S9S_MB_2U_LIB.S9S_MB_2U(SCH_1):PAGE239
     4    GND @S9S_MB_2U_LIB.S9S_MB_2U(SCH_1):GND   I103 @S9S_MB_2U_LIB.S9S_MB_2U(SCH_1):PAGE239
     6 TP_ADC128_INT @S9S_MB_2U_LIB.S9S_MB_2U(SCH_1):TP_ADC128_INT   I103 @S9S_MB_2U_LIB.S9S_MB_2U(SCH_1):PAGE239

U270 LM75BD-LM75BD,SMLF,IC,AL0075BDA
     1 SMB_LM75_0_3V3AUX_SDA_R1 @S9S_MB_2U_LIB.S9S_MB_2U(SCH_1):SMB_LM75_0_3V3AUX_SDA_R1   I164 @S9S_MB_2U_LIB.S9S_MB_2U(SCH_1):PAGE161
     2 SMB_LM75_0_3V3AUX_SCL_R1 @S9S_MB_2U_LIB.S9S_MB_2U(SCH_1):SMB_LM75_0_3V3AUX_SCL_R1   I164 @S9S_MB_2U_LIB.S9S_MB_2U(SCH_1):PAGE161
     3 FM_G751_0_ALERT_N @S9S_MB_2U_LIB.S9S_MB_2U(SCH_1):FM_G751_0_ALERT_N   I164 @S9S_MB_2U_LIB.S9S_MB_2U(SCH_1):PAGE161
     4    GND @S9S_MB_2U_LIB.S9S_MB_2U(SCH_1):GND   I164 @S9S_MB_2U_LIB.S9S_MB_2U(SCH_1):PAGE161
     5 U270_0_ADD2 @S9S_MB_2U_LIB.S9S_MB_2U(SCH_1):U270_0_ADD2   I164 @S9S_MB_2U_LIB.S9S_MB_2U(SCH_1):PAGE161
     6 U270_0_ADD1 @S9S_MB_2U_LIB.S9S_MB_2U(SCH_1):U270_0_ADD1   I164 @S9S_MB_2U_LIB.S9S_MB_2U(SCH_1):PAGE161
     7 U270_0_ADD0 @S9S_MB_2U_LIB.S9S_MB_2U(SCH_1):U270_0_ADD0   I164 @S9S_MB_2U_LIB.S9S_MB_2U(SCH_1):PAGE161
     8 P3V3_AUX @S9S_MB_2U_LIB.S9S_MB_2U(SCH_1):P3V3_AUX   I164 @S9S_MB_2U_LIB.S9S_MB_2U(SCH_1):PAGE161

U271 LM75BD-LM75BD,SMLF,IC,AL0075BDA
     1 SMB_LM75_1_3V3AUX_SDA_R1 @S9S_MB_2U_LIB.S9S_MB_2U(SCH_1):SMB_LM75_1_3V3AUX_SDA_R1   I165 @S9S_MB_2U_LIB.S9S_MB_2U(SCH_1):PAGE161
     2 SMB_LM75_1_3V3AUX_SCL_R1 @S9S_MB_2U_LIB.S9S_MB_2U(SCH_1):SMB_LM75_1_3V3AUX_SCL_R1   I165 @S9S_MB_2U_LIB.S9S_MB_2U(SCH_1):PAGE161
     3 FM_G751_1_ALERT_N @S9S_MB_2U_LIB.S9S_MB_2U(SCH_1):FM_G751_1_ALERT_N   I165 @S9S_MB_2U_LIB.S9S_MB_2U(SCH_1):PAGE161
     4    GND @S9S_MB_2U_LIB.S9S_MB_2U(SCH_1):GND   I165 @S9S_MB_2U_LIB.S9S_MB_2U(SCH_1):PAGE161
     5 U271_1_ADD2 @S9S_MB_2U_LIB.S9S_MB_2U(SCH_1):U271_1_ADD2   I165 @S9S_MB_2U_LIB.S9S_MB_2U(SCH_1):PAGE161
     6 U271_1_ADD1 @S9S_MB_2U_LIB.S9S_MB_2U(SCH_1):U271_1_ADD1   I165 @S9S_MB_2U_LIB.S9S_MB_2U(SCH_1):PAGE161
     7 U271_1_ADD0 @S9S_MB_2U_LIB.S9S_MB_2U(SCH_1):U271_1_ADD0   I165 @S9S_MB_2U_LIB.S9S_MB_2U(SCH_1):PAGE161
     8 P3V3_AUX @S9S_MB_2U_LIB.S9S_MB_2U(SCH_1):P3V3_AUX   I165 @S9S_MB_2U_LIB.S9S_MB_2U(SCH_1):PAGE161

U272 LM75BD-LM75BD,SMLF,IC,AL0075BDA
     1 SMB_LM75_2_3V3AUX_SDA_R1 @S9S_MB_2U_LIB.S9S_MB_2U(SCH_1):SMB_LM75_2_3V3AUX_SDA_R1   I166 @S9S_MB_2U_LIB.S9S_MB_2U(SCH_1):PAGE161
     2 SMB_LM75_2_3V3AUX_SCL_R1 @S9S_MB_2U_LIB.S9S_MB_2U(SCH_1):SMB_LM75_2_3V3AUX_SCL_R1   I166 @S9S_MB_2U_LIB.S9S_MB_2U(SCH_1):PAGE161
     3 FM_LM75_2_ALERT_N @S9S_MB_2U_LIB.S9S_MB_2U(SCH_1):FM_LM75_2_ALERT_N   I166 @S9S_MB_2U_LIB.S9S_MB_2U(SCH_1):PAGE161
     4    GND @S9S_MB_2U_LIB.S9S_MB_2U(SCH_1):GND   I166 @S9S_MB_2U_LIB.S9S_MB_2U(SCH_1):PAGE161
     5 U272_2_ADD2 @S9S_MB_2U_LIB.S9S_MB_2U(SCH_1):U272_2_ADD2   I166 @S9S_MB_2U_LIB.S9S_MB_2U(SCH_1):PAGE161
     6 U272_2_ADD1 @S9S_MB_2U_LIB.S9S_MB_2U(SCH_1):U272_2_ADD1   I166 @S9S_MB_2U_LIB.S9S_MB_2U(SCH_1):PAGE161
     7 U272_2_ADD0 @S9S_MB_2U_LIB.S9S_MB_2U(SCH_1):U272_2_ADD0   I166 @S9S_MB_2U_LIB.S9S_MB_2U(SCH_1):PAGE161
     8 P3V3_AUX @S9S_MB_2U_LIB.S9S_MB_2U(SCH_1):P3V3_AUX   I166 @S9S_MB_2U_LIB.S9S_MB_2U(SCH_1):PAGE161

U273 LM75BD-LM75BD,SMLF,IC,AL0075BDA
     1 SMB_LM75_3_3V3AUX_SDA_R1 @S9S_MB_2U_LIB.S9S_MB_2U(SCH_1):SMB_LM75_3_3V3AUX_SDA_R1   I167 @S9S_MB_2U_LIB.S9S_MB_2U(SCH_1):PAGE161
     2 SMB_LM75_3_3V3AUX_SCL_R1 @S9S_MB_2U_LIB.S9S_MB_2U(SCH_1):SMB_LM75_3_3V3AUX_SCL_R1   I167 @S9S_MB_2U_LIB.S9S_MB_2U(SCH_1):PAGE161
     3 FM_LM75_3_ALERT_N @S9S_MB_2U_LIB.S9S_MB_2U(SCH_1):FM_LM75_3_ALERT_N   I167 @S9S_MB_2U_LIB.S9S_MB_2U(SCH_1):PAGE161
     4    GND @S9S_MB_2U_LIB.S9S_MB_2U(SCH_1):GND   I167 @S9S_MB_2U_LIB.S9S_MB_2U(SCH_1):PAGE161
     5 U273_3_ADD2 @S9S_MB_2U_LIB.S9S_MB_2U(SCH_1):U273_3_ADD2   I167 @S9S_MB_2U_LIB.S9S_MB_2U(SCH_1):PAGE161
     6 U273_3_ADD1 @S9S_MB_2U_LIB.S9S_MB_2U(SCH_1):U273_3_ADD1   I167 @S9S_MB_2U_LIB.S9S_MB_2U(SCH_1):PAGE161
     7 U273_3_ADD0 @S9S_MB_2U_LIB.S9S_MB_2U(SCH_1):U273_3_ADD0   I167 @S9S_MB_2U_LIB.S9S_MB_2U(SCH_1):PAGE161
     8 P3V3_AUX @S9S_MB_2U_LIB.S9S_MB_2U(SCH_1):P3V3_AUX   I167 @S9S_MB_2U_LIB.S9S_MB_2U(SCH_1):PAGE161

U276 INA230AIRGTR-INA230AIRGTR,SMLFB
     9 P3V3_AUX @S9S_MB_2U_LIB.S9S_MB_2U(SCH_1):P3V3_AUX   I129 @S9S_MB_2U_LIB.S9S_MB_2U(SCH_1):PAGE295
     1 INA230_2_A1 @S9S_MB_2U_LIB.S9S_MB_2U(SCH_1):INA230_2_A1   I129 @S9S_MB_2U_LIB.S9S_MB_2U(SCH_1):PAGE295
     2 INA230_2_A0 @S9S_MB_2U_LIB.S9S_MB_2U(SCH_1):INA230_2_A0   I129 @S9S_MB_2U_LIB.S9S_MB_2U(SCH_1):PAGE295
     5 SMB_INA230_2_3V3AUX_SCL_R1 @S9S_MB_2U_LIB.S9S_MB_2U(SCH_1):SMB_INA230_2_3V3AUX_SCL_R1   I129 @S9S_MB_2U_LIB.S9S_MB_2U(SCH_1):PAGE295
     4 SMB_INA230_2_3V3AUX_SDA_R1 @S9S_MB_2U_LIB.S9S_MB_2U(SCH_1):SMB_INA230_2_3V3AUX_SDA_R1   I129 @S9S_MB_2U_LIB.S9S_MB_2U(SCH_1):PAGE295
    11 P3V3_E1S_0_R @S9S_MB_2U_LIB.S9S_MB_2U(SCH_1):P3V3_E1S_0_R   I129 @S9S_MB_2U_LIB.S9S_MB_2U(SCH_1):PAGE295
    13 VSENSE_P3V3_INA230_2_INP @S9S_MB_2U_LIB.S9S_MB_2U(SCH_1):VSENSE_P3V3_INA230_2_INP   I129 @S9S_MB_2U_LIB.S9S_MB_2U(SCH_1):PAGE295
    12 VSENSE_P3V3_INA230_2_INN @S9S_MB_2U_LIB.S9S_MB_2U(SCH_1):VSENSE_P3V3_INA230_2_INN   I129 @S9S_MB_2U_LIB.S9S_MB_2U(SCH_1):PAGE295
     3 E1S_0_P3V3_ADC_ALERT_R @S9S_MB_2U_LIB.S9S_MB_2U(SCH_1):E1S_0_P3V3_ADC_ALERT_R   I129 @S9S_MB_2U_LIB.S9S_MB_2U(SCH_1):PAGE295
     6 NC_INA230_2_NC0 @S9S_MB_2U_LIB.S9S_MB_2U(SCH_1):NC_INA230_2_NC0   I129 @S9S_MB_2U_LIB.S9S_MB_2U(SCH_1):PAGE295
     7 NC_INA230_2_NC1 @S9S_MB_2U_LIB.S9S_MB_2U(SCH_1):NC_INA230_2_NC1   I129 @S9S_MB_2U_LIB.S9S_MB_2U(SCH_1):PAGE295
     8 NC_INA230_2_NC2 @S9S_MB_2U_LIB.S9S_MB_2U(SCH_1):NC_INA230_2_NC2   I129 @S9S_MB_2U_LIB.S9S_MB_2U(SCH_1):PAGE295
    14 NC_INA230_2_NC3 @S9S_MB_2U_LIB.S9S_MB_2U(SCH_1):NC_INA230_2_NC3   I129 @S9S_MB_2U_LIB.S9S_MB_2U(SCH_1):PAGE295
    15 NC_INA230_2_NC4 @S9S_MB_2U_LIB.S9S_MB_2U(SCH_1):NC_INA230_2_NC4   I129 @S9S_MB_2U_LIB.S9S_MB_2U(SCH_1):PAGE295
    16 NC_INA230_2_NC5 @S9S_MB_2U_LIB.S9S_MB_2U(SCH_1):NC_INA230_2_NC5   I129 @S9S_MB_2U_LIB.S9S_MB_2U(SCH_1):PAGE295
    10    GND @S9S_MB_2U_LIB.S9S_MB_2U(SCH_1):GND   I129 @S9S_MB_2U_LIB.S9S_MB_2U(SCH_1):PAGE295
    TH    GND @S9S_MB_2U_LIB.S9S_MB_2U(SCH_1):GND   I129 @S9S_MB_2U_LIB.S9S_MB_2U(SCH_1):PAGE295

U278 74LVC1G08W57-74LVC1G08W5-7,SMLA
     1 FM_GPU_HSC_EN @S9S_MB_2U_LIB.S9S_MB_2U(SCH_1):FM_GPU_HSC_EN    I31 @S9S_MB_2U_LIB.S9S_MB_2U(SCH_1):PAGE230
     2 GPU_PRSNT_R @S9S_MB_2U_LIB.S9S_MB_2U(SCH_1):GPU_PRSNT_R    I31 @S9S_MB_2U_LIB.S9S_MB_2U(SCH_1):PAGE230
     3    GND @S9S_MB_2U_LIB.S9S_MB_2U(SCH_1):GND    I31 @S9S_MB_2U_LIB.S9S_MB_2U(SCH_1):PAGE230
     4 FM_GPU_HSC_EN_BUF_R @S9S_MB_2U_LIB.S9S_MB_2U(SCH_1):FM_GPU_HSC_EN_BUF_R    I31 @S9S_MB_2U_LIB.S9S_MB_2U(SCH_1):PAGE230
     5 P3V3_AUX @S9S_MB_2U_LIB.S9S_MB_2U(SCH_1):P3V3_AUX    I31 @S9S_MB_2U_LIB.S9S_MB_2U(SCH_1):PAGE230

U279 PCA9617ADP-PCA9617ADP,SMLF,IC,A
     5 SMB_PCIE_E1S_ISO_EN_R @S9S_MB_2U_LIB.S9S_MB_2U(SCH_1):SMB_PCIE_E1S_ISO_EN_R    I93 @S9S_MB_2U_LIB.S9S_MB_2U(SCH_1):PAGE183
     1 P3V3_E1S_0 @S9S_MB_2U_LIB.S9S_MB_2U(SCH_1):P3V3_E1S_0    I93 @S9S_MB_2U_LIB.S9S_MB_2U(SCH_1):PAGE183
     8 P3V3_AUX @S9S_MB_2U_LIB.S9S_MB_2U(SCH_1):P3V3_AUX    I93 @S9S_MB_2U_LIB.S9S_MB_2U(SCH_1):PAGE183
     2 SMB_E1S_3V3AUX_ISO_SCL_R @S9S_MB_2U_LIB.S9S_MB_2U(SCH_1):SMB_E1S_3V3AUX_ISO_SCL_R    I93 @S9S_MB_2U_LIB.S9S_MB_2U(SCH_1):PAGE183
     3 SMB_E1S_3V3AUX_ISO_SDA_R @S9S_MB_2U_LIB.S9S_MB_2U(SCH_1):SMB_E1S_3V3AUX_ISO_SDA_R    I93 @S9S_MB_2U_LIB.S9S_MB_2U(SCH_1):PAGE183
     6 SMB_SENSOR_E1S_3V3AUX_SDA @S9S_MB_2U_LIB.S9S_MB_2U(SCH_1):SMB_SENSOR_E1S_3V3AUX_SDA    I93 @S9S_MB_2U_LIB.S9S_MB_2U(SCH_1):PAGE183
     7 SMB_SENSOR_E1S_3V3AUX_SCL @S9S_MB_2U_LIB.S9S_MB_2U(SCH_1):SMB_SENSOR_E1S_3V3AUX_SCL    I93 @S9S_MB_2U_LIB.S9S_MB_2U(SCH_1):PAGE183
     4    GND @S9S_MB_2U_LIB.S9S_MB_2U(SCH_1):GND    I93 @S9S_MB_2U_LIB.S9S_MB_2U(SCH_1):PAGE183

U286 74LVC1G126SE7-74LVC1G126SE-7,SA
     2 FM_OCP_V3_2_PWR_GOOD @S9S_MB_2U_LIB.S9S_MB_2U(SCH_1):FM_OCP_V3_2_PWR_GOOD    I80 @S9S_MB_2U_LIB.S9S_MB_2U(SCH_1):PAGE307
     4 FB_BMC_ISOLATE_R2 @S9S_MB_2U_LIB.S9S_MB_2U(SCH_1):FB_BMC_ISOLATE_R2    I80 @S9S_MB_2U_LIB.S9S_MB_2U(SCH_1):PAGE307
     5 P3V3_AUX @S9S_MB_2U_LIB.S9S_MB_2U(SCH_1):P3V3_AUX    I80 @S9S_MB_2U_LIB.S9S_MB_2U(SCH_1):PAGE307
     3    GND @S9S_MB_2U_LIB.S9S_MB_2U(SCH_1):GND    I80 @S9S_MB_2U_LIB.S9S_MB_2U(SCH_1):PAGE307
     1 OCP_V3_2_AUX_PWR_EN_R1 @S9S_MB_2U_LIB.S9S_MB_2U(SCH_1):OCP_V3_2_AUX_PWR_EN_R1    I80 @S9S_MB_2U_LIB.S9S_MB_2U(SCH_1):PAGE307

U290 MOSFET_NCH_GDS_ESD_PROTECTED-2A
     D HSC_EN @S9S_MB_2U_LIB.S9S_MB_2U(SCH_1):HSC_EN     I5 @S9S_MB_2U_LIB.S9S_MB_2U(SCH_1):PAGE303
     G PDB_PRSNT_N @S9S_MB_2U_LIB.S9S_MB_2U(SCH_1):PDB_PRSNT_N     I5 @S9S_MB_2U_LIB.S9S_MB_2U(SCH_1):PAGE303
     S    GND @S9S_MB_2U_LIB.S9S_MB_2U(SCH_1):GND     I5 @S9S_MB_2U_LIB.S9S_MB_2U(SCH_1):PAGE303

U301 GTL2014PW-GTL2014PW,SMLF,IC,ALA
     2 H_CPU_CATERR_LVC1_R_N @S9S_MB_2U_LIB.S9S_MB_2U(SCH_1):H_CPU_CATERR_LVC1_R_N    I91 @S9S_MB_2U_LIB.S9S_MB_2U(SCH_1):PAGE321
     3 H_CPU_CATERR_LVC1_R_N @S9S_MB_2U_LIB.S9S_MB_2U(SCH_1):H_CPU_CATERR_LVC1_R_N    I91 @S9S_MB_2U_LIB.S9S_MB_2U(SCH_1):PAGE321
     5 H_CPU_RMCA_LVC1_R_N @S9S_MB_2U_LIB.S9S_MB_2U(SCH_1):H_CPU_RMCA_LVC1_R_N    I91 @S9S_MB_2U_LIB.S9S_MB_2U(SCH_1):PAGE321
     6 PWRGD_CPUPWRGD_LVC1 @S9S_MB_2U_LIB.S9S_MB_2U(SCH_1):PWRGD_CPUPWRGD_LVC1    I91 @S9S_MB_2U_LIB.S9S_MB_2U(SCH_1):PAGE321
    11    GND @S9S_MB_2U_LIB.S9S_MB_2U(SCH_1):GND    I91 @S9S_MB_2U_LIB.S9S_MB_2U(SCH_1):PAGE321
     8    GND @S9S_MB_2U_LIB.S9S_MB_2U(SCH_1):GND    I91 @S9S_MB_2U_LIB.S9S_MB_2U(SCH_1):PAGE321
     7    GND @S9S_MB_2U_LIB.S9S_MB_2U(SCH_1):GND    I91 @S9S_MB_2U_LIB.S9S_MB_2U(SCH_1):PAGE321
     9 PWRGD_CPUPWRGD_LVC2_R @S9S_MB_2U_LIB.S9S_MB_2U(SCH_1):PWRGD_CPUPWRGD_LVC2_R    I91 @S9S_MB_2U_LIB.S9S_MB_2U(SCH_1):PAGE321
    10 H_CPU_RMCA_LVC2_R1_N @S9S_MB_2U_LIB.S9S_MB_2U(SCH_1):H_CPU_RMCA_LVC2_R1_N    I91 @S9S_MB_2U_LIB.S9S_MB_2U(SCH_1):PAGE321
    12 H_CPU_CATERR_LVC2_R1_N @S9S_MB_2U_LIB.S9S_MB_2U(SCH_1):H_CPU_CATERR_LVC2_R1_N    I91 @S9S_MB_2U_LIB.S9S_MB_2U(SCH_1):PAGE321
    13 H_CPU_CATERR_LVC2_BMC_R_N @S9S_MB_2U_LIB.S9S_MB_2U(SCH_1):H_CPU_CATERR_LVC2_BMC_R_N    I91 @S9S_MB_2U_LIB.S9S_MB_2U(SCH_1):PAGE321
     1 PD_CPU0_ERRS_DIR @S9S_MB_2U_LIB.S9S_MB_2U(SCH_1):PD_CPU0_ERRS_DIR    I91 @S9S_MB_2U_LIB.S9S_MB_2U(SCH_1):PAGE321
     4 P0V62_CPU0_ERRS_VREF @S9S_MB_2U_LIB.S9S_MB_2U(SCH_1):P0V62_CPU0_ERRS_VREF    I91 @S9S_MB_2U_LIB.S9S_MB_2U(SCH_1):PAGE321
    14   P3V3 @S9S_MB_2U_LIB.S9S_MB_2U(SCH_1):P3V3    I91 @S9S_MB_2U_LIB.S9S_MB_2U(SCH_1):PAGE321

U304 GTL2014PW-GTL2014PW,SMLF,IC,ALA
     2 RST_CPU0_DRAM_GH_PLD_N @S9S_MB_2U_LIB.S9S_MB_2U(SCH_1):RST_CPU0_DRAM_GH_PLD_N    I27 @S9S_MB_2U_LIB.S9S_MB_2U(SCH_1):PAGE322
     3 RST_CPU0_DRAM_EF_PLD_N @S9S_MB_2U_LIB.S9S_MB_2U(SCH_1):RST_CPU0_DRAM_EF_PLD_N    I27 @S9S_MB_2U_LIB.S9S_MB_2U(SCH_1):PAGE322
     5 RST_CPU0_DRAM_CD_PLD_N @S9S_MB_2U_LIB.S9S_MB_2U(SCH_1):RST_CPU0_DRAM_CD_PLD_N    I27 @S9S_MB_2U_LIB.S9S_MB_2U(SCH_1):PAGE322
     6 RST_CPU0_DRAM_AB_PLD_N @S9S_MB_2U_LIB.S9S_MB_2U(SCH_1):RST_CPU0_DRAM_AB_PLD_N    I27 @S9S_MB_2U_LIB.S9S_MB_2U(SCH_1):PAGE322
    11    GND @S9S_MB_2U_LIB.S9S_MB_2U(SCH_1):GND    I27 @S9S_MB_2U_LIB.S9S_MB_2U(SCH_1):PAGE322
     8    GND @S9S_MB_2U_LIB.S9S_MB_2U(SCH_1):GND    I27 @S9S_MB_2U_LIB.S9S_MB_2U(SCH_1):PAGE322
     7    GND @S9S_MB_2U_LIB.S9S_MB_2U(SCH_1):GND    I27 @S9S_MB_2U_LIB.S9S_MB_2U(SCH_1):PAGE322
     9 RST_CPU0_DRAM_AB_PLD_LVT3_R_N @S9S_MB_2U_LIB.S9S_MB_2U(SCH_1):RST_CPU0_DRAM_AB_PLD_LVT3_R_N    I27 @S9S_MB_2U_LIB.S9S_MB_2U(SCH_1):PAGE322
    10 RST_CPU0_DRAM_CD_PLD_LVT3_R_N @S9S_MB_2U_LIB.S9S_MB_2U(SCH_1):RST_CPU0_DRAM_CD_PLD_LVT3_R_N    I27 @S9S_MB_2U_LIB.S9S_MB_2U(SCH_1):PAGE322
    12 RST_CPU0_DRAM_EF_PLD_LVT3_R_N @S9S_MB_2U_LIB.S9S_MB_2U(SCH_1):RST_CPU0_DRAM_EF_PLD_LVT3_R_N    I27 @S9S_MB_2U_LIB.S9S_MB_2U(SCH_1):PAGE322
    13 RST_CPU0_DRAM_GH_PLD_LVT3_R_N @S9S_MB_2U_LIB.S9S_MB_2U(SCH_1):RST_CPU0_DRAM_GH_PLD_LVT3_R_N    I27 @S9S_MB_2U_LIB.S9S_MB_2U(SCH_1):PAGE322
     1 PD_GTL2014_BMC_JTAG_DIR_0 @S9S_MB_2U_LIB.S9S_MB_2U(SCH_1):PD_GTL2014_BMC_JTAG_DIR_0    I27 @S9S_MB_2U_LIB.S9S_MB_2U(SCH_1):PAGE322
     4 P0V62_CPU0_RST_DDR_VREF @S9S_MB_2U_LIB.S9S_MB_2U(SCH_1):P0V62_CPU0_RST_DDR_VREF    I27 @S9S_MB_2U_LIB.S9S_MB_2U(SCH_1):PAGE322
    14 P3V3_AUX @S9S_MB_2U_LIB.S9S_MB_2U(SCH_1):P3V3_AUX    I27 @S9S_MB_2U_LIB.S9S_MB_2U(SCH_1):PAGE322

U305 GTL2014PW-GTL2014PW,SMLF,IC,ALA
     2 RST_CPU1_DRAM_GH_PLD_N @S9S_MB_2U_LIB.S9S_MB_2U(SCH_1):RST_CPU1_DRAM_GH_PLD_N    I44 @S9S_MB_2U_LIB.S9S_MB_2U(SCH_1):PAGE322
     3 RST_CPU1_DRAM_EF_PLD_N @S9S_MB_2U_LIB.S9S_MB_2U(SCH_1):RST_CPU1_DRAM_EF_PLD_N    I44 @S9S_MB_2U_LIB.S9S_MB_2U(SCH_1):PAGE322
     5 RST_CPU1_DRAM_CD_PLD_N @S9S_MB_2U_LIB.S9S_MB_2U(SCH_1):RST_CPU1_DRAM_CD_PLD_N    I44 @S9S_MB_2U_LIB.S9S_MB_2U(SCH_1):PAGE322
     6 RST_CPU1_DRAM_AB_PLD_N @S9S_MB_2U_LIB.S9S_MB_2U(SCH_1):RST_CPU1_DRAM_AB_PLD_N    I44 @S9S_MB_2U_LIB.S9S_MB_2U(SCH_1):PAGE322
    11    GND @S9S_MB_2U_LIB.S9S_MB_2U(SCH_1):GND    I44 @S9S_MB_2U_LIB.S9S_MB_2U(SCH_1):PAGE322
     8    GND @S9S_MB_2U_LIB.S9S_MB_2U(SCH_1):GND    I44 @S9S_MB_2U_LIB.S9S_MB_2U(SCH_1):PAGE322
     7    GND @S9S_MB_2U_LIB.S9S_MB_2U(SCH_1):GND    I44 @S9S_MB_2U_LIB.S9S_MB_2U(SCH_1):PAGE322
     9 RST_CPU1_DRAM_AB_PLD_LVT3_R_N @S9S_MB_2U_LIB.S9S_MB_2U(SCH_1):RST_CPU1_DRAM_AB_PLD_LVT3_R_N    I44 @S9S_MB_2U_LIB.S9S_MB_2U(SCH_1):PAGE322
    10 RST_CPU1_DRAM_CD_PLD_LVT3_R_N @S9S_MB_2U_LIB.S9S_MB_2U(SCH_1):RST_CPU1_DRAM_CD_PLD_LVT3_R_N    I44 @S9S_MB_2U_LIB.S9S_MB_2U(SCH_1):PAGE322
    12 RST_CPU1_DRAM_EF_PLD_LVT3_R_N @S9S_MB_2U_LIB.S9S_MB_2U(SCH_1):RST_CPU1_DRAM_EF_PLD_LVT3_R_N    I44 @S9S_MB_2U_LIB.S9S_MB_2U(SCH_1):PAGE322
    13 RST_CPU1_DRAM_GH_PLD_LVT3_R_N @S9S_MB_2U_LIB.S9S_MB_2U(SCH_1):RST_CPU1_DRAM_GH_PLD_LVT3_R_N    I44 @S9S_MB_2U_LIB.S9S_MB_2U(SCH_1):PAGE322
     1 PD_GTL2014_BMC_JTAG_DIR_1 @S9S_MB_2U_LIB.S9S_MB_2U(SCH_1):PD_GTL2014_BMC_JTAG_DIR_1    I44 @S9S_MB_2U_LIB.S9S_MB_2U(SCH_1):PAGE322
     4 P0V62_CPU1_RST_DDR_VREF @S9S_MB_2U_LIB.S9S_MB_2U(SCH_1):P0V62_CPU1_RST_DDR_VREF    I44 @S9S_MB_2U_LIB.S9S_MB_2U(SCH_1):PAGE322
    14 P3V3_AUX @S9S_MB_2U_LIB.S9S_MB_2U(SCH_1):P3V3_AUX    I44 @S9S_MB_2U_LIB.S9S_MB_2U(SCH_1):PAGE322

U306 GTL2014PW-GTL2014PW,SMLF,IC,ALA
     2 PD_GTL2014_ERROR_B0 @S9S_MB_2U_LIB.S9S_MB_2U(SCH_1):PD_GTL2014_ERROR_B0    I80 @S9S_MB_2U_LIB.S9S_MB_2U(SCH_1):PAGE322
     3 H_CPU_ERR2_LVC1_N @S9S_MB_2U_LIB.S9S_MB_2U(SCH_1):H_CPU_ERR2_LVC1_N    I80 @S9S_MB_2U_LIB.S9S_MB_2U(SCH_1):PAGE322
     5 H_CPU_ERR1_LVC1_N @S9S_MB_2U_LIB.S9S_MB_2U(SCH_1):H_CPU_ERR1_LVC1_N    I80 @S9S_MB_2U_LIB.S9S_MB_2U(SCH_1):PAGE322
     6 H_CPU_ERR0_LVC1_N @S9S_MB_2U_LIB.S9S_MB_2U(SCH_1):H_CPU_ERR0_LVC1_N    I80 @S9S_MB_2U_LIB.S9S_MB_2U(SCH_1):PAGE322
    11    GND @S9S_MB_2U_LIB.S9S_MB_2U(SCH_1):GND    I80 @S9S_MB_2U_LIB.S9S_MB_2U(SCH_1):PAGE322
     8    GND @S9S_MB_2U_LIB.S9S_MB_2U(SCH_1):GND    I80 @S9S_MB_2U_LIB.S9S_MB_2U(SCH_1):PAGE322
     7    GND @S9S_MB_2U_LIB.S9S_MB_2U(SCH_1):GND    I80 @S9S_MB_2U_LIB.S9S_MB_2U(SCH_1):PAGE322
     9 H_CPU_ERR0_LVC2_R_N @S9S_MB_2U_LIB.S9S_MB_2U(SCH_1):H_CPU_ERR0_LVC2_R_N    I80 @S9S_MB_2U_LIB.S9S_MB_2U(SCH_1):PAGE322
    10 H_CPU_ERR1_LVC2_R_N @S9S_MB_2U_LIB.S9S_MB_2U(SCH_1):H_CPU_ERR1_LVC2_R_N    I80 @S9S_MB_2U_LIB.S9S_MB_2U(SCH_1):PAGE322
    12 H_CPU_ERR2_LVC2_R_N @S9S_MB_2U_LIB.S9S_MB_2U(SCH_1):H_CPU_ERR2_LVC2_R_N    I80 @S9S_MB_2U_LIB.S9S_MB_2U(SCH_1):PAGE322
    13 NC_U306_A0 @S9S_MB_2U_LIB.S9S_MB_2U(SCH_1):NC_U306_A0    I80 @S9S_MB_2U_LIB.S9S_MB_2U(SCH_1):PAGE322
     1 PD_CPU1_ERRS_U306_DIR @S9S_MB_2U_LIB.S9S_MB_2U(SCH_1):PD_CPU1_ERRS_U306_DIR    I80 @S9S_MB_2U_LIB.S9S_MB_2U(SCH_1):PAGE322
     4 P0V62_CPU0_ERRS_U306_VREF @S9S_MB_2U_LIB.S9S_MB_2U(SCH_1):P0V62_CPU0_ERRS_U306_VREF    I80 @S9S_MB_2U_LIB.S9S_MB_2U(SCH_1):PAGE322
    14   P3V3 @S9S_MB_2U_LIB.S9S_MB_2U(SCH_1):P3V3    I80 @S9S_MB_2U_LIB.S9S_MB_2U(SCH_1):PAGE322

U307 MOSFET_N_SMLF-BSS138K,BSS138K,A
     G FM_ESPI_PLD_R_EN_BUF_R @S9S_MB_2U_LIB.S9S_MB_2U(SCH_1):FM_ESPI_PLD_R_EN_BUF_R    I15 @S9S_MB_2U_LIB.S9S_MB_2U(SCH_1):PAGE243
     D FM_LPC_ESPI_SEL @S9S_MB_2U_LIB.S9S_MB_2U(SCH_1):FM_LPC_ESPI_SEL    I15 @S9S_MB_2U_LIB.S9S_MB_2U(SCH_1):PAGE243
     S    GND @S9S_MB_2U_LIB.S9S_MB_2U(SCH_1):GND    I15 @S9S_MB_2U_LIB.S9S_MB_2U(SCH_1):PAGE243

U308 74LVC2G07DW7-74LVC2G07DW-7,SMLA
     1 PWRGD_P3V3_AUX_PDB_R @S9S_MB_2U_LIB.S9S_MB_2U(SCH_1):PWRGD_P3V3_AUX_PDB_R    I37 @S9S_MB_2U_LIB.S9S_MB_2U(SCH_1):PAGE230
     3     NC     NC    I37 @S9S_MB_2U_LIB.S9S_MB_2U(SCH_1):PAGE230
     6 PWRGD_P3V3_AUX_PDB_BUF_R @S9S_MB_2U_LIB.S9S_MB_2U(SCH_1):PWRGD_P3V3_AUX_PDB_BUF_R    I37 @S9S_MB_2U_LIB.S9S_MB_2U(SCH_1):PAGE230
     4     NC     NC    I37 @S9S_MB_2U_LIB.S9S_MB_2U(SCH_1):PAGE230
     2    GND @S9S_MB_2U_LIB.S9S_MB_2U(SCH_1):GND    I37 @S9S_MB_2U_LIB.S9S_MB_2U(SCH_1):PAGE230
     5 P3V3_AUX @S9S_MB_2U_LIB.S9S_MB_2U(SCH_1):P3V3_AUX    I37 @S9S_MB_2U_LIB.S9S_MB_2U(SCH_1):PAGE230

U309 PI3EQX1002EZREX-PI3EQX1002EZREA
     9    GND @S9S_MB_2U_LIB.S9S_MB_2U(SCH_1):GND    I43 @S9S_MB_2U_LIB.S9S_MB_2U(SCH_1):PAGE162
    17 P3V3_AUX_USB_BUF @S9S_MB_2U_LIB.S9S_MB_2U(SCH_1):P3V3_AUX_USB_BUF    I43 @S9S_MB_2U_LIB.S9S_MB_2U(SCH_1):PAGE162
     4 FM_USB3_1_EN_N @S9S_MB_2U_LIB.S9S_MB_2U(SCH_1):FM_USB3_1_EN_N    I43 @S9S_MB_2U_LIB.S9S_MB_2U(SCH_1):PAGE162
     5 P3V3_AUX_USB_BUF @S9S_MB_2U_LIB.S9S_MB_2U(SCH_1):P3V3_AUX_USB_BUF    I43 @S9S_MB_2U_LIB.S9S_MB_2U(SCH_1):PAGE162
    23 USB3_PCH_TX_BUF_DN<4> @S9S_MB_2U_LIB.S9S_MB_2U(SCH_1):USB3_PCH_TX_BUF_DN(4)    I43 @S9S_MB_2U_LIB.S9S_MB_2U(SCH_1):PAGE162
    24 USB3_PCH_TX_BUF_DP<4> @S9S_MB_2U_LIB.S9S_MB_2U(SCH_1):USB3_PCH_TX_BUF_DP(4)    I43 @S9S_MB_2U_LIB.S9S_MB_2U(SCH_1):PAGE162
    22    GND @S9S_MB_2U_LIB.S9S_MB_2U(SCH_1):GND    I43 @S9S_MB_2U_LIB.S9S_MB_2U(SCH_1):PAGE162
     7 USB3_PCH_TX_C_DN<4> @S9S_MB_2U_LIB.S9S_MB_2U(SCH_1):USB3_PCH_TX_C_DN(4)    I43 @S9S_MB_2U_LIB.S9S_MB_2U(SCH_1):PAGE162
     1 FM_USB3_1_EQA @S9S_MB_2U_LIB.S9S_MB_2U(SCH_1):FM_USB3_1_EQA    I43 @S9S_MB_2U_LIB.S9S_MB_2U(SCH_1):PAGE162
     2 FM_USB3_1_FGA @S9S_MB_2U_LIB.S9S_MB_2U(SCH_1):FM_USB3_1_FGA    I43 @S9S_MB_2U_LIB.S9S_MB_2U(SCH_1):PAGE162
    13 FM_USB3_1_RXDET_EN @S9S_MB_2U_LIB.S9S_MB_2U(SCH_1):FM_USB3_1_RXDET_EN    I43 @S9S_MB_2U_LIB.S9S_MB_2U(SCH_1):PAGE162
     6 USB3_PCH_TX_C_DP<4> @S9S_MB_2U_LIB.S9S_MB_2U(SCH_1):USB3_PCH_TX_C_DP(4)    I43 @S9S_MB_2U_LIB.S9S_MB_2U(SCH_1):PAGE162
    TH    GND @S9S_MB_2U_LIB.S9S_MB_2U(SCH_1):GND    I43 @S9S_MB_2U_LIB.S9S_MB_2U(SCH_1):PAGE162
    15 FM_USB3_1_FGB @S9S_MB_2U_LIB.S9S_MB_2U(SCH_1):FM_USB3_1_FGB    I43 @S9S_MB_2U_LIB.S9S_MB_2U(SCH_1):PAGE162
    19 USB3_PCH_RX_C_DN<4> @S9S_MB_2U_LIB.S9S_MB_2U(SCH_1):USB3_PCH_RX_C_DN(4)    I43 @S9S_MB_2U_LIB.S9S_MB_2U(SCH_1):PAGE162
    14 FM_USB3_1_SWB @S9S_MB_2U_LIB.S9S_MB_2U(SCH_1):FM_USB3_1_SWB    I43 @S9S_MB_2U_LIB.S9S_MB_2U(SCH_1):PAGE162
    18 USB3_PCH_RX_C_DP<4> @S9S_MB_2U_LIB.S9S_MB_2U(SCH_1):USB3_PCH_RX_C_DP(4)    I43 @S9S_MB_2U_LIB.S9S_MB_2U(SCH_1):PAGE162
     3 FM_USB3_1_SWA @S9S_MB_2U_LIB.S9S_MB_2U(SCH_1):FM_USB3_1_SWA    I43 @S9S_MB_2U_LIB.S9S_MB_2U(SCH_1):PAGE162
     8    GND @S9S_MB_2U_LIB.S9S_MB_2U(SCH_1):GND    I43 @S9S_MB_2U_LIB.S9S_MB_2U(SCH_1):PAGE162
    16 FM_USB3_1_EQB @S9S_MB_2U_LIB.S9S_MB_2U(SCH_1):FM_USB3_1_EQB    I43 @S9S_MB_2U_LIB.S9S_MB_2U(SCH_1):PAGE162
    10    GND @S9S_MB_2U_LIB.S9S_MB_2U(SCH_1):GND    I43 @S9S_MB_2U_LIB.S9S_MB_2U(SCH_1):PAGE162
    21    GND @S9S_MB_2U_LIB.S9S_MB_2U(SCH_1):GND    I43 @S9S_MB_2U_LIB.S9S_MB_2U(SCH_1):PAGE162
    11 USB3_PCH_RX_BUF_C_DN<4> @S9S_MB_2U_LIB.S9S_MB_2U(SCH_1):USB3_PCH_RX_BUF_C_DN(4)    I43 @S9S_MB_2U_LIB.S9S_MB_2U(SCH_1):PAGE162
    12 USB3_PCH_RX_BUF_C_DP<4> @S9S_MB_2U_LIB.S9S_MB_2U(SCH_1):USB3_PCH_RX_BUF_C_DP(4)    I43 @S9S_MB_2U_LIB.S9S_MB_2U(SCH_1):PAGE162
    20    GND @S9S_MB_2U_LIB.S9S_MB_2U(SCH_1):GND    I43 @S9S_MB_2U_LIB.S9S_MB_2U(SCH_1):PAGE162

U312 TUSB211IRWBR-TUSB211IRWBR,SMLFA
     5 PD_USB_HUB_2_RSTN @S9S_MB_2U_LIB.S9S_MB_2U(SCH_1):PD_USB_HUB_2_RSTN    I20 @S9S_MB_2U_LIB.S9S_MB_2U(SCH_1):PAGE194
     8 USB2_HUB_2_BUF_EXT_R_DN @S9S_MB_2U_LIB.S9S_MB_2U(SCH_1):USB2_HUB_2_BUF_EXT_R_DN    I20 @S9S_MB_2U_LIB.S9S_MB_2U(SCH_1):PAGE194
    11 PD_USB_HUB_2_VREG @S9S_MB_2U_LIB.S9S_MB_2U(SCH_1):PD_USB_HUB_2_VREG    I20 @S9S_MB_2U_LIB.S9S_MB_2U(SCH_1):PAGE194
     3 TP_USB_HUB_2_TEST @S9S_MB_2U_LIB.S9S_MB_2U(SCH_1):TP_USB_HUB_2_TEST    I20 @S9S_MB_2U_LIB.S9S_MB_2U(SCH_1):PAGE194
    12 P3V3_AUX @S9S_MB_2U_LIB.S9S_MB_2U(SCH_1):P3V3_AUX    I20 @S9S_MB_2U_LIB.S9S_MB_2U(SCH_1):PAGE194
     9 TP_USB_HUB_2_ENA_HS @S9S_MB_2U_LIB.S9S_MB_2U(SCH_1):TP_USB_HUB_2_ENA_HS    I20 @S9S_MB_2U_LIB.S9S_MB_2U(SCH_1):PAGE194
     4 TP_USB_HUB_2_CD @S9S_MB_2U_LIB.S9S_MB_2U(SCH_1):TP_USB_HUB_2_CD    I20 @S9S_MB_2U_LIB.S9S_MB_2U(SCH_1):PAGE194
     1 USB2_HUB_2_BUF_EXT_R_DN @S9S_MB_2U_LIB.S9S_MB_2U(SCH_1):USB2_HUB_2_BUF_EXT_R_DN    I20 @S9S_MB_2U_LIB.S9S_MB_2U(SCH_1):PAGE194
     2 USB2_HUB_2_BUF_EXT_R_DP @S9S_MB_2U_LIB.S9S_MB_2U(SCH_1):USB2_HUB_2_BUF_EXT_R_DP    I20 @S9S_MB_2U_LIB.S9S_MB_2U(SCH_1):PAGE194
     7 USB2_HUB_2_BUF_EXT_R_DP @S9S_MB_2U_LIB.S9S_MB_2U(SCH_1):USB2_HUB_2_BUF_EXT_R_DP    I20 @S9S_MB_2U_LIB.S9S_MB_2U(SCH_1):PAGE194
     6 PD_USB_HUB_2_EQ @S9S_MB_2U_LIB.S9S_MB_2U(SCH_1):PD_USB_HUB_2_EQ    I20 @S9S_MB_2U_LIB.S9S_MB_2U(SCH_1):PAGE194
    10    GND @S9S_MB_2U_LIB.S9S_MB_2U(SCH_1):GND    I20 @S9S_MB_2U_LIB.S9S_MB_2U(SCH_1):PAGE194

U313 GL852GOHY60-GL852G-OHY60,SMLF,B
    10 USB_HUB_2_XTAL_IN @S9S_MB_2U_LIB.S9S_MB_2U(SCH_1):USB_HUB_2_XTAL_IN    I40 @S9S_MB_2U_LIB.S9S_MB_2U(SCH_1):PAGE194
    11 USB_HUB_2_XTAL_OUT @S9S_MB_2U_LIB.S9S_MB_2U(SCH_1):USB_HUB_2_XTAL_OUT    I40 @S9S_MB_2U_LIB.S9S_MB_2U(SCH_1):PAGE194
    18 USB_HUB_2_TEST @S9S_MB_2U_LIB.S9S_MB_2U(SCH_1):USB_HUB_2_TEST    I40 @S9S_MB_2U_LIB.S9S_MB_2U(SCH_1):PAGE194
    26 NC_USB_HUB_2_SDA @S9S_MB_2U_LIB.S9S_MB_2U(SCH_1):NC_USB_HUB_2_SDA    I40 @S9S_MB_2U_LIB.S9S_MB_2U(SCH_1):PAGE194
    27 P3V3_AUX_USB_HUB_2 @S9S_MB_2U_LIB.S9S_MB_2U(SCH_1):P3V3_AUX_USB_HUB_2    I40 @S9S_MB_2U_LIB.S9S_MB_2U(SCH_1):PAGE194
    28 P3V3_AUX_USB_HUB_2 @S9S_MB_2U_LIB.S9S_MB_2U(SCH_1):P3V3_AUX_USB_HUB_2    I40 @S9S_MB_2U_LIB.S9S_MB_2U(SCH_1):PAGE194
     5 P3V3_AUX_USB_HUB_2 @S9S_MB_2U_LIB.S9S_MB_2U(SCH_1):P3V3_AUX_USB_HUB_2    I40 @S9S_MB_2U_LIB.S9S_MB_2U(SCH_1):PAGE194
     9 P3V3_AUX_USB_HUB_2 @S9S_MB_2U_LIB.S9S_MB_2U(SCH_1):P3V3_AUX_USB_HUB_2    I40 @S9S_MB_2U_LIB.S9S_MB_2U(SCH_1):PAGE194
    14 P3V3_AUX_USB_HUB_2 @S9S_MB_2U_LIB.S9S_MB_2U(SCH_1):P3V3_AUX_USB_HUB_2    I40 @S9S_MB_2U_LIB.S9S_MB_2U(SCH_1):PAGE194
    21 USB_HUB_2_DVDD @S9S_MB_2U_LIB.S9S_MB_2U(SCH_1):USB_HUB_2_DVDD    I40 @S9S_MB_2U_LIB.S9S_MB_2U(SCH_1):PAGE194
    TH    GND @S9S_MB_2U_LIB.S9S_MB_2U(SCH_1):GND    I40 @S9S_MB_2U_LIB.S9S_MB_2U(SCH_1):PAGE194
    25 USB_HUB_2_OVCUR1 @S9S_MB_2U_LIB.S9S_MB_2U(SCH_1):USB_HUB_2_OVCUR1    I40 @S9S_MB_2U_LIB.S9S_MB_2U(SCH_1):PAGE194
    24 USB_HUB_2_OVCUR2 @S9S_MB_2U_LIB.S9S_MB_2U(SCH_1):USB_HUB_2_OVCUR2    I40 @S9S_MB_2U_LIB.S9S_MB_2U(SCH_1):PAGE194
    20 USB_HUB_2_OVCUR3 @S9S_MB_2U_LIB.S9S_MB_2U(SCH_1):USB_HUB_2_OVCUR3    I40 @S9S_MB_2U_LIB.S9S_MB_2U(SCH_1):PAGE194
    19 USB_HUB_2_OVCUR4 @S9S_MB_2U_LIB.S9S_MB_2U(SCH_1):USB_HUB_2_OVCUR4    I40 @S9S_MB_2U_LIB.S9S_MB_2U(SCH_1):PAGE194
    17 RST_USB_HUB_2_R_N @S9S_MB_2U_LIB.S9S_MB_2U(SCH_1):RST_USB_HUB_2_R_N    I40 @S9S_MB_2U_LIB.S9S_MB_2U(SCH_1):PAGE194
    23 USB_HUB_2_PGANG @S9S_MB_2U_LIB.S9S_MB_2U(SCH_1):USB_HUB_2_PGANG    I40 @S9S_MB_2U_LIB.S9S_MB_2U(SCH_1):PAGE194
    22 USB_HUB_2_PSELF @S9S_MB_2U_LIB.S9S_MB_2U(SCH_1):USB_HUB_2_PSELF    I40 @S9S_MB_2U_LIB.S9S_MB_2U(SCH_1):PAGE194
     8 USB_HUB_2_RREF @S9S_MB_2U_LIB.S9S_MB_2U(SCH_1):USB_HUB_2_RREF    I40 @S9S_MB_2U_LIB.S9S_MB_2U(SCH_1):PAGE194
     2 USB2_PCH_0_R_DP @S9S_MB_2U_LIB.S9S_MB_2U(SCH_1):USB2_PCH_0_R_DP    I40 @S9S_MB_2U_LIB.S9S_MB_2U(SCH_1):PAGE194
     1 USB2_PCH_0_R_DN @S9S_MB_2U_LIB.S9S_MB_2U(SCH_1):USB2_PCH_0_R_DN    I40 @S9S_MB_2U_LIB.S9S_MB_2U(SCH_1):PAGE194
     4 USB2_HUB_2_EXT_DP @S9S_MB_2U_LIB.S9S_MB_2U(SCH_1):USB2_HUB_2_EXT_DP    I40 @S9S_MB_2U_LIB.S9S_MB_2U(SCH_1):PAGE194
     3 USB2_HUB_2_EXT_DN @S9S_MB_2U_LIB.S9S_MB_2U(SCH_1):USB2_HUB_2_EXT_DN    I40 @S9S_MB_2U_LIB.S9S_MB_2U(SCH_1):PAGE194
     7 NC_USB_HUB_2_DP2 @S9S_MB_2U_LIB.S9S_MB_2U(SCH_1):NC_USB_HUB_2_DP2    I40 @S9S_MB_2U_LIB.S9S_MB_2U(SCH_1):PAGE194
     6 NC_USB_HUB_2_DM2 @S9S_MB_2U_LIB.S9S_MB_2U(SCH_1):NC_USB_HUB_2_DM2    I40 @S9S_MB_2U_LIB.S9S_MB_2U(SCH_1):PAGE194
    13 NC_USB_HUB_2_DP3 @S9S_MB_2U_LIB.S9S_MB_2U(SCH_1):NC_USB_HUB_2_DP3    I40 @S9S_MB_2U_LIB.S9S_MB_2U(SCH_1):PAGE194
    12 NC_USB_HUB_2_DM3 @S9S_MB_2U_LIB.S9S_MB_2U(SCH_1):NC_USB_HUB_2_DM3    I40 @S9S_MB_2U_LIB.S9S_MB_2U(SCH_1):PAGE194
    16 NC_USB_HUB_2_DP4 @S9S_MB_2U_LIB.S9S_MB_2U(SCH_1):NC_USB_HUB_2_DP4    I40 @S9S_MB_2U_LIB.S9S_MB_2U(SCH_1):PAGE194
    15 NC_USB_HUB_2_DM4 @S9S_MB_2U_LIB.S9S_MB_2U(SCH_1):NC_USB_HUB_2_DM4    I40 @S9S_MB_2U_LIB.S9S_MB_2U(SCH_1):PAGE194

U314 9ZXL0451EKILFT-9ZXL0451EKILFT,A
     3 CLK_100M_GPU_SWB_REF_DP @S9S_MB_2U_LIB.S9S_MB_2U(SCH_1):CLK_100M_GPU_SWB_REF_DP     I1 @S9S_MB_2U_LIB.S9S_MB_2U(SCH_1):PAGE200
     4 CLK_100M_GPU_SWB_REF_DN @S9S_MB_2U_LIB.S9S_MB_2U(SCH_1):CLK_100M_GPU_SWB_REF_DN     I1 @S9S_MB_2U_LIB.S9S_MB_2U(SCH_1):PAGE200
     2 P3V3_9ZXL045_VDDR @S9S_MB_2U_LIB.S9S_MB_2U(SCH_1):P3V3_9ZXL045_VDDR     I1 @S9S_MB_2U_LIB.S9S_MB_2U(SCH_1):PAGE200
    25 P3V3_9ZXL045_VDD @S9S_MB_2U_LIB.S9S_MB_2U(SCH_1):P3V3_9ZXL045_VDD     I1 @S9S_MB_2U_LIB.S9S_MB_2U(SCH_1):PAGE200
    29 P3V3_9ZXL045_VDD @S9S_MB_2U_LIB.S9S_MB_2U(SCH_1):P3V3_9ZXL045_VDD     I1 @S9S_MB_2U_LIB.S9S_MB_2U(SCH_1):PAGE200
     9 NC_U314_FBOUT @S9S_MB_2U_LIB.S9S_MB_2U(SCH_1):NC_U314_FBOUT     I1 @S9S_MB_2U_LIB.S9S_MB_2U(SCH_1):PAGE200
    15 FM_9ZXL045_0_OE_N @S9S_MB_2U_LIB.S9S_MB_2U(SCH_1):FM_9ZXL045_0_OE_N     I1 @S9S_MB_2U_LIB.S9S_MB_2U(SCH_1):PAGE200
    26 FM_9ZXL045_3_OE_N @S9S_MB_2U_LIB.S9S_MB_2U(SCH_1):FM_9ZXL045_3_OE_N     I1 @S9S_MB_2U_LIB.S9S_MB_2U(SCH_1):PAGE200
     6 SMB_HOST_9ZXL045_3V3AUX_SDA @S9S_MB_2U_LIB.S9S_MB_2U(SCH_1):SMB_HOST_9ZXL045_3V3AUX_SDA     I1 @S9S_MB_2U_LIB.S9S_MB_2U(SCH_1):PAGE200
    11 NC_U314_NC1 @S9S_MB_2U_LIB.S9S_MB_2U(SCH_1):NC_U314_NC1     I1 @S9S_MB_2U_LIB.S9S_MB_2U(SCH_1):PAGE200
     8 NC_U314_FBOUT_N @S9S_MB_2U_LIB.S9S_MB_2U(SCH_1):NC_U314_FBOUT_N     I1 @S9S_MB_2U_LIB.S9S_MB_2U(SCH_1):PAGE200
     7 SMB_HOST_9ZXL045_3V3AUX_SCL @S9S_MB_2U_LIB.S9S_MB_2U(SCH_1):SMB_HOST_9ZXL045_3V3AUX_SCL     I1 @S9S_MB_2U_LIB.S9S_MB_2U(SCH_1):PAGE200
    21 P3V3_9ZXL045_VDD @S9S_MB_2U_LIB.S9S_MB_2U(SCH_1):P3V3_9ZXL045_VDD     I1 @S9S_MB_2U_LIB.S9S_MB_2U(SCH_1):PAGE200
     1 FM_9ZXL045_DEV_EN @S9S_MB_2U_LIB.S9S_MB_2U(SCH_1):FM_9ZXL045_DEV_EN     I1 @S9S_MB_2U_LIB.S9S_MB_2U(SCH_1):PAGE200
    14 CLK_100M_SWB_R_DN @S9S_MB_2U_LIB.S9S_MB_2U(SCH_1):CLK_100M_SWB_R_DN     I1 @S9S_MB_2U_LIB.S9S_MB_2U(SCH_1):PAGE200
    13 CLK_100M_SWB_R_DP @S9S_MB_2U_LIB.S9S_MB_2U(SCH_1):CLK_100M_SWB_R_DP     I1 @S9S_MB_2U_LIB.S9S_MB_2U(SCH_1):PAGE200
    18 FM_9ZXL045_1_OE_N @S9S_MB_2U_LIB.S9S_MB_2U(SCH_1):FM_9ZXL045_1_OE_N     I1 @S9S_MB_2U_LIB.S9S_MB_2U(SCH_1):PAGE200
    20 CLK_100M_GPU_1_R_DN @S9S_MB_2U_LIB.S9S_MB_2U(SCH_1):CLK_100M_GPU_1_R_DN     I1 @S9S_MB_2U_LIB.S9S_MB_2U(SCH_1):PAGE200
    22 CLK_100M_GPU_2_R_DP @S9S_MB_2U_LIB.S9S_MB_2U(SCH_1):CLK_100M_GPU_2_R_DP     I1 @S9S_MB_2U_LIB.S9S_MB_2U(SCH_1):PAGE200
    24 FM_9ZXL045_2_OE_N @S9S_MB_2U_LIB.S9S_MB_2U(SCH_1):FM_9ZXL045_2_OE_N     I1 @S9S_MB_2U_LIB.S9S_MB_2U(SCH_1):PAGE200
    23 CLK_100M_GPU_2_R_DN @S9S_MB_2U_LIB.S9S_MB_2U(SCH_1):CLK_100M_GPU_2_R_DN     I1 @S9S_MB_2U_LIB.S9S_MB_2U(SCH_1):PAGE200
    28 TP_CLK_100M_BUF_DIF3_DN @S9S_MB_2U_LIB.S9S_MB_2U(SCH_1):TP_CLK_100M_BUF_DIF3_DN     I1 @S9S_MB_2U_LIB.S9S_MB_2U(SCH_1):PAGE200
    10 NC_U314_NC0 @S9S_MB_2U_LIB.S9S_MB_2U(SCH_1):NC_U314_NC0     I1 @S9S_MB_2U_LIB.S9S_MB_2U(SCH_1):PAGE200
    31 P3V3_9ZXL045_VDDA @S9S_MB_2U_LIB.S9S_MB_2U(SCH_1):P3V3_9ZXL045_VDDA     I1 @S9S_MB_2U_LIB.S9S_MB_2U(SCH_1):PAGE200
    16 P3V3_9ZXL045_VDD @S9S_MB_2U_LIB.S9S_MB_2U(SCH_1):P3V3_9ZXL045_VDD     I1 @S9S_MB_2U_LIB.S9S_MB_2U(SCH_1):PAGE200
    32 CLK_9ZXL045_HIBW @S9S_MB_2U_LIB.S9S_MB_2U(SCH_1):CLK_9ZXL045_HIBW     I1 @S9S_MB_2U_LIB.S9S_MB_2U(SCH_1):PAGE200
    33    GND @S9S_MB_2U_LIB.S9S_MB_2U(SCH_1):GND     I1 @S9S_MB_2U_LIB.S9S_MB_2U(SCH_1):PAGE200
    19 CLK_100M_GPU_1_R_DP @S9S_MB_2U_LIB.S9S_MB_2U(SCH_1):CLK_100M_GPU_1_R_DP     I1 @S9S_MB_2U_LIB.S9S_MB_2U(SCH_1):PAGE200
    27 TP_CLK_100M_BUF_DIF3_DP @S9S_MB_2U_LIB.S9S_MB_2U(SCH_1):TP_CLK_100M_BUF_DIF3_DP     I1 @S9S_MB_2U_LIB.S9S_MB_2U(SCH_1):PAGE200
    12 P3V3_9ZXL045_VDD @S9S_MB_2U_LIB.S9S_MB_2U(SCH_1):P3V3_9ZXL045_VDD     I1 @S9S_MB_2U_LIB.S9S_MB_2U(SCH_1):PAGE200
    30 NC_U314_NC3 @S9S_MB_2U_LIB.S9S_MB_2U(SCH_1):NC_U314_NC3     I1 @S9S_MB_2U_LIB.S9S_MB_2U(SCH_1):PAGE200
    17 NC_U314_NC2 @S9S_MB_2U_LIB.S9S_MB_2U(SCH_1):NC_U314_NC2     I1 @S9S_MB_2U_LIB.S9S_MB_2U(SCH_1):PAGE200
     5 CLK_9ZXL045_SADR0 @S9S_MB_2U_LIB.S9S_MB_2U(SCH_1):CLK_9ZXL045_SADR0     I1 @S9S_MB_2U_LIB.S9S_MB_2U(SCH_1):PAGE200

U315 PCA9617ADP-PCA9617ADP,SMLF,IC,A
     5 PU_CLK_BUF_ISO_EN @S9S_MB_2U_LIB.S9S_MB_2U(SCH_1):PU_CLK_BUF_ISO_EN    I17 @S9S_MB_2U_LIB.S9S_MB_2U(SCH_1):PAGE225
     1 P3V3_AUX @S9S_MB_2U_LIB.S9S_MB_2U(SCH_1):P3V3_AUX    I17 @S9S_MB_2U_LIB.S9S_MB_2U(SCH_1):PAGE225
     8   P3V3 @S9S_MB_2U_LIB.S9S_MB_2U(SCH_1):P3V3    I17 @S9S_MB_2U_LIB.S9S_MB_2U(SCH_1):PAGE225
     2 SMB_HOST_CLK_BUF_3V3AUX_SCL @S9S_MB_2U_LIB.S9S_MB_2U(SCH_1):SMB_HOST_CLK_BUF_3V3AUX_SCL    I17 @S9S_MB_2U_LIB.S9S_MB_2U(SCH_1):PAGE225
     3 SMB_HOST_CLK_BUF_3V3AUX_SDA @S9S_MB_2U_LIB.S9S_MB_2U(SCH_1):SMB_HOST_CLK_BUF_3V3AUX_SDA    I17 @S9S_MB_2U_LIB.S9S_MB_2U(SCH_1):PAGE225
     6 SMB_HOST_CLK_BUF_ISO_3V3AUX_S_2 @S9S_MB_2U_LIB.S9S_MB_2U(SCH_1):SMB_HOST_CLK_BUF_ISO_3V3AUX_SDA_R    I17 @S9S_MB_2U_LIB.S9S_MB_2U(SCH_1):PAGE225
     7 SMB_HOST_CLK_BUF_ISO_3V3AUX_S_1 @S9S_MB_2U_LIB.S9S_MB_2U(SCH_1):SMB_HOST_CLK_BUF_ISO_3V3AUX_SCL_R    I17 @S9S_MB_2U_LIB.S9S_MB_2U(SCH_1):PAGE225
     4    GND @S9S_MB_2U_LIB.S9S_MB_2U(SCH_1):GND    I17 @S9S_MB_2U_LIB.S9S_MB_2U(SCH_1):PAGE225

U316 74LVC2G17GW-74LVC2G17GW,SMLF,IA
     5 P3V3_AUX @S9S_MB_2U_LIB.S9S_MB_2U(SCH_1):P3V3_AUX    I86 @S9S_MB_2U_LIB.S9S_MB_2U(SCH_1):PAGE139
     4 NC_U316_2Y @S9S_MB_2U_LIB.S9S_MB_2U(SCH_1):NC_U316_2Y    I86 @S9S_MB_2U_LIB.S9S_MB_2U(SCH_1):PAGE139
     2    GND @S9S_MB_2U_LIB.S9S_MB_2U(SCH_1):GND    I86 @S9S_MB_2U_LIB.S9S_MB_2U(SCH_1):PAGE139
     1 SWB_HSC_EN @S9S_MB_2U_LIB.S9S_MB_2U(SCH_1):SWB_HSC_EN    I86 @S9S_MB_2U_LIB.S9S_MB_2U(SCH_1):PAGE139
     3    GND @S9S_MB_2U_LIB.S9S_MB_2U(SCH_1):GND    I86 @S9S_MB_2U_LIB.S9S_MB_2U(SCH_1):PAGE139
     6 SWB_HSC_EN_BUF_R @S9S_MB_2U_LIB.S9S_MB_2U(SCH_1):SWB_HSC_EN_BUF_R    I86 @S9S_MB_2U_LIB.S9S_MB_2U(SCH_1):PAGE139

U320 74LVC1G66GV-74LVC1G66GV,SMLF,IA
     1 CLK_50M_NCSI_OCP_SFF @S9S_MB_2U_LIB.S9S_MB_2U(SCH_1):CLK_50M_NCSI_OCP_SFF    I92 @S9S_MB_2U_LIB.S9S_MB_2U(SCH_1):PAGE152
     2 CLK_50M_NCSI_OCP_SFF_ISO_R @S9S_MB_2U_LIB.S9S_MB_2U(SCH_1):CLK_50M_NCSI_OCP_SFF_ISO_R    I92 @S9S_MB_2U_LIB.S9S_MB_2U(SCH_1):PAGE152
     3    GND @S9S_MB_2U_LIB.S9S_MB_2U(SCH_1):GND    I92 @S9S_MB_2U_LIB.S9S_MB_2U(SCH_1):PAGE152
     4 FB_BMC_ISOLATE @S9S_MB_2U_LIB.S9S_MB_2U(SCH_1):FB_BMC_ISOLATE    I92 @S9S_MB_2U_LIB.S9S_MB_2U(SCH_1):PAGE152
     5 P3V3_AUX @S9S_MB_2U_LIB.S9S_MB_2U(SCH_1):P3V3_AUX    I92 @S9S_MB_2U_LIB.S9S_MB_2U(SCH_1):PAGE152

U321 74LVC1G66GV-74LVC1G66GV,SMLF,IA
     1 CLK_50M_NCSI_OCP_V3_2 @S9S_MB_2U_LIB.S9S_MB_2U(SCH_1):CLK_50M_NCSI_OCP_V3_2    I92 @S9S_MB_2U_LIB.S9S_MB_2U(SCH_1):PAGE156
     2 CLK_50M_NCSI_OCP_V3_2_ISO_R @S9S_MB_2U_LIB.S9S_MB_2U(SCH_1):CLK_50M_NCSI_OCP_V3_2_ISO_R    I92 @S9S_MB_2U_LIB.S9S_MB_2U(SCH_1):PAGE156
     3    GND @S9S_MB_2U_LIB.S9S_MB_2U(SCH_1):GND    I92 @S9S_MB_2U_LIB.S9S_MB_2U(SCH_1):PAGE156
     4 FB_BMC_ISOLATE1 @S9S_MB_2U_LIB.S9S_MB_2U(SCH_1):FB_BMC_ISOLATE1    I92 @S9S_MB_2U_LIB.S9S_MB_2U(SCH_1):PAGE156
     5 P3V3_AUX @S9S_MB_2U_LIB.S9S_MB_2U(SCH_1):P3V3_AUX    I92 @S9S_MB_2U_LIB.S9S_MB_2U(SCH_1):PAGE156

U322 74LVC1G08W57-74LVC1G08W5-7,SMLA
     1 HP_OCP_V3_1_RST_R @S9S_MB_2U_LIB.S9S_MB_2U(SCH_1):HP_OCP_V3_1_RST_R   I221 @S9S_MB_2U_LIB.S9S_MB_2U(SCH_1):PAGE154
     2 HP_LVC3_OCP_V3_1_P12V_PWRGD @S9S_MB_2U_LIB.S9S_MB_2U(SCH_1):HP_LVC3_OCP_V3_1_P12V_PWRGD   I221 @S9S_MB_2U_LIB.S9S_MB_2U(SCH_1):PAGE154
     3    GND @S9S_MB_2U_LIB.S9S_MB_2U(SCH_1):GND   I221 @S9S_MB_2U_LIB.S9S_MB_2U(SCH_1):PAGE154
     4 HP_LVC3_OCP_V3_1_PWRGD @S9S_MB_2U_LIB.S9S_MB_2U(SCH_1):HP_LVC3_OCP_V3_1_PWRGD   I221 @S9S_MB_2U_LIB.S9S_MB_2U(SCH_1):PAGE154
     5 P3V3_AUX @S9S_MB_2U_LIB.S9S_MB_2U(SCH_1):P3V3_AUX   I221 @S9S_MB_2U_LIB.S9S_MB_2U(SCH_1):PAGE154

U323 74LVC1G08W57-74LVC1G08W5-7,SMLA
     1 HP_OCP_V3_2_RST_R @S9S_MB_2U_LIB.S9S_MB_2U(SCH_1):HP_OCP_V3_2_RST_R    I92 @S9S_MB_2U_LIB.S9S_MB_2U(SCH_1):PAGE132
     2 HP_LVC3_OCP_V3_2_P12V_PWRGD @S9S_MB_2U_LIB.S9S_MB_2U(SCH_1):HP_LVC3_OCP_V3_2_P12V_PWRGD    I92 @S9S_MB_2U_LIB.S9S_MB_2U(SCH_1):PAGE132
     3    GND @S9S_MB_2U_LIB.S9S_MB_2U(SCH_1):GND    I92 @S9S_MB_2U_LIB.S9S_MB_2U(SCH_1):PAGE132
     4 HP_LVC3_OCP_V3_2_PWRGD @S9S_MB_2U_LIB.S9S_MB_2U(SCH_1):HP_LVC3_OCP_V3_2_PWRGD    I92 @S9S_MB_2U_LIB.S9S_MB_2U(SCH_1):PAGE132
     5 P3V3_AUX @S9S_MB_2U_LIB.S9S_MB_2U(SCH_1):P3V3_AUX    I92 @S9S_MB_2U_LIB.S9S_MB_2U(SCH_1):PAGE132

U324 MOSFET_NCH_GDS_ESD_PROTECTED-2A
     D VR_P5V_EN_D @S9S_MB_2U_LIB.S9S_MB_2U(SCH_1):VR_P5V_EN_D    I67 @S9S_MB_2U_LIB.S9S_MB_2U(SCH_1):PAGE246
     G VR_P5V_EN_N @S9S_MB_2U_LIB.S9S_MB_2U(SCH_1):VR_P5V_EN_N    I67 @S9S_MB_2U_LIB.S9S_MB_2U(SCH_1):PAGE246
     S    GND @S9S_MB_2U_LIB.S9S_MB_2U(SCH_1):GND    I67 @S9S_MB_2U_LIB.S9S_MB_2U(SCH_1):PAGE246

U325 MOSFET_N_SMLF-BSS138K,BSS138K,A
     G A_P12V_STBY_FPH_GATE @S9S_MB_2U_LIB.S9S_MB_2U(SCH_1):A_P12V_STBY_FPH_GATE    I38 @S9S_MB_2U_LIB.S9S_MB_2U(SCH_1):PAGE326
     D IRQ_UV_DETECT_N @S9S_MB_2U_LIB.S9S_MB_2U(SCH_1):IRQ_UV_DETECT_N    I38 @S9S_MB_2U_LIB.S9S_MB_2U(SCH_1):PAGE326
     S    GND @S9S_MB_2U_LIB.S9S_MB_2U(SCH_1):GND    I38 @S9S_MB_2U_LIB.S9S_MB_2U(SCH_1):PAGE326

U327 74CBTLV3126PW-74CBTLV3126PW,SMA
     5 JTAG_BMC_TMS_R @S9S_MB_2U_LIB.S9S_MB_2U(SCH_1):JTAG_BMC_TMS_R    I19 @S9S_MB_2U_LIB.S9S_MB_2U(SCH_1):PAGE235
     8 JTAG_BMC_SW_TDI_R @S9S_MB_2U_LIB.S9S_MB_2U(SCH_1):JTAG_BMC_SW_TDI_R    I19 @S9S_MB_2U_LIB.S9S_MB_2U(SCH_1):PAGE235
     1 JTAG_BMC_SW_R_OE @S9S_MB_2U_LIB.S9S_MB_2U(SCH_1):JTAG_BMC_SW_R_OE    I19 @S9S_MB_2U_LIB.S9S_MB_2U(SCH_1):PAGE235
     4 JTAG_BMC_SW_R_OE @S9S_MB_2U_LIB.S9S_MB_2U(SCH_1):JTAG_BMC_SW_R_OE    I19 @S9S_MB_2U_LIB.S9S_MB_2U(SCH_1):PAGE235
     3 JTAG_BMC_SW_TCK_R @S9S_MB_2U_LIB.S9S_MB_2U(SCH_1):JTAG_BMC_SW_TCK_R    I19 @S9S_MB_2U_LIB.S9S_MB_2U(SCH_1):PAGE235
     6 JTAG_BMC_SW_TMS_R @S9S_MB_2U_LIB.S9S_MB_2U(SCH_1):JTAG_BMC_SW_TMS_R    I19 @S9S_MB_2U_LIB.S9S_MB_2U(SCH_1):PAGE235
     2 JTAG_BMC_TCK_R @S9S_MB_2U_LIB.S9S_MB_2U(SCH_1):JTAG_BMC_TCK_R    I19 @S9S_MB_2U_LIB.S9S_MB_2U(SCH_1):PAGE235
     7    GND @S9S_MB_2U_LIB.S9S_MB_2U(SCH_1):GND    I19 @S9S_MB_2U_LIB.S9S_MB_2U(SCH_1):PAGE235
     9 JTAG_BMC_TDI_R @S9S_MB_2U_LIB.S9S_MB_2U(SCH_1):JTAG_BMC_TDI_R    I19 @S9S_MB_2U_LIB.S9S_MB_2U(SCH_1):PAGE235
    10 JTAG_BMC_SW_R_OE @S9S_MB_2U_LIB.S9S_MB_2U(SCH_1):JTAG_BMC_SW_R_OE    I19 @S9S_MB_2U_LIB.S9S_MB_2U(SCH_1):PAGE235
    11 JTAG_BMC_SW_TDO_R @S9S_MB_2U_LIB.S9S_MB_2U(SCH_1):JTAG_BMC_SW_TDO_R    I19 @S9S_MB_2U_LIB.S9S_MB_2U(SCH_1):PAGE235
    12 JTAG_BMC_TDO_R @S9S_MB_2U_LIB.S9S_MB_2U(SCH_1):JTAG_BMC_TDO_R    I19 @S9S_MB_2U_LIB.S9S_MB_2U(SCH_1):PAGE235
    13 JTAG_BMC_SW_R_OE @S9S_MB_2U_LIB.S9S_MB_2U(SCH_1):JTAG_BMC_SW_R_OE    I19 @S9S_MB_2U_LIB.S9S_MB_2U(SCH_1):PAGE235
    14 P3V3_AUX @S9S_MB_2U_LIB.S9S_MB_2U(SCH_1):P3V3_AUX    I19 @S9S_MB_2U_LIB.S9S_MB_2U(SCH_1):PAGE235

U328 DS125BR111RTWR-DS125BR111RTWR,A
     1 FM_P2E_BUF2_EQB0 @S9S_MB_2U_LIB.S9S_MB_2U(SCH_1):FM_P2E_BUF2_EQB0    I95 @S9S_MB_2U_LIB.S9S_MB_2U(SCH_1):PAGE159
     2 FM_P2E_BUF2_EQB1 @S9S_MB_2U_LIB.S9S_MB_2U(SCH_1):FM_P2E_BUF2_EQB1    I95 @S9S_MB_2U_LIB.S9S_MB_2U(SCH_1):PAGE159
     3 PD_P2E_BUF2_ENSMB @S9S_MB_2U_LIB.S9S_MB_2U(SCH_1):PD_P2E_BUF2_ENSMB    I95 @S9S_MB_2U_LIB.S9S_MB_2U(SCH_1):PAGE159
     4 FM_P2E_BUF2_VODA_DB @S9S_MB_2U_LIB.S9S_MB_2U(SCH_1):FM_P2E_BUF2_VODA_DB    I95 @S9S_MB_2U_LIB.S9S_MB_2U(SCH_1):PAGE159
     5 FM_P2E_BUF2_VODB_DB @S9S_MB_2U_LIB.S9S_MB_2U(SCH_1):FM_P2E_BUF2_VODB_DB    I95 @S9S_MB_2U_LIB.S9S_MB_2U(SCH_1):PAGE159
     6 FM_P2E_EN2_N @S9S_MB_2U_LIB.S9S_MB_2U(SCH_1):FM_P2E_EN2_N    I95 @S9S_MB_2U_LIB.S9S_MB_2U(SCH_1):PAGE159
     7 P2E_MB_BMC_TX_BUF2_DP<0> @S9S_MB_2U_LIB.S9S_MB_2U(SCH_1):P2E_MB_BMC_TX_BUF2_DP(0)    I95 @S9S_MB_2U_LIB.S9S_MB_2U(SCH_1):PAGE159
     8 P2E_MB_BMC_TX_BUF2_DN<0> @S9S_MB_2U_LIB.S9S_MB_2U(SCH_1):P2E_MB_BMC_TX_BUF2_DN(0)    I95 @S9S_MB_2U_LIB.S9S_MB_2U(SCH_1):PAGE159
     9 FM_P2E_BUF2_EQA1 @S9S_MB_2U_LIB.S9S_MB_2U(SCH_1):FM_P2E_BUF2_EQA1    I95 @S9S_MB_2U_LIB.S9S_MB_2U(SCH_1):PAGE159
    10 FM_P2E_BUF2_EQA0 @S9S_MB_2U_LIB.S9S_MB_2U(SCH_1):FM_P2E_BUF2_EQA0    I95 @S9S_MB_2U_LIB.S9S_MB_2U(SCH_1):PAGE159
    11 P2E_MB_BMC_RX_R2_DP<0> @S9S_MB_2U_LIB.S9S_MB_2U(SCH_1):P2E_MB_BMC_RX_R2_DP(0)    I95 @S9S_MB_2U_LIB.S9S_MB_2U(SCH_1):PAGE159
    12 P2E_MB_BMC_RX_R2_DN<0> @S9S_MB_2U_LIB.S9S_MB_2U(SCH_1):P2E_MB_BMC_RX_R2_DN(0)    I95 @S9S_MB_2U_LIB.S9S_MB_2U(SCH_1):PAGE159
    13 NC_RES @S9S_MB_2U_LIB.S9S_MB_2U(SCH_1):NC_RES    I95 @S9S_MB_2U_LIB.S9S_MB_2U(SCH_1):PAGE159
    14 FM_P2E_BUF2_SD_TH @S9S_MB_2U_LIB.S9S_MB_2U(SCH_1):FM_P2E_BUF2_SD_TH    I95 @S9S_MB_2U_LIB.S9S_MB_2U(SCH_1):PAGE159
    15 P3V3_AUX @S9S_MB_2U_LIB.S9S_MB_2U(SCH_1):P3V3_AUX    I95 @S9S_MB_2U_LIB.S9S_MB_2U(SCH_1):PAGE159
    16    GND @S9S_MB_2U_LIB.S9S_MB_2U(SCH_1):GND    I95 @S9S_MB_2U_LIB.S9S_MB_2U(SCH_1):PAGE159
    17 FM_P2E_BUF2_VOD_SEL @S9S_MB_2U_LIB.S9S_MB_2U(SCH_1):FM_P2E_BUF2_VOD_SEL    I95 @S9S_MB_2U_LIB.S9S_MB_2U(SCH_1):PAGE159
    18 FM_P2E_BUF2_RXDET @S9S_MB_2U_LIB.S9S_MB_2U(SCH_1):FM_P2E_BUF2_RXDET    I95 @S9S_MB_2U_LIB.S9S_MB_2U(SCH_1):PAGE159
    19 P2E_MB_BMC_RX_BUF2_C_DN<0> @S9S_MB_2U_LIB.S9S_MB_2U(SCH_1):P2E_MB_BMC_RX_BUF2_C_DN(0)    I95 @S9S_MB_2U_LIB.S9S_MB_2U(SCH_1):PAGE159
    20 P2E_MB_BMC_RX_BUF2_C_DP<0> @S9S_MB_2U_LIB.S9S_MB_2U(SCH_1):P2E_MB_BMC_RX_BUF2_C_DP(0)    I95 @S9S_MB_2U_LIB.S9S_MB_2U(SCH_1):PAGE159
    21 P2E_BUF2_VDD @S9S_MB_2U_LIB.S9S_MB_2U(SCH_1):P2E_BUF2_VDD    I95 @S9S_MB_2U_LIB.S9S_MB_2U(SCH_1):PAGE159
    22 P2E_BUF2_VDD @S9S_MB_2U_LIB.S9S_MB_2U(SCH_1):P2E_BUF2_VDD    I95 @S9S_MB_2U_LIB.S9S_MB_2U(SCH_1):PAGE159
    23 P2E_MB_BMC_TX_C_R2_DN<0> @S9S_MB_2U_LIB.S9S_MB_2U(SCH_1):P2E_MB_BMC_TX_C_R2_DN(0)    I95 @S9S_MB_2U_LIB.S9S_MB_2U(SCH_1):PAGE159
    24 P2E_MB_BMC_TX_C_R2_DP<0> @S9S_MB_2U_LIB.S9S_MB_2U(SCH_1):P2E_MB_BMC_TX_C_R2_DP(0)    I95 @S9S_MB_2U_LIB.S9S_MB_2U(SCH_1):PAGE159
    25    GND @S9S_MB_2U_LIB.S9S_MB_2U(SCH_1):GND    I95 @S9S_MB_2U_LIB.S9S_MB_2U(SCH_1):PAGE159

U329 MOSFET_NCH_GDS_ESD_PROTECTED-2B
     D A_HSC_LOW_DRAIN @S9S_MB_2U_LIB.S9S_MB_2U(SCH_1):A_HSC_LOW_DRAIN    I46 @S9S_MB_2U_LIB.S9S_MB_2U(SCH_1):PAGE326
     G A_HSC_LOW_GATE @S9S_MB_2U_LIB.S9S_MB_2U(SCH_1):A_HSC_LOW_GATE    I46 @S9S_MB_2U_LIB.S9S_MB_2U(SCH_1):PAGE326
     S    GND @S9S_MB_2U_LIB.S9S_MB_2U(SCH_1):GND    I46 @S9S_MB_2U_LIB.S9S_MB_2U(SCH_1):PAGE326

U330 APX80929SAG7-APX809-29SAG-7,SMA
     3   P3V3 @S9S_MB_2U_LIB.S9S_MB_2U(SCH_1):P3V3   I105 @S9S_MB_2U_LIB.S9S_MB_2U(SCH_1):PAGE246
     2 PWRGD_P3V3_R1 @S9S_MB_2U_LIB.S9S_MB_2U(SCH_1):PWRGD_P3V3_R1   I105 @S9S_MB_2U_LIB.S9S_MB_2U(SCH_1):PAGE246
     1    GND @S9S_MB_2U_LIB.S9S_MB_2U(SCH_1):GND   I105 @S9S_MB_2U_LIB.S9S_MB_2U(SCH_1):PAGE246

U331 INA230AIRGTR-INA230AIRGTR,SMLFA
     9 P3V3_AUX @S9S_MB_2U_LIB.S9S_MB_2U(SCH_1):P3V3_AUX    I39 @S9S_MB_2U_LIB.S9S_MB_2U(SCH_1):PAGE240
     1 HSC_TYPE_ADC_A1 @S9S_MB_2U_LIB.S9S_MB_2U(SCH_1):HSC_TYPE_ADC_A1    I39 @S9S_MB_2U_LIB.S9S_MB_2U(SCH_1):PAGE240
     2 HSC_TYPE_ADC_A0 @S9S_MB_2U_LIB.S9S_MB_2U(SCH_1):HSC_TYPE_ADC_A0    I39 @S9S_MB_2U_LIB.S9S_MB_2U(SCH_1):PAGE240
     5 SMB_HSC_TYPE_ADC_SCL @S9S_MB_2U_LIB.S9S_MB_2U(SCH_1):SMB_HSC_TYPE_ADC_SCL    I39 @S9S_MB_2U_LIB.S9S_MB_2U(SCH_1):PAGE240
     4 SMB_HSC_TYPE_ADC_SDA @S9S_MB_2U_LIB.S9S_MB_2U(SCH_1):SMB_HSC_TYPE_ADC_SDA    I39 @S9S_MB_2U_LIB.S9S_MB_2U(SCH_1):PAGE240
    11 HSC_TYPE_ADC @S9S_MB_2U_LIB.S9S_MB_2U(SCH_1):HSC_TYPE_ADC    I39 @S9S_MB_2U_LIB.S9S_MB_2U(SCH_1):PAGE240
    13 NC_HSC_TYPE_VINP @S9S_MB_2U_LIB.S9S_MB_2U(SCH_1):NC_HSC_TYPE_VINP    I39 @S9S_MB_2U_LIB.S9S_MB_2U(SCH_1):PAGE240
    12 NC_HSC_TYPE_VINM @S9S_MB_2U_LIB.S9S_MB_2U(SCH_1):NC_HSC_TYPE_VINM    I39 @S9S_MB_2U_LIB.S9S_MB_2U(SCH_1):PAGE240
     3 TP_HSC_TYPE_ADC_ALERT @S9S_MB_2U_LIB.S9S_MB_2U(SCH_1):TP_HSC_TYPE_ADC_ALERT    I39 @S9S_MB_2U_LIB.S9S_MB_2U(SCH_1):PAGE240
     6 NC_HSC_TYPE_NC0 @S9S_MB_2U_LIB.S9S_MB_2U(SCH_1):NC_HSC_TYPE_NC0    I39 @S9S_MB_2U_LIB.S9S_MB_2U(SCH_1):PAGE240
     7 NC_HSC_TYPE_NC1 @S9S_MB_2U_LIB.S9S_MB_2U(SCH_1):NC_HSC_TYPE_NC1    I39 @S9S_MB_2U_LIB.S9S_MB_2U(SCH_1):PAGE240
     8 NC_HSC_TYPE_NC2 @S9S_MB_2U_LIB.S9S_MB_2U(SCH_1):NC_HSC_TYPE_NC2    I39 @S9S_MB_2U_LIB.S9S_MB_2U(SCH_1):PAGE240
    14 NC_HSC_TYPE_NC3 @S9S_MB_2U_LIB.S9S_MB_2U(SCH_1):NC_HSC_TYPE_NC3    I39 @S9S_MB_2U_LIB.S9S_MB_2U(SCH_1):PAGE240
    15 NC_HSC_TYPE_NC4 @S9S_MB_2U_LIB.S9S_MB_2U(SCH_1):NC_HSC_TYPE_NC4    I39 @S9S_MB_2U_LIB.S9S_MB_2U(SCH_1):PAGE240
    16 NC_HSC_TYPE_NC5 @S9S_MB_2U_LIB.S9S_MB_2U(SCH_1):NC_HSC_TYPE_NC5    I39 @S9S_MB_2U_LIB.S9S_MB_2U(SCH_1):PAGE240
    10    GND @S9S_MB_2U_LIB.S9S_MB_2U(SCH_1):GND    I39 @S9S_MB_2U_LIB.S9S_MB_2U(SCH_1):PAGE240
    TH    GND @S9S_MB_2U_LIB.S9S_MB_2U(SCH_1):GND    I39 @S9S_MB_2U_LIB.S9S_MB_2U(SCH_1):PAGE240

U332 74LVC2G07DW7-74LVC2G07DW-7,SMLB
     1 FM_AC_PWR_BTN_PLD_N @S9S_MB_2U_LIB.S9S_MB_2U(SCH_1):FM_AC_PWR_BTN_PLD_N    I37 @S9S_MB_2U_LIB.S9S_MB_2U(SCH_1):PAGE213
     3    GND @S9S_MB_2U_LIB.S9S_MB_2U(SCH_1):GND    I37 @S9S_MB_2U_LIB.S9S_MB_2U(SCH_1):PAGE213
     6 FM_AC_PWR_BTN_PLD_ISO_R_N @S9S_MB_2U_LIB.S9S_MB_2U(SCH_1):FM_AC_PWR_BTN_PLD_ISO_R_N    I37 @S9S_MB_2U_LIB.S9S_MB_2U(SCH_1):PAGE213
     4 NC_UXX_2Y @S9S_MB_2U_LIB.S9S_MB_2U(SCH_1):NC_UXX_2Y    I37 @S9S_MB_2U_LIB.S9S_MB_2U(SCH_1):PAGE213
     2    GND @S9S_MB_2U_LIB.S9S_MB_2U(SCH_1):GND    I37 @S9S_MB_2U_LIB.S9S_MB_2U(SCH_1):PAGE213
     5 P3V3_AUX @S9S_MB_2U_LIB.S9S_MB_2U(SCH_1):P3V3_AUX    I37 @S9S_MB_2U_LIB.S9S_MB_2U(SCH_1):PAGE213

U334 74LVC1G08W57-74LVC1G08W5-7,SMLA
     1 HP_LVC3_OCP_V3_1_PWRGD_R2 @S9S_MB_2U_LIB.S9S_MB_2U(SCH_1):HP_LVC3_OCP_V3_1_PWRGD_R2   I243 @S9S_MB_2U_LIB.S9S_MB_2U(SCH_1):PAGE154
     2 OCP_SFF_AUX_PWR_PLD_EN_R @S9S_MB_2U_LIB.S9S_MB_2U(SCH_1):OCP_SFF_AUX_PWR_PLD_EN_R   I243 @S9S_MB_2U_LIB.S9S_MB_2U(SCH_1):PAGE154
     3    GND @S9S_MB_2U_LIB.S9S_MB_2U(SCH_1):GND   I243 @S9S_MB_2U_LIB.S9S_MB_2U(SCH_1):PAGE154
     4 OCP_SFF_AUX_PWR_EN_R2 @S9S_MB_2U_LIB.S9S_MB_2U(SCH_1):OCP_SFF_AUX_PWR_EN_R2   I243 @S9S_MB_2U_LIB.S9S_MB_2U(SCH_1):PAGE154
     5 P3V3_AUX @S9S_MB_2U_LIB.S9S_MB_2U(SCH_1):P3V3_AUX   I243 @S9S_MB_2U_LIB.S9S_MB_2U(SCH_1):PAGE154

U335 74LVC1G08W57-74LVC1G08W5-7,SMLA
     1 HP_LVC3_OCP_V3_2_PWRGD_R2 @S9S_MB_2U_LIB.S9S_MB_2U(SCH_1):HP_LVC3_OCP_V3_2_PWRGD_R2   I108 @S9S_MB_2U_LIB.S9S_MB_2U(SCH_1):PAGE132
     2 OCP_V3_2_AUX_PWR_PLD_EN_R @S9S_MB_2U_LIB.S9S_MB_2U(SCH_1):OCP_V3_2_AUX_PWR_PLD_EN_R   I108 @S9S_MB_2U_LIB.S9S_MB_2U(SCH_1):PAGE132
     3    GND @S9S_MB_2U_LIB.S9S_MB_2U(SCH_1):GND   I108 @S9S_MB_2U_LIB.S9S_MB_2U(SCH_1):PAGE132
     4 OCP_V3_2_AUX_PWR_EN_R2 @S9S_MB_2U_LIB.S9S_MB_2U(SCH_1):OCP_V3_2_AUX_PWR_EN_R2   I108 @S9S_MB_2U_LIB.S9S_MB_2U(SCH_1):PAGE132
     5 P3V3_AUX @S9S_MB_2U_LIB.S9S_MB_2U(SCH_1):P3V3_AUX   I108 @S9S_MB_2U_LIB.S9S_MB_2U(SCH_1):PAGE132

U336 APX80929SAG7-APX809-29SAG-7,SMA
     3 P3V3_E1S_0 @S9S_MB_2U_LIB.S9S_MB_2U(SCH_1):P3V3_E1S_0   I329 @S9S_MB_2U_LIB.S9S_MB_2U(SCH_1):PAGE297
     2 HP_E1S_0_P3V3_PWRGD @S9S_MB_2U_LIB.S9S_MB_2U(SCH_1):HP_E1S_0_P3V3_PWRGD   I329 @S9S_MB_2U_LIB.S9S_MB_2U(SCH_1):PAGE297
     1    GND @S9S_MB_2U_LIB.S9S_MB_2U(SCH_1):GND   I329 @S9S_MB_2U_LIB.S9S_MB_2U(SCH_1):PAGE297

U337 LM4040AIM3X25NOPB-LM4040AIM3X-A
     1 UV_ADR_P2V5_COMP @S9S_MB_2U_LIB.S9S_MB_2U(SCH_1):UV_ADR_P2V5_COMP     I3 @S9S_MB_2U_LIB.S9S_MB_2U(SCH_1):PAGE329
     2    GND @S9S_MB_2U_LIB.S9S_MB_2U(SCH_1):GND     I3 @S9S_MB_2U_LIB.S9S_MB_2U(SCH_1):PAGE329
     3     NC     NC     I3 @S9S_MB_2U_LIB.S9S_MB_2U(SCH_1):PAGE329

U338 LM4040AIM3X25NOPB-LM4040AIM3X-A
     1 UV_P2V5_COMP @S9S_MB_2U_LIB.S9S_MB_2U(SCH_1):UV_P2V5_COMP    I43 @S9S_MB_2U_LIB.S9S_MB_2U(SCH_1):PAGE329
     2    GND @S9S_MB_2U_LIB.S9S_MB_2U(SCH_1):GND    I43 @S9S_MB_2U_LIB.S9S_MB_2U(SCH_1):PAGE329
     3     NC     NC    I43 @S9S_MB_2U_LIB.S9S_MB_2U(SCH_1):PAGE329

U339 AP331AWG7-AP331AWG-7,SMLF,EMPTA
     3 P12V_AUX_UV_ADR_TRIGGER @S9S_MB_2U_LIB.S9S_MB_2U(SCH_1):P12V_AUX_UV_ADR_TRIGGER    I12 @S9S_MB_2U_LIB.S9S_MB_2U(SCH_1):PAGE329
     1 UV_ADR_P2V5_COMP @S9S_MB_2U_LIB.S9S_MB_2U(SCH_1):UV_ADR_P2V5_COMP    I12 @S9S_MB_2U_LIB.S9S_MB_2U(SCH_1):PAGE329
     4 FM_UV_ADR_TRIGGER_N_R2 @S9S_MB_2U_LIB.S9S_MB_2U(SCH_1):FM_UV_ADR_TRIGGER_N_R2    I12 @S9S_MB_2U_LIB.S9S_MB_2U(SCH_1):PAGE329
     5 P12V_AUX @S9S_MB_2U_LIB.S9S_MB_2U(SCH_1):P12V_AUX    I12 @S9S_MB_2U_LIB.S9S_MB_2U(SCH_1):PAGE329
     2    GND @S9S_MB_2U_LIB.S9S_MB_2U(SCH_1):GND    I12 @S9S_MB_2U_LIB.S9S_MB_2U(SCH_1):PAGE329

U340 AP331AWG7-AP331AWG-7,SMLF,EMPTA
     3 P12V_AUX_UV_TRIGGER @S9S_MB_2U_LIB.S9S_MB_2U(SCH_1):P12V_AUX_UV_TRIGGER    I23 @S9S_MB_2U_LIB.S9S_MB_2U(SCH_1):PAGE329
     1 UV_P2V5_COMP @S9S_MB_2U_LIB.S9S_MB_2U(SCH_1):UV_P2V5_COMP    I23 @S9S_MB_2U_LIB.S9S_MB_2U(SCH_1):PAGE329
     4 IRQ_UV_DETECT_R2_N @S9S_MB_2U_LIB.S9S_MB_2U(SCH_1):IRQ_UV_DETECT_R2_N    I23 @S9S_MB_2U_LIB.S9S_MB_2U(SCH_1):PAGE329
     5 P12V_AUX @S9S_MB_2U_LIB.S9S_MB_2U(SCH_1):P12V_AUX    I23 @S9S_MB_2U_LIB.S9S_MB_2U(SCH_1):PAGE329
     2    GND @S9S_MB_2U_LIB.S9S_MB_2U(SCH_1):GND    I23 @S9S_MB_2U_LIB.S9S_MB_2U(SCH_1):PAGE329

U341 LM4040AIM3X25NOPB-LM4040AIM3X-A
     1 DSW_PWROK_P2V5_COMP @S9S_MB_2U_LIB.S9S_MB_2U(SCH_1):DSW_PWROK_P2V5_COMP    I63 @S9S_MB_2U_LIB.S9S_MB_2U(SCH_1):PAGE329
     2    GND @S9S_MB_2U_LIB.S9S_MB_2U(SCH_1):GND    I63 @S9S_MB_2U_LIB.S9S_MB_2U(SCH_1):PAGE329
     3     NC     NC    I63 @S9S_MB_2U_LIB.S9S_MB_2U(SCH_1):PAGE329

U342 AP331AWG7-AP331AWG-7,SMLF,EMPTA
     3 PWRGD_DSW_PWROK_TRIGGER @S9S_MB_2U_LIB.S9S_MB_2U(SCH_1):PWRGD_DSW_PWROK_TRIGGER    I45 @S9S_MB_2U_LIB.S9S_MB_2U(SCH_1):PAGE329
     1 DSW_PWROK_P2V5_COMP @S9S_MB_2U_LIB.S9S_MB_2U(SCH_1):DSW_PWROK_P2V5_COMP    I45 @S9S_MB_2U_LIB.S9S_MB_2U(SCH_1):PAGE329
     4 PWRGD_DSW_PWROK_R5 @S9S_MB_2U_LIB.S9S_MB_2U(SCH_1):PWRGD_DSW_PWROK_R5    I45 @S9S_MB_2U_LIB.S9S_MB_2U(SCH_1):PAGE329
     5 P12V_AUX @S9S_MB_2U_LIB.S9S_MB_2U(SCH_1):P12V_AUX    I45 @S9S_MB_2U_LIB.S9S_MB_2U(SCH_1):PAGE329
     2    GND @S9S_MB_2U_LIB.S9S_MB_2U(SCH_1):GND    I45 @S9S_MB_2U_LIB.S9S_MB_2U(SCH_1):PAGE329

U343 LM4040AIM3X25NOPB-LM4040AIM3X-A
     1 OC_P2V5_COMP @S9S_MB_2U_LIB.S9S_MB_2U(SCH_1):OC_P2V5_COMP    I56 @S9S_MB_2U_LIB.S9S_MB_2U(SCH_1):PAGE326
     2    GND @S9S_MB_2U_LIB.S9S_MB_2U(SCH_1):GND    I56 @S9S_MB_2U_LIB.S9S_MB_2U(SCH_1):PAGE326
     3     NC     NC    I56 @S9S_MB_2U_LIB.S9S_MB_2U(SCH_1):PAGE326

U344 AP331AWG7-AP331AWG-7,SMLF,EMPTA
     3 HSC_OC_VOL @S9S_MB_2U_LIB.S9S_MB_2U(SCH_1):HSC_OC_VOL    I66 @S9S_MB_2U_LIB.S9S_MB_2U(SCH_1):PAGE326
     1 OC_P2V5_COMP @S9S_MB_2U_LIB.S9S_MB_2U(SCH_1):OC_P2V5_COMP    I66 @S9S_MB_2U_LIB.S9S_MB_2U(SCH_1):PAGE326
     4 HSC_D_OC_R2 @S9S_MB_2U_LIB.S9S_MB_2U(SCH_1):HSC_D_OC_R2    I66 @S9S_MB_2U_LIB.S9S_MB_2U(SCH_1):PAGE326
     5 P12V_AUX @S9S_MB_2U_LIB.S9S_MB_2U(SCH_1):P12V_AUX    I66 @S9S_MB_2U_LIB.S9S_MB_2U(SCH_1):PAGE326
     2    GND @S9S_MB_2U_LIB.S9S_MB_2U(SCH_1):GND    I66 @S9S_MB_2U_LIB.S9S_MB_2U(SCH_1):PAGE326

U345 NCT7718W-NCT7718W,SMLF,EMPTY,AA
     1 P3V3_AUX @S9S_MB_2U_LIB.S9S_MB_2U(SCH_1):P3V3_AUX    I10 @S9S_MB_2U_LIB.S9S_MB_2U(SCH_1):PAGE327
     2 P12V_HSC_TEMP_D+ @S9S_MB_2U_LIB.S9S_MB_2U(SCH_1):P12V_HSC_TEMP_D+    I10 @S9S_MB_2U_LIB.S9S_MB_2U(SCH_1):PAGE327
     3 P12V_HSC_TEMP_D- @S9S_MB_2U_LIB.S9S_MB_2U(SCH_1):P12V_HSC_TEMP_D-    I10 @S9S_MB_2U_LIB.S9S_MB_2U(SCH_1):PAGE327
     4 P12V_HSC_T_CRIT_N @S9S_MB_2U_LIB.S9S_MB_2U(SCH_1):P12V_HSC_T_CRIT_N    I10 @S9S_MB_2U_LIB.S9S_MB_2U(SCH_1):PAGE327
     5    GND @S9S_MB_2U_LIB.S9S_MB_2U(SCH_1):GND    I10 @S9S_MB_2U_LIB.S9S_MB_2U(SCH_1):PAGE327
     6 P12V_HSC_TEMP_ALERT_N @S9S_MB_2U_LIB.S9S_MB_2U(SCH_1):P12V_HSC_TEMP_ALERT_N    I10 @S9S_MB_2U_LIB.S9S_MB_2U(SCH_1):PAGE327
     7 P12V_HSC_TEMP_SDA @S9S_MB_2U_LIB.S9S_MB_2U(SCH_1):P12V_HSC_TEMP_SDA    I10 @S9S_MB_2U_LIB.S9S_MB_2U(SCH_1):PAGE327
     8 P12V_HSC_TEMP_SCL @S9S_MB_2U_LIB.S9S_MB_2U(SCH_1):P12V_HSC_TEMP_SCL    I10 @S9S_MB_2U_LIB.S9S_MB_2U(SCH_1):PAGE327

U365 MMBT3904_SMLF-MMBT3904    ,EMPA
     B P12V_HSC_TEMP_R @S9S_MB_2U_LIB.S9S_MB_2U(SCH_1):P12V_HSC_TEMP_R    I49 @S9S_MB_2U_LIB.S9S_MB_2U(SCH_1):PAGE327
     E P12V_HSC_TEMP_E @S9S_MB_2U_LIB.S9S_MB_2U(SCH_1):P12V_HSC_TEMP_E    I49 @S9S_MB_2U_LIB.S9S_MB_2U(SCH_1):PAGE327
     C P12V_HSC_TEMP_R @S9S_MB_2U_LIB.S9S_MB_2U(SCH_1):P12V_HSC_TEMP_R    I49 @S9S_MB_2U_LIB.S9S_MB_2U(SCH_1):PAGE327

U369 TPS3700DDCR-TPS3700DDCR,SMLF,EA
     5 U369_VDD @S9S_MB_2U_LIB.S9S_MB_2U(SCH_1):U369_VDD    I30 @S9S_MB_2U_LIB.S9S_MB_2U(SCH_1):PAGE326
     4 A_HSC_HIGH @S9S_MB_2U_LIB.S9S_MB_2U(SCH_1):A_HSC_HIGH    I30 @S9S_MB_2U_LIB.S9S_MB_2U(SCH_1):PAGE326
     2    GND @S9S_MB_2U_LIB.S9S_MB_2U(SCH_1):GND    I30 @S9S_MB_2U_LIB.S9S_MB_2U(SCH_1):PAGE326
     1 A_HSC_LOW_GATE @S9S_MB_2U_LIB.S9S_MB_2U(SCH_1):A_HSC_LOW_GATE    I30 @S9S_MB_2U_LIB.S9S_MB_2U(SCH_1):PAGE326
     3 A_HSC_LOW @S9S_MB_2U_LIB.S9S_MB_2U(SCH_1):A_HSC_LOW    I30 @S9S_MB_2U_LIB.S9S_MB_2U(SCH_1):PAGE326
     6 HSC_D_OC @S9S_MB_2U_LIB.S9S_MB_2U(SCH_1):HSC_D_OC    I30 @S9S_MB_2U_LIB.S9S_MB_2U(SCH_1):PAGE326

U5201 TUSB211IRWBR-TUSB211IRWBR,SMLFA
     5 PD_U5201_RSTN @S9S_MB_2U_LIB.S9S_MB_2U(SCH_1):PD_U5201_RSTN    I84 @S9S_MB_2U_LIB.S9S_MB_2U(SCH_1):PAGE155
     8 USB2_HUB_BUF_SWB_R_DN @S9S_MB_2U_LIB.S9S_MB_2U(SCH_1):USB2_HUB_BUF_SWB_R_DN    I84 @S9S_MB_2U_LIB.S9S_MB_2U(SCH_1):PAGE155
    11 PD_U5201_VREG @S9S_MB_2U_LIB.S9S_MB_2U(SCH_1):PD_U5201_VREG    I84 @S9S_MB_2U_LIB.S9S_MB_2U(SCH_1):PAGE155
     3 TP_USB2_TEST @S9S_MB_2U_LIB.S9S_MB_2U(SCH_1):TP_USB2_TEST    I84 @S9S_MB_2U_LIB.S9S_MB_2U(SCH_1):PAGE155
    12 P3V3_AUX @S9S_MB_2U_LIB.S9S_MB_2U(SCH_1):P3V3_AUX    I84 @S9S_MB_2U_LIB.S9S_MB_2U(SCH_1):PAGE155
     9 TP_USB2_ENA_HS @S9S_MB_2U_LIB.S9S_MB_2U(SCH_1):TP_USB2_ENA_HS    I84 @S9S_MB_2U_LIB.S9S_MB_2U(SCH_1):PAGE155
     4 TP_USB2_CD @S9S_MB_2U_LIB.S9S_MB_2U(SCH_1):TP_USB2_CD    I84 @S9S_MB_2U_LIB.S9S_MB_2U(SCH_1):PAGE155
     1 USB2_HUB_BUF_SWB_R_DN @S9S_MB_2U_LIB.S9S_MB_2U(SCH_1):USB2_HUB_BUF_SWB_R_DN    I84 @S9S_MB_2U_LIB.S9S_MB_2U(SCH_1):PAGE155
     2 USB2_HUB_BUF_SWB_R_DP @S9S_MB_2U_LIB.S9S_MB_2U(SCH_1):USB2_HUB_BUF_SWB_R_DP    I84 @S9S_MB_2U_LIB.S9S_MB_2U(SCH_1):PAGE155
     7 USB2_HUB_BUF_SWB_R_DP @S9S_MB_2U_LIB.S9S_MB_2U(SCH_1):USB2_HUB_BUF_SWB_R_DP    I84 @S9S_MB_2U_LIB.S9S_MB_2U(SCH_1):PAGE155
     6 PD_U5201_EQ @S9S_MB_2U_LIB.S9S_MB_2U(SCH_1):PD_U5201_EQ    I84 @S9S_MB_2U_LIB.S9S_MB_2U(SCH_1):PAGE155
    10    GND @S9S_MB_2U_LIB.S9S_MB_2U(SCH_1):GND    I84 @S9S_MB_2U_LIB.S9S_MB_2U(SCH_1):PAGE155

  X1 TP_TDR_4P_FTS_TH-TP_TDR_4P_DIPA
     2 T1_GND @S9S_MB_2U_LIB.S9S_MB_2U(SCH_1):T1_GND    I28 @S9S_MB_2U_LIB.S9S_MB_2U(SCH_1):PAGE288
     3 T1_GND @S9S_MB_2U_LIB.S9S_MB_2U(SCH_1):T1_GND    I28 @S9S_MB_2U_LIB.S9S_MB_2U(SCH_1):PAGE288
     1 TDR_DIFF_85_TOP_DP @S9S_MB_2U_LIB.S9S_MB_2U(SCH_1):TDR_DIFF_85_TOP_DP    I28 @S9S_MB_2U_LIB.S9S_MB_2U(SCH_1):PAGE288
     4 TDR_DIFF_85_TOP_DN @S9S_MB_2U_LIB.S9S_MB_2U(SCH_1):TDR_DIFF_85_TOP_DN    I28 @S9S_MB_2U_LIB.S9S_MB_2U(SCH_1):PAGE288

  X2 TP_TDR_4P_FTS_TH-TP_TDR_4P_DIPA
     2 T1_GND @S9S_MB_2U_LIB.S9S_MB_2U(SCH_1):T1_GND    I30 @S9S_MB_2U_LIB.S9S_MB_2U(SCH_1):PAGE288
     3 T1_GND @S9S_MB_2U_LIB.S9S_MB_2U(SCH_1):T1_GND    I30 @S9S_MB_2U_LIB.S9S_MB_2U(SCH_1):PAGE288
     1 TDR_DIFF_85_IN1_DP @S9S_MB_2U_LIB.S9S_MB_2U(SCH_1):TDR_DIFF_85_IN1_DP    I30 @S9S_MB_2U_LIB.S9S_MB_2U(SCH_1):PAGE288
     4 TDR_DIFF_85_IN1_DN @S9S_MB_2U_LIB.S9S_MB_2U(SCH_1):TDR_DIFF_85_IN1_DN    I30 @S9S_MB_2U_LIB.S9S_MB_2U(SCH_1):PAGE288

  X3 TP_TDR_4P_FTS_TH-TP_TDR_4P_DIPA
     2 T1_GND @S9S_MB_2U_LIB.S9S_MB_2U(SCH_1):T1_GND    I35 @S9S_MB_2U_LIB.S9S_MB_2U(SCH_1):PAGE288
     3 T1_GND @S9S_MB_2U_LIB.S9S_MB_2U(SCH_1):T1_GND    I35 @S9S_MB_2U_LIB.S9S_MB_2U(SCH_1):PAGE288
     1 TDR_DIFF_85_IN2_DP @S9S_MB_2U_LIB.S9S_MB_2U(SCH_1):TDR_DIFF_85_IN2_DP    I35 @S9S_MB_2U_LIB.S9S_MB_2U(SCH_1):PAGE288
     4 TDR_DIFF_85_IN2_DN @S9S_MB_2U_LIB.S9S_MB_2U(SCH_1):TDR_DIFF_85_IN2_DN    I35 @S9S_MB_2U_LIB.S9S_MB_2U(SCH_1):PAGE288

  X4 TP_TDR_4P_FTS_TH-TP_TDR_4P_DIPA
     2 T1_GND @S9S_MB_2U_LIB.S9S_MB_2U(SCH_1):T1_GND    I37 @S9S_MB_2U_LIB.S9S_MB_2U(SCH_1):PAGE288
     3 T1_GND @S9S_MB_2U_LIB.S9S_MB_2U(SCH_1):T1_GND    I37 @S9S_MB_2U_LIB.S9S_MB_2U(SCH_1):PAGE288
     1 TDR_DIFF_85_IN3_DP @S9S_MB_2U_LIB.S9S_MB_2U(SCH_1):TDR_DIFF_85_IN3_DP    I37 @S9S_MB_2U_LIB.S9S_MB_2U(SCH_1):PAGE288
     4 TDR_DIFF_85_IN3_DN @S9S_MB_2U_LIB.S9S_MB_2U(SCH_1):TDR_DIFF_85_IN3_DN    I37 @S9S_MB_2U_LIB.S9S_MB_2U(SCH_1):PAGE288

  X5 TP_TDR_4P_FTS_TH-TP_TDR_4P_DIPA
     2 T1_GND @S9S_MB_2U_LIB.S9S_MB_2U(SCH_1):T1_GND    I39 @S9S_MB_2U_LIB.S9S_MB_2U(SCH_1):PAGE288
     3 T1_GND @S9S_MB_2U_LIB.S9S_MB_2U(SCH_1):T1_GND    I39 @S9S_MB_2U_LIB.S9S_MB_2U(SCH_1):PAGE288
     1 TDR_DIFF_85_IN4_DP @S9S_MB_2U_LIB.S9S_MB_2U(SCH_1):TDR_DIFF_85_IN4_DP    I39 @S9S_MB_2U_LIB.S9S_MB_2U(SCH_1):PAGE288
     4 TDR_DIFF_85_IN4_DN @S9S_MB_2U_LIB.S9S_MB_2U(SCH_1):TDR_DIFF_85_IN4_DN    I39 @S9S_MB_2U_LIB.S9S_MB_2U(SCH_1):PAGE288

  X6 TP_TDR_4P_FTS_TH-TP_TDR_4P_DIPA
     2 T1_GND @S9S_MB_2U_LIB.S9S_MB_2U(SCH_1):T1_GND    I47 @S9S_MB_2U_LIB.S9S_MB_2U(SCH_1):PAGE288
     3 T1_GND @S9S_MB_2U_LIB.S9S_MB_2U(SCH_1):T1_GND    I47 @S9S_MB_2U_LIB.S9S_MB_2U(SCH_1):PAGE288
     1 TDR_DIFF_85_BOT_DP @S9S_MB_2U_LIB.S9S_MB_2U(SCH_1):TDR_DIFF_85_BOT_DP    I47 @S9S_MB_2U_LIB.S9S_MB_2U(SCH_1):PAGE288
     4 TDR_DIFF_85_BOT_DN @S9S_MB_2U_LIB.S9S_MB_2U(SCH_1):TDR_DIFF_85_BOT_DN    I47 @S9S_MB_2U_LIB.S9S_MB_2U(SCH_1):PAGE288

  X7 TP_TDR_4P_FTS_TH-TP_TDR_4P_DIPA
     2 T1_GND @S9S_MB_2U_LIB.S9S_MB_2U(SCH_1):T1_GND    I26 @S9S_MB_2U_LIB.S9S_MB_2U(SCH_1):PAGE288
     3 T1_GND @S9S_MB_2U_LIB.S9S_MB_2U(SCH_1):T1_GND    I26 @S9S_MB_2U_LIB.S9S_MB_2U(SCH_1):PAGE288
     1 TDR_DIFF_85_TOP_DN @S9S_MB_2U_LIB.S9S_MB_2U(SCH_1):TDR_DIFF_85_TOP_DN    I26 @S9S_MB_2U_LIB.S9S_MB_2U(SCH_1):PAGE288
     4 TDR_DIFF_85_TOP_DP @S9S_MB_2U_LIB.S9S_MB_2U(SCH_1):TDR_DIFF_85_TOP_DP    I26 @S9S_MB_2U_LIB.S9S_MB_2U(SCH_1):PAGE288

  X8 TP_TDR_4P_FTS_TH-TP_TDR_4P_DIPA
     2 T1_GND @S9S_MB_2U_LIB.S9S_MB_2U(SCH_1):T1_GND    I27 @S9S_MB_2U_LIB.S9S_MB_2U(SCH_1):PAGE288
     3 T1_GND @S9S_MB_2U_LIB.S9S_MB_2U(SCH_1):T1_GND    I27 @S9S_MB_2U_LIB.S9S_MB_2U(SCH_1):PAGE288
     1 TDR_DIFF_85_IN1_DN @S9S_MB_2U_LIB.S9S_MB_2U(SCH_1):TDR_DIFF_85_IN1_DN    I27 @S9S_MB_2U_LIB.S9S_MB_2U(SCH_1):PAGE288
     4 TDR_DIFF_85_IN1_DP @S9S_MB_2U_LIB.S9S_MB_2U(SCH_1):TDR_DIFF_85_IN1_DP    I27 @S9S_MB_2U_LIB.S9S_MB_2U(SCH_1):PAGE288

  X9 TP_TDR_4P_FTS_TH-TP_TDR_4P_DIPA
     2 T1_GND @S9S_MB_2U_LIB.S9S_MB_2U(SCH_1):T1_GND    I32 @S9S_MB_2U_LIB.S9S_MB_2U(SCH_1):PAGE288
     3 T1_GND @S9S_MB_2U_LIB.S9S_MB_2U(SCH_1):T1_GND    I32 @S9S_MB_2U_LIB.S9S_MB_2U(SCH_1):PAGE288
     1 TDR_DIFF_85_IN2_DN @S9S_MB_2U_LIB.S9S_MB_2U(SCH_1):TDR_DIFF_85_IN2_DN    I32 @S9S_MB_2U_LIB.S9S_MB_2U(SCH_1):PAGE288
     4 TDR_DIFF_85_IN2_DP @S9S_MB_2U_LIB.S9S_MB_2U(SCH_1):TDR_DIFF_85_IN2_DP    I32 @S9S_MB_2U_LIB.S9S_MB_2U(SCH_1):PAGE288

 X10 TP_TDR_4P_FTS_TH-TP_TDR_4P_DIPA
     2 T1_GND @S9S_MB_2U_LIB.S9S_MB_2U(SCH_1):T1_GND    I33 @S9S_MB_2U_LIB.S9S_MB_2U(SCH_1):PAGE288
     3 T1_GND @S9S_MB_2U_LIB.S9S_MB_2U(SCH_1):T1_GND    I33 @S9S_MB_2U_LIB.S9S_MB_2U(SCH_1):PAGE288
     1 TDR_DIFF_85_IN3_DN @S9S_MB_2U_LIB.S9S_MB_2U(SCH_1):TDR_DIFF_85_IN3_DN    I33 @S9S_MB_2U_LIB.S9S_MB_2U(SCH_1):PAGE288
     4 TDR_DIFF_85_IN3_DP @S9S_MB_2U_LIB.S9S_MB_2U(SCH_1):TDR_DIFF_85_IN3_DP    I33 @S9S_MB_2U_LIB.S9S_MB_2U(SCH_1):PAGE288

 X11 TP_TDR_4P_FTS_TH-TP_TDR_4P_DIPA
     2 T1_GND @S9S_MB_2U_LIB.S9S_MB_2U(SCH_1):T1_GND    I34 @S9S_MB_2U_LIB.S9S_MB_2U(SCH_1):PAGE288
     3 T1_GND @S9S_MB_2U_LIB.S9S_MB_2U(SCH_1):T1_GND    I34 @S9S_MB_2U_LIB.S9S_MB_2U(SCH_1):PAGE288
     1 TDR_DIFF_85_IN4_DN @S9S_MB_2U_LIB.S9S_MB_2U(SCH_1):TDR_DIFF_85_IN4_DN    I34 @S9S_MB_2U_LIB.S9S_MB_2U(SCH_1):PAGE288
     4 TDR_DIFF_85_IN4_DP @S9S_MB_2U_LIB.S9S_MB_2U(SCH_1):TDR_DIFF_85_IN4_DP    I34 @S9S_MB_2U_LIB.S9S_MB_2U(SCH_1):PAGE288

 X12 TP_TDR_4P_FTS_TH-TP_TDR_4P_DIPA
     2 T1_GND @S9S_MB_2U_LIB.S9S_MB_2U(SCH_1):T1_GND    I46 @S9S_MB_2U_LIB.S9S_MB_2U(SCH_1):PAGE288
     3 T1_GND @S9S_MB_2U_LIB.S9S_MB_2U(SCH_1):T1_GND    I46 @S9S_MB_2U_LIB.S9S_MB_2U(SCH_1):PAGE288
     1 TDR_DIFF_85_BOT_DN @S9S_MB_2U_LIB.S9S_MB_2U(SCH_1):TDR_DIFF_85_BOT_DN    I46 @S9S_MB_2U_LIB.S9S_MB_2U(SCH_1):PAGE288
     4 TDR_DIFF_85_BOT_DP @S9S_MB_2U_LIB.S9S_MB_2U(SCH_1):TDR_DIFF_85_BOT_DP    I46 @S9S_MB_2U_LIB.S9S_MB_2U(SCH_1):PAGE288

 X13 TP_TDR_4P_FTS_TH-TP_TDR_4P_DIPA
     2 T1_GND @S9S_MB_2U_LIB.S9S_MB_2U(SCH_1):T1_GND    I11 @S9S_MB_2U_LIB.S9S_MB_2U(SCH_1):PAGE288
     3 T1_GND @S9S_MB_2U_LIB.S9S_MB_2U(SCH_1):T1_GND    I11 @S9S_MB_2U_LIB.S9S_MB_2U(SCH_1):PAGE288
     1 TDR_DIFF_100_TOP_DP @S9S_MB_2U_LIB.S9S_MB_2U(SCH_1):TDR_DIFF_100_TOP_DP    I11 @S9S_MB_2U_LIB.S9S_MB_2U(SCH_1):PAGE288
     4 TDR_DIFF_100_TOP_DN @S9S_MB_2U_LIB.S9S_MB_2U(SCH_1):TDR_DIFF_100_TOP_DN    I11 @S9S_MB_2U_LIB.S9S_MB_2U(SCH_1):PAGE288

 X14 TP_TDR_4P_FTS_TH-TP_TDR_4P_DIPA
     2 T1_GND @S9S_MB_2U_LIB.S9S_MB_2U(SCH_1):T1_GND    I12 @S9S_MB_2U_LIB.S9S_MB_2U(SCH_1):PAGE288
     3 T1_GND @S9S_MB_2U_LIB.S9S_MB_2U(SCH_1):T1_GND    I12 @S9S_MB_2U_LIB.S9S_MB_2U(SCH_1):PAGE288
     1 TDR_DIFF_100_IN1_DP @S9S_MB_2U_LIB.S9S_MB_2U(SCH_1):TDR_DIFF_100_IN1_DP    I12 @S9S_MB_2U_LIB.S9S_MB_2U(SCH_1):PAGE288
     4 TDR_DIFF_100_IN1_DN @S9S_MB_2U_LIB.S9S_MB_2U(SCH_1):TDR_DIFF_100_IN1_DN    I12 @S9S_MB_2U_LIB.S9S_MB_2U(SCH_1):PAGE288

 X15 TP_TDR_4P_FTS_TH-TP_TDR_4P_DIPA
     2 T1_GND @S9S_MB_2U_LIB.S9S_MB_2U(SCH_1):T1_GND    I17 @S9S_MB_2U_LIB.S9S_MB_2U(SCH_1):PAGE288
     3 T1_GND @S9S_MB_2U_LIB.S9S_MB_2U(SCH_1):T1_GND    I17 @S9S_MB_2U_LIB.S9S_MB_2U(SCH_1):PAGE288
     1 TDR_DIFF_100_IN2_DP @S9S_MB_2U_LIB.S9S_MB_2U(SCH_1):TDR_DIFF_100_IN2_DP    I17 @S9S_MB_2U_LIB.S9S_MB_2U(SCH_1):PAGE288
     4 TDR_DIFF_100_IN2_DN @S9S_MB_2U_LIB.S9S_MB_2U(SCH_1):TDR_DIFF_100_IN2_DN    I17 @S9S_MB_2U_LIB.S9S_MB_2U(SCH_1):PAGE288

 X16 TP_TDR_4P_FTS_TH-TP_TDR_4P_DIPA
     2 T1_GND @S9S_MB_2U_LIB.S9S_MB_2U(SCH_1):T1_GND    I18 @S9S_MB_2U_LIB.S9S_MB_2U(SCH_1):PAGE288
     3 T1_GND @S9S_MB_2U_LIB.S9S_MB_2U(SCH_1):T1_GND    I18 @S9S_MB_2U_LIB.S9S_MB_2U(SCH_1):PAGE288
     1 TDR_DIFF_100_IN3_DP @S9S_MB_2U_LIB.S9S_MB_2U(SCH_1):TDR_DIFF_100_IN3_DP    I18 @S9S_MB_2U_LIB.S9S_MB_2U(SCH_1):PAGE288
     4 TDR_DIFF_100_IN3_DN @S9S_MB_2U_LIB.S9S_MB_2U(SCH_1):TDR_DIFF_100_IN3_DN    I18 @S9S_MB_2U_LIB.S9S_MB_2U(SCH_1):PAGE288

 X17 TP_TDR_4P_FTS_TH-TP_TDR_4P_DIPA
     2 T1_GND @S9S_MB_2U_LIB.S9S_MB_2U(SCH_1):T1_GND    I19 @S9S_MB_2U_LIB.S9S_MB_2U(SCH_1):PAGE288
     3 T1_GND @S9S_MB_2U_LIB.S9S_MB_2U(SCH_1):T1_GND    I19 @S9S_MB_2U_LIB.S9S_MB_2U(SCH_1):PAGE288
     1 TDR_DIFF_100_IN4_DP @S9S_MB_2U_LIB.S9S_MB_2U(SCH_1):TDR_DIFF_100_IN4_DP    I19 @S9S_MB_2U_LIB.S9S_MB_2U(SCH_1):PAGE288
     4 TDR_DIFF_100_IN4_DN @S9S_MB_2U_LIB.S9S_MB_2U(SCH_1):TDR_DIFF_100_IN4_DN    I19 @S9S_MB_2U_LIB.S9S_MB_2U(SCH_1):PAGE288

 X18 TP_TDR_4P_FTS_TH-TP_TDR_4P_DIPA
     2 T1_GND @S9S_MB_2U_LIB.S9S_MB_2U(SCH_1):T1_GND    I43 @S9S_MB_2U_LIB.S9S_MB_2U(SCH_1):PAGE288
     3 T1_GND @S9S_MB_2U_LIB.S9S_MB_2U(SCH_1):T1_GND    I43 @S9S_MB_2U_LIB.S9S_MB_2U(SCH_1):PAGE288
     1 TDR_DIFF_100_BOT_DP @S9S_MB_2U_LIB.S9S_MB_2U(SCH_1):TDR_DIFF_100_BOT_DP    I43 @S9S_MB_2U_LIB.S9S_MB_2U(SCH_1):PAGE288
     4 TDR_DIFF_100_BOT_DN @S9S_MB_2U_LIB.S9S_MB_2U(SCH_1):TDR_DIFF_100_BOT_DN    I43 @S9S_MB_2U_LIB.S9S_MB_2U(SCH_1):PAGE288

 X19 TP_TDR_4P_FTS_TH-TP_TDR_4P_DIPA
     2 T1_GND @S9S_MB_2U_LIB.S9S_MB_2U(SCH_1):T1_GND     I3 @S9S_MB_2U_LIB.S9S_MB_2U(SCH_1):PAGE288
     3 T1_GND @S9S_MB_2U_LIB.S9S_MB_2U(SCH_1):T1_GND     I3 @S9S_MB_2U_LIB.S9S_MB_2U(SCH_1):PAGE288
     1 TDR_DIFF_100_TOP_DN @S9S_MB_2U_LIB.S9S_MB_2U(SCH_1):TDR_DIFF_100_TOP_DN     I3 @S9S_MB_2U_LIB.S9S_MB_2U(SCH_1):PAGE288
     4 TDR_DIFF_100_TOP_DP @S9S_MB_2U_LIB.S9S_MB_2U(SCH_1):TDR_DIFF_100_TOP_DP     I3 @S9S_MB_2U_LIB.S9S_MB_2U(SCH_1):PAGE288

 X20 TP_TDR_4P_FTS_TH-TP_TDR_4P_DIPA
     2 T1_GND @S9S_MB_2U_LIB.S9S_MB_2U(SCH_1):T1_GND     I4 @S9S_MB_2U_LIB.S9S_MB_2U(SCH_1):PAGE288
     3 T1_GND @S9S_MB_2U_LIB.S9S_MB_2U(SCH_1):T1_GND     I4 @S9S_MB_2U_LIB.S9S_MB_2U(SCH_1):PAGE288
     1 TDR_DIFF_100_IN1_DN @S9S_MB_2U_LIB.S9S_MB_2U(SCH_1):TDR_DIFF_100_IN1_DN     I4 @S9S_MB_2U_LIB.S9S_MB_2U(SCH_1):PAGE288
     4 TDR_DIFF_100_IN1_DP @S9S_MB_2U_LIB.S9S_MB_2U(SCH_1):TDR_DIFF_100_IN1_DP     I4 @S9S_MB_2U_LIB.S9S_MB_2U(SCH_1):PAGE288

 X21 TP_TDR_4P_FTS_TH-TP_TDR_4P_DIPA
     2 T1_GND @S9S_MB_2U_LIB.S9S_MB_2U(SCH_1):T1_GND     I9 @S9S_MB_2U_LIB.S9S_MB_2U(SCH_1):PAGE288
     3 T1_GND @S9S_MB_2U_LIB.S9S_MB_2U(SCH_1):T1_GND     I9 @S9S_MB_2U_LIB.S9S_MB_2U(SCH_1):PAGE288
     1 TDR_DIFF_100_IN2_DN @S9S_MB_2U_LIB.S9S_MB_2U(SCH_1):TDR_DIFF_100_IN2_DN     I9 @S9S_MB_2U_LIB.S9S_MB_2U(SCH_1):PAGE288
     4 TDR_DIFF_100_IN2_DP @S9S_MB_2U_LIB.S9S_MB_2U(SCH_1):TDR_DIFF_100_IN2_DP     I9 @S9S_MB_2U_LIB.S9S_MB_2U(SCH_1):PAGE288

 X22 TP_TDR_4P_FTS_TH-TP_TDR_4P_DIPA
     2 T1_GND @S9S_MB_2U_LIB.S9S_MB_2U(SCH_1):T1_GND     I8 @S9S_MB_2U_LIB.S9S_MB_2U(SCH_1):PAGE288
     3 T1_GND @S9S_MB_2U_LIB.S9S_MB_2U(SCH_1):T1_GND     I8 @S9S_MB_2U_LIB.S9S_MB_2U(SCH_1):PAGE288
     1 TDR_DIFF_100_IN3_DN @S9S_MB_2U_LIB.S9S_MB_2U(SCH_1):TDR_DIFF_100_IN3_DN     I8 @S9S_MB_2U_LIB.S9S_MB_2U(SCH_1):PAGE288
     4 TDR_DIFF_100_IN3_DP @S9S_MB_2U_LIB.S9S_MB_2U(SCH_1):TDR_DIFF_100_IN3_DP     I8 @S9S_MB_2U_LIB.S9S_MB_2U(SCH_1):PAGE288

 X23 TP_TDR_4P_FTS_TH-TP_TDR_4P_DIPA
     2 T1_GND @S9S_MB_2U_LIB.S9S_MB_2U(SCH_1):T1_GND    I10 @S9S_MB_2U_LIB.S9S_MB_2U(SCH_1):PAGE288
     3 T1_GND @S9S_MB_2U_LIB.S9S_MB_2U(SCH_1):T1_GND    I10 @S9S_MB_2U_LIB.S9S_MB_2U(SCH_1):PAGE288
     1 TDR_DIFF_100_IN4_DN @S9S_MB_2U_LIB.S9S_MB_2U(SCH_1):TDR_DIFF_100_IN4_DN    I10 @S9S_MB_2U_LIB.S9S_MB_2U(SCH_1):PAGE288
     4 TDR_DIFF_100_IN4_DP @S9S_MB_2U_LIB.S9S_MB_2U(SCH_1):TDR_DIFF_100_IN4_DP    I10 @S9S_MB_2U_LIB.S9S_MB_2U(SCH_1):PAGE288

 X24 TP_TDR_4P_FTS_TH-TP_TDR_4P_DIPA
     2 T1_GND @S9S_MB_2U_LIB.S9S_MB_2U(SCH_1):T1_GND    I42 @S9S_MB_2U_LIB.S9S_MB_2U(SCH_1):PAGE288
     3 T1_GND @S9S_MB_2U_LIB.S9S_MB_2U(SCH_1):T1_GND    I42 @S9S_MB_2U_LIB.S9S_MB_2U(SCH_1):PAGE288
     1 TDR_DIFF_100_BOT_DN @S9S_MB_2U_LIB.S9S_MB_2U(SCH_1):TDR_DIFF_100_BOT_DN    I42 @S9S_MB_2U_LIB.S9S_MB_2U(SCH_1):PAGE288
     4 TDR_DIFF_100_BOT_DP @S9S_MB_2U_LIB.S9S_MB_2U(SCH_1):TDR_DIFF_100_BOT_DP    I42 @S9S_MB_2U_LIB.S9S_MB_2U(SCH_1):PAGE288

 X25 TP_TDR_4P_FTS_TH-TP_TDR_4P_DIPA
     2 T1_GND @S9S_MB_2U_LIB.S9S_MB_2U(SCH_1):T1_GND   I108 @S9S_MB_2U_LIB.S9S_MB_2U(SCH_1):PAGE288
     3 T1_GND @S9S_MB_2U_LIB.S9S_MB_2U(SCH_1):T1_GND   I108 @S9S_MB_2U_LIB.S9S_MB_2U(SCH_1):PAGE288
     1 TDR_DIFF_85_IN5_DP @S9S_MB_2U_LIB.S9S_MB_2U(SCH_1):TDR_DIFF_85_IN5_DP   I108 @S9S_MB_2U_LIB.S9S_MB_2U(SCH_1):PAGE288
     4 TDR_DIFF_85_IN5_DN @S9S_MB_2U_LIB.S9S_MB_2U(SCH_1):TDR_DIFF_85_IN5_DN   I108 @S9S_MB_2U_LIB.S9S_MB_2U(SCH_1):PAGE288

 X26 TP_TDR_4P_FTS_TH-TP_TDR_4P_DIPA
     2 T1_GND @S9S_MB_2U_LIB.S9S_MB_2U(SCH_1):T1_GND   I110 @S9S_MB_2U_LIB.S9S_MB_2U(SCH_1):PAGE288
     3 T1_GND @S9S_MB_2U_LIB.S9S_MB_2U(SCH_1):T1_GND   I110 @S9S_MB_2U_LIB.S9S_MB_2U(SCH_1):PAGE288
     1 TDR_DIFF_85_IN6_DP @S9S_MB_2U_LIB.S9S_MB_2U(SCH_1):TDR_DIFF_85_IN6_DP   I110 @S9S_MB_2U_LIB.S9S_MB_2U(SCH_1):PAGE288
     4 TDR_DIFF_85_IN6_DN @S9S_MB_2U_LIB.S9S_MB_2U(SCH_1):TDR_DIFF_85_IN6_DN   I110 @S9S_MB_2U_LIB.S9S_MB_2U(SCH_1):PAGE288

 X27 TP_TDR_4P_FTS_TH-TP_TDR_4P_DIPA
     2 T1_GND @S9S_MB_2U_LIB.S9S_MB_2U(SCH_1):T1_GND   I106 @S9S_MB_2U_LIB.S9S_MB_2U(SCH_1):PAGE288
     3 T1_GND @S9S_MB_2U_LIB.S9S_MB_2U(SCH_1):T1_GND   I106 @S9S_MB_2U_LIB.S9S_MB_2U(SCH_1):PAGE288
     1 TDR_DIFF_85_IN5_DN @S9S_MB_2U_LIB.S9S_MB_2U(SCH_1):TDR_DIFF_85_IN5_DN   I106 @S9S_MB_2U_LIB.S9S_MB_2U(SCH_1):PAGE288
     4 TDR_DIFF_85_IN5_DP @S9S_MB_2U_LIB.S9S_MB_2U(SCH_1):TDR_DIFF_85_IN5_DP   I106 @S9S_MB_2U_LIB.S9S_MB_2U(SCH_1):PAGE288

 X28 TP_TDR_4P_FTS_TH-TP_TDR_4P_DIPA
     2 T1_GND @S9S_MB_2U_LIB.S9S_MB_2U(SCH_1):T1_GND   I107 @S9S_MB_2U_LIB.S9S_MB_2U(SCH_1):PAGE288
     3 T1_GND @S9S_MB_2U_LIB.S9S_MB_2U(SCH_1):T1_GND   I107 @S9S_MB_2U_LIB.S9S_MB_2U(SCH_1):PAGE288
     1 TDR_DIFF_85_IN6_DN @S9S_MB_2U_LIB.S9S_MB_2U(SCH_1):TDR_DIFF_85_IN6_DN   I107 @S9S_MB_2U_LIB.S9S_MB_2U(SCH_1):PAGE288
     4 TDR_DIFF_85_IN6_DP @S9S_MB_2U_LIB.S9S_MB_2U(SCH_1):TDR_DIFF_85_IN6_DP   I107 @S9S_MB_2U_LIB.S9S_MB_2U(SCH_1):PAGE288

 X29 TP_TDR_4P_FTS_TH-TP_TDR_4P_DIPA
     2 T1_GND @S9S_MB_2U_LIB.S9S_MB_2U(SCH_1):T1_GND   I116 @S9S_MB_2U_LIB.S9S_MB_2U(SCH_1):PAGE288
     3 T1_GND @S9S_MB_2U_LIB.S9S_MB_2U(SCH_1):T1_GND   I116 @S9S_MB_2U_LIB.S9S_MB_2U(SCH_1):PAGE288
     1 TDR_DIFF_100_IN5_DP @S9S_MB_2U_LIB.S9S_MB_2U(SCH_1):TDR_DIFF_100_IN5_DP   I116 @S9S_MB_2U_LIB.S9S_MB_2U(SCH_1):PAGE288
     4 TDR_DIFF_100_IN5_DN @S9S_MB_2U_LIB.S9S_MB_2U(SCH_1):TDR_DIFF_100_IN5_DN   I116 @S9S_MB_2U_LIB.S9S_MB_2U(SCH_1):PAGE288

 X30 TP_TDR_4P_FTS_TH-TP_TDR_4P_DIPA
     2 T1_GND @S9S_MB_2U_LIB.S9S_MB_2U(SCH_1):T1_GND   I117 @S9S_MB_2U_LIB.S9S_MB_2U(SCH_1):PAGE288
     3 T1_GND @S9S_MB_2U_LIB.S9S_MB_2U(SCH_1):T1_GND   I117 @S9S_MB_2U_LIB.S9S_MB_2U(SCH_1):PAGE288
     1 TDR_DIFF_100_IN6_DP @S9S_MB_2U_LIB.S9S_MB_2U(SCH_1):TDR_DIFF_100_IN6_DP   I117 @S9S_MB_2U_LIB.S9S_MB_2U(SCH_1):PAGE288
     4 TDR_DIFF_100_IN6_DN @S9S_MB_2U_LIB.S9S_MB_2U(SCH_1):TDR_DIFF_100_IN6_DN   I117 @S9S_MB_2U_LIB.S9S_MB_2U(SCH_1):PAGE288

 X31 TP_TDR_4P_FTS_TH-TP_TDR_4P_DIPA
     2 T1_GND @S9S_MB_2U_LIB.S9S_MB_2U(SCH_1):T1_GND   I112 @S9S_MB_2U_LIB.S9S_MB_2U(SCH_1):PAGE288
     3 T1_GND @S9S_MB_2U_LIB.S9S_MB_2U(SCH_1):T1_GND   I112 @S9S_MB_2U_LIB.S9S_MB_2U(SCH_1):PAGE288
     1 TDR_DIFF_100_IN5_DN @S9S_MB_2U_LIB.S9S_MB_2U(SCH_1):TDR_DIFF_100_IN5_DN   I112 @S9S_MB_2U_LIB.S9S_MB_2U(SCH_1):PAGE288
     4 TDR_DIFF_100_IN5_DP @S9S_MB_2U_LIB.S9S_MB_2U(SCH_1):TDR_DIFF_100_IN5_DP   I112 @S9S_MB_2U_LIB.S9S_MB_2U(SCH_1):PAGE288

 X32 TP_TDR_4P_FTS_TH-TP_TDR_4P_DIPA
     2 T1_GND @S9S_MB_2U_LIB.S9S_MB_2U(SCH_1):T1_GND   I115 @S9S_MB_2U_LIB.S9S_MB_2U(SCH_1):PAGE288
     3 T1_GND @S9S_MB_2U_LIB.S9S_MB_2U(SCH_1):T1_GND   I115 @S9S_MB_2U_LIB.S9S_MB_2U(SCH_1):PAGE288
     1 TDR_DIFF_100_IN6_DN @S9S_MB_2U_LIB.S9S_MB_2U(SCH_1):TDR_DIFF_100_IN6_DN   I115 @S9S_MB_2U_LIB.S9S_MB_2U(SCH_1):PAGE288
     4 TDR_DIFF_100_IN6_DP @S9S_MB_2U_LIB.S9S_MB_2U(SCH_1):TDR_DIFF_100_IN6_DP   I115 @S9S_MB_2U_LIB.S9S_MB_2U(SCH_1):PAGE288

 X33 TP_TDR_4P_FTS_TH-TP_TDR_4P_DIPA
     2 T1_GND @S9S_MB_2U_LIB.S9S_MB_2U(SCH_1):T1_GND    I20 @S9S_MB_2U_LIB.S9S_MB_2U(SCH_1):PAGE310
     3 T1_GND @S9S_MB_2U_LIB.S9S_MB_2U(SCH_1):T1_GND    I20 @S9S_MB_2U_LIB.S9S_MB_2U(SCH_1):PAGE310
     1 UNNAMED_310_TPTDR4PFTS_I20_S1 @S9S_MB_2U_LIB.S9S_MB_2U(SCH_1):UNNAMED_310_TPTDR4PFTS_I20_S1    I20 @S9S_MB_2U_LIB.S9S_MB_2U(SCH_1):PAGE310
     4 UNNAMED_310_TPTDR4PFTS_I20_S2 @S9S_MB_2U_LIB.S9S_MB_2U(SCH_1):UNNAMED_310_TPTDR4PFTS_I20_S2    I20 @S9S_MB_2U_LIB.S9S_MB_2U(SCH_1):PAGE310

 X34 TP_TDR_4P_FTS_TH-TP_TDR_4P_DIPA
     2 T1_GND @S9S_MB_2U_LIB.S9S_MB_2U(SCH_1):T1_GND    I19 @S9S_MB_2U_LIB.S9S_MB_2U(SCH_1):PAGE310
     3 T1_GND @S9S_MB_2U_LIB.S9S_MB_2U(SCH_1):T1_GND    I19 @S9S_MB_2U_LIB.S9S_MB_2U(SCH_1):PAGE310
     1 UNNAMED_310_TPTDR4PFTS_I19_S1 @S9S_MB_2U_LIB.S9S_MB_2U(SCH_1):UNNAMED_310_TPTDR4PFTS_I19_S1    I19 @S9S_MB_2U_LIB.S9S_MB_2U(SCH_1):PAGE310
     4 UNNAMED_310_TPTDR4PFTS_I19_S2 @S9S_MB_2U_LIB.S9S_MB_2U(SCH_1):UNNAMED_310_TPTDR4PFTS_I19_S2    I19 @S9S_MB_2U_LIB.S9S_MB_2U(SCH_1):PAGE310

 X35 TP_TDR_4P_FTS_TH-TP_TDR_4P_DIPA
     2 T1_GND @S9S_MB_2U_LIB.S9S_MB_2U(SCH_1):T1_GND    I16 @S9S_MB_2U_LIB.S9S_MB_2U(SCH_1):PAGE310
     3 T1_GND @S9S_MB_2U_LIB.S9S_MB_2U(SCH_1):T1_GND    I16 @S9S_MB_2U_LIB.S9S_MB_2U(SCH_1):PAGE310
     1 UNNAMED_310_TPTDR4PFTS_I15_S2 @S9S_MB_2U_LIB.S9S_MB_2U(SCH_1):UNNAMED_310_TPTDR4PFTS_I15_S2    I16 @S9S_MB_2U_LIB.S9S_MB_2U(SCH_1):PAGE310
     4 UNNAMED_310_TPTDR4PFTS_I15_S1 @S9S_MB_2U_LIB.S9S_MB_2U(SCH_1):UNNAMED_310_TPTDR4PFTS_I15_S1    I16 @S9S_MB_2U_LIB.S9S_MB_2U(SCH_1):PAGE310

 X36 TP_TDR_4P_FTS_TH-TP_TDR_4P_DIPA
     2 T1_GND @S9S_MB_2U_LIB.S9S_MB_2U(SCH_1):T1_GND     I8 @S9S_MB_2U_LIB.S9S_MB_2U(SCH_1):PAGE310
     3 T1_GND @S9S_MB_2U_LIB.S9S_MB_2U(SCH_1):T1_GND     I8 @S9S_MB_2U_LIB.S9S_MB_2U(SCH_1):PAGE310
     1 UNNAMED_310_TPTDR4PFTS_I10_S2 @S9S_MB_2U_LIB.S9S_MB_2U(SCH_1):UNNAMED_310_TPTDR4PFTS_I10_S2     I8 @S9S_MB_2U_LIB.S9S_MB_2U(SCH_1):PAGE310
     4 UNNAMED_310_TPTDR4PFTS_I10_S1 @S9S_MB_2U_LIB.S9S_MB_2U(SCH_1):UNNAMED_310_TPTDR4PFTS_I10_S1     I8 @S9S_MB_2U_LIB.S9S_MB_2U(SCH_1):PAGE310

 X37 TP_TDR_4P_FTS_TH-TP_TDR_4P_DIPA
     2 T1_GND @S9S_MB_2U_LIB.S9S_MB_2U(SCH_1):T1_GND     I7 @S9S_MB_2U_LIB.S9S_MB_2U(SCH_1):PAGE310
     3 T1_GND @S9S_MB_2U_LIB.S9S_MB_2U(SCH_1):T1_GND     I7 @S9S_MB_2U_LIB.S9S_MB_2U(SCH_1):PAGE310
     1 UNNAMED_310_TPTDR4PFTS_I7_S1 @S9S_MB_2U_LIB.S9S_MB_2U(SCH_1):UNNAMED_310_TPTDR4PFTS_I7_S1     I7 @S9S_MB_2U_LIB.S9S_MB_2U(SCH_1):PAGE310
     4 UNNAMED_310_TPTDR4PFTS_I7_S2 @S9S_MB_2U_LIB.S9S_MB_2U(SCH_1):UNNAMED_310_TPTDR4PFTS_I7_S2     I7 @S9S_MB_2U_LIB.S9S_MB_2U(SCH_1):PAGE310

 X38 TP_TDR_4P_FTS_TH-TP_TDR_4P_DIPA
     2 T1_GND @S9S_MB_2U_LIB.S9S_MB_2U(SCH_1):T1_GND     I5 @S9S_MB_2U_LIB.S9S_MB_2U(SCH_1):PAGE310
     3 T1_GND @S9S_MB_2U_LIB.S9S_MB_2U(SCH_1):T1_GND     I5 @S9S_MB_2U_LIB.S9S_MB_2U(SCH_1):PAGE310
     1 UNNAMED_310_TPTDR4PFTS_I5_S1 @S9S_MB_2U_LIB.S9S_MB_2U(SCH_1):UNNAMED_310_TPTDR4PFTS_I5_S1     I5 @S9S_MB_2U_LIB.S9S_MB_2U(SCH_1):PAGE310
     4 UNNAMED_310_TPTDR4PFTS_I5_S2 @S9S_MB_2U_LIB.S9S_MB_2U(SCH_1):UNNAMED_310_TPTDR4PFTS_I5_S2     I5 @S9S_MB_2U_LIB.S9S_MB_2U(SCH_1):PAGE310

 X39 TP_TDR_4P_FTS_TH-TP_TDR_4P_DIPA
     2 T1_GND @S9S_MB_2U_LIB.S9S_MB_2U(SCH_1):T1_GND    I22 @S9S_MB_2U_LIB.S9S_MB_2U(SCH_1):PAGE310
     3 T1_GND @S9S_MB_2U_LIB.S9S_MB_2U(SCH_1):T1_GND    I22 @S9S_MB_2U_LIB.S9S_MB_2U(SCH_1):PAGE310
     1 UNNAMED_310_TPTDR4PFTS_I20_S2 @S9S_MB_2U_LIB.S9S_MB_2U(SCH_1):UNNAMED_310_TPTDR4PFTS_I20_S2    I22 @S9S_MB_2U_LIB.S9S_MB_2U(SCH_1):PAGE310
     4 UNNAMED_310_TPTDR4PFTS_I20_S1 @S9S_MB_2U_LIB.S9S_MB_2U(SCH_1):UNNAMED_310_TPTDR4PFTS_I20_S1    I22 @S9S_MB_2U_LIB.S9S_MB_2U(SCH_1):PAGE310

 X40 TP_TDR_4P_FTS_TH-TP_TDR_4P_DIPA
     2 T1_GND @S9S_MB_2U_LIB.S9S_MB_2U(SCH_1):T1_GND    I21 @S9S_MB_2U_LIB.S9S_MB_2U(SCH_1):PAGE310
     3 T1_GND @S9S_MB_2U_LIB.S9S_MB_2U(SCH_1):T1_GND    I21 @S9S_MB_2U_LIB.S9S_MB_2U(SCH_1):PAGE310
     1 UNNAMED_310_TPTDR4PFTS_I19_S2 @S9S_MB_2U_LIB.S9S_MB_2U(SCH_1):UNNAMED_310_TPTDR4PFTS_I19_S2    I21 @S9S_MB_2U_LIB.S9S_MB_2U(SCH_1):PAGE310
     4 UNNAMED_310_TPTDR4PFTS_I19_S1 @S9S_MB_2U_LIB.S9S_MB_2U(SCH_1):UNNAMED_310_TPTDR4PFTS_I19_S1    I21 @S9S_MB_2U_LIB.S9S_MB_2U(SCH_1):PAGE310

 X41 TP_TDR_4P_FTS_TH-TP_TDR_4P_DIPA
     2 T1_GND @S9S_MB_2U_LIB.S9S_MB_2U(SCH_1):T1_GND    I15 @S9S_MB_2U_LIB.S9S_MB_2U(SCH_1):PAGE310
     3 T1_GND @S9S_MB_2U_LIB.S9S_MB_2U(SCH_1):T1_GND    I15 @S9S_MB_2U_LIB.S9S_MB_2U(SCH_1):PAGE310
     1 UNNAMED_310_TPTDR4PFTS_I15_S1 @S9S_MB_2U_LIB.S9S_MB_2U(SCH_1):UNNAMED_310_TPTDR4PFTS_I15_S1    I15 @S9S_MB_2U_LIB.S9S_MB_2U(SCH_1):PAGE310
     4 UNNAMED_310_TPTDR4PFTS_I15_S2 @S9S_MB_2U_LIB.S9S_MB_2U(SCH_1):UNNAMED_310_TPTDR4PFTS_I15_S2    I15 @S9S_MB_2U_LIB.S9S_MB_2U(SCH_1):PAGE310

 X42 TP_TDR_4P_FTS_TH-TP_TDR_4P_DIPA
     2 T1_GND @S9S_MB_2U_LIB.S9S_MB_2U(SCH_1):T1_GND    I10 @S9S_MB_2U_LIB.S9S_MB_2U(SCH_1):PAGE310
     3 T1_GND @S9S_MB_2U_LIB.S9S_MB_2U(SCH_1):T1_GND    I10 @S9S_MB_2U_LIB.S9S_MB_2U(SCH_1):PAGE310
     1 UNNAMED_310_TPTDR4PFTS_I10_S1 @S9S_MB_2U_LIB.S9S_MB_2U(SCH_1):UNNAMED_310_TPTDR4PFTS_I10_S1    I10 @S9S_MB_2U_LIB.S9S_MB_2U(SCH_1):PAGE310
     4 UNNAMED_310_TPTDR4PFTS_I10_S2 @S9S_MB_2U_LIB.S9S_MB_2U(SCH_1):UNNAMED_310_TPTDR4PFTS_I10_S2    I10 @S9S_MB_2U_LIB.S9S_MB_2U(SCH_1):PAGE310

 X43 TP_TDR_4P_FTS_TH-TP_TDR_4P_DIPA
     2 T1_GND @S9S_MB_2U_LIB.S9S_MB_2U(SCH_1):T1_GND     I9 @S9S_MB_2U_LIB.S9S_MB_2U(SCH_1):PAGE310
     3 T1_GND @S9S_MB_2U_LIB.S9S_MB_2U(SCH_1):T1_GND     I9 @S9S_MB_2U_LIB.S9S_MB_2U(SCH_1):PAGE310
     1 UNNAMED_310_TPTDR4PFTS_I7_S2 @S9S_MB_2U_LIB.S9S_MB_2U(SCH_1):UNNAMED_310_TPTDR4PFTS_I7_S2     I9 @S9S_MB_2U_LIB.S9S_MB_2U(SCH_1):PAGE310
     4 UNNAMED_310_TPTDR4PFTS_I7_S1 @S9S_MB_2U_LIB.S9S_MB_2U(SCH_1):UNNAMED_310_TPTDR4PFTS_I7_S1     I9 @S9S_MB_2U_LIB.S9S_MB_2U(SCH_1):PAGE310

 X44 TP_TDR_4P_FTS_TH-TP_TDR_4P_DIPA
     2 T1_GND @S9S_MB_2U_LIB.S9S_MB_2U(SCH_1):T1_GND     I6 @S9S_MB_2U_LIB.S9S_MB_2U(SCH_1):PAGE310
     3 T1_GND @S9S_MB_2U_LIB.S9S_MB_2U(SCH_1):T1_GND     I6 @S9S_MB_2U_LIB.S9S_MB_2U(SCH_1):PAGE310
     1 UNNAMED_310_TPTDR4PFTS_I5_S2 @S9S_MB_2U_LIB.S9S_MB_2U(SCH_1):UNNAMED_310_TPTDR4PFTS_I5_S2     I6 @S9S_MB_2U_LIB.S9S_MB_2U(SCH_1):PAGE310
     4 UNNAMED_310_TPTDR4PFTS_I5_S1 @S9S_MB_2U_LIB.S9S_MB_2U(SCH_1):UNNAMED_310_TPTDR4PFTS_I5_S1     I6 @S9S_MB_2U_LIB.S9S_MB_2U(SCH_1):PAGE310

  Y1 Q_CRYSTAL_SMLF-32.768KHZ,IC,BGA
     1 XTAL_PCH_RTC2_R @S9S_MB_2U_LIB.S9S_MB_2U(SCH_1):XTAL_PCH_RTC2_R    I11 @S9S_MB_2U_LIB.S9S_MB_2U(SCH_1):PAGE171
     2 XTAL_PCH_RTC1 @S9S_MB_2U_LIB.S9S_MB_2U(SCH_1):XTAL_PCH_RTC1    I11 @S9S_MB_2U_LIB.S9S_MB_2U(SCH_1):PAGE171

  Y2 Q_XTAL_4P_13BI_24GND-25MHZ,SMLB
     1 XTAL_CLK_GEN1_25M_X1_R @S9S_MB_2U_LIB.S9S_MB_2U(SCH_1):XTAL_CLK_GEN1_25M_X1_R   I391 @S9S_MB_2U_LIB.S9S_MB_2U(SCH_1):PAGE197
     2    GND @S9S_MB_2U_LIB.S9S_MB_2U(SCH_1):GND   I391 @S9S_MB_2U_LIB.S9S_MB_2U(SCH_1):PAGE197
     4    GND @S9S_MB_2U_LIB.S9S_MB_2U(SCH_1):GND   I391 @S9S_MB_2U_LIB.S9S_MB_2U(SCH_1):PAGE197
     3 XTAL_CLK_GEN1_25M_X2 @S9S_MB_2U_LIB.S9S_MB_2U(SCH_1):XTAL_CLK_GEN1_25M_X2   I391 @S9S_MB_2U_LIB.S9S_MB_2U(SCH_1):PAGE197

  Y3 Q_XTAL_4P_13BI_24GND-25MHZ,SMLB
     1 CLK_GEN2_XTAL_IN_R @S9S_MB_2U_LIB.S9S_MB_2U(SCH_1):CLK_GEN2_XTAL_IN_R   I159 @S9S_MB_2U_LIB.S9S_MB_2U(SCH_1):PAGE201
     2    GND @S9S_MB_2U_LIB.S9S_MB_2U(SCH_1):GND   I159 @S9S_MB_2U_LIB.S9S_MB_2U(SCH_1):PAGE201
     4    GND @S9S_MB_2U_LIB.S9S_MB_2U(SCH_1):GND   I159 @S9S_MB_2U_LIB.S9S_MB_2U(SCH_1):PAGE201
     3 CLK_GEN2_XTAL_OUT @S9S_MB_2U_LIB.S9S_MB_2U(SCH_1):CLK_GEN2_XTAL_OUT   I159 @S9S_MB_2U_LIB.S9S_MB_2U(SCH_1):PAGE201

  Y4 Q_XTAL_4P_13BI_24GND-12MHZ,SMLA
     1 USB_HUB_XTAL_IN @S9S_MB_2U_LIB.S9S_MB_2U(SCH_1):USB_HUB_XTAL_IN   I200 @S9S_MB_2U_LIB.S9S_MB_2U(SCH_1):PAGE155
     2    GND @S9S_MB_2U_LIB.S9S_MB_2U(SCH_1):GND   I200 @S9S_MB_2U_LIB.S9S_MB_2U(SCH_1):PAGE155
     4    GND @S9S_MB_2U_LIB.S9S_MB_2U(SCH_1):GND   I200 @S9S_MB_2U_LIB.S9S_MB_2U(SCH_1):PAGE155
     3 USB_HUB_XTAL_OUT @S9S_MB_2U_LIB.S9S_MB_2U(SCH_1):USB_HUB_XTAL_OUT   I200 @S9S_MB_2U_LIB.S9S_MB_2U(SCH_1):PAGE155

  Y7 Q_XTAL_4P_13BI_24GND-25MHZ,SMLA
     1 XTAL_PCH_25M_IN_R @S9S_MB_2U_LIB.S9S_MB_2U(SCH_1):XTAL_PCH_25M_IN_R    I75 @S9S_MB_2U_LIB.S9S_MB_2U(SCH_1):PAGE171
     2    GND @S9S_MB_2U_LIB.S9S_MB_2U(SCH_1):GND    I75 @S9S_MB_2U_LIB.S9S_MB_2U(SCH_1):PAGE171
     4    GND @S9S_MB_2U_LIB.S9S_MB_2U(SCH_1):GND    I75 @S9S_MB_2U_LIB.S9S_MB_2U(SCH_1):PAGE171
     3 XTAL_PCH_25M_OUT @S9S_MB_2U_LIB.S9S_MB_2U(SCH_1):XTAL_PCH_25M_OUT    I75 @S9S_MB_2U_LIB.S9S_MB_2U(SCH_1):PAGE171

  Y9 Q_XTAL_4P_13BI_24GND-12MHZ,SMLB
     1 USB_HUB_2_XTAL_IN @S9S_MB_2U_LIB.S9S_MB_2U(SCH_1):USB_HUB_2_XTAL_IN    I83 @S9S_MB_2U_LIB.S9S_MB_2U(SCH_1):PAGE194
     2    GND @S9S_MB_2U_LIB.S9S_MB_2U(SCH_1):GND    I83 @S9S_MB_2U_LIB.S9S_MB_2U(SCH_1):PAGE194
     4    GND @S9S_MB_2U_LIB.S9S_MB_2U(SCH_1):GND    I83 @S9S_MB_2U_LIB.S9S_MB_2U(SCH_1):PAGE194
     3 USB_HUB_2_XTAL_OUT @S9S_MB_2U_LIB.S9S_MB_2U(SCH_1):USB_HUB_2_XTAL_OUT    I83 @S9S_MB_2U_LIB.S9S_MB_2U(SCH_1):PAGE194

END GLOBAL PART CROSS REFERENCE
